LOGICAL PART CROSS REFERENCE - 30-Nov-2015 AT 15:33:22

DRAWING: @BASEBOARD_FAB2_LIB.BASEBOARD_FAB2(SCH_1):PAGE209 

RES_0402-1.00K,1%,1/16W,EMPTY,A  I3  R1E5
   1 VSENSE_PVCCIN_CPU1_P      A @BASEBOARD_FAB2_LIB.BASEBOARD_FAB2(SCH_1):VSENSE_PVCCIN_CPU1_P
   2 VSENSE_PVCCIN_CPU1_N      B @BASEBOARD_FAB2_LIB.BASEBOARD_FAB2(SCH_1):VSENSE_PVCCIN_CPU1_N

CAP_0805-10UF,16V,10%,X6S,C953A  I5  C9N27
   1 VR_FET_SW_P12V_STBY_PVCCIN_CPU1      A @BASEBOARD_FAB2_LIB.BASEBOARD_FAB2(SCH_1):VR_FET_SW_P12V_STBY_PVCCIN_CPU1
   2    GND      B @BASEBOARD_FAB2_LIB.BASEBOARD_FAB2(SCH_1):GND

CAP_0805-10UF,16V,10%,X6S,C953A  I7  C9N26
   1 VR_FET_SW_P12V_STBY_PVCCIN_CPU1      A @BASEBOARD_FAB2_LIB.BASEBOARD_FAB2(SCH_1):VR_FET_SW_P12V_STBY_PVCCIN_CPU1
   2    GND      B @BASEBOARD_FAB2_LIB.BASEBOARD_FAB2(SCH_1):GND

CAP_0805-10UF,16V,10%,X6S,C953A  I8  C9N25
   1 VR_FET_SW_P12V_STBY_PVCCIN_CPU1      A @BASEBOARD_FAB2_LIB.BASEBOARD_FAB2(SCH_1):VR_FET_SW_P12V_STBY_PVCCIN_CPU1
   2    GND      B @BASEBOARD_FAB2_LIB.BASEBOARD_FAB2(SCH_1):GND

RES_0402-100.0,1%,1/16W,CHIP,GA  I9  R1E8
   1 VSENSE_PVCCIN_CPU1_N      A @BASEBOARD_FAB2_LIB.BASEBOARD_FAB2(SCH_1):VSENSE_PVCCIN_CPU1_N
   2    GND      B @BASEBOARD_FAB2_LIB.BASEBOARD_FAB2(SCH_1):GND

RES_0402-0.0,5%,1/16W,CHIP,G21A  I10  R1E7
   1 VSENSE_PVCCIN_CPU1_N      A @BASEBOARD_FAB2_LIB.BASEBOARD_FAB2(SCH_1):VSENSE_PVCCIN_CPU1_N
   2 VSENSE_PVCCIN_CPU1_SKT_VRTN      B @BASEBOARD_FAB2_LIB.BASEBOARD_FAB2(SCH_1):VSENSE_PVCCIN_CPU1_SKT_VRTN

RES_0402-0.0,5%,1/16W,CHIP,G21A  I11  R1E6
   1 VSENSE_PVCCIN_CPU1_P      A @BASEBOARD_FAB2_LIB.BASEBOARD_FAB2(SCH_1):VSENSE_PVCCIN_CPU1_P
   2 VSENSE_PVCCIN_CPU1_SKT_VSEN      B @BASEBOARD_FAB2_LIB.BASEBOARD_FAB2(SCH_1):VSENSE_PVCCIN_CPU1_SKT_VSEN

RES_0402-100.0,1%,1/16W,CHIP,GA  I15  R1E4
   1 VSENSE_PVCCIN_CPU1_P      A @BASEBOARD_FAB2_LIB.BASEBOARD_FAB2(SCH_1):VSENSE_PVCCIN_CPU1_P
   2 PVCCIN_CPU1      B @BASEBOARD_FAB2_LIB.BASEBOARD_FAB2(SCH_1):PVCCIN_CPU1

CAP_0402-1.0UF,16V,10%,X6S,D97A  I16  C1C26
   1 VR_FET_SW_P12V_STBY_PVCCIN_CPU1      A @BASEBOARD_FAB2_LIB.BASEBOARD_FAB2(SCH_1):VR_FET_SW_P12V_STBY_PVCCIN_CPU1
   2    GND      B @BASEBOARD_FAB2_LIB.BASEBOARD_FAB2(SCH_1):GND

CAP_A_0402V-0.1UF,16V,10%,X7R,A  I17  C1C25
   1 VR_FET_SW_P12V_STBY_PVCCIN_CPU1      A @BASEBOARD_FAB2_LIB.BASEBOARD_FAB2(SCH_1):VR_FET_SW_P12V_STBY_PVCCIN_CPU1
   2    GND      B @BASEBOARD_FAB2_LIB.BASEBOARD_FAB2(SCH_1):GND

CAP_0402-1.0UF,16V,10%,X6S,D97A  I18  C1D32
   1 VR_PVCCIN_CPU1_PH5_VCIN      A @BASEBOARD_FAB2_LIB.BASEBOARD_FAB2(SCH_1):VR_PVCCIN_CPU1_PH5_VCIN
   2    GND      B @BASEBOARD_FAB2_LIB.BASEBOARD_FAB2(SCH_1):GND

CAP_0402-0.220UF,16V,10%,X7R,AA  I20  C1C24
   1 VR_PVCCIN_CPU1_PH5_BOOT      A @BASEBOARD_FAB2_LIB.BASEBOARD_FAB2(SCH_1):VR_PVCCIN_CPU1_PH5_BOOT
   2 VR_PVCCIN_CPU1_PH5_PHASE      B @BASEBOARD_FAB2_LIB.BASEBOARD_FAB2(SCH_1):VR_PVCCIN_CPU1_PH5_PHASE

CAP_A_0402V-1.0UF,6.3V,10%,X6SA  I21  C1C18
   1 P5V_STBY      A @BASEBOARD_FAB2_LIB.BASEBOARD_FAB2(SCH_1):P5V_STBY
   2    GND      B @BASEBOARD_FAB2_LIB.BASEBOARD_FAB2(SCH_1):GND

CAP_0402-0.22UF,16V,10%,X7R,A3A  I22  C1D33
   1 P5V_STBY      A @BASEBOARD_FAB2_LIB.BASEBOARD_FAB2(SCH_1):P5V_STBY
   2    GND      B @BASEBOARD_FAB2_LIB.BASEBOARD_FAB2(SCH_1):GND

RES_0402-1.0,1%,1/16W,CHIP,G21A  I24  R9P32
   1 VR_PVCCIN_CPU1_PH5_VCIN      A @BASEBOARD_FAB2_LIB.BASEBOARD_FAB2(SCH_1):VR_PVCCIN_CPU1_PH5_VCIN
   2 P5V_STBY      B @BASEBOARD_FAB2_LIB.BASEBOARD_FAB2(SCH_1):P5V_STBY

CAP_A_0402V-0.1UF,16V,10%,EMPTA  I30  C1B16
   1 VR_FET_SW_P12V_PVCCIN_CPU1_R      A @BASEBOARD_FAB2_LIB.BASEBOARD_FAB2(SCH_1):VR_FET_SW_P12V_PVCCIN_CPU1_R
   2    GND      B @BASEBOARD_FAB2_LIB.BASEBOARD_FAB2(SCH_1):GND

INDUCTOR_SM-100NH,IND,D92183-0A  I32  L1B2
   1 P12V_STBY    INA @BASEBOARD_FAB2_LIB.BASEBOARD_FAB2(SCH_1):P12V_STBY
   2 VR_FET_SW_P12V_PVCCIN_CPU1_R    INB @BASEBOARD_FAB2_LIB.BASEBOARD_FAB2(SCH_1):VR_FET_SW_P12V_PVCCIN_CPU1_R

CAPP_2626-270UF,16V,20%,OSCON,A  I35  C1C1
   1 VR_FET_SW_P12V_STBY_PVCCIN_CPU1      A @BASEBOARD_FAB2_LIB.BASEBOARD_FAB2(SCH_1):VR_FET_SW_P12V_STBY_PVCCIN_CPU1
   2    GND      B @BASEBOARD_FAB2_LIB.BASEBOARD_FAB2(SCH_1):GND

CAPP_2626-270UF,16V,20%,OSCON,A  I37  C1E18
   1 VR_FET_SW_P12V_STBY_PVCCIN_CPU1      A @BASEBOARD_FAB2_LIB.BASEBOARD_FAB2(SCH_1):VR_FET_SW_P12V_STBY_PVCCIN_CPU1
   2    GND      B @BASEBOARD_FAB2_LIB.BASEBOARD_FAB2(SCH_1):GND

CAPP_2626-270UF,16V,20%,OSCON,A  I38  C1C2
   1 VR_FET_SW_P12V_STBY_PVCCIN_CPU1      A @BASEBOARD_FAB2_LIB.BASEBOARD_FAB2(SCH_1):VR_FET_SW_P12V_STBY_PVCCIN_CPU1
   2    GND      B @BASEBOARD_FAB2_LIB.BASEBOARD_FAB2(SCH_1):GND

RES_2010-0.001,1%,1W,CHIP,E309A  I39  R1B20
   1 VR_FET_SW_P12V_PVCCIN_CPU1_R      A @BASEBOARD_FAB2_LIB.BASEBOARD_FAB2(SCH_1):VR_FET_SW_P12V_PVCCIN_CPU1_R
   2 VR_FET_SW_P12V_STBY_PVCCIN_CPU1      B @BASEBOARD_FAB2_LIB.BASEBOARD_FAB2(SCH_1):VR_FET_SW_P12V_STBY_PVCCIN_CPU1

INDUCTOR_SM-0.12UH,IND,D92183-A  I40  L1C2
   1 VR_PVCCIN_CPU1_PHASE5    INA @BASEBOARD_FAB2_LIB.BASEBOARD_FAB2(SCH_1):VR_PVCCIN_CPU1_PHASE5
   2 PVCCIN_CPU1    INB @BASEBOARD_FAB2_LIB.BASEBOARD_FAB2(SCH_1):PVCCIN_CPU1

CAP_A_0603V-22.0UF,4V,20%,X6S,A  I42  C1D24
   1 PVCCIN_CPU1      A @BASEBOARD_FAB2_LIB.BASEBOARD_FAB2(SCH_1):PVCCIN_CPU1
   2    GND      B @BASEBOARD_FAB2_LIB.BASEBOARD_FAB2(SCH_1):GND

ADM4073_SM-EMPTY,G12194-001  I52  U1B3
   2    GND GND<1> @BASEBOARD_FAB2_LIB.BASEBOARD_FAB2(SCH_1):GND
   1    GND GND<0> @BASEBOARD_FAB2_LIB.BASEBOARD_FAB2(SCH_1):GND
   6 PVCCIN_PVSA_CPU1_IINSEN    OUT @BASEBOARD_FAB2_LIB.BASEBOARD_FAB2(SCH_1):PVCCIN_PVSA_CPU1_IINSEN
   5 VR_FET_SW_P12V_STBY_PVCCIN_CPU1    RSN @BASEBOARD_FAB2_LIB.BASEBOARD_FAB2(SCH_1):VR_FET_SW_P12V_STBY_PVCCIN_CPU1
   4 VR_FET_SW_P12V_PVCCIN_CPU1_R    RSP @BASEBOARD_FAB2_LIB.BASEBOARD_FAB2(SCH_1):VR_FET_SW_P12V_PVCCIN_CPU1_R
   3 VR_FET_SW_P12V_PVCCIN_CPU1_R    VCC @BASEBOARD_FAB2_LIB.BASEBOARD_FAB2(SCH_1):VR_FET_SW_P12V_PVCCIN_CPU1_R

CAP_A_0603V-22.0UF,4V,20%,X6S,A  I55  C9P20
   1 PVCCIN_CPU1      A @BASEBOARD_FAB2_LIB.BASEBOARD_FAB2(SCH_1):PVCCIN_CPU1
   2    GND      B @BASEBOARD_FAB2_LIB.BASEBOARD_FAB2(SCH_1):GND

IR354XX_SM-IR35411,IC,H73688-0A  I56  EU1C3
  33 VR_PVCCIN_CPU1_PH5_BOOT_R  BOOST @BASEBOARD_FAB2_LIB.BASEBOARD_FAB2(SCH_1):VR_PVCCIN_CPU1_PH5_BOOT_R
  35 P5V_STBY     EN @BASEBOARD_FAB2_LIB.BASEBOARD_FAB2(SCH_1):P5V_STBY
  41 TP_PVCCIN_CPU1_PH5_GL_1  GL<1> @BASEBOARD_FAB2_LIB.BASEBOARD_FAB2(SCH_1):TP_PVCCIN_CPU1_PH5_GL_1
   6 TP_PVCCIN_CPU1_PH5_GL_0  GL<0> @BASEBOARD_FAB2_LIB.BASEBOARD_FAB2(SCH_1):TP_PVCCIN_CPU1_PH5_GL_0
  38 ISENSE_PVCCIN_CPU1_PH5_IMON   IOUT @BASEBOARD_FAB2_LIB.BASEBOARD_FAB2(SCH_1):ISENSE_PVCCIN_CPU1_PH5_IMON
   2    GND   LGND @BASEBOARD_FAB2_LIB.BASEBOARD_FAB2(SCH_1):GND
  31 NC_PVCCIN_CPU1_PH5_P31     NC @BASEBOARD_FAB2_LIB.BASEBOARD_FAB2(SCH_1):NC_PVCCIN_CPU1_PH5_P31
  37 VR_PVCCIN_CPU1_PH5_OCSET  OCSET @BASEBOARD_FAB2_LIB.BASEBOARD_FAB2(SCH_1):VR_PVCCIN_CPU1_PH5_OCSET
  40    GND PGND<2> @BASEBOARD_FAB2_LIB.BASEBOARD_FAB2(SCH_1):GND
   7    GND PGND<1> @BASEBOARD_FAB2_LIB.BASEBOARD_FAB2(SCH_1):GND
   5    GND PGND<0> @BASEBOARD_FAB2_LIB.BASEBOARD_FAB2(SCH_1):GND
  32 VR_PVCCIN_CPU1_PH5_PHASE  PHASE @BASEBOARD_FAB2_LIB.BASEBOARD_FAB2(SCH_1):VR_PVCCIN_CPU1_PH5_PHASE
  34 VR_PVCCIN_CPU1_PWM5    PWM @BASEBOARD_FAB2_LIB.BASEBOARD_FAB2(SCH_1):VR_PVCCIN_CPU1_PWM5
  39 VR_PVCCIN_CPU1_AIREF5  REFIN @BASEBOARD_FAB2_LIB.BASEBOARD_FAB2(SCH_1):VR_PVCCIN_CPU1_AIREF5
  10 VR_PVCCIN_CPU1_PHASE5     SW @BASEBOARD_FAB2_LIB.BASEBOARD_FAB2(SCH_1):VR_PVCCIN_CPU1_PHASE5
  36 A_TSENSE_PVCCIN_CPU1 TOUT_FLT @BASEBOARD_FAB2_LIB.BASEBOARD_FAB2(SCH_1):A_TSENSE_PVCCIN_CPU1
   3 VR_PVCCIN_CPU1_PH5_VCIN    VCC @BASEBOARD_FAB2_LIB.BASEBOARD_FAB2(SCH_1):VR_PVCCIN_CPU1_PH5_VCIN
   4 P5V_STBY   VDRV @BASEBOARD_FAB2_LIB.BASEBOARD_FAB2(SCH_1):P5V_STBY
  30 VR_FET_SW_P12V_STBY_PVCCIN_CPU1 VIN<1> @BASEBOARD_FAB2_LIB.BASEBOARD_FAB2(SCH_1):VR_FET_SW_P12V_STBY_PVCCIN_CPU1
  25 VR_FET_SW_P12V_STBY_PVCCIN_CPU1 VIN<0> @BASEBOARD_FAB2_LIB.BASEBOARD_FAB2(SCH_1):VR_FET_SW_P12V_STBY_PVCCIN_CPU1
   1 PVCCIN_CPU1    VOS @BASEBOARD_FAB2_LIB.BASEBOARD_FAB2(SCH_1):PVCCIN_CPU1

RES_0402-68.1K,1%,1/16W,EMPTY,A  I59  R1D52
   1 VR_PVCCIN_CPU1_PH5_OCSET      A @BASEBOARD_FAB2_LIB.BASEBOARD_FAB2(SCH_1):VR_PVCCIN_CPU1_PH5_OCSET
   2    GND      B @BASEBOARD_FAB2_LIB.BASEBOARD_FAB2(SCH_1):GND

CAP_A_0402V-0.1UF,16V,10%,X7R,A  I62  CT13
   1 VR_PVCCIN_CPU1_AIREF5      A @BASEBOARD_FAB2_LIB.BASEBOARD_FAB2(SCH_1):VR_PVCCIN_CPU1_AIREF5
   2    GND      B @BASEBOARD_FAB2_LIB.BASEBOARD_FAB2(SCH_1):GND

SC2K2P50V3KX-GP_SMD-BCG6-SC2K2A  I64  CT14
   1 VR_PVCCIN_CPU1_PHASE5      1 @BASEBOARD_FAB2_LIB.BASEBOARD_FAB2(SCH_1):VR_PVCCIN_CPU1_PHASE5
   2 UNNAMED_209_3D01R5F-GP_I66_2      2 @BASEBOARD_FAB2_LIB.BASEBOARD_FAB2(SCH_1):UNNAMED_209_3D01R5F-GP_I66_2

CAP_0402LF-1000PF,50V,10%,X7R,A  I67  CT15
   1 A_TSENSE_PVCCIN_CPU1      A @BASEBOARD_FAB2_LIB.BASEBOARD_FAB2(SCH_1):A_TSENSE_PVCCIN_CPU1
   2    GND      B @BASEBOARD_FAB2_LIB.BASEBOARD_FAB2(SCH_1):GND

3D01R5F-GP_SMD-RG5-3D01R5F-GP,A  I66  RT10
   1    GND      1 @BASEBOARD_FAB2_LIB.BASEBOARD_FAB2(SCH_1):GND
   2 UNNAMED_209_3D01R5F-GP_I66_2      2 @BASEBOARD_FAB2_LIB.BASEBOARD_FAB2(SCH_1):UNNAMED_209_3D01R5F-GP_I66_2

RES_0402-0.0,5%,1/16W,CHIP,G21A  I69  RT9
   1 VR_PVCCIN_CPU1_PH5_BOOT      A @BASEBOARD_FAB2_LIB.BASEBOARD_FAB2(SCH_1):VR_PVCCIN_CPU1_PH5_BOOT
   2 VR_PVCCIN_CPU1_PH5_BOOT_R      B @BASEBOARD_FAB2_LIB.BASEBOARD_FAB2(SCH_1):VR_PVCCIN_CPU1_PH5_BOOT_R


DRAWING: @BASEBOARD_FAB2_LIB.BASEBOARD_FAB2(SCH_1):PAGE227 

CAP_0805LF-22UF,4V,20%,X6S,C95A  I6  C1A12
   1 PVDDQ_KLM      A @BASEBOARD_FAB2_LIB.BASEBOARD_FAB2(SCH_1):PVDDQ_KLM
   2    GND      B @BASEBOARD_FAB2_LIB.BASEBOARD_FAB2(SCH_1):GND

CAP_0402-0.220UF,16V,10%,X7R,AA  I44  C1A18
   1 VR_PVDDQ_KLM_PH1_BOOT      A @BASEBOARD_FAB2_LIB.BASEBOARD_FAB2(SCH_1):VR_PVDDQ_KLM_PH1_BOOT
   2 VR_PVDDQ_KLM_PH1_PHASE      B @BASEBOARD_FAB2_LIB.BASEBOARD_FAB2(SCH_1):VR_PVDDQ_KLM_PH1_PHASE

CAP_0805-10UF,16V,10%,X6S,C953A  I45  C9L11
   1 VR_FET_SW_P12V_STBY_PVDDQ_KLM      A @BASEBOARD_FAB2_LIB.BASEBOARD_FAB2(SCH_1):VR_FET_SW_P12V_STBY_PVDDQ_KLM
   2    GND      B @BASEBOARD_FAB2_LIB.BASEBOARD_FAB2(SCH_1):GND

CAP_0805-10UF,16V,10%,X6S,C953A  I46  C9L10
   1 VR_FET_SW_P12V_STBY_PVDDQ_KLM      A @BASEBOARD_FAB2_LIB.BASEBOARD_FAB2(SCH_1):VR_FET_SW_P12V_STBY_PVDDQ_KLM
   2    GND      B @BASEBOARD_FAB2_LIB.BASEBOARD_FAB2(SCH_1):GND

CAP_0805-10UF,16V,10%,X6S,C953A  I47  C9L6
   1 VR_FET_SW_P12V_STBY_PVDDQ_KLM      A @BASEBOARD_FAB2_LIB.BASEBOARD_FAB2(SCH_1):VR_FET_SW_P12V_STBY_PVDDQ_KLM
   2    GND      B @BASEBOARD_FAB2_LIB.BASEBOARD_FAB2(SCH_1):GND

CAP_0402-1.0UF,16V,10%,X6S,D97A  I48  C1A19
   1 VR_FET_SW_P12V_STBY_PVDDQ_KLM      A @BASEBOARD_FAB2_LIB.BASEBOARD_FAB2(SCH_1):VR_FET_SW_P12V_STBY_PVDDQ_KLM
   2    GND      B @BASEBOARD_FAB2_LIB.BASEBOARD_FAB2(SCH_1):GND

CAP_0402-1.0UF,16V,10%,X6S,D97A  I50  C1B20
   1 VR_PVDDQ_KLM_PH1_VCIN      A @BASEBOARD_FAB2_LIB.BASEBOARD_FAB2(SCH_1):VR_PVDDQ_KLM_PH1_VCIN
   2    GND      B @BASEBOARD_FAB2_LIB.BASEBOARD_FAB2(SCH_1):GND

CAP_A_0402V-0.1UF,16V,10%,X7R,A  I51  C1A10
   1 VR_FET_SW_P12V_STBY_PVDDQ_KLM      A @BASEBOARD_FAB2_LIB.BASEBOARD_FAB2(SCH_1):VR_FET_SW_P12V_STBY_PVDDQ_KLM
   2    GND      B @BASEBOARD_FAB2_LIB.BASEBOARD_FAB2(SCH_1):GND

RES_0402-1.0,1%,1/16W,CHIP,G21A  I52  R9L9
   1 VR_PVDDQ_KLM_PH1_VCIN      A @BASEBOARD_FAB2_LIB.BASEBOARD_FAB2(SCH_1):VR_PVDDQ_KLM_PH1_VCIN
   2 P5V_STBY      B @BASEBOARD_FAB2_LIB.BASEBOARD_FAB2(SCH_1):P5V_STBY

CAP_A_0402V-1.0UF,6.3V,10%,X6SA  I53  C1A2
   1 P5V_STBY      A @BASEBOARD_FAB2_LIB.BASEBOARD_FAB2(SCH_1):P5V_STBY
   2    GND      B @BASEBOARD_FAB2_LIB.BASEBOARD_FAB2(SCH_1):GND

CAP_0402-0.22UF,16V,10%,X7R,A3A  I54  C1B21
   1 P5V_STBY      A @BASEBOARD_FAB2_LIB.BASEBOARD_FAB2(SCH_1):P5V_STBY
   2    GND      B @BASEBOARD_FAB2_LIB.BASEBOARD_FAB2(SCH_1):GND

INDUCTOR_SM-0.12UH,IND,D92183-A  I55  L1A2
   1 VR_PVDDQ_KLM_PH1_SW    INA @BASEBOARD_FAB2_LIB.BASEBOARD_FAB2(SCH_1):VR_PVDDQ_KLM_PH1_SW
   2 PVDDQ_KLM    INB @BASEBOARD_FAB2_LIB.BASEBOARD_FAB2(SCH_1):PVDDQ_KLM

INDUCTOR_SM-0.12UH,IND,D92183-A  I65  L1A1
   1 VR_PVDDQ_KLM_PH2_SW    INA @BASEBOARD_FAB2_LIB.BASEBOARD_FAB2(SCH_1):VR_PVDDQ_KLM_PH2_SW
   2 PVDDQ_KLM    INB @BASEBOARD_FAB2_LIB.BASEBOARD_FAB2(SCH_1):PVDDQ_KLM

CAP_0805LF-22UF,4V,20%,X6S,C95A  I68  C1A1
   1 PVDDQ_KLM      A @BASEBOARD_FAB2_LIB.BASEBOARD_FAB2(SCH_1):PVDDQ_KLM
   2    GND      B @BASEBOARD_FAB2_LIB.BASEBOARD_FAB2(SCH_1):GND

CAP_0402-0.22UF,16V,10%,X7R,A3A  I72  C1A13
   1 P5V_STBY      A @BASEBOARD_FAB2_LIB.BASEBOARD_FAB2(SCH_1):P5V_STBY
   2    GND      B @BASEBOARD_FAB2_LIB.BASEBOARD_FAB2(SCH_1):GND

CAP_A_0402V-1.0UF,6.3V,10%,X6SA  I73  C1A11
   1 P5V_STBY      A @BASEBOARD_FAB2_LIB.BASEBOARD_FAB2(SCH_1):P5V_STBY
   2    GND      B @BASEBOARD_FAB2_LIB.BASEBOARD_FAB2(SCH_1):GND

CAP_0402-0.220UF,16V,10%,X7R,AA  I75  C1A8
   1 VR_PVDDQ_KLM_PH2_BOOT      A @BASEBOARD_FAB2_LIB.BASEBOARD_FAB2(SCH_1):VR_PVDDQ_KLM_PH2_BOOT
   2 VR_PVDDQ_KLM_PH2_PHASE      B @BASEBOARD_FAB2_LIB.BASEBOARD_FAB2(SCH_1):VR_PVDDQ_KLM_PH2_PHASE

RES_0402-1.0,1%,1/16W,CHIP,G21A  I76  R9L4
   1 VR_PVDDQ_KLM_PH2_VCIN      A @BASEBOARD_FAB2_LIB.BASEBOARD_FAB2(SCH_1):VR_PVDDQ_KLM_PH2_VCIN
   2 P5V_STBY      B @BASEBOARD_FAB2_LIB.BASEBOARD_FAB2(SCH_1):P5V_STBY

CAP_0402-1.0UF,16V,10%,X6S,D97A  I77  C1A6
   1 VR_PVDDQ_KLM_PH2_VCIN      A @BASEBOARD_FAB2_LIB.BASEBOARD_FAB2(SCH_1):VR_PVDDQ_KLM_PH2_VCIN
   2    GND      B @BASEBOARD_FAB2_LIB.BASEBOARD_FAB2(SCH_1):GND

CAP_A_0402V-0.1UF,16V,10%,X7R,A  I78  C1A20
   1 VR_FET_SW_P12V_STBY_PVDDQ_KLM      A @BASEBOARD_FAB2_LIB.BASEBOARD_FAB2(SCH_1):VR_FET_SW_P12V_STBY_PVDDQ_KLM
   2    GND      B @BASEBOARD_FAB2_LIB.BASEBOARD_FAB2(SCH_1):GND

CAP_0402-1.0UF,16V,10%,X6S,D97A  I79  C1A9
   1 VR_FET_SW_P12V_STBY_PVDDQ_KLM      A @BASEBOARD_FAB2_LIB.BASEBOARD_FAB2(SCH_1):VR_FET_SW_P12V_STBY_PVDDQ_KLM
   2    GND      B @BASEBOARD_FAB2_LIB.BASEBOARD_FAB2(SCH_1):GND

CAP_0805-10UF,16V,10%,X6S,C953A  I80  C9L5
   1 VR_FET_SW_P12V_STBY_PVDDQ_KLM      A @BASEBOARD_FAB2_LIB.BASEBOARD_FAB2(SCH_1):VR_FET_SW_P12V_STBY_PVDDQ_KLM
   2    GND      B @BASEBOARD_FAB2_LIB.BASEBOARD_FAB2(SCH_1):GND

CAP_0805-10UF,16V,10%,X6S,C953A  I81  C9L13
   1 VR_FET_SW_P12V_STBY_PVDDQ_KLM      A @BASEBOARD_FAB2_LIB.BASEBOARD_FAB2(SCH_1):VR_FET_SW_P12V_STBY_PVDDQ_KLM
   2    GND      B @BASEBOARD_FAB2_LIB.BASEBOARD_FAB2(SCH_1):GND

CAP_0805-10UF,16V,10%,X6S,C953A  I84  C9L14
   1 VR_FET_SW_P12V_STBY_PVDDQ_KLM      A @BASEBOARD_FAB2_LIB.BASEBOARD_FAB2(SCH_1):VR_FET_SW_P12V_STBY_PVDDQ_KLM
   2    GND      B @BASEBOARD_FAB2_LIB.BASEBOARD_FAB2(SCH_1):GND

IR354XX_SM-IR35411,IC,H73688-0A  I101  EU1A2
  33 VR_PVDDQ_KLM_PH1_BOOT_R  BOOST @BASEBOARD_FAB2_LIB.BASEBOARD_FAB2(SCH_1):VR_PVDDQ_KLM_PH1_BOOT_R
  35 P5V_STBY     EN @BASEBOARD_FAB2_LIB.BASEBOARD_FAB2(SCH_1):P5V_STBY
  41 TP_PVDDQ_KLM_PH1_GL_1  GL<1> @BASEBOARD_FAB2_LIB.BASEBOARD_FAB2(SCH_1):TP_PVDDQ_KLM_PH1_GL_1
   6 TP_PVDDQ_KLM_PH1_GL_0  GL<0> @BASEBOARD_FAB2_LIB.BASEBOARD_FAB2(SCH_1):TP_PVDDQ_KLM_PH1_GL_0
  38 ISENSE_PVDDQ_KLM_PH1_IMON   IOUT @BASEBOARD_FAB2_LIB.BASEBOARD_FAB2(SCH_1):ISENSE_PVDDQ_KLM_PH1_IMON
   2    GND   LGND @BASEBOARD_FAB2_LIB.BASEBOARD_FAB2(SCH_1):GND
  31 NC_PVDDQ_KLM_PH1_P31     NC @BASEBOARD_FAB2_LIB.BASEBOARD_FAB2(SCH_1):NC_PVDDQ_KLM_PH1_P31
  37 VR_PVDDQ_KLM_PH1_OCSET  OCSET @BASEBOARD_FAB2_LIB.BASEBOARD_FAB2(SCH_1):VR_PVDDQ_KLM_PH1_OCSET
  40    GND PGND<2> @BASEBOARD_FAB2_LIB.BASEBOARD_FAB2(SCH_1):GND
   7    GND PGND<1> @BASEBOARD_FAB2_LIB.BASEBOARD_FAB2(SCH_1):GND
   5    GND PGND<0> @BASEBOARD_FAB2_LIB.BASEBOARD_FAB2(SCH_1):GND
  32 VR_PVDDQ_KLM_PH1_PHASE  PHASE @BASEBOARD_FAB2_LIB.BASEBOARD_FAB2(SCH_1):VR_PVDDQ_KLM_PH1_PHASE
  34 VR_PVDDQ_KLM_PWM1    PWM @BASEBOARD_FAB2_LIB.BASEBOARD_FAB2(SCH_1):VR_PVDDQ_KLM_PWM1
  39 VR_PVDDQ_KLM_AIREF1  REFIN @BASEBOARD_FAB2_LIB.BASEBOARD_FAB2(SCH_1):VR_PVDDQ_KLM_AIREF1
  10 VR_PVDDQ_KLM_PH1_SW     SW @BASEBOARD_FAB2_LIB.BASEBOARD_FAB2(SCH_1):VR_PVDDQ_KLM_PH1_SW
  36 A_TSENSE_PVDDQ_KLM TOUT_FLT @BASEBOARD_FAB2_LIB.BASEBOARD_FAB2(SCH_1):A_TSENSE_PVDDQ_KLM
   3 VR_PVDDQ_KLM_PH1_VCIN    VCC @BASEBOARD_FAB2_LIB.BASEBOARD_FAB2(SCH_1):VR_PVDDQ_KLM_PH1_VCIN
   4 P5V_STBY   VDRV @BASEBOARD_FAB2_LIB.BASEBOARD_FAB2(SCH_1):P5V_STBY
  30 VR_FET_SW_P12V_STBY_PVDDQ_KLM VIN<1> @BASEBOARD_FAB2_LIB.BASEBOARD_FAB2(SCH_1):VR_FET_SW_P12V_STBY_PVDDQ_KLM
  25 VR_FET_SW_P12V_STBY_PVDDQ_KLM VIN<0> @BASEBOARD_FAB2_LIB.BASEBOARD_FAB2(SCH_1):VR_FET_SW_P12V_STBY_PVDDQ_KLM
   1 PVDDQ_KLM    VOS @BASEBOARD_FAB2_LIB.BASEBOARD_FAB2(SCH_1):PVDDQ_KLM

IR354XX_SM-IR35411,IC,H73688-0A  I102  EU1A1
  33 VR_PVDDQ_KLM_PH2_BOOT_R  BOOST @BASEBOARD_FAB2_LIB.BASEBOARD_FAB2(SCH_1):VR_PVDDQ_KLM_PH2_BOOT_R
  35 P5V_STBY     EN @BASEBOARD_FAB2_LIB.BASEBOARD_FAB2(SCH_1):P5V_STBY
  41 TP_PVDDQ_KLM_PH2_GL_1  GL<1> @BASEBOARD_FAB2_LIB.BASEBOARD_FAB2(SCH_1):TP_PVDDQ_KLM_PH2_GL_1
   6 TP_PVDDQ_KLM_PH2_GL_0  GL<0> @BASEBOARD_FAB2_LIB.BASEBOARD_FAB2(SCH_1):TP_PVDDQ_KLM_PH2_GL_0
  38 ISENSE_PVDDQ_KLM_PH2_IMON   IOUT @BASEBOARD_FAB2_LIB.BASEBOARD_FAB2(SCH_1):ISENSE_PVDDQ_KLM_PH2_IMON
   2    GND   LGND @BASEBOARD_FAB2_LIB.BASEBOARD_FAB2(SCH_1):GND
  31 NC_PVDDQ_KLM_PH2_P31     NC @BASEBOARD_FAB2_LIB.BASEBOARD_FAB2(SCH_1):NC_PVDDQ_KLM_PH2_P31
  37 VR_PVDDQ_KLM_PH2_OCSET  OCSET @BASEBOARD_FAB2_LIB.BASEBOARD_FAB2(SCH_1):VR_PVDDQ_KLM_PH2_OCSET
  40    GND PGND<2> @BASEBOARD_FAB2_LIB.BASEBOARD_FAB2(SCH_1):GND
   7    GND PGND<1> @BASEBOARD_FAB2_LIB.BASEBOARD_FAB2(SCH_1):GND
   5    GND PGND<0> @BASEBOARD_FAB2_LIB.BASEBOARD_FAB2(SCH_1):GND
  32 VR_PVDDQ_KLM_PH2_PHASE  PHASE @BASEBOARD_FAB2_LIB.BASEBOARD_FAB2(SCH_1):VR_PVDDQ_KLM_PH2_PHASE
  34 VR_PVDDQ_KLM_PWM2    PWM @BASEBOARD_FAB2_LIB.BASEBOARD_FAB2(SCH_1):VR_PVDDQ_KLM_PWM2
  39 VR_PVDDQ_KLM_AIREF2  REFIN @BASEBOARD_FAB2_LIB.BASEBOARD_FAB2(SCH_1):VR_PVDDQ_KLM_AIREF2
  10 VR_PVDDQ_KLM_PH2_SW     SW @BASEBOARD_FAB2_LIB.BASEBOARD_FAB2(SCH_1):VR_PVDDQ_KLM_PH2_SW
  36 A_TSENSE_PVDDQ_KLM TOUT_FLT @BASEBOARD_FAB2_LIB.BASEBOARD_FAB2(SCH_1):A_TSENSE_PVDDQ_KLM
   3 VR_PVDDQ_KLM_PH2_VCIN    VCC @BASEBOARD_FAB2_LIB.BASEBOARD_FAB2(SCH_1):VR_PVDDQ_KLM_PH2_VCIN
   4 P5V_STBY   VDRV @BASEBOARD_FAB2_LIB.BASEBOARD_FAB2(SCH_1):P5V_STBY
  30 VR_FET_SW_P12V_STBY_PVDDQ_KLM VIN<1> @BASEBOARD_FAB2_LIB.BASEBOARD_FAB2(SCH_1):VR_FET_SW_P12V_STBY_PVDDQ_KLM
  25 VR_FET_SW_P12V_STBY_PVDDQ_KLM VIN<0> @BASEBOARD_FAB2_LIB.BASEBOARD_FAB2(SCH_1):VR_FET_SW_P12V_STBY_PVDDQ_KLM
   1 PVDDQ_KLM    VOS @BASEBOARD_FAB2_LIB.BASEBOARD_FAB2(SCH_1):PVDDQ_KLM

RES_0402-68.1K,1%,1/16W,EMPTY,A  I103  R1A3
   1 VR_PVDDQ_KLM_PH1_OCSET      A @BASEBOARD_FAB2_LIB.BASEBOARD_FAB2(SCH_1):VR_PVDDQ_KLM_PH1_OCSET
   2    GND      B @BASEBOARD_FAB2_LIB.BASEBOARD_FAB2(SCH_1):GND

RES_0402-68.1K,1%,1/16W,EMPTY,A  I105  R1A2
   1 VR_PVDDQ_KLM_PH2_OCSET      A @BASEBOARD_FAB2_LIB.BASEBOARD_FAB2(SCH_1):VR_PVDDQ_KLM_PH2_OCSET
   2    GND      B @BASEBOARD_FAB2_LIB.BASEBOARD_FAB2(SCH_1):GND

CAP_A_0402V-0.1UF,16V,10%,X7R,A  I109  CT7
   1 VR_PVDDQ_KLM_AIREF1      A @BASEBOARD_FAB2_LIB.BASEBOARD_FAB2(SCH_1):VR_PVDDQ_KLM_AIREF1
   2    GND      B @BASEBOARD_FAB2_LIB.BASEBOARD_FAB2(SCH_1):GND

SC2K2P50V3KX-GP_SMD-BCG6-SC2K2A  I111  CT9
   1 VR_PVDDQ_KLM_PH1_SW      1 @BASEBOARD_FAB2_LIB.BASEBOARD_FAB2(SCH_1):VR_PVDDQ_KLM_PH1_SW
   2 UNNAMED_227_3D01R5F-GP_I125_1      2 @BASEBOARD_FAB2_LIB.BASEBOARD_FAB2(SCH_1):UNNAMED_227_3D01R5F-GP_I125_1

CAP_0402LF-1000PF,50V,10%,X7R,A  I114  CT8
   1 A_TSENSE_PVDDQ_KLM      A @BASEBOARD_FAB2_LIB.BASEBOARD_FAB2(SCH_1):A_TSENSE_PVDDQ_KLM
   2    GND      B @BASEBOARD_FAB2_LIB.BASEBOARD_FAB2(SCH_1):GND

SC2K2P50V3KX-GP_SMD-BCG6-SC2K2A  I116  CT11
   1 VR_PVDDQ_KLM_PH2_SW      1 @BASEBOARD_FAB2_LIB.BASEBOARD_FAB2(SCH_1):VR_PVDDQ_KLM_PH2_SW
   2 UNNAMED_227_3D01R5F-GP_I124_1      2 @BASEBOARD_FAB2_LIB.BASEBOARD_FAB2(SCH_1):UNNAMED_227_3D01R5F-GP_I124_1

CAP_0402LF-1000PF,50V,10%,X7R,A  I119  CT10
   1 A_TSENSE_PVDDQ_KLM      A @BASEBOARD_FAB2_LIB.BASEBOARD_FAB2(SCH_1):A_TSENSE_PVDDQ_KLM
   2    GND      B @BASEBOARD_FAB2_LIB.BASEBOARD_FAB2(SCH_1):GND

CAP_A_0402V-0.1UF,16V,10%,X7R,A  I122  CT12
   1 VR_PVDDQ_KLM_AIREF2      A @BASEBOARD_FAB2_LIB.BASEBOARD_FAB2(SCH_1):VR_PVDDQ_KLM_AIREF2
   2    GND      B @BASEBOARD_FAB2_LIB.BASEBOARD_FAB2(SCH_1):GND

3D01R5F-GP_SMD-RG5-3D01R5F-GP,A  I124  RT7
   1 UNNAMED_227_3D01R5F-GP_I124_1      1 @BASEBOARD_FAB2_LIB.BASEBOARD_FAB2(SCH_1):UNNAMED_227_3D01R5F-GP_I124_1
   2    GND      2 @BASEBOARD_FAB2_LIB.BASEBOARD_FAB2(SCH_1):GND

3D01R5F-GP_SMD-RG5-3D01R5F-GP,A  I125  RT6
   1 UNNAMED_227_3D01R5F-GP_I125_1      1 @BASEBOARD_FAB2_LIB.BASEBOARD_FAB2(SCH_1):UNNAMED_227_3D01R5F-GP_I125_1
   2    GND      2 @BASEBOARD_FAB2_LIB.BASEBOARD_FAB2(SCH_1):GND

RES_0402-0.0,5%,1/16W,CHIP,G21A  I126  RT5
   1 VR_PVDDQ_KLM_PH1_BOOT      A @BASEBOARD_FAB2_LIB.BASEBOARD_FAB2(SCH_1):VR_PVDDQ_KLM_PH1_BOOT
   2 VR_PVDDQ_KLM_PH1_BOOT_R      B @BASEBOARD_FAB2_LIB.BASEBOARD_FAB2(SCH_1):VR_PVDDQ_KLM_PH1_BOOT_R

RES_0402-0.0,5%,1/16W,CHIP,G21A  I127  RT8
   1 VR_PVDDQ_KLM_PH2_BOOT      A @BASEBOARD_FAB2_LIB.BASEBOARD_FAB2(SCH_1):VR_PVDDQ_KLM_PH2_BOOT
   2 VR_PVDDQ_KLM_PH2_BOOT_R      B @BASEBOARD_FAB2_LIB.BASEBOARD_FAB2(SCH_1):VR_PVDDQ_KLM_PH2_BOOT_R


DRAWING: @BASEBOARD_FAB2_LIB.BASEBOARD_FAB2(SCH_1):PAGE208 

RES_0603-100.0,1%,1/10W,CHIP,GA  I7  R1E3
   1 PVCCIN_CPU1      A @BASEBOARD_FAB2_LIB.BASEBOARD_FAB2(SCH_1):PVCCIN_CPU1
   2    GND      B @BASEBOARD_FAB2_LIB.BASEBOARD_FAB2(SCH_1):GND

CAP_A_0603V-22.0UF,4V,20%,X6S,A  I9  C1D14
   1 PVCCIN_CPU1      A @BASEBOARD_FAB2_LIB.BASEBOARD_FAB2(SCH_1):PVCCIN_CPU1
   2    GND      B @BASEBOARD_FAB2_LIB.BASEBOARD_FAB2(SCH_1):GND

INDUCTOR_SM-0.12UH,IND,D92183-A  I11  L1D2
   1 VR_PVCCIN_CPU1_PHASE3    INA @BASEBOARD_FAB2_LIB.BASEBOARD_FAB2(SCH_1):VR_PVCCIN_CPU1_PHASE3
   2 PVCCIN_CPU1    INB @BASEBOARD_FAB2_LIB.BASEBOARD_FAB2(SCH_1):PVCCIN_CPU1

CAPP_3018-470UF,2.5V,20%,ALUM,A  I12  C9P8
   1 PVCCIN_CPU1      A @BASEBOARD_FAB2_LIB.BASEBOARD_FAB2(SCH_1):PVCCIN_CPU1
   2    GND      B @BASEBOARD_FAB2_LIB.BASEBOARD_FAB2(SCH_1):GND

CAPP_3018-470UF,2.5V,20%,ALUM,A  I14  C9P5
   1 PVCCIN_CPU1      A @BASEBOARD_FAB2_LIB.BASEBOARD_FAB2(SCH_1):PVCCIN_CPU1
   2    GND      B @BASEBOARD_FAB2_LIB.BASEBOARD_FAB2(SCH_1):GND

INDUCTOR_SM-0.12UH,IND,D92183-A  I20  L1D1
   1 VR_PVCCIN_CPU1_PHASE4    INA @BASEBOARD_FAB2_LIB.BASEBOARD_FAB2(SCH_1):VR_PVCCIN_CPU1_PHASE4
   2 PVCCIN_CPU1    INB @BASEBOARD_FAB2_LIB.BASEBOARD_FAB2(SCH_1):PVCCIN_CPU1

CAP_A_0603V-22.0UF,4V,20%,X6S,A  I22  C1D3
   1 PVCCIN_CPU1      A @BASEBOARD_FAB2_LIB.BASEBOARD_FAB2(SCH_1):PVCCIN_CPU1
   2    GND      B @BASEBOARD_FAB2_LIB.BASEBOARD_FAB2(SCH_1):GND

CAPP_3018-470UF,2.5V,20%,ALUM,A  I24  C9N24
   1 PVCCIN_CPU1      A @BASEBOARD_FAB2_LIB.BASEBOARD_FAB2(SCH_1):PVCCIN_CPU1
   2    GND      B @BASEBOARD_FAB2_LIB.BASEBOARD_FAB2(SCH_1):GND

CAPP_3018-470UF,2.5V,20%,ALUM,A  I25  C9R9
   1 PVCCIN_CPU1      A @BASEBOARD_FAB2_LIB.BASEBOARD_FAB2(SCH_1):PVCCIN_CPU1
   2    GND      B @BASEBOARD_FAB2_LIB.BASEBOARD_FAB2(SCH_1):GND

CAPP_3018-470UF,2.5V,20%,ALUM,A  I26  C9R3
   1 PVCCIN_CPU1      A @BASEBOARD_FAB2_LIB.BASEBOARD_FAB2(SCH_1):PVCCIN_CPU1
   2    GND      B @BASEBOARD_FAB2_LIB.BASEBOARD_FAB2(SCH_1):GND

IR354XX_SM-IR35411,IC,H73688-0A  I27  EU1D3
  33 VR_PVCCIN_CPU1_PH3_BOOT_R  BOOST @BASEBOARD_FAB2_LIB.BASEBOARD_FAB2(SCH_1):VR_PVCCIN_CPU1_PH3_BOOT_R
  35 P5V_STBY     EN @BASEBOARD_FAB2_LIB.BASEBOARD_FAB2(SCH_1):P5V_STBY
  41 TP_PVCCIN_CPU1_PH3_GL_1  GL<1> @BASEBOARD_FAB2_LIB.BASEBOARD_FAB2(SCH_1):TP_PVCCIN_CPU1_PH3_GL_1
   6 TP_PVCCIN_CPU1_PH3_GL_0  GL<0> @BASEBOARD_FAB2_LIB.BASEBOARD_FAB2(SCH_1):TP_PVCCIN_CPU1_PH3_GL_0
  38 ISENSE_PVCCIN_CPU1_PH3_IMON   IOUT @BASEBOARD_FAB2_LIB.BASEBOARD_FAB2(SCH_1):ISENSE_PVCCIN_CPU1_PH3_IMON
   2    GND   LGND @BASEBOARD_FAB2_LIB.BASEBOARD_FAB2(SCH_1):GND
  31 NC_PVCCIN_CPU1_PH3_P31     NC @BASEBOARD_FAB2_LIB.BASEBOARD_FAB2(SCH_1):NC_PVCCIN_CPU1_PH3_P31
  37 VR_PVCCIN_CPU1_PH3_OCSET  OCSET @BASEBOARD_FAB2_LIB.BASEBOARD_FAB2(SCH_1):VR_PVCCIN_CPU1_PH3_OCSET
  40    GND PGND<2> @BASEBOARD_FAB2_LIB.BASEBOARD_FAB2(SCH_1):GND
   7    GND PGND<1> @BASEBOARD_FAB2_LIB.BASEBOARD_FAB2(SCH_1):GND
   5    GND PGND<0> @BASEBOARD_FAB2_LIB.BASEBOARD_FAB2(SCH_1):GND
  32 VR_PVCCIN_CPU1_PH3_PHASE  PHASE @BASEBOARD_FAB2_LIB.BASEBOARD_FAB2(SCH_1):VR_PVCCIN_CPU1_PH3_PHASE
  34 VR_PVCCIN_CPU1_PWM3    PWM @BASEBOARD_FAB2_LIB.BASEBOARD_FAB2(SCH_1):VR_PVCCIN_CPU1_PWM3
  39 VR_PVCCIN_CPU1_AIREF3  REFIN @BASEBOARD_FAB2_LIB.BASEBOARD_FAB2(SCH_1):VR_PVCCIN_CPU1_AIREF3
  10 VR_PVCCIN_CPU1_PHASE3     SW @BASEBOARD_FAB2_LIB.BASEBOARD_FAB2(SCH_1):VR_PVCCIN_CPU1_PHASE3
  36 A_TSENSE_PVCCIN_CPU1 TOUT_FLT @BASEBOARD_FAB2_LIB.BASEBOARD_FAB2(SCH_1):A_TSENSE_PVCCIN_CPU1
   3 VR_PVCCIN_CPU1_PH3_VCIN    VCC @BASEBOARD_FAB2_LIB.BASEBOARD_FAB2(SCH_1):VR_PVCCIN_CPU1_PH3_VCIN
   4 P5V_STBY   VDRV @BASEBOARD_FAB2_LIB.BASEBOARD_FAB2(SCH_1):P5V_STBY
  30 VR_FET_SW_P12V_STBY_PVCCIN_CPU1 VIN<1> @BASEBOARD_FAB2_LIB.BASEBOARD_FAB2(SCH_1):VR_FET_SW_P12V_STBY_PVCCIN_CPU1
  25 VR_FET_SW_P12V_STBY_PVCCIN_CPU1 VIN<0> @BASEBOARD_FAB2_LIB.BASEBOARD_FAB2(SCH_1):VR_FET_SW_P12V_STBY_PVCCIN_CPU1
   1 PVCCIN_CPU1    VOS @BASEBOARD_FAB2_LIB.BASEBOARD_FAB2(SCH_1):PVCCIN_CPU1

CAPP_3018-470UF,2.5V,20%,ALUM,A  I28  C9P23
   1 PVCCIN_CPU1      A @BASEBOARD_FAB2_LIB.BASEBOARD_FAB2(SCH_1):PVCCIN_CPU1
   2    GND      B @BASEBOARD_FAB2_LIB.BASEBOARD_FAB2(SCH_1):GND

CAPP_3018-470UF,2.5V,20%,ALUM,A  I30  C9P18
   1 PVCCIN_CPU1      A @BASEBOARD_FAB2_LIB.BASEBOARD_FAB2(SCH_1):PVCCIN_CPU1
   2    GND      B @BASEBOARD_FAB2_LIB.BASEBOARD_FAB2(SCH_1):GND

RES_0402-1.0,1%,1/16W,CHIP,G21A  I36  R9P22
   1 VR_PVCCIN_CPU1_PH3_VCIN      A @BASEBOARD_FAB2_LIB.BASEBOARD_FAB2(SCH_1):VR_PVCCIN_CPU1_PH3_VCIN
   2 P5V_STBY      B @BASEBOARD_FAB2_LIB.BASEBOARD_FAB2(SCH_1):P5V_STBY

CAP_0402-0.22UF,16V,10%,X7R,A3A  I38  C1D16
   1 P5V_STBY      A @BASEBOARD_FAB2_LIB.BASEBOARD_FAB2(SCH_1):P5V_STBY
   2    GND      B @BASEBOARD_FAB2_LIB.BASEBOARD_FAB2(SCH_1):GND

CAP_A_0402V-1.0UF,6.3V,10%,X6SA  I39  C1D15
   1 P5V_STBY      A @BASEBOARD_FAB2_LIB.BASEBOARD_FAB2(SCH_1):P5V_STBY
   2    GND      B @BASEBOARD_FAB2_LIB.BASEBOARD_FAB2(SCH_1):GND

CAP_0402-0.220UF,16V,10%,X7R,AA  I40  C1D20
   1 VR_PVCCIN_CPU1_PH3_BOOT      A @BASEBOARD_FAB2_LIB.BASEBOARD_FAB2(SCH_1):VR_PVCCIN_CPU1_PH3_BOOT
   2 VR_PVCCIN_CPU1_PH3_PHASE      B @BASEBOARD_FAB2_LIB.BASEBOARD_FAB2(SCH_1):VR_PVCCIN_CPU1_PH3_PHASE

CAP_0402-1.0UF,16V,10%,X6S,D97A  I43  C1D17
   1 VR_PVCCIN_CPU1_PH3_VCIN      A @BASEBOARD_FAB2_LIB.BASEBOARD_FAB2(SCH_1):VR_PVCCIN_CPU1_PH3_VCIN
   2    GND      B @BASEBOARD_FAB2_LIB.BASEBOARD_FAB2(SCH_1):GND

CAP_A_0402V-0.1UF,16V,10%,X7R,A  I44  C1D28
   1 VR_FET_SW_P12V_STBY_PVCCIN_CPU1      A @BASEBOARD_FAB2_LIB.BASEBOARD_FAB2(SCH_1):VR_FET_SW_P12V_STBY_PVCCIN_CPU1
   2    GND      B @BASEBOARD_FAB2_LIB.BASEBOARD_FAB2(SCH_1):GND

CAP_0402-1.0UF,16V,10%,X6S,D97A  I45  C1D23
   1 VR_FET_SW_P12V_STBY_PVCCIN_CPU1      A @BASEBOARD_FAB2_LIB.BASEBOARD_FAB2(SCH_1):VR_FET_SW_P12V_STBY_PVCCIN_CPU1
   2    GND      B @BASEBOARD_FAB2_LIB.BASEBOARD_FAB2(SCH_1):GND

CAP_0402-0.22UF,16V,10%,X7R,A3A  I46  C1D6
   1 P5V_STBY      A @BASEBOARD_FAB2_LIB.BASEBOARD_FAB2(SCH_1):P5V_STBY
   2    GND      B @BASEBOARD_FAB2_LIB.BASEBOARD_FAB2(SCH_1):GND

CAP_A_0402V-1.0UF,6.3V,10%,X6SA  I47  C1D5
   1 P5V_STBY      A @BASEBOARD_FAB2_LIB.BASEBOARD_FAB2(SCH_1):P5V_STBY
   2    GND      B @BASEBOARD_FAB2_LIB.BASEBOARD_FAB2(SCH_1):GND

CAP_0402-0.220UF,16V,10%,X7R,AA  I48  C1D10
   1 VR_PVCCIN_CPU1_PH4_BOOT      A @BASEBOARD_FAB2_LIB.BASEBOARD_FAB2(SCH_1):VR_PVCCIN_CPU1_PH4_BOOT
   2 VR_PVCCIN_CPU1_PH4_PHASE      B @BASEBOARD_FAB2_LIB.BASEBOARD_FAB2(SCH_1):VR_PVCCIN_CPU1_PH4_PHASE

RES_0402-1.0,1%,1/16W,CHIP,G21A  I49  R9P8
   1 VR_PVCCIN_CPU1_PH4_VCIN      A @BASEBOARD_FAB2_LIB.BASEBOARD_FAB2(SCH_1):VR_PVCCIN_CPU1_PH4_VCIN
   2 P5V_STBY      B @BASEBOARD_FAB2_LIB.BASEBOARD_FAB2(SCH_1):P5V_STBY

CAP_0402-1.0UF,16V,10%,X6S,D97A  I50  C1D7
   1 VR_PVCCIN_CPU1_PH4_VCIN      A @BASEBOARD_FAB2_LIB.BASEBOARD_FAB2(SCH_1):VR_PVCCIN_CPU1_PH4_VCIN
   2    GND      B @BASEBOARD_FAB2_LIB.BASEBOARD_FAB2(SCH_1):GND

CAP_A_0402V-0.1UF,16V,10%,X7R,A  I51  C1D13
   1 VR_FET_SW_P12V_STBY_PVCCIN_CPU1      A @BASEBOARD_FAB2_LIB.BASEBOARD_FAB2(SCH_1):VR_FET_SW_P12V_STBY_PVCCIN_CPU1
   2    GND      B @BASEBOARD_FAB2_LIB.BASEBOARD_FAB2(SCH_1):GND

CAP_0402-1.0UF,16V,10%,X6S,D97A  I52  C1D12
   1 VR_FET_SW_P12V_STBY_PVCCIN_CPU1      A @BASEBOARD_FAB2_LIB.BASEBOARD_FAB2(SCH_1):VR_FET_SW_P12V_STBY_PVCCIN_CPU1
   2    GND      B @BASEBOARD_FAB2_LIB.BASEBOARD_FAB2(SCH_1):GND

CAP_0805-10UF,16V,10%,X6S,C953A  I53  C9P4
   1 VR_FET_SW_P12V_STBY_PVCCIN_CPU1      A @BASEBOARD_FAB2_LIB.BASEBOARD_FAB2(SCH_1):VR_FET_SW_P12V_STBY_PVCCIN_CPU1
   2    GND      B @BASEBOARD_FAB2_LIB.BASEBOARD_FAB2(SCH_1):GND

CAP_0805-10UF,16V,10%,X6S,C953A  I54  C9P7
   1 VR_FET_SW_P12V_STBY_PVCCIN_CPU1      A @BASEBOARD_FAB2_LIB.BASEBOARD_FAB2(SCH_1):VR_FET_SW_P12V_STBY_PVCCIN_CPU1
   2    GND      B @BASEBOARD_FAB2_LIB.BASEBOARD_FAB2(SCH_1):GND

CAP_0805-10UF,16V,10%,X6S,C953A  I55  C9P9
   1 VR_FET_SW_P12V_STBY_PVCCIN_CPU1      A @BASEBOARD_FAB2_LIB.BASEBOARD_FAB2(SCH_1):VR_FET_SW_P12V_STBY_PVCCIN_CPU1
   2    GND      B @BASEBOARD_FAB2_LIB.BASEBOARD_FAB2(SCH_1):GND

CAP_0805-10UF,16V,10%,X6S,C953A  I58  C9P24
   1 VR_FET_SW_P12V_STBY_PVCCIN_CPU1      A @BASEBOARD_FAB2_LIB.BASEBOARD_FAB2(SCH_1):VR_FET_SW_P12V_STBY_PVCCIN_CPU1
   2    GND      B @BASEBOARD_FAB2_LIB.BASEBOARD_FAB2(SCH_1):GND

CAP_0805-10UF,16V,10%,X6S,C953A  I59  C9P1
   1 VR_FET_SW_P12V_STBY_PVCCIN_CPU1      A @BASEBOARD_FAB2_LIB.BASEBOARD_FAB2(SCH_1):VR_FET_SW_P12V_STBY_PVCCIN_CPU1
   2    GND      B @BASEBOARD_FAB2_LIB.BASEBOARD_FAB2(SCH_1):GND

CAP_0805-10UF,16V,10%,X6S,C953A  I60  C9P2
   1 VR_FET_SW_P12V_STBY_PVCCIN_CPU1      A @BASEBOARD_FAB2_LIB.BASEBOARD_FAB2(SCH_1):VR_FET_SW_P12V_STBY_PVCCIN_CPU1
   2    GND      B @BASEBOARD_FAB2_LIB.BASEBOARD_FAB2(SCH_1):GND

CAP_A_0603V-22.0UF,4V,20%,X6S,A  I66  C9P10
   1 PVCCIN_CPU1      A @BASEBOARD_FAB2_LIB.BASEBOARD_FAB2(SCH_1):PVCCIN_CPU1
   2    GND      B @BASEBOARD_FAB2_LIB.BASEBOARD_FAB2(SCH_1):GND

CAP_A_0603V-22.0UF,4V,20%,X6S,A  I67  C9R2
   1 PVCCIN_CPU1      A @BASEBOARD_FAB2_LIB.BASEBOARD_FAB2(SCH_1):PVCCIN_CPU1
   2    GND      B @BASEBOARD_FAB2_LIB.BASEBOARD_FAB2(SCH_1):GND

IR354XX_SM-IR35411,IC,H73688-0A  I71  EU1D1
  33 VR_PVCCIN_CPU1_PH4_BOOT_R  BOOST @BASEBOARD_FAB2_LIB.BASEBOARD_FAB2(SCH_1):VR_PVCCIN_CPU1_PH4_BOOT_R
  35 P5V_STBY     EN @BASEBOARD_FAB2_LIB.BASEBOARD_FAB2(SCH_1):P5V_STBY
  41 TP_PVCCIN_CPU1_PH4_GL_1  GL<1> @BASEBOARD_FAB2_LIB.BASEBOARD_FAB2(SCH_1):TP_PVCCIN_CPU1_PH4_GL_1
   6 TP_PVCCIN_CPU1_PH4_GL_0  GL<0> @BASEBOARD_FAB2_LIB.BASEBOARD_FAB2(SCH_1):TP_PVCCIN_CPU1_PH4_GL_0
  38 ISENSE_PVCCIN_CPU1_PH4_IMON   IOUT @BASEBOARD_FAB2_LIB.BASEBOARD_FAB2(SCH_1):ISENSE_PVCCIN_CPU1_PH4_IMON
   2    GND   LGND @BASEBOARD_FAB2_LIB.BASEBOARD_FAB2(SCH_1):GND
  31 NC_PVCCIN_CPU1_PH4_P31     NC @BASEBOARD_FAB2_LIB.BASEBOARD_FAB2(SCH_1):NC_PVCCIN_CPU1_PH4_P31
  37 VR_PVCCIN_CPU1_PH4_OCSET  OCSET @BASEBOARD_FAB2_LIB.BASEBOARD_FAB2(SCH_1):VR_PVCCIN_CPU1_PH4_OCSET
  40    GND PGND<2> @BASEBOARD_FAB2_LIB.BASEBOARD_FAB2(SCH_1):GND
   7    GND PGND<1> @BASEBOARD_FAB2_LIB.BASEBOARD_FAB2(SCH_1):GND
   5    GND PGND<0> @BASEBOARD_FAB2_LIB.BASEBOARD_FAB2(SCH_1):GND
  32 VR_PVCCIN_CPU1_PH4_PHASE  PHASE @BASEBOARD_FAB2_LIB.BASEBOARD_FAB2(SCH_1):VR_PVCCIN_CPU1_PH4_PHASE
  34 VR_PVCCIN_CPU1_PWM4    PWM @BASEBOARD_FAB2_LIB.BASEBOARD_FAB2(SCH_1):VR_PVCCIN_CPU1_PWM4
  39 VR_PVCCIN_CPU1_AIREF4  REFIN @BASEBOARD_FAB2_LIB.BASEBOARD_FAB2(SCH_1):VR_PVCCIN_CPU1_AIREF4
  10 VR_PVCCIN_CPU1_PHASE4     SW @BASEBOARD_FAB2_LIB.BASEBOARD_FAB2(SCH_1):VR_PVCCIN_CPU1_PHASE4
  36 A_TSENSE_PVCCIN_CPU1 TOUT_FLT @BASEBOARD_FAB2_LIB.BASEBOARD_FAB2(SCH_1):A_TSENSE_PVCCIN_CPU1
   3 VR_PVCCIN_CPU1_PH4_VCIN    VCC @BASEBOARD_FAB2_LIB.BASEBOARD_FAB2(SCH_1):VR_PVCCIN_CPU1_PH4_VCIN
   4 P5V_STBY   VDRV @BASEBOARD_FAB2_LIB.BASEBOARD_FAB2(SCH_1):P5V_STBY
  30 VR_FET_SW_P12V_STBY_PVCCIN_CPU1 VIN<1> @BASEBOARD_FAB2_LIB.BASEBOARD_FAB2(SCH_1):VR_FET_SW_P12V_STBY_PVCCIN_CPU1
  25 VR_FET_SW_P12V_STBY_PVCCIN_CPU1 VIN<0> @BASEBOARD_FAB2_LIB.BASEBOARD_FAB2(SCH_1):VR_FET_SW_P12V_STBY_PVCCIN_CPU1
   1 PVCCIN_CPU1    VOS @BASEBOARD_FAB2_LIB.BASEBOARD_FAB2(SCH_1):PVCCIN_CPU1

RES_0402-68.1K,1%,1/16W,EMPTY,A  I75  R1D54
   1 VR_PVCCIN_CPU1_PH4_OCSET      A @BASEBOARD_FAB2_LIB.BASEBOARD_FAB2(SCH_1):VR_PVCCIN_CPU1_PH4_OCSET
   2    GND      B @BASEBOARD_FAB2_LIB.BASEBOARD_FAB2(SCH_1):GND

RES_0402-68.1K,1%,1/16W,EMPTY,A  I76  R1D55
   1 VR_PVCCIN_CPU1_PH3_OCSET      A @BASEBOARD_FAB2_LIB.BASEBOARD_FAB2(SCH_1):VR_PVCCIN_CPU1_PH3_OCSET
   2    GND      B @BASEBOARD_FAB2_LIB.BASEBOARD_FAB2(SCH_1):GND

CAP_A_0402V-0.1UF,16V,10%,X7R,A  I80  CT16
   1 VR_PVCCIN_CPU1_AIREF3      A @BASEBOARD_FAB2_LIB.BASEBOARD_FAB2(SCH_1):VR_PVCCIN_CPU1_AIREF3
   2    GND      B @BASEBOARD_FAB2_LIB.BASEBOARD_FAB2(SCH_1):GND

CAP_0402LF-1000PF,50V,10%,X7R,A  I82  CTI7
   1 A_TSENSE_PVCCIN_CPU1      A @BASEBOARD_FAB2_LIB.BASEBOARD_FAB2(SCH_1):A_TSENSE_PVCCIN_CPU1
   2    GND      B @BASEBOARD_FAB2_LIB.BASEBOARD_FAB2(SCH_1):GND

SC2K2P50V3KX-GP_SMD-BCG6-SC2K2A  I84  CT18
   1 VR_PVCCIN_CPU1_PHASE3      1 @BASEBOARD_FAB2_LIB.BASEBOARD_FAB2(SCH_1):VR_PVCCIN_CPU1_PHASE3
   2 UNNAMED_208_3D01R5F-GP_I86_2      2 @BASEBOARD_FAB2_LIB.BASEBOARD_FAB2(SCH_1):UNNAMED_208_3D01R5F-GP_I86_2

CAP_A_0402V-0.1UF,16V,10%,X7R,A  I87  CT21
   1 VR_PVCCIN_CPU1_AIREF4      A @BASEBOARD_FAB2_LIB.BASEBOARD_FAB2(SCH_1):VR_PVCCIN_CPU1_AIREF4
   2    GND      B @BASEBOARD_FAB2_LIB.BASEBOARD_FAB2(SCH_1):GND

CAP_0402LF-1000PF,50V,10%,X7R,A  I90  CT19
   1 A_TSENSE_PVCCIN_CPU1      A @BASEBOARD_FAB2_LIB.BASEBOARD_FAB2(SCH_1):A_TSENSE_PVCCIN_CPU1
   2    GND      B @BASEBOARD_FAB2_LIB.BASEBOARD_FAB2(SCH_1):GND

SC2K2P50V3KX-GP_SMD-BCG6-SC2K2A  I92  CT20
   1 VR_PVCCIN_CPU1_PHASE4      1 @BASEBOARD_FAB2_LIB.BASEBOARD_FAB2(SCH_1):VR_PVCCIN_CPU1_PHASE4
   2 UNNAMED_208_3D01R5F-GP_I94_2      2 @BASEBOARD_FAB2_LIB.BASEBOARD_FAB2(SCH_1):UNNAMED_208_3D01R5F-GP_I94_2

3D01R5F-GP_SMD-RG5-3D01R5F-GP,A  I94  RT13
   1    GND      1 @BASEBOARD_FAB2_LIB.BASEBOARD_FAB2(SCH_1):GND
   2 UNNAMED_208_3D01R5F-GP_I94_2      2 @BASEBOARD_FAB2_LIB.BASEBOARD_FAB2(SCH_1):UNNAMED_208_3D01R5F-GP_I94_2

3D01R5F-GP_SMD-RG5-3D01R5F-GP,A  I86  RT12
   1    GND      1 @BASEBOARD_FAB2_LIB.BASEBOARD_FAB2(SCH_1):GND
   2 UNNAMED_208_3D01R5F-GP_I86_2      2 @BASEBOARD_FAB2_LIB.BASEBOARD_FAB2(SCH_1):UNNAMED_208_3D01R5F-GP_I86_2

RES_0402-0.0,5%,1/16W,CHIP,G21A  I96  RT11
   1 VR_PVCCIN_CPU1_PH3_BOOT      A @BASEBOARD_FAB2_LIB.BASEBOARD_FAB2(SCH_1):VR_PVCCIN_CPU1_PH3_BOOT
   2 VR_PVCCIN_CPU1_PH3_BOOT_R      B @BASEBOARD_FAB2_LIB.BASEBOARD_FAB2(SCH_1):VR_PVCCIN_CPU1_PH3_BOOT_R

RES_0402-0.0,5%,1/16W,CHIP,G21A  I97  RT14
   1 VR_PVCCIN_CPU1_PH4_BOOT      A @BASEBOARD_FAB2_LIB.BASEBOARD_FAB2(SCH_1):VR_PVCCIN_CPU1_PH4_BOOT
   2 VR_PVCCIN_CPU1_PH4_BOOT_R      B @BASEBOARD_FAB2_LIB.BASEBOARD_FAB2(SCH_1):VR_PVCCIN_CPU1_PH4_BOOT_R


DRAWING: @BASEBOARD_FAB2_LIB.BASEBOARD_FAB2(SCH_1):PAGE207 

CAP_A_0603V-22.0UF,4V,20%,X6S,A  I8  C9R8
   1 PVCCIN_CPU1      A @BASEBOARD_FAB2_LIB.BASEBOARD_FAB2(SCH_1):PVCCIN_CPU1
   2    GND      B @BASEBOARD_FAB2_LIB.BASEBOARD_FAB2(SCH_1):GND

INDUCTOR_SM-0.12UH,IND,D92183-A  I10  L1E1
   1 VR_PVCCIN_CPU1_PHASE1    INA @BASEBOARD_FAB2_LIB.BASEBOARD_FAB2(SCH_1):VR_PVCCIN_CPU1_PHASE1
   2 PVCCIN_CPU1    INB @BASEBOARD_FAB2_LIB.BASEBOARD_FAB2(SCH_1):PVCCIN_CPU1

INDUCTOR_SM-0.12UH,IND,D92183-A  I16  L1D3
   1 VR_PVCCIN_CPU1_PHASE2    INA @BASEBOARD_FAB2_LIB.BASEBOARD_FAB2(SCH_1):VR_PVCCIN_CPU1_PHASE2
   2 PVCCIN_CPU1    INB @BASEBOARD_FAB2_LIB.BASEBOARD_FAB2(SCH_1):PVCCIN_CPU1

CAP_A_0603V-22.0UF,4V,20%,X6S,A  I18  C1E3
   1 PVCCIN_CPU1      A @BASEBOARD_FAB2_LIB.BASEBOARD_FAB2(SCH_1):PVCCIN_CPU1
   2    GND      B @BASEBOARD_FAB2_LIB.BASEBOARD_FAB2(SCH_1):GND

IR354XX_SM-IR35411,IC,H73688-0A  I20  EU1E2
  33 VR_PVCCIN_CPU1_PH1_BOOT_R  BOOST @BASEBOARD_FAB2_LIB.BASEBOARD_FAB2(SCH_1):VR_PVCCIN_CPU1_PH1_BOOT_R
  35 P5V_STBY     EN @BASEBOARD_FAB2_LIB.BASEBOARD_FAB2(SCH_1):P5V_STBY
  41 TP_PVCCINC_CPU1_PH1_GL_1  GL<1> @BASEBOARD_FAB2_LIB.BASEBOARD_FAB2(SCH_1):TP_PVCCINC_CPU1_PH1_GL_1
   6 TP_PVCCINC_CPU1_PH1_GL_0  GL<0> @BASEBOARD_FAB2_LIB.BASEBOARD_FAB2(SCH_1):TP_PVCCINC_CPU1_PH1_GL_0
  38 ISENSE_PVCCIN_CPU1_PH1_IMON   IOUT @BASEBOARD_FAB2_LIB.BASEBOARD_FAB2(SCH_1):ISENSE_PVCCIN_CPU1_PH1_IMON
   2    GND   LGND @BASEBOARD_FAB2_LIB.BASEBOARD_FAB2(SCH_1):GND
  31 NC_PVCCIN_CPU1_PH1_P31     NC @BASEBOARD_FAB2_LIB.BASEBOARD_FAB2(SCH_1):NC_PVCCIN_CPU1_PH1_P31
  37 VR_PVCCIN_CPU1_PH1_OCSET  OCSET @BASEBOARD_FAB2_LIB.BASEBOARD_FAB2(SCH_1):VR_PVCCIN_CPU1_PH1_OCSET
  40    GND PGND<2> @BASEBOARD_FAB2_LIB.BASEBOARD_FAB2(SCH_1):GND
   7    GND PGND<1> @BASEBOARD_FAB2_LIB.BASEBOARD_FAB2(SCH_1):GND
   5    GND PGND<0> @BASEBOARD_FAB2_LIB.BASEBOARD_FAB2(SCH_1):GND
  32 VR_PVCCIN_CPU1_PH1_PHASE  PHASE @BASEBOARD_FAB2_LIB.BASEBOARD_FAB2(SCH_1):VR_PVCCIN_CPU1_PH1_PHASE
  34 VR_PVCCIN_CPU1_PWM1    PWM @BASEBOARD_FAB2_LIB.BASEBOARD_FAB2(SCH_1):VR_PVCCIN_CPU1_PWM1
  39 VR_PVCCIN_CPU1_AIREF1  REFIN @BASEBOARD_FAB2_LIB.BASEBOARD_FAB2(SCH_1):VR_PVCCIN_CPU1_AIREF1
  10 VR_PVCCIN_CPU1_PHASE1     SW @BASEBOARD_FAB2_LIB.BASEBOARD_FAB2(SCH_1):VR_PVCCIN_CPU1_PHASE1
  36 A_TSENSE_PVCCIN_CPU1 TOUT_FLT @BASEBOARD_FAB2_LIB.BASEBOARD_FAB2(SCH_1):A_TSENSE_PVCCIN_CPU1
   3 VR_PVCCIN_CPU1_PH1_VCIN    VCC @BASEBOARD_FAB2_LIB.BASEBOARD_FAB2(SCH_1):VR_PVCCIN_CPU1_PH1_VCIN
   4 P5V_STBY   VDRV @BASEBOARD_FAB2_LIB.BASEBOARD_FAB2(SCH_1):P5V_STBY
  30 VR_FET_SW_P12V_STBY_PVCCIN_CPU1 VIN<1> @BASEBOARD_FAB2_LIB.BASEBOARD_FAB2(SCH_1):VR_FET_SW_P12V_STBY_PVCCIN_CPU1
  25 VR_FET_SW_P12V_STBY_PVCCIN_CPU1 VIN<0> @BASEBOARD_FAB2_LIB.BASEBOARD_FAB2(SCH_1):VR_FET_SW_P12V_STBY_PVCCIN_CPU1
   1 PVCCIN_CPU1    VOS @BASEBOARD_FAB2_LIB.BASEBOARD_FAB2(SCH_1):PVCCIN_CPU1

IR354XX_SM-IR35411,IC,H73688-0A  I24  EU1D4
  33 VR_PVCCIN_CPU1_PH2_BOOT_R  BOOST @BASEBOARD_FAB2_LIB.BASEBOARD_FAB2(SCH_1):VR_PVCCIN_CPU1_PH2_BOOT_R
  35 P5V_STBY     EN @BASEBOARD_FAB2_LIB.BASEBOARD_FAB2(SCH_1):P5V_STBY
  41 TP_PVCCINC_CPU1_PH2_GL_1  GL<1> @BASEBOARD_FAB2_LIB.BASEBOARD_FAB2(SCH_1):TP_PVCCINC_CPU1_PH2_GL_1
   6 TP_PVCCINC_CPU1_PH2_GL_0  GL<0> @BASEBOARD_FAB2_LIB.BASEBOARD_FAB2(SCH_1):TP_PVCCINC_CPU1_PH2_GL_0
  38 ISENSE_PVCCIN_CPU1_PH2_IMON   IOUT @BASEBOARD_FAB2_LIB.BASEBOARD_FAB2(SCH_1):ISENSE_PVCCIN_CPU1_PH2_IMON
   2    GND   LGND @BASEBOARD_FAB2_LIB.BASEBOARD_FAB2(SCH_1):GND
  31 NC_PVCCIN_CPU1_PH2_P31     NC @BASEBOARD_FAB2_LIB.BASEBOARD_FAB2(SCH_1):NC_PVCCIN_CPU1_PH2_P31
  37 VR_PVCCIN_CPU1_PH2_OCSET  OCSET @BASEBOARD_FAB2_LIB.BASEBOARD_FAB2(SCH_1):VR_PVCCIN_CPU1_PH2_OCSET
  40    GND PGND<2> @BASEBOARD_FAB2_LIB.BASEBOARD_FAB2(SCH_1):GND
   7    GND PGND<1> @BASEBOARD_FAB2_LIB.BASEBOARD_FAB2(SCH_1):GND
   5    GND PGND<0> @BASEBOARD_FAB2_LIB.BASEBOARD_FAB2(SCH_1):GND
  32 VR_PVCCIN_CPU1_PH2_PHASE  PHASE @BASEBOARD_FAB2_LIB.BASEBOARD_FAB2(SCH_1):VR_PVCCIN_CPU1_PH2_PHASE
  34 VR_PVCCIN_CPU1_PWM2    PWM @BASEBOARD_FAB2_LIB.BASEBOARD_FAB2(SCH_1):VR_PVCCIN_CPU1_PWM2
  39 VR_PVCCIN_CPU1_AIREF2  REFIN @BASEBOARD_FAB2_LIB.BASEBOARD_FAB2(SCH_1):VR_PVCCIN_CPU1_AIREF2
  10 VR_PVCCIN_CPU1_PHASE2     SW @BASEBOARD_FAB2_LIB.BASEBOARD_FAB2(SCH_1):VR_PVCCIN_CPU1_PHASE2
  36 A_TSENSE_PVCCIN_CPU1 TOUT_FLT @BASEBOARD_FAB2_LIB.BASEBOARD_FAB2(SCH_1):A_TSENSE_PVCCIN_CPU1
   3 VR_PVCCIN_CPU1_PH2_VCIN    VCC @BASEBOARD_FAB2_LIB.BASEBOARD_FAB2(SCH_1):VR_PVCCIN_CPU1_PH2_VCIN
   4 P5V_STBY   VDRV @BASEBOARD_FAB2_LIB.BASEBOARD_FAB2(SCH_1):P5V_STBY
  30 VR_FET_SW_P12V_STBY_PVCCIN_CPU1 VIN<1> @BASEBOARD_FAB2_LIB.BASEBOARD_FAB2(SCH_1):VR_FET_SW_P12V_STBY_PVCCIN_CPU1
  25 VR_FET_SW_P12V_STBY_PVCCIN_CPU1 VIN<0> @BASEBOARD_FAB2_LIB.BASEBOARD_FAB2(SCH_1):VR_FET_SW_P12V_STBY_PVCCIN_CPU1
   1 PVCCIN_CPU1    VOS @BASEBOARD_FAB2_LIB.BASEBOARD_FAB2(SCH_1):PVCCIN_CPU1

RES_0402-1.0,1%,1/16W,CHIP,G21A  I26  R9R2
   1 VR_PVCCIN_CPU1_PH1_VCIN      A @BASEBOARD_FAB2_LIB.BASEBOARD_FAB2(SCH_1):VR_PVCCIN_CPU1_PH1_VCIN
   2 P5V_STBY      B @BASEBOARD_FAB2_LIB.BASEBOARD_FAB2(SCH_1):P5V_STBY

CAP_0402-0.22UF,16V,10%,X7R,A3A  I28  C1E7
   1 P5V_STBY      A @BASEBOARD_FAB2_LIB.BASEBOARD_FAB2(SCH_1):P5V_STBY
   2    GND      B @BASEBOARD_FAB2_LIB.BASEBOARD_FAB2(SCH_1):GND

CAP_A_0402V-1.0UF,6.3V,10%,X6SA  I29  C1E6
   1 P5V_STBY      A @BASEBOARD_FAB2_LIB.BASEBOARD_FAB2(SCH_1):P5V_STBY
   2    GND      B @BASEBOARD_FAB2_LIB.BASEBOARD_FAB2(SCH_1):GND

CAP_0402-0.220UF,16V,10%,X7R,AA  I30  C1E11
   1 VR_PVCCIN_CPU1_PH1_BOOT      A @BASEBOARD_FAB2_LIB.BASEBOARD_FAB2(SCH_1):VR_PVCCIN_CPU1_PH1_BOOT
   2 VR_PVCCIN_CPU1_PH1_PHASE      B @BASEBOARD_FAB2_LIB.BASEBOARD_FAB2(SCH_1):VR_PVCCIN_CPU1_PH1_PHASE

CAP_0402-1.0UF,16V,10%,X6S,D97A  I32  C1E8
   1 VR_PVCCIN_CPU1_PH1_VCIN      A @BASEBOARD_FAB2_LIB.BASEBOARD_FAB2(SCH_1):VR_PVCCIN_CPU1_PH1_VCIN
   2    GND      B @BASEBOARD_FAB2_LIB.BASEBOARD_FAB2(SCH_1):GND

CAP_A_0402V-0.1UF,16V,10%,X7R,A  I33  C1E14
   1 VR_FET_SW_P12V_STBY_PVCCIN_CPU1      A @BASEBOARD_FAB2_LIB.BASEBOARD_FAB2(SCH_1):VR_FET_SW_P12V_STBY_PVCCIN_CPU1
   2    GND      B @BASEBOARD_FAB2_LIB.BASEBOARD_FAB2(SCH_1):GND

CAP_0402-1.0UF,16V,10%,X6S,D97A  I34  C1E13
   1 VR_FET_SW_P12V_STBY_PVCCIN_CPU1      A @BASEBOARD_FAB2_LIB.BASEBOARD_FAB2(SCH_1):VR_FET_SW_P12V_STBY_PVCCIN_CPU1
   2    GND      B @BASEBOARD_FAB2_LIB.BASEBOARD_FAB2(SCH_1):GND

CAP_0402-0.22UF,16V,10%,X7R,A3A  I36  C1E25
   1 P5V_STBY      A @BASEBOARD_FAB2_LIB.BASEBOARD_FAB2(SCH_1):P5V_STBY
   2    GND      B @BASEBOARD_FAB2_LIB.BASEBOARD_FAB2(SCH_1):GND

CAP_A_0402V-1.0UF,6.3V,10%,X6SA  I37  C1E23
   1 P5V_STBY      A @BASEBOARD_FAB2_LIB.BASEBOARD_FAB2(SCH_1):P5V_STBY
   2    GND      B @BASEBOARD_FAB2_LIB.BASEBOARD_FAB2(SCH_1):GND

CAP_0402-0.220UF,16V,10%,X7R,AA  I38  C1D36
   1 VR_PVCCIN_CPU1_PH2_BOOT      A @BASEBOARD_FAB2_LIB.BASEBOARD_FAB2(SCH_1):VR_PVCCIN_CPU1_PH2_BOOT
   2 VR_PVCCIN_CPU1_PH2_PHASE      B @BASEBOARD_FAB2_LIB.BASEBOARD_FAB2(SCH_1):VR_PVCCIN_CPU1_PH2_PHASE

RES_0402-1.0,1%,1/16W,CHIP,G21A  I39  R9R11
   1 VR_PVCCIN_CPU1_PH2_VCIN      A @BASEBOARD_FAB2_LIB.BASEBOARD_FAB2(SCH_1):VR_PVCCIN_CPU1_PH2_VCIN
   2 P5V_STBY      B @BASEBOARD_FAB2_LIB.BASEBOARD_FAB2(SCH_1):P5V_STBY

CAP_0402-1.0UF,16V,10%,X6S,D97A  I40  C1E24
   1 VR_PVCCIN_CPU1_PH2_VCIN      A @BASEBOARD_FAB2_LIB.BASEBOARD_FAB2(SCH_1):VR_PVCCIN_CPU1_PH2_VCIN
   2    GND      B @BASEBOARD_FAB2_LIB.BASEBOARD_FAB2(SCH_1):GND

CAP_A_0402V-0.1UF,16V,10%,X7R,A  I41  C1D34
   1 VR_FET_SW_P12V_STBY_PVCCIN_CPU1      A @BASEBOARD_FAB2_LIB.BASEBOARD_FAB2(SCH_1):VR_FET_SW_P12V_STBY_PVCCIN_CPU1
   2    GND      B @BASEBOARD_FAB2_LIB.BASEBOARD_FAB2(SCH_1):GND

CAP_0402-1.0UF,16V,10%,X6S,D97A  I42  C1D35
   1 VR_FET_SW_P12V_STBY_PVCCIN_CPU1      A @BASEBOARD_FAB2_LIB.BASEBOARD_FAB2(SCH_1):VR_FET_SW_P12V_STBY_PVCCIN_CPU1
   2    GND      B @BASEBOARD_FAB2_LIB.BASEBOARD_FAB2(SCH_1):GND

CAP_0805-10UF,16V,10%,X6S,C953A  I43  C9R7
   1 VR_FET_SW_P12V_STBY_PVCCIN_CPU1      A @BASEBOARD_FAB2_LIB.BASEBOARD_FAB2(SCH_1):VR_FET_SW_P12V_STBY_PVCCIN_CPU1
   2    GND      B @BASEBOARD_FAB2_LIB.BASEBOARD_FAB2(SCH_1):GND

CAP_0805-10UF,16V,10%,X6S,C953A  I44  C9R10
   1 VR_FET_SW_P12V_STBY_PVCCIN_CPU1      A @BASEBOARD_FAB2_LIB.BASEBOARD_FAB2(SCH_1):VR_FET_SW_P12V_STBY_PVCCIN_CPU1
   2    GND      B @BASEBOARD_FAB2_LIB.BASEBOARD_FAB2(SCH_1):GND

CAP_0805-10UF,16V,10%,X6S,C953A  I48  C9R11
   1 VR_FET_SW_P12V_STBY_PVCCIN_CPU1      A @BASEBOARD_FAB2_LIB.BASEBOARD_FAB2(SCH_1):VR_FET_SW_P12V_STBY_PVCCIN_CPU1
   2    GND      B @BASEBOARD_FAB2_LIB.BASEBOARD_FAB2(SCH_1):GND

CAP_0805-10UF,16V,10%,X6S,C953A  I50  C9P22
   1 VR_FET_SW_P12V_STBY_PVCCIN_CPU1      A @BASEBOARD_FAB2_LIB.BASEBOARD_FAB2(SCH_1):VR_FET_SW_P12V_STBY_PVCCIN_CPU1
   2    GND      B @BASEBOARD_FAB2_LIB.BASEBOARD_FAB2(SCH_1):GND

CAP_0805-10UF,16V,10%,X6S,C953A  I51  C9P25
   1 VR_FET_SW_P12V_STBY_PVCCIN_CPU1      A @BASEBOARD_FAB2_LIB.BASEBOARD_FAB2(SCH_1):VR_FET_SW_P12V_STBY_PVCCIN_CPU1
   2    GND      B @BASEBOARD_FAB2_LIB.BASEBOARD_FAB2(SCH_1):GND

CAP_0805-10UF,16V,10%,X6S,C953A  I54  C9P26
   1 VR_FET_SW_P12V_STBY_PVCCIN_CPU1      A @BASEBOARD_FAB2_LIB.BASEBOARD_FAB2(SCH_1):VR_FET_SW_P12V_STBY_PVCCIN_CPU1
   2    GND      B @BASEBOARD_FAB2_LIB.BASEBOARD_FAB2(SCH_1):GND

CAP_A_0603V-22.0UF,4V,20%,X6S,A  I58  C1E9
   1 PVCCIN_CPU1      A @BASEBOARD_FAB2_LIB.BASEBOARD_FAB2(SCH_1):PVCCIN_CPU1
   2    GND      B @BASEBOARD_FAB2_LIB.BASEBOARD_FAB2(SCH_1):GND

CAP_A_0603V-22.0UF,4V,20%,X6S,A  I59  C9P3
   1 PVCCIN_CPU1      A @BASEBOARD_FAB2_LIB.BASEBOARD_FAB2(SCH_1):PVCCIN_CPU1
   2    GND      B @BASEBOARD_FAB2_LIB.BASEBOARD_FAB2(SCH_1):GND

RES_0402-68.1K,1%,1/16W,EMPTY,A  I67  R1E13
   1 VR_PVCCIN_CPU1_PH2_OCSET      A @BASEBOARD_FAB2_LIB.BASEBOARD_FAB2(SCH_1):VR_PVCCIN_CPU1_PH2_OCSET
   2    GND      B @BASEBOARD_FAB2_LIB.BASEBOARD_FAB2(SCH_1):GND

RES_0402-68.1K,1%,1/16W,EMPTY,A  I68  R1E14
   1 VR_PVCCIN_CPU1_PH1_OCSET      A @BASEBOARD_FAB2_LIB.BASEBOARD_FAB2(SCH_1):VR_PVCCIN_CPU1_PH1_OCSET
   2    GND      B @BASEBOARD_FAB2_LIB.BASEBOARD_FAB2(SCH_1):GND

CAP_A_0402V-0.1UF,16V,10%,X7R,A  I71  CT24
   1 VR_PVCCIN_CPU1_AIREF1      A @BASEBOARD_FAB2_LIB.BASEBOARD_FAB2(SCH_1):VR_PVCCIN_CPU1_AIREF1
   2    GND      B @BASEBOARD_FAB2_LIB.BASEBOARD_FAB2(SCH_1):GND

CAP_0402LF-1000PF,50V,10%,X7R,A  I74  CT22
   1 A_TSENSE_PVCCIN_CPU1      A @BASEBOARD_FAB2_LIB.BASEBOARD_FAB2(SCH_1):A_TSENSE_PVCCIN_CPU1
   2    GND      B @BASEBOARD_FAB2_LIB.BASEBOARD_FAB2(SCH_1):GND

SC2K2P50V3KX-GP_SMD-BCG6-SC2K2A  I77  CT23
   1 VR_PVCCIN_CPU1_PHASE1      1 @BASEBOARD_FAB2_LIB.BASEBOARD_FAB2(SCH_1):VR_PVCCIN_CPU1_PHASE1
   2 UNNAMED_207_3D01R5F-GP_I76_2      2 @BASEBOARD_FAB2_LIB.BASEBOARD_FAB2(SCH_1):UNNAMED_207_3D01R5F-GP_I76_2

CAP_A_0402V-0.1UF,16V,10%,X7R,A  I81  CT25
   1 VR_PVCCIN_CPU1_AIREF2      A @BASEBOARD_FAB2_LIB.BASEBOARD_FAB2(SCH_1):VR_PVCCIN_CPU1_AIREF2
   2    GND      B @BASEBOARD_FAB2_LIB.BASEBOARD_FAB2(SCH_1):GND

CAP_0402LF-1000PF,50V,10%,X7R,A  I82  CT26
   1 A_TSENSE_PVCCIN_CPU1      A @BASEBOARD_FAB2_LIB.BASEBOARD_FAB2(SCH_1):A_TSENSE_PVCCIN_CPU1
   2    GND      B @BASEBOARD_FAB2_LIB.BASEBOARD_FAB2(SCH_1):GND

SC2K2P50V3KX-GP_SMD-BCG6-SC2K2A  I84  CT27
   1 VR_PVCCIN_CPU1_PHASE2      1 @BASEBOARD_FAB2_LIB.BASEBOARD_FAB2(SCH_1):VR_PVCCIN_CPU1_PHASE2
   2 UNNAMED_207_3D01R5F-GP_I85_2      2 @BASEBOARD_FAB2_LIB.BASEBOARD_FAB2(SCH_1):UNNAMED_207_3D01R5F-GP_I85_2

3D01R5F-GP_SMD-RG5-3D01R5F-GP,A  I85  RT18
   1    GND      1 @BASEBOARD_FAB2_LIB.BASEBOARD_FAB2(SCH_1):GND
   2 UNNAMED_207_3D01R5F-GP_I85_2      2 @BASEBOARD_FAB2_LIB.BASEBOARD_FAB2(SCH_1):UNNAMED_207_3D01R5F-GP_I85_2

3D01R5F-GP_SMD-RG5-3D01R5F-GP,A  I76  RT16
   1    GND      1 @BASEBOARD_FAB2_LIB.BASEBOARD_FAB2(SCH_1):GND
   2 UNNAMED_207_3D01R5F-GP_I76_2      2 @BASEBOARD_FAB2_LIB.BASEBOARD_FAB2(SCH_1):UNNAMED_207_3D01R5F-GP_I76_2

RES_0402-0.0,5%,1/16W,CHIP,G21A  I87  RT15
   1 VR_PVCCIN_CPU1_PH1_BOOT      A @BASEBOARD_FAB2_LIB.BASEBOARD_FAB2(SCH_1):VR_PVCCIN_CPU1_PH1_BOOT
   2 VR_PVCCIN_CPU1_PH1_BOOT_R      B @BASEBOARD_FAB2_LIB.BASEBOARD_FAB2(SCH_1):VR_PVCCIN_CPU1_PH1_BOOT_R

RES_0402-0.0,5%,1/16W,CHIP,G21A  I88  RT17
   1 VR_PVCCIN_CPU1_PH2_BOOT      A @BASEBOARD_FAB2_LIB.BASEBOARD_FAB2(SCH_1):VR_PVCCIN_CPU1_PH2_BOOT
   2 VR_PVCCIN_CPU1_PH2_BOOT_R      B @BASEBOARD_FAB2_LIB.BASEBOARD_FAB2(SCH_1):VR_PVCCIN_CPU1_PH2_BOOT_R


DRAWING: @BASEBOARD_FAB2_LIB.BASEBOARD_FAB2(SCH_1):PAGE224 

CAP_0805LF-22UF,4V,20%,X6S,C95A  I6  C1G17
   1 PVDDQ_GHJ      A @BASEBOARD_FAB2_LIB.BASEBOARD_FAB2(SCH_1):PVDDQ_GHJ
   2    GND      B @BASEBOARD_FAB2_LIB.BASEBOARD_FAB2(SCH_1):GND

CAP_0402-0.220UF,16V,10%,X7R,AA  I44  C1G11
   1 VR_PVDDQ_GHJ_PH1_BOOT      A @BASEBOARD_FAB2_LIB.BASEBOARD_FAB2(SCH_1):VR_PVDDQ_GHJ_PH1_BOOT
   2 VR_PVDDQ_GHJ_PH1_PHASE      B @BASEBOARD_FAB2_LIB.BASEBOARD_FAB2(SCH_1):VR_PVDDQ_GHJ_PH1_PHASE

CAP_0805-10UF,16V,10%,X6S,C953A  I45  C9U6
   1 VR_FET_SW_P12V_STBY_PVDDQ_GHJ      A @BASEBOARD_FAB2_LIB.BASEBOARD_FAB2(SCH_1):VR_FET_SW_P12V_STBY_PVDDQ_GHJ
   2    GND      B @BASEBOARD_FAB2_LIB.BASEBOARD_FAB2(SCH_1):GND

CAP_0805-10UF,16V,10%,X6S,C953A  I46  C9U4
   1 VR_FET_SW_P12V_STBY_PVDDQ_GHJ      A @BASEBOARD_FAB2_LIB.BASEBOARD_FAB2(SCH_1):VR_FET_SW_P12V_STBY_PVDDQ_GHJ
   2    GND      B @BASEBOARD_FAB2_LIB.BASEBOARD_FAB2(SCH_1):GND

CAP_0805-10UF,16V,10%,X6S,C953A  I47  C9T4
   1 VR_FET_SW_P12V_STBY_PVDDQ_GHJ      A @BASEBOARD_FAB2_LIB.BASEBOARD_FAB2(SCH_1):VR_FET_SW_P12V_STBY_PVDDQ_GHJ
   2    GND      B @BASEBOARD_FAB2_LIB.BASEBOARD_FAB2(SCH_1):GND

CAP_0402-1.0UF,16V,10%,X6S,D97A  I48  C1F27
   1 VR_FET_SW_P12V_STBY_PVDDQ_GHJ      A @BASEBOARD_FAB2_LIB.BASEBOARD_FAB2(SCH_1):VR_FET_SW_P12V_STBY_PVDDQ_GHJ
   2    GND      B @BASEBOARD_FAB2_LIB.BASEBOARD_FAB2(SCH_1):GND

CAP_0402-1.0UF,16V,10%,X6S,D97A  I50  C1G6
   1 VR_PVDDQ_GHJ_PH1_VCIN      A @BASEBOARD_FAB2_LIB.BASEBOARD_FAB2(SCH_1):VR_PVDDQ_GHJ_PH1_VCIN
   2    GND      B @BASEBOARD_FAB2_LIB.BASEBOARD_FAB2(SCH_1):GND

CAP_A_0402V-0.1UF,16V,10%,X7R,A  I51  C1G14
   1 VR_FET_SW_P12V_STBY_PVDDQ_GHJ      A @BASEBOARD_FAB2_LIB.BASEBOARD_FAB2(SCH_1):VR_FET_SW_P12V_STBY_PVDDQ_GHJ
   2    GND      B @BASEBOARD_FAB2_LIB.BASEBOARD_FAB2(SCH_1):GND

RES_0402-1.0,1%,1/16W,CHIP,G21A  I52  R9U1
   1 VR_PVDDQ_GHJ_PH1_VCIN      A @BASEBOARD_FAB2_LIB.BASEBOARD_FAB2(SCH_1):VR_PVDDQ_GHJ_PH1_VCIN
   2 P5V_STBY      B @BASEBOARD_FAB2_LIB.BASEBOARD_FAB2(SCH_1):P5V_STBY

CAP_A_0402V-1.0UF,6.3V,10%,X6SA  I53  C1G4
   1 P5V_STBY      A @BASEBOARD_FAB2_LIB.BASEBOARD_FAB2(SCH_1):P5V_STBY
   2    GND      B @BASEBOARD_FAB2_LIB.BASEBOARD_FAB2(SCH_1):GND

CAP_0402-0.22UF,16V,10%,X7R,A3A  I54  C1G5
   1 P5V_STBY      A @BASEBOARD_FAB2_LIB.BASEBOARD_FAB2(SCH_1):P5V_STBY
   2    GND      B @BASEBOARD_FAB2_LIB.BASEBOARD_FAB2(SCH_1):GND

INDUCTOR_SM-0.12UH,IND,D92183-A  I55  L1G1
   1 VR_PVDDQ_GHJ_PH1_SW    INA @BASEBOARD_FAB2_LIB.BASEBOARD_FAB2(SCH_1):VR_PVDDQ_GHJ_PH1_SW
   2 PVDDQ_GHJ    INB @BASEBOARD_FAB2_LIB.BASEBOARD_FAB2(SCH_1):PVDDQ_GHJ

INDUCTOR_SM-0.12UH,IND,D92183-A  I65  L1F2
   1 VR_PVDDQ_GHJ_PH2_SW    INA @BASEBOARD_FAB2_LIB.BASEBOARD_FAB2(SCH_1):VR_PVDDQ_GHJ_PH2_SW
   2 PVDDQ_GHJ    INB @BASEBOARD_FAB2_LIB.BASEBOARD_FAB2(SCH_1):PVDDQ_GHJ

CAP_0805LF-22UF,4V,20%,X6S,C95A  I68  C1G20
   1 PVDDQ_GHJ      A @BASEBOARD_FAB2_LIB.BASEBOARD_FAB2(SCH_1):PVDDQ_GHJ
   2    GND      B @BASEBOARD_FAB2_LIB.BASEBOARD_FAB2(SCH_1):GND

CAP_0402-0.22UF,16V,10%,X7R,A3A  I72  C1G29
   1 P5V_STBY      A @BASEBOARD_FAB2_LIB.BASEBOARD_FAB2(SCH_1):P5V_STBY
   2    GND      B @BASEBOARD_FAB2_LIB.BASEBOARD_FAB2(SCH_1):GND

CAP_A_0402V-1.0UF,6.3V,10%,X6SA  I73  C1F21
   1 P5V_STBY      A @BASEBOARD_FAB2_LIB.BASEBOARD_FAB2(SCH_1):P5V_STBY
   2    GND      B @BASEBOARD_FAB2_LIB.BASEBOARD_FAB2(SCH_1):GND

CAP_0402-0.220UF,16V,10%,X7R,AA  I75  C1F26
   1 VR_PVDDQ_GHJ_PH2_BOOT      A @BASEBOARD_FAB2_LIB.BASEBOARD_FAB2(SCH_1):VR_PVDDQ_GHJ_PH2_BOOT
   2 VR_PVDDQ_GHJ_PH2_PHASE      B @BASEBOARD_FAB2_LIB.BASEBOARD_FAB2(SCH_1):VR_PVDDQ_GHJ_PH2_PHASE

RES_0402-1.0,1%,1/16W,CHIP,G21A  I76  R9U12
   1 VR_PVDDQ_GHJ_PH2_VCIN      A @BASEBOARD_FAB2_LIB.BASEBOARD_FAB2(SCH_1):VR_PVDDQ_GHJ_PH2_VCIN
   2 P5V_STBY      B @BASEBOARD_FAB2_LIB.BASEBOARD_FAB2(SCH_1):P5V_STBY

CAP_0402-1.0UF,16V,10%,X6S,D97A  I77  C1G28
   1 VR_PVDDQ_GHJ_PH2_VCIN      A @BASEBOARD_FAB2_LIB.BASEBOARD_FAB2(SCH_1):VR_PVDDQ_GHJ_PH2_VCIN
   2    GND      B @BASEBOARD_FAB2_LIB.BASEBOARD_FAB2(SCH_1):GND

CAP_A_0402V-0.1UF,16V,10%,X7R,A  I78  C1F28
   1 VR_FET_SW_P12V_STBY_PVDDQ_GHJ      A @BASEBOARD_FAB2_LIB.BASEBOARD_FAB2(SCH_1):VR_FET_SW_P12V_STBY_PVDDQ_GHJ
   2    GND      B @BASEBOARD_FAB2_LIB.BASEBOARD_FAB2(SCH_1):GND

CAP_0402-1.0UF,16V,10%,X6S,D97A  I79  C1G13
   1 VR_FET_SW_P12V_STBY_PVDDQ_GHJ      A @BASEBOARD_FAB2_LIB.BASEBOARD_FAB2(SCH_1):VR_FET_SW_P12V_STBY_PVDDQ_GHJ
   2    GND      B @BASEBOARD_FAB2_LIB.BASEBOARD_FAB2(SCH_1):GND

CAP_0805-10UF,16V,10%,X6S,C953A  I80  C9U3
   1 VR_FET_SW_P12V_STBY_PVDDQ_GHJ      A @BASEBOARD_FAB2_LIB.BASEBOARD_FAB2(SCH_1):VR_FET_SW_P12V_STBY_PVDDQ_GHJ
   2    GND      B @BASEBOARD_FAB2_LIB.BASEBOARD_FAB2(SCH_1):GND

CAP_0805-10UF,16V,10%,X6S,C953A  I81  C9T6
   1 VR_FET_SW_P12V_STBY_PVDDQ_GHJ      A @BASEBOARD_FAB2_LIB.BASEBOARD_FAB2(SCH_1):VR_FET_SW_P12V_STBY_PVDDQ_GHJ
   2    GND      B @BASEBOARD_FAB2_LIB.BASEBOARD_FAB2(SCH_1):GND

CAP_0805-10UF,16V,10%,X6S,C953A  I84  C9T9
   1 VR_FET_SW_P12V_STBY_PVDDQ_GHJ      A @BASEBOARD_FAB2_LIB.BASEBOARD_FAB2(SCH_1):VR_FET_SW_P12V_STBY_PVDDQ_GHJ
   2    GND      B @BASEBOARD_FAB2_LIB.BASEBOARD_FAB2(SCH_1):GND

IR354XX_SM-IR35411,IC,H73688-0A  I110  EU1G1
  33 VR_PVDDQ_GHJ_PH1_BOOT_R  BOOST @BASEBOARD_FAB2_LIB.BASEBOARD_FAB2(SCH_1):VR_PVDDQ_GHJ_PH1_BOOT_R
  35 P5V_STBY     EN @BASEBOARD_FAB2_LIB.BASEBOARD_FAB2(SCH_1):P5V_STBY
  41 TP_PVDDQ_GHJ_PH1_GL_1  GL<1> @BASEBOARD_FAB2_LIB.BASEBOARD_FAB2(SCH_1):TP_PVDDQ_GHJ_PH1_GL_1
   6 TP_PVDDQ_GHJ_PH1_GL_0  GL<0> @BASEBOARD_FAB2_LIB.BASEBOARD_FAB2(SCH_1):TP_PVDDQ_GHJ_PH1_GL_0
  38 ISENSE_PVDDQ_GHJ_PH1_IMON   IOUT @BASEBOARD_FAB2_LIB.BASEBOARD_FAB2(SCH_1):ISENSE_PVDDQ_GHJ_PH1_IMON
   2    GND   LGND @BASEBOARD_FAB2_LIB.BASEBOARD_FAB2(SCH_1):GND
  31 NC_PVDDQ_GHJ_PH1_P31     NC @BASEBOARD_FAB2_LIB.BASEBOARD_FAB2(SCH_1):NC_PVDDQ_GHJ_PH1_P31
  37 VR_PVDDQ_GHJ_PH1_OCSET  OCSET @BASEBOARD_FAB2_LIB.BASEBOARD_FAB2(SCH_1):VR_PVDDQ_GHJ_PH1_OCSET
  40    GND PGND<2> @BASEBOARD_FAB2_LIB.BASEBOARD_FAB2(SCH_1):GND
   7    GND PGND<1> @BASEBOARD_FAB2_LIB.BASEBOARD_FAB2(SCH_1):GND
   5    GND PGND<0> @BASEBOARD_FAB2_LIB.BASEBOARD_FAB2(SCH_1):GND
  32 VR_PVDDQ_GHJ_PH1_PHASE  PHASE @BASEBOARD_FAB2_LIB.BASEBOARD_FAB2(SCH_1):VR_PVDDQ_GHJ_PH1_PHASE
  34 VR_PVDDQ_GHJ_PWM1    PWM @BASEBOARD_FAB2_LIB.BASEBOARD_FAB2(SCH_1):VR_PVDDQ_GHJ_PWM1
  39 VR_PVDDQ_GHJ_AIREF1  REFIN @BASEBOARD_FAB2_LIB.BASEBOARD_FAB2(SCH_1):VR_PVDDQ_GHJ_AIREF1
  10 VR_PVDDQ_GHJ_PH1_SW     SW @BASEBOARD_FAB2_LIB.BASEBOARD_FAB2(SCH_1):VR_PVDDQ_GHJ_PH1_SW
  36 A_TSENSE_PVDDQ_GHJ TOUT_FLT @BASEBOARD_FAB2_LIB.BASEBOARD_FAB2(SCH_1):A_TSENSE_PVDDQ_GHJ
   3 VR_PVDDQ_GHJ_PH1_VCIN    VCC @BASEBOARD_FAB2_LIB.BASEBOARD_FAB2(SCH_1):VR_PVDDQ_GHJ_PH1_VCIN
   4 P5V_STBY   VDRV @BASEBOARD_FAB2_LIB.BASEBOARD_FAB2(SCH_1):P5V_STBY
  30 VR_FET_SW_P12V_STBY_PVDDQ_GHJ VIN<1> @BASEBOARD_FAB2_LIB.BASEBOARD_FAB2(SCH_1):VR_FET_SW_P12V_STBY_PVDDQ_GHJ
  25 VR_FET_SW_P12V_STBY_PVDDQ_GHJ VIN<0> @BASEBOARD_FAB2_LIB.BASEBOARD_FAB2(SCH_1):VR_FET_SW_P12V_STBY_PVDDQ_GHJ
   1 PVDDQ_GHJ    VOS @BASEBOARD_FAB2_LIB.BASEBOARD_FAB2(SCH_1):PVDDQ_GHJ

IR354XX_SM-IR35411,IC,H73688-0A  I111  EU1F1
  33 VR_PVDDQ_GHJ_PH2_BOOT_R  BOOST @BASEBOARD_FAB2_LIB.BASEBOARD_FAB2(SCH_1):VR_PVDDQ_GHJ_PH2_BOOT_R
  35 P5V_STBY     EN @BASEBOARD_FAB2_LIB.BASEBOARD_FAB2(SCH_1):P5V_STBY
  41 TP_PVDDQ_GHJ_PH2_GL_1  GL<1> @BASEBOARD_FAB2_LIB.BASEBOARD_FAB2(SCH_1):TP_PVDDQ_GHJ_PH2_GL_1
   6 TP_PVDDQ_GHJ_PH2_GL_0  GL<0> @BASEBOARD_FAB2_LIB.BASEBOARD_FAB2(SCH_1):TP_PVDDQ_GHJ_PH2_GL_0
  38 ISENSE_PVDDQ_GHJ_PH2_IMON   IOUT @BASEBOARD_FAB2_LIB.BASEBOARD_FAB2(SCH_1):ISENSE_PVDDQ_GHJ_PH2_IMON
   2    GND   LGND @BASEBOARD_FAB2_LIB.BASEBOARD_FAB2(SCH_1):GND
  31 NC_PVDDQ_GHJ_PH2_P31     NC @BASEBOARD_FAB2_LIB.BASEBOARD_FAB2(SCH_1):NC_PVDDQ_GHJ_PH2_P31
  37 VR_PVDDQ_GHJ_PH2_OCSET  OCSET @BASEBOARD_FAB2_LIB.BASEBOARD_FAB2(SCH_1):VR_PVDDQ_GHJ_PH2_OCSET
  40    GND PGND<2> @BASEBOARD_FAB2_LIB.BASEBOARD_FAB2(SCH_1):GND
   7    GND PGND<1> @BASEBOARD_FAB2_LIB.BASEBOARD_FAB2(SCH_1):GND
   5    GND PGND<0> @BASEBOARD_FAB2_LIB.BASEBOARD_FAB2(SCH_1):GND
  32 VR_PVDDQ_GHJ_PH2_PHASE  PHASE @BASEBOARD_FAB2_LIB.BASEBOARD_FAB2(SCH_1):VR_PVDDQ_GHJ_PH2_PHASE
  34 VR_PVDDQ_GHJ_PWM2    PWM @BASEBOARD_FAB2_LIB.BASEBOARD_FAB2(SCH_1):VR_PVDDQ_GHJ_PWM2
  39 VR_PVDDQ_GHJ_AIREF2  REFIN @BASEBOARD_FAB2_LIB.BASEBOARD_FAB2(SCH_1):VR_PVDDQ_GHJ_AIREF2
  10 VR_PVDDQ_GHJ_PH2_SW     SW @BASEBOARD_FAB2_LIB.BASEBOARD_FAB2(SCH_1):VR_PVDDQ_GHJ_PH2_SW
  36 A_TSENSE_PVDDQ_GHJ TOUT_FLT @BASEBOARD_FAB2_LIB.BASEBOARD_FAB2(SCH_1):A_TSENSE_PVDDQ_GHJ
   3 VR_PVDDQ_GHJ_PH2_VCIN    VCC @BASEBOARD_FAB2_LIB.BASEBOARD_FAB2(SCH_1):VR_PVDDQ_GHJ_PH2_VCIN
   4 P5V_STBY   VDRV @BASEBOARD_FAB2_LIB.BASEBOARD_FAB2(SCH_1):P5V_STBY
  30 VR_FET_SW_P12V_STBY_PVDDQ_GHJ VIN<1> @BASEBOARD_FAB2_LIB.BASEBOARD_FAB2(SCH_1):VR_FET_SW_P12V_STBY_PVDDQ_GHJ
  25 VR_FET_SW_P12V_STBY_PVDDQ_GHJ VIN<0> @BASEBOARD_FAB2_LIB.BASEBOARD_FAB2(SCH_1):VR_FET_SW_P12V_STBY_PVDDQ_GHJ
   1 PVDDQ_GHJ    VOS @BASEBOARD_FAB2_LIB.BASEBOARD_FAB2(SCH_1):PVDDQ_GHJ

RES_0402-68.1K,1%,1/16W,EMPTY,A  I112  R1G26
   1 VR_PVDDQ_GHJ_PH1_OCSET      A @BASEBOARD_FAB2_LIB.BASEBOARD_FAB2(SCH_1):VR_PVDDQ_GHJ_PH1_OCSET
   2    GND      B @BASEBOARD_FAB2_LIB.BASEBOARD_FAB2(SCH_1):GND

RES_0402-68.1K,1%,1/16W,EMPTY,A  I114  R1G25
   1 VR_PVDDQ_GHJ_PH2_OCSET      A @BASEBOARD_FAB2_LIB.BASEBOARD_FAB2(SCH_1):VR_PVDDQ_GHJ_PH2_OCSET
   2    GND      B @BASEBOARD_FAB2_LIB.BASEBOARD_FAB2(SCH_1):GND

CAP_A_0402V-0.1UF,16V,10%,X7R,A  I117  CT30
   1 VR_PVDDQ_GHJ_AIREF1      A @BASEBOARD_FAB2_LIB.BASEBOARD_FAB2(SCH_1):VR_PVDDQ_GHJ_AIREF1
   2    GND      B @BASEBOARD_FAB2_LIB.BASEBOARD_FAB2(SCH_1):GND

SC2K2P50V3KX-GP_SMD-BCG6-SC2K2A  I121  CT29
   1 VR_PVDDQ_GHJ_PH1_SW      1 @BASEBOARD_FAB2_LIB.BASEBOARD_FAB2(SCH_1):VR_PVDDQ_GHJ_PH1_SW
   2 UNNAMED_224_3D01R5F-GP_I119_2      2 @BASEBOARD_FAB2_LIB.BASEBOARD_FAB2(SCH_1):UNNAMED_224_3D01R5F-GP_I119_2

CAP_0402LF-1000PF,50V,10%,X7R,A  I122  CT28
   1 A_TSENSE_PVDDQ_GHJ      A @BASEBOARD_FAB2_LIB.BASEBOARD_FAB2(SCH_1):A_TSENSE_PVDDQ_GHJ
   2    GND      B @BASEBOARD_FAB2_LIB.BASEBOARD_FAB2(SCH_1):GND

CAP_A_0402V-0.1UF,16V,10%,X7R,A  I124  CT31
   1 VR_PVDDQ_GHJ_AIREF2      A @BASEBOARD_FAB2_LIB.BASEBOARD_FAB2(SCH_1):VR_PVDDQ_GHJ_AIREF2
   2    GND      B @BASEBOARD_FAB2_LIB.BASEBOARD_FAB2(SCH_1):GND

SC2K2P50V3KX-GP_SMD-BCG6-SC2K2A  I127  CT33
   1 VR_PVDDQ_GHJ_PH2_SW      1 @BASEBOARD_FAB2_LIB.BASEBOARD_FAB2(SCH_1):VR_PVDDQ_GHJ_PH2_SW
   2 UNNAMED_224_3D01R5F-GP_I129_2      2 @BASEBOARD_FAB2_LIB.BASEBOARD_FAB2(SCH_1):UNNAMED_224_3D01R5F-GP_I129_2

CAP_0402LF-1000PF,50V,10%,X7R,A  I130  CT32
   1 A_TSENSE_PVDDQ_GHJ      A @BASEBOARD_FAB2_LIB.BASEBOARD_FAB2(SCH_1):A_TSENSE_PVDDQ_GHJ
   2    GND      B @BASEBOARD_FAB2_LIB.BASEBOARD_FAB2(SCH_1):GND

3D01R5F-GP_SMD-RG5-3D01R5F-GP,A  I129  RT22
   1    GND      1 @BASEBOARD_FAB2_LIB.BASEBOARD_FAB2(SCH_1):GND
   2 UNNAMED_224_3D01R5F-GP_I129_2      2 @BASEBOARD_FAB2_LIB.BASEBOARD_FAB2(SCH_1):UNNAMED_224_3D01R5F-GP_I129_2

3D01R5F-GP_SMD-RG5-3D01R5F-GP,A  I119  RT20
   1    GND      1 @BASEBOARD_FAB2_LIB.BASEBOARD_FAB2(SCH_1):GND
   2 UNNAMED_224_3D01R5F-GP_I119_2      2 @BASEBOARD_FAB2_LIB.BASEBOARD_FAB2(SCH_1):UNNAMED_224_3D01R5F-GP_I119_2

RES_0402-0.0,5%,1/16W,CHIP,G21A  I132  RT19
   1 VR_PVDDQ_GHJ_PH1_BOOT      A @BASEBOARD_FAB2_LIB.BASEBOARD_FAB2(SCH_1):VR_PVDDQ_GHJ_PH1_BOOT
   2 VR_PVDDQ_GHJ_PH1_BOOT_R      B @BASEBOARD_FAB2_LIB.BASEBOARD_FAB2(SCH_1):VR_PVDDQ_GHJ_PH1_BOOT_R

RES_0402-0.0,5%,1/16W,CHIP,G21A  I133  RT21
   1 VR_PVDDQ_GHJ_PH2_BOOT      A @BASEBOARD_FAB2_LIB.BASEBOARD_FAB2(SCH_1):VR_PVDDQ_GHJ_PH2_BOOT
   2 VR_PVDDQ_GHJ_PH2_BOOT_R      B @BASEBOARD_FAB2_LIB.BASEBOARD_FAB2(SCH_1):VR_PVDDQ_GHJ_PH2_BOOT_R


DRAWING: @BASEBOARD_FAB2_LIB.BASEBOARD_FAB2(SCH_1):PAGE204 

INDUCTOR_SM-0.12UH,IND,D92183-A  I5  L4C3
   1 VR_PVCCIN_CPU0_PHASE5    INA @BASEBOARD_FAB2_LIB.BASEBOARD_FAB2(SCH_1):VR_PVCCIN_CPU0_PHASE5
   2 PVCCIN_CPU0    INB @BASEBOARD_FAB2_LIB.BASEBOARD_FAB2(SCH_1):PVCCIN_CPU0

CAP_A_0603V-22.0UF,4V,20%,X6S,A  I9  C4D12
   1 PVCCIN_CPU0      A @BASEBOARD_FAB2_LIB.BASEBOARD_FAB2(SCH_1):PVCCIN_CPU0
   2    GND      B @BASEBOARD_FAB2_LIB.BASEBOARD_FAB2(SCH_1):GND

CAP_0402-0.22UF,16V,10%,X7R,A3A  I18  C4D47
   1 P5V_STBY      A @BASEBOARD_FAB2_LIB.BASEBOARD_FAB2(SCH_1):P5V_STBY
   2    GND      B @BASEBOARD_FAB2_LIB.BASEBOARD_FAB2(SCH_1):GND

CAP_A_0402V-1.0UF,6.3V,10%,X6SA  I19  C4C14
   1 P5V_STBY      A @BASEBOARD_FAB2_LIB.BASEBOARD_FAB2(SCH_1):P5V_STBY
   2    GND      B @BASEBOARD_FAB2_LIB.BASEBOARD_FAB2(SCH_1):GND

CAP_0402-0.220UF,16V,10%,X7R,AA  I22  C4C17
   1 VR_PVCCIN_CPU0_PH5_BOOT      A @BASEBOARD_FAB2_LIB.BASEBOARD_FAB2(SCH_1):VR_PVCCIN_CPU0_PH5_BOOT
   2 VR_PVCCIN_CPU0_PH5_PHASE      B @BASEBOARD_FAB2_LIB.BASEBOARD_FAB2(SCH_1):VR_PVCCIN_CPU0_PH5_PHASE

RES_0402-1.0,1%,1/16W,CHIP,G21A  I33  R6P47
   1 VR_PVCCIN_CPU0_PH5_VCIN      A @BASEBOARD_FAB2_LIB.BASEBOARD_FAB2(SCH_1):VR_PVCCIN_CPU0_PH5_VCIN
   2 P5V_STBY      B @BASEBOARD_FAB2_LIB.BASEBOARD_FAB2(SCH_1):P5V_STBY

CAP_0402-1.0UF,16V,10%,X6S,D97A  I34  C4D46
   1 VR_PVCCIN_CPU0_PH5_VCIN      A @BASEBOARD_FAB2_LIB.BASEBOARD_FAB2(SCH_1):VR_PVCCIN_CPU0_PH5_VCIN
   2    GND      B @BASEBOARD_FAB2_LIB.BASEBOARD_FAB2(SCH_1):GND

CAP_A_0402V-0.1UF,16V,10%,X7R,A  I35  C4C19
   1 VR_FET_SW_P12V_STBY_PVCCIN_CPU0      A @BASEBOARD_FAB2_LIB.BASEBOARD_FAB2(SCH_1):VR_FET_SW_P12V_STBY_PVCCIN_CPU0
   2    GND      B @BASEBOARD_FAB2_LIB.BASEBOARD_FAB2(SCH_1):GND

CAP_0402-1.0UF,16V,10%,X6S,D97A  I36  C4C18
   1 VR_FET_SW_P12V_STBY_PVCCIN_CPU0      A @BASEBOARD_FAB2_LIB.BASEBOARD_FAB2(SCH_1):VR_FET_SW_P12V_STBY_PVCCIN_CPU0
   2    GND      B @BASEBOARD_FAB2_LIB.BASEBOARD_FAB2(SCH_1):GND

CAP_0805-10UF,16V,10%,X6S,C953A  I37  C6N10
   1 VR_FET_SW_P12V_STBY_PVCCIN_CPU0      A @BASEBOARD_FAB2_LIB.BASEBOARD_FAB2(SCH_1):VR_FET_SW_P12V_STBY_PVCCIN_CPU0
   2    GND      B @BASEBOARD_FAB2_LIB.BASEBOARD_FAB2(SCH_1):GND

CAP_0805-10UF,16V,10%,X6S,C953A  I38  C6P17
   1 VR_FET_SW_P12V_STBY_PVCCIN_CPU0      A @BASEBOARD_FAB2_LIB.BASEBOARD_FAB2(SCH_1):VR_FET_SW_P12V_STBY_PVCCIN_CPU0
   2    GND      B @BASEBOARD_FAB2_LIB.BASEBOARD_FAB2(SCH_1):GND

CAP_0805-10UF,16V,10%,X6S,C953A  I42  C6N11
   1 VR_FET_SW_P12V_STBY_PVCCIN_CPU0      A @BASEBOARD_FAB2_LIB.BASEBOARD_FAB2(SCH_1):VR_FET_SW_P12V_STBY_PVCCIN_CPU0
   2    GND      B @BASEBOARD_FAB2_LIB.BASEBOARD_FAB2(SCH_1):GND

RES_2010-0.001,1%,1W,CHIP,E309A  I45  R4C6
   1 VR_FET_SW_P12V_PVCCIN_CPU0_R      A @BASEBOARD_FAB2_LIB.BASEBOARD_FAB2(SCH_1):VR_FET_SW_P12V_PVCCIN_CPU0_R
   2 VR_FET_SW_P12V_STBY_PVCCIN_CPU0      B @BASEBOARD_FAB2_LIB.BASEBOARD_FAB2(SCH_1):VR_FET_SW_P12V_STBY_PVCCIN_CPU0

INDUCTOR_SM-100NH,IND,D92183-0A  I46  L4C1
   1 P12V_STBY    INA @BASEBOARD_FAB2_LIB.BASEBOARD_FAB2(SCH_1):P12V_STBY
   2 VR_FET_SW_P12V_PVCCIN_CPU0_R    INB @BASEBOARD_FAB2_LIB.BASEBOARD_FAB2(SCH_1):VR_FET_SW_P12V_PVCCIN_CPU0_R

CAPP_2626-270UF,16V,20%,OSCON,A  I48  C4D2
   1 VR_FET_SW_P12V_STBY_PVCCIN_CPU0      A @BASEBOARD_FAB2_LIB.BASEBOARD_FAB2(SCH_1):VR_FET_SW_P12V_STBY_PVCCIN_CPU0
   2    GND      B @BASEBOARD_FAB2_LIB.BASEBOARD_FAB2(SCH_1):GND

CAPP_2626-270UF,16V,20%,OSCON,A  I50  C4E16
   1 VR_FET_SW_P12V_STBY_PVCCIN_CPU0      A @BASEBOARD_FAB2_LIB.BASEBOARD_FAB2(SCH_1):VR_FET_SW_P12V_STBY_PVCCIN_CPU0
   2    GND      B @BASEBOARD_FAB2_LIB.BASEBOARD_FAB2(SCH_1):GND

CAP_A_0402V-0.1UF,16V,10%,EMPTA  I51  C4C2
   1 VR_FET_SW_P12V_PVCCIN_CPU0_R      A @BASEBOARD_FAB2_LIB.BASEBOARD_FAB2(SCH_1):VR_FET_SW_P12V_PVCCIN_CPU0_R
   2    GND      B @BASEBOARD_FAB2_LIB.BASEBOARD_FAB2(SCH_1):GND

ADM4073_SM-EMPTY,G12194-001  I53  U4C1
   2    GND GND<1> @BASEBOARD_FAB2_LIB.BASEBOARD_FAB2(SCH_1):GND
   1    GND GND<0> @BASEBOARD_FAB2_LIB.BASEBOARD_FAB2(SCH_1):GND
   6 PVCCIN_PVSA_CPU0_IINSEN    OUT @BASEBOARD_FAB2_LIB.BASEBOARD_FAB2(SCH_1):PVCCIN_PVSA_CPU0_IINSEN
   5 VR_FET_SW_P12V_STBY_PVCCIN_CPU0    RSN @BASEBOARD_FAB2_LIB.BASEBOARD_FAB2(SCH_1):VR_FET_SW_P12V_STBY_PVCCIN_CPU0
   4 VR_FET_SW_P12V_PVCCIN_CPU0_R    RSP @BASEBOARD_FAB2_LIB.BASEBOARD_FAB2(SCH_1):VR_FET_SW_P12V_PVCCIN_CPU0_R
   3 VR_FET_SW_P12V_PVCCIN_CPU0_R    VCC @BASEBOARD_FAB2_LIB.BASEBOARD_FAB2(SCH_1):VR_FET_SW_P12V_PVCCIN_CPU0_R

RES_0402-100.0,1%,1/16W,CHIP,GA  I60  R4E14
   1 VSENSE_PVCCIN_CPU0_P      A @BASEBOARD_FAB2_LIB.BASEBOARD_FAB2(SCH_1):VSENSE_PVCCIN_CPU0_P
   2 PVCCIN_CPU0      B @BASEBOARD_FAB2_LIB.BASEBOARD_FAB2(SCH_1):PVCCIN_CPU0

RES_0402-0.0,5%,1/16W,CHIP,G21A  I61  R4E16
   1 VSENSE_PVCCIN_CPU0_P      A @BASEBOARD_FAB2_LIB.BASEBOARD_FAB2(SCH_1):VSENSE_PVCCIN_CPU0_P
   2 VSENSE_PVCCIN_CPU0_SKT_VSEN      B @BASEBOARD_FAB2_LIB.BASEBOARD_FAB2(SCH_1):VSENSE_PVCCIN_CPU0_SKT_VSEN

RES_0402-0.0,5%,1/16W,CHIP,G21A  I62  R4E17
   1 VSENSE_PVCCIN_CPU0_N      A @BASEBOARD_FAB2_LIB.BASEBOARD_FAB2(SCH_1):VSENSE_PVCCIN_CPU0_N
   2 VSENSE_PVCCIN_CPU0_SKT_VRTN      B @BASEBOARD_FAB2_LIB.BASEBOARD_FAB2(SCH_1):VSENSE_PVCCIN_CPU0_SKT_VRTN

RES_0402-1.00K,1%,1/16W,EMPTY,A  I63  R4E15
   1 VSENSE_PVCCIN_CPU0_P      A @BASEBOARD_FAB2_LIB.BASEBOARD_FAB2(SCH_1):VSENSE_PVCCIN_CPU0_P
   2 VSENSE_PVCCIN_CPU0_N      B @BASEBOARD_FAB2_LIB.BASEBOARD_FAB2(SCH_1):VSENSE_PVCCIN_CPU0_N

RES_0402-100.0,1%,1/16W,CHIP,GA  I64  R4E18
   1 VSENSE_PVCCIN_CPU0_N      A @BASEBOARD_FAB2_LIB.BASEBOARD_FAB2(SCH_1):VSENSE_PVCCIN_CPU0_N
   2    GND      B @BASEBOARD_FAB2_LIB.BASEBOARD_FAB2(SCH_1):GND

CAPP_2626-270UF,16V,20%,OSCON,A  I67  C4C12
   1 VR_FET_SW_P12V_STBY_PVCCIN_CPU0      A @BASEBOARD_FAB2_LIB.BASEBOARD_FAB2(SCH_1):VR_FET_SW_P12V_STBY_PVCCIN_CPU0
   2    GND      B @BASEBOARD_FAB2_LIB.BASEBOARD_FAB2(SCH_1):GND

CAP_A_0603V-22.0UF,4V,20%,X6S,A  I70  C6R2
   1 PVCCIN_CPU0      A @BASEBOARD_FAB2_LIB.BASEBOARD_FAB2(SCH_1):PVCCIN_CPU0
   2    GND      B @BASEBOARD_FAB2_LIB.BASEBOARD_FAB2(SCH_1):GND

IR354XX_SM-IR35411,IC,H73688-0A  I71  EU4C2
  33 VR_PVCCIN_CPU0_PH5_BOOT_R  BOOST @BASEBOARD_FAB2_LIB.BASEBOARD_FAB2(SCH_1):VR_PVCCIN_CPU0_PH5_BOOT_R
  35 P5V_STBY     EN @BASEBOARD_FAB2_LIB.BASEBOARD_FAB2(SCH_1):P5V_STBY
  41 TP_PVCCIN_CPU0_PH5_GL_1  GL<1> @BASEBOARD_FAB2_LIB.BASEBOARD_FAB2(SCH_1):TP_PVCCIN_CPU0_PH5_GL_1
   6 TP_PVCCIN_CPU0_PH5_GL_0  GL<0> @BASEBOARD_FAB2_LIB.BASEBOARD_FAB2(SCH_1):TP_PVCCIN_CPU0_PH5_GL_0
  38 ISENSE_PVCCIN_CPU0_PH5_IMON   IOUT @BASEBOARD_FAB2_LIB.BASEBOARD_FAB2(SCH_1):ISENSE_PVCCIN_CPU0_PH5_IMON
   2    GND   LGND @BASEBOARD_FAB2_LIB.BASEBOARD_FAB2(SCH_1):GND
  31 NC_PVCCIN_CPU0_PH5_P31     NC @BASEBOARD_FAB2_LIB.BASEBOARD_FAB2(SCH_1):NC_PVCCIN_CPU0_PH5_P31
  37 VR_PVCCIN_CPU0_PH5_OCSET  OCSET @BASEBOARD_FAB2_LIB.BASEBOARD_FAB2(SCH_1):VR_PVCCIN_CPU0_PH5_OCSET
  40    GND PGND<2> @BASEBOARD_FAB2_LIB.BASEBOARD_FAB2(SCH_1):GND
   7    GND PGND<1> @BASEBOARD_FAB2_LIB.BASEBOARD_FAB2(SCH_1):GND
   5    GND PGND<0> @BASEBOARD_FAB2_LIB.BASEBOARD_FAB2(SCH_1):GND
  32 VR_PVCCIN_CPU0_PH5_PHASE  PHASE @BASEBOARD_FAB2_LIB.BASEBOARD_FAB2(SCH_1):VR_PVCCIN_CPU0_PH5_PHASE
  34 VR_PVCCIN_CPU0_PWM5    PWM @BASEBOARD_FAB2_LIB.BASEBOARD_FAB2(SCH_1):VR_PVCCIN_CPU0_PWM5
  39 VR_PVCCIN_CPU0_AIREF5  REFIN @BASEBOARD_FAB2_LIB.BASEBOARD_FAB2(SCH_1):VR_PVCCIN_CPU0_AIREF5
  10 VR_PVCCIN_CPU0_PHASE5     SW @BASEBOARD_FAB2_LIB.BASEBOARD_FAB2(SCH_1):VR_PVCCIN_CPU0_PHASE5
  36 A_TSENSE_PVCCIN_CPU0 TOUT_FLT @BASEBOARD_FAB2_LIB.BASEBOARD_FAB2(SCH_1):A_TSENSE_PVCCIN_CPU0
   3 VR_PVCCIN_CPU0_PH5_VCIN    VCC @BASEBOARD_FAB2_LIB.BASEBOARD_FAB2(SCH_1):VR_PVCCIN_CPU0_PH5_VCIN
   4 P5V_STBY   VDRV @BASEBOARD_FAB2_LIB.BASEBOARD_FAB2(SCH_1):P5V_STBY
  30 VR_FET_SW_P12V_STBY_PVCCIN_CPU0 VIN<1> @BASEBOARD_FAB2_LIB.BASEBOARD_FAB2(SCH_1):VR_FET_SW_P12V_STBY_PVCCIN_CPU0
  25 VR_FET_SW_P12V_STBY_PVCCIN_CPU0 VIN<0> @BASEBOARD_FAB2_LIB.BASEBOARD_FAB2(SCH_1):VR_FET_SW_P12V_STBY_PVCCIN_CPU0
   1 PVCCIN_CPU0    VOS @BASEBOARD_FAB2_LIB.BASEBOARD_FAB2(SCH_1):PVCCIN_CPU0

RES_0402-68.1K,1%,1/16W,EMPTY,A  I83  R4D68
   1 VR_PVCCIN_CPU0_PH5_OCSET      A @BASEBOARD_FAB2_LIB.BASEBOARD_FAB2(SCH_1):VR_PVCCIN_CPU0_PH5_OCSET
   2    GND      B @BASEBOARD_FAB2_LIB.BASEBOARD_FAB2(SCH_1):GND

CAP_A_0402V-0.1UF,16V,10%,X7R,A  I85  CT36
   1 VR_PVCCIN_CPU0_AIREF5      A @BASEBOARD_FAB2_LIB.BASEBOARD_FAB2(SCH_1):VR_PVCCIN_CPU0_AIREF5
   2    GND      B @BASEBOARD_FAB2_LIB.BASEBOARD_FAB2(SCH_1):GND

CAP_0402LF-1000PF,50V,10%,X7R,A  I88  CT34
   1 A_TSENSE_PVCCIN_CPU0      A @BASEBOARD_FAB2_LIB.BASEBOARD_FAB2(SCH_1):A_TSENSE_PVCCIN_CPU0
   2    GND      B @BASEBOARD_FAB2_LIB.BASEBOARD_FAB2(SCH_1):GND

SC2K2P50V3KX-GP_SMD-BCG6-SC2K2A  I90  CT35
   1 VR_PVCCIN_CPU0_PHASE5      1 @BASEBOARD_FAB2_LIB.BASEBOARD_FAB2(SCH_1):VR_PVCCIN_CPU0_PHASE5
   2 UNNAMED_204_3D01R5F-GP_I91_2      2 @BASEBOARD_FAB2_LIB.BASEBOARD_FAB2(SCH_1):UNNAMED_204_3D01R5F-GP_I91_2

3D01R5F-GP_SMD-RG5-3D01R5F-GP,A  I91  RT24
   1    GND      1 @BASEBOARD_FAB2_LIB.BASEBOARD_FAB2(SCH_1):GND
   2 UNNAMED_204_3D01R5F-GP_I91_2      2 @BASEBOARD_FAB2_LIB.BASEBOARD_FAB2(SCH_1):UNNAMED_204_3D01R5F-GP_I91_2

RES_0402-0.0,5%,1/16W,CHIP,G21A  I93  RT23
   1 VR_PVCCIN_CPU0_PH5_BOOT      A @BASEBOARD_FAB2_LIB.BASEBOARD_FAB2(SCH_1):VR_PVCCIN_CPU0_PH5_BOOT
   2 VR_PVCCIN_CPU0_PH5_BOOT_R      B @BASEBOARD_FAB2_LIB.BASEBOARD_FAB2(SCH_1):VR_PVCCIN_CPU0_PH5_BOOT_R


DRAWING: @BASEBOARD_FAB2_LIB.BASEBOARD_FAB2(SCH_1):PAGE203 

CAP_0805-10UF,16V,10%,X6S,C953A  I1  C6P24
   1 VR_FET_SW_P12V_STBY_PVCCIN_CPU0      A @BASEBOARD_FAB2_LIB.BASEBOARD_FAB2(SCH_1):VR_FET_SW_P12V_STBY_PVCCIN_CPU0
   2    GND      B @BASEBOARD_FAB2_LIB.BASEBOARD_FAB2(SCH_1):GND

CAP_0805-10UF,16V,10%,X6S,C953A  I2  C6R6
   1 VR_FET_SW_P12V_STBY_PVCCIN_CPU0      A @BASEBOARD_FAB2_LIB.BASEBOARD_FAB2(SCH_1):VR_FET_SW_P12V_STBY_PVCCIN_CPU0
   2    GND      B @BASEBOARD_FAB2_LIB.BASEBOARD_FAB2(SCH_1):GND

CAP_0402-0.220UF,16V,10%,X7R,AA  I3  C4D9
   1 VR_PVCCIN_CPU0_PH4_BOOT      A @BASEBOARD_FAB2_LIB.BASEBOARD_FAB2(SCH_1):VR_PVCCIN_CPU0_PH4_BOOT
   2 VR_PVCCIN_CPU0_PH4_PHASE      B @BASEBOARD_FAB2_LIB.BASEBOARD_FAB2(SCH_1):VR_PVCCIN_CPU0_PH4_PHASE

INDUCTOR_SM-0.12UH,IND,D92183-A  I15  L4D2
   1 VR_PVCCIN_CPU0_PHASE3    INA @BASEBOARD_FAB2_LIB.BASEBOARD_FAB2(SCH_1):VR_PVCCIN_CPU0_PHASE3
   2 PVCCIN_CPU0    INB @BASEBOARD_FAB2_LIB.BASEBOARD_FAB2(SCH_1):PVCCIN_CPU0

CAPP_3018-470UF,2.5V,20%,ALUM,A  I16  C6R3
   1 PVCCIN_CPU0      A @BASEBOARD_FAB2_LIB.BASEBOARD_FAB2(SCH_1):PVCCIN_CPU0
   2    GND      B @BASEBOARD_FAB2_LIB.BASEBOARD_FAB2(SCH_1):GND

CAPP_3018-470UF,2.5V,20%,ALUM,A  I18  C6R9
   1 PVCCIN_CPU0      A @BASEBOARD_FAB2_LIB.BASEBOARD_FAB2(SCH_1):PVCCIN_CPU0
   2    GND      B @BASEBOARD_FAB2_LIB.BASEBOARD_FAB2(SCH_1):GND

INDUCTOR_SM-0.12UH,IND,D92183-A  I24  L4D1
   1 VR_PVCCIN_CPU0_PHASE4    INA @BASEBOARD_FAB2_LIB.BASEBOARD_FAB2(SCH_1):VR_PVCCIN_CPU0_PHASE4
   2 PVCCIN_CPU0    INB @BASEBOARD_FAB2_LIB.BASEBOARD_FAB2(SCH_1):PVCCIN_CPU0

CAP_A_0603V-22.0UF,4V,20%,X6S,A  I25  C6P3
   1 PVCCIN_CPU0      A @BASEBOARD_FAB2_LIB.BASEBOARD_FAB2(SCH_1):PVCCIN_CPU0
   2    GND      B @BASEBOARD_FAB2_LIB.BASEBOARD_FAB2(SCH_1):GND

CAPP_3018-470UF,2.5V,20%,ALUM,A  I28  C6P23
   1 PVCCIN_CPU0      A @BASEBOARD_FAB2_LIB.BASEBOARD_FAB2(SCH_1):PVCCIN_CPU0
   2    GND      B @BASEBOARD_FAB2_LIB.BASEBOARD_FAB2(SCH_1):GND

CAPP_3018-470UF,2.5V,20%,ALUM,A  I29  C6P14
   1 PVCCIN_CPU0      A @BASEBOARD_FAB2_LIB.BASEBOARD_FAB2(SCH_1):PVCCIN_CPU0
   2    GND      B @BASEBOARD_FAB2_LIB.BASEBOARD_FAB2(SCH_1):GND

CAPP_3018-470UF,2.5V,20%,ALUM,A  I30  C6P18
   1 PVCCIN_CPU0      A @BASEBOARD_FAB2_LIB.BASEBOARD_FAB2(SCH_1):PVCCIN_CPU0
   2    GND      B @BASEBOARD_FAB2_LIB.BASEBOARD_FAB2(SCH_1):GND

CAPP_3018-470UF,2.5V,20%,ALUM,A  I32  C6P8
   1 PVCCIN_CPU0      A @BASEBOARD_FAB2_LIB.BASEBOARD_FAB2(SCH_1):PVCCIN_CPU0
   2    GND      B @BASEBOARD_FAB2_LIB.BASEBOARD_FAB2(SCH_1):GND

CAPP_3018-470UF,2.5V,20%,ALUM,A  I34  C6N9
   1 PVCCIN_CPU0      A @BASEBOARD_FAB2_LIB.BASEBOARD_FAB2(SCH_1):PVCCIN_CPU0
   2    GND      B @BASEBOARD_FAB2_LIB.BASEBOARD_FAB2(SCH_1):GND

RES_0402-1.0,1%,1/16W,CHIP,G21A  I38  R6P19
   1 VR_PVCCIN_CPU0_PH3_VCIN      A @BASEBOARD_FAB2_LIB.BASEBOARD_FAB2(SCH_1):VR_PVCCIN_CPU0_PH3_VCIN
   2 P5V_STBY      B @BASEBOARD_FAB2_LIB.BASEBOARD_FAB2(SCH_1):P5V_STBY

CAP_0402-0.22UF,16V,10%,X7R,A3A  I40  C4D13
   1 P5V_STBY      A @BASEBOARD_FAB2_LIB.BASEBOARD_FAB2(SCH_1):P5V_STBY
   2    GND      B @BASEBOARD_FAB2_LIB.BASEBOARD_FAB2(SCH_1):GND

CAP_A_0402V-1.0UF,6.3V,10%,X6SA  I41  C4D14
   1 P5V_STBY      A @BASEBOARD_FAB2_LIB.BASEBOARD_FAB2(SCH_1):P5V_STBY
   2    GND      B @BASEBOARD_FAB2_LIB.BASEBOARD_FAB2(SCH_1):GND

CAP_0402-0.220UF,16V,10%,X7R,AA  I42  C4D28
   1 VR_PVCCIN_CPU0_PH3_BOOT      A @BASEBOARD_FAB2_LIB.BASEBOARD_FAB2(SCH_1):VR_PVCCIN_CPU0_PH3_BOOT
   2 VR_PVCCIN_CPU0_PH3_PHASE      B @BASEBOARD_FAB2_LIB.BASEBOARD_FAB2(SCH_1):VR_PVCCIN_CPU0_PH3_PHASE

CAP_0402-1.0UF,16V,10%,X6S,D97A  I45  C4D16
   1 VR_PVCCIN_CPU0_PH3_VCIN      A @BASEBOARD_FAB2_LIB.BASEBOARD_FAB2(SCH_1):VR_PVCCIN_CPU0_PH3_VCIN
   2    GND      B @BASEBOARD_FAB2_LIB.BASEBOARD_FAB2(SCH_1):GND

CAP_A_0402V-0.1UF,16V,10%,X7R,A  I46  C4D35
   1 VR_FET_SW_P12V_STBY_PVCCIN_CPU0      A @BASEBOARD_FAB2_LIB.BASEBOARD_FAB2(SCH_1):VR_FET_SW_P12V_STBY_PVCCIN_CPU0
   2    GND      B @BASEBOARD_FAB2_LIB.BASEBOARD_FAB2(SCH_1):GND

CAP_0402-1.0UF,16V,10%,X6S,D97A  I47  C4D30
   1 VR_FET_SW_P12V_STBY_PVCCIN_CPU0      A @BASEBOARD_FAB2_LIB.BASEBOARD_FAB2(SCH_1):VR_FET_SW_P12V_STBY_PVCCIN_CPU0
   2    GND      B @BASEBOARD_FAB2_LIB.BASEBOARD_FAB2(SCH_1):GND

CAP_0402-0.22UF,16V,10%,X7R,A3A  I48  C4D5
   1 P5V_STBY      A @BASEBOARD_FAB2_LIB.BASEBOARD_FAB2(SCH_1):P5V_STBY
   2    GND      B @BASEBOARD_FAB2_LIB.BASEBOARD_FAB2(SCH_1):GND

CAP_A_0402V-1.0UF,6.3V,10%,X6SA  I49  C4D6
   1 P5V_STBY      A @BASEBOARD_FAB2_LIB.BASEBOARD_FAB2(SCH_1):P5V_STBY
   2    GND      B @BASEBOARD_FAB2_LIB.BASEBOARD_FAB2(SCH_1):GND

RES_0402-1.0,1%,1/16W,CHIP,G21A  I50  R6P10
   1 VR_PVCCIN_CPU0_PH4_VCIN      A @BASEBOARD_FAB2_LIB.BASEBOARD_FAB2(SCH_1):VR_PVCCIN_CPU0_PH4_VCIN
   2 P5V_STBY      B @BASEBOARD_FAB2_LIB.BASEBOARD_FAB2(SCH_1):P5V_STBY

CAP_0402-1.0UF,16V,10%,X6S,D97A  I51  C4D7
   1 VR_PVCCIN_CPU0_PH4_VCIN      A @BASEBOARD_FAB2_LIB.BASEBOARD_FAB2(SCH_1):VR_PVCCIN_CPU0_PH4_VCIN
   2    GND      B @BASEBOARD_FAB2_LIB.BASEBOARD_FAB2(SCH_1):GND

CAP_A_0402V-0.1UF,16V,10%,X7R,A  I52  C4D11
   1 VR_FET_SW_P12V_STBY_PVCCIN_CPU0      A @BASEBOARD_FAB2_LIB.BASEBOARD_FAB2(SCH_1):VR_FET_SW_P12V_STBY_PVCCIN_CPU0
   2    GND      B @BASEBOARD_FAB2_LIB.BASEBOARD_FAB2(SCH_1):GND

CAP_0402-1.0UF,16V,10%,X6S,D97A  I53  C4D10
   1 VR_FET_SW_P12V_STBY_PVCCIN_CPU0      A @BASEBOARD_FAB2_LIB.BASEBOARD_FAB2(SCH_1):VR_FET_SW_P12V_STBY_PVCCIN_CPU0
   2    GND      B @BASEBOARD_FAB2_LIB.BASEBOARD_FAB2(SCH_1):GND

CAP_0805-10UF,16V,10%,X6S,C953A  I54  C6P19
   1 VR_FET_SW_P12V_STBY_PVCCIN_CPU0      A @BASEBOARD_FAB2_LIB.BASEBOARD_FAB2(SCH_1):VR_FET_SW_P12V_STBY_PVCCIN_CPU0
   2    GND      B @BASEBOARD_FAB2_LIB.BASEBOARD_FAB2(SCH_1):GND

CAP_0805-10UF,16V,10%,X6S,C953A  I57  C6P20
   1 VR_FET_SW_P12V_STBY_PVCCIN_CPU0      A @BASEBOARD_FAB2_LIB.BASEBOARD_FAB2(SCH_1):VR_FET_SW_P12V_STBY_PVCCIN_CPU0
   2    GND      B @BASEBOARD_FAB2_LIB.BASEBOARD_FAB2(SCH_1):GND

CAP_0805-10UF,16V,10%,X6S,C953A  I58  C6P15
   1 VR_FET_SW_P12V_STBY_PVCCIN_CPU0      A @BASEBOARD_FAB2_LIB.BASEBOARD_FAB2(SCH_1):VR_FET_SW_P12V_STBY_PVCCIN_CPU0
   2    GND      B @BASEBOARD_FAB2_LIB.BASEBOARD_FAB2(SCH_1):GND

CAP_0805-10UF,16V,10%,X6S,C953A  I59  C6P7
   1 VR_FET_SW_P12V_STBY_PVCCIN_CPU0      A @BASEBOARD_FAB2_LIB.BASEBOARD_FAB2(SCH_1):VR_FET_SW_P12V_STBY_PVCCIN_CPU0
   2    GND      B @BASEBOARD_FAB2_LIB.BASEBOARD_FAB2(SCH_1):GND

CAP_A_0603V-22.0UF,4V,20%,X6S,A  I66  C6P21
   1 PVCCIN_CPU0      A @BASEBOARD_FAB2_LIB.BASEBOARD_FAB2(SCH_1):PVCCIN_CPU0
   2    GND      B @BASEBOARD_FAB2_LIB.BASEBOARD_FAB2(SCH_1):GND

RES_0603-100.0,1%,1/10W,CHIP,GA  I67  R4E13
   1 PVCCIN_CPU0      A @BASEBOARD_FAB2_LIB.BASEBOARD_FAB2(SCH_1):PVCCIN_CPU0
   2    GND      B @BASEBOARD_FAB2_LIB.BASEBOARD_FAB2(SCH_1):GND

CAP_A_0603V-22.0UF,4V,20%,X6S,A  I68  C4D34
   1 PVCCIN_CPU0      A @BASEBOARD_FAB2_LIB.BASEBOARD_FAB2(SCH_1):PVCCIN_CPU0
   2    GND      B @BASEBOARD_FAB2_LIB.BASEBOARD_FAB2(SCH_1):GND

CAP_A_0603V-22.0UF,4V,20%,X6S,A  I69  C4D4
   1 PVCCIN_CPU0      A @BASEBOARD_FAB2_LIB.BASEBOARD_FAB2(SCH_1):PVCCIN_CPU0
   2    GND      B @BASEBOARD_FAB2_LIB.BASEBOARD_FAB2(SCH_1):GND

IR354XX_SM-IR35411,IC,H73688-0A  I70  EU4D3
  33 VR_PVCCIN_CPU0_PH3_BOOT_R  BOOST @BASEBOARD_FAB2_LIB.BASEBOARD_FAB2(SCH_1):VR_PVCCIN_CPU0_PH3_BOOT_R
  35 P5V_STBY     EN @BASEBOARD_FAB2_LIB.BASEBOARD_FAB2(SCH_1):P5V_STBY
  41 TP_PVCCIN_CPU0_PH3_GL_1  GL<1> @BASEBOARD_FAB2_LIB.BASEBOARD_FAB2(SCH_1):TP_PVCCIN_CPU0_PH3_GL_1
   6 TP_PVCCIN_CPU0_PH3_GL_0  GL<0> @BASEBOARD_FAB2_LIB.BASEBOARD_FAB2(SCH_1):TP_PVCCIN_CPU0_PH3_GL_0
  38 ISENSE_PVCCIN_CPU0_PH3_IMON   IOUT @BASEBOARD_FAB2_LIB.BASEBOARD_FAB2(SCH_1):ISENSE_PVCCIN_CPU0_PH3_IMON
   2    GND   LGND @BASEBOARD_FAB2_LIB.BASEBOARD_FAB2(SCH_1):GND
  31 NC_PVCCIN_CPU0_PH3_P31     NC @BASEBOARD_FAB2_LIB.BASEBOARD_FAB2(SCH_1):NC_PVCCIN_CPU0_PH3_P31
  37 VR_PVCCIN_CPU0_PH3_OCSET  OCSET @BASEBOARD_FAB2_LIB.BASEBOARD_FAB2(SCH_1):VR_PVCCIN_CPU0_PH3_OCSET
  40    GND PGND<2> @BASEBOARD_FAB2_LIB.BASEBOARD_FAB2(SCH_1):GND
   7    GND PGND<1> @BASEBOARD_FAB2_LIB.BASEBOARD_FAB2(SCH_1):GND
   5    GND PGND<0> @BASEBOARD_FAB2_LIB.BASEBOARD_FAB2(SCH_1):GND
  32 VR_PVCCIN_CPU0_PH3_PHASE  PHASE @BASEBOARD_FAB2_LIB.BASEBOARD_FAB2(SCH_1):VR_PVCCIN_CPU0_PH3_PHASE
  34 VR_PVCCIN_CPU0_PWM3    PWM @BASEBOARD_FAB2_LIB.BASEBOARD_FAB2(SCH_1):VR_PVCCIN_CPU0_PWM3
  39 VR_PVCCIN_CPU0_AIREF3  REFIN @BASEBOARD_FAB2_LIB.BASEBOARD_FAB2(SCH_1):VR_PVCCIN_CPU0_AIREF3
  10 VR_PVCCIN_CPU0_PHASE3     SW @BASEBOARD_FAB2_LIB.BASEBOARD_FAB2(SCH_1):VR_PVCCIN_CPU0_PHASE3
  36 A_TSENSE_PVCCIN_CPU0 TOUT_FLT @BASEBOARD_FAB2_LIB.BASEBOARD_FAB2(SCH_1):A_TSENSE_PVCCIN_CPU0
   3 VR_PVCCIN_CPU0_PH3_VCIN    VCC @BASEBOARD_FAB2_LIB.BASEBOARD_FAB2(SCH_1):VR_PVCCIN_CPU0_PH3_VCIN
   4 P5V_STBY   VDRV @BASEBOARD_FAB2_LIB.BASEBOARD_FAB2(SCH_1):P5V_STBY
  30 VR_FET_SW_P12V_STBY_PVCCIN_CPU0 VIN<1> @BASEBOARD_FAB2_LIB.BASEBOARD_FAB2(SCH_1):VR_FET_SW_P12V_STBY_PVCCIN_CPU0
  25 VR_FET_SW_P12V_STBY_PVCCIN_CPU0 VIN<0> @BASEBOARD_FAB2_LIB.BASEBOARD_FAB2(SCH_1):VR_FET_SW_P12V_STBY_PVCCIN_CPU0
   1 PVCCIN_CPU0    VOS @BASEBOARD_FAB2_LIB.BASEBOARD_FAB2(SCH_1):PVCCIN_CPU0

IR354XX_SM-IR35411,IC,H73688-0A  I71  EU4D1
  33 VR_PVCCIN_CPU0_PH4_BOOT_R  BOOST @BASEBOARD_FAB2_LIB.BASEBOARD_FAB2(SCH_1):VR_PVCCIN_CPU0_PH4_BOOT_R
  35 P5V_STBY     EN @BASEBOARD_FAB2_LIB.BASEBOARD_FAB2(SCH_1):P5V_STBY
  41 TP_PVCCIN_CPU0_PH4_GL_1  GL<1> @BASEBOARD_FAB2_LIB.BASEBOARD_FAB2(SCH_1):TP_PVCCIN_CPU0_PH4_GL_1
   6 TP_PVCCIN_CPU0_PH4_GL_0  GL<0> @BASEBOARD_FAB2_LIB.BASEBOARD_FAB2(SCH_1):TP_PVCCIN_CPU0_PH4_GL_0
  38 ISENSE_PVCCIN_CPU0_PH4_IMON   IOUT @BASEBOARD_FAB2_LIB.BASEBOARD_FAB2(SCH_1):ISENSE_PVCCIN_CPU0_PH4_IMON
   2    GND   LGND @BASEBOARD_FAB2_LIB.BASEBOARD_FAB2(SCH_1):GND
  31 NC_PVCCIN_CPU0_PH4_P31     NC @BASEBOARD_FAB2_LIB.BASEBOARD_FAB2(SCH_1):NC_PVCCIN_CPU0_PH4_P31
  37 VR_PVCCIN_CPU0_PH4_OCSET  OCSET @BASEBOARD_FAB2_LIB.BASEBOARD_FAB2(SCH_1):VR_PVCCIN_CPU0_PH4_OCSET
  40    GND PGND<2> @BASEBOARD_FAB2_LIB.BASEBOARD_FAB2(SCH_1):GND
   7    GND PGND<1> @BASEBOARD_FAB2_LIB.BASEBOARD_FAB2(SCH_1):GND
   5    GND PGND<0> @BASEBOARD_FAB2_LIB.BASEBOARD_FAB2(SCH_1):GND
  32 VR_PVCCIN_CPU0_PH4_PHASE  PHASE @BASEBOARD_FAB2_LIB.BASEBOARD_FAB2(SCH_1):VR_PVCCIN_CPU0_PH4_PHASE
  34 VR_PVCCIN_CPU0_PWM4    PWM @BASEBOARD_FAB2_LIB.BASEBOARD_FAB2(SCH_1):VR_PVCCIN_CPU0_PWM4
  39 VR_PVCCIN_CPU0_AIREF4  REFIN @BASEBOARD_FAB2_LIB.BASEBOARD_FAB2(SCH_1):VR_PVCCIN_CPU0_AIREF4
  10 VR_PVCCIN_CPU0_PHASE4     SW @BASEBOARD_FAB2_LIB.BASEBOARD_FAB2(SCH_1):VR_PVCCIN_CPU0_PHASE4
  36 A_TSENSE_PVCCIN_CPU0 TOUT_FLT @BASEBOARD_FAB2_LIB.BASEBOARD_FAB2(SCH_1):A_TSENSE_PVCCIN_CPU0
   3 VR_PVCCIN_CPU0_PH4_VCIN    VCC @BASEBOARD_FAB2_LIB.BASEBOARD_FAB2(SCH_1):VR_PVCCIN_CPU0_PH4_VCIN
   4 P5V_STBY   VDRV @BASEBOARD_FAB2_LIB.BASEBOARD_FAB2(SCH_1):P5V_STBY
  30 VR_FET_SW_P12V_STBY_PVCCIN_CPU0 VIN<1> @BASEBOARD_FAB2_LIB.BASEBOARD_FAB2(SCH_1):VR_FET_SW_P12V_STBY_PVCCIN_CPU0
  25 VR_FET_SW_P12V_STBY_PVCCIN_CPU0 VIN<0> @BASEBOARD_FAB2_LIB.BASEBOARD_FAB2(SCH_1):VR_FET_SW_P12V_STBY_PVCCIN_CPU0
   1 PVCCIN_CPU0    VOS @BASEBOARD_FAB2_LIB.BASEBOARD_FAB2(SCH_1):PVCCIN_CPU0

RES_0402-68.1K,1%,1/16W,EMPTY,A  I89  R4D72
   1 VR_PVCCIN_CPU0_PH3_OCSET      A @BASEBOARD_FAB2_LIB.BASEBOARD_FAB2(SCH_1):VR_PVCCIN_CPU0_PH3_OCSET
   2    GND      B @BASEBOARD_FAB2_LIB.BASEBOARD_FAB2(SCH_1):GND

RES_0402-68.1K,1%,1/16W,EMPTY,A  I91  R4D71
   1 VR_PVCCIN_CPU0_PH4_OCSET      A @BASEBOARD_FAB2_LIB.BASEBOARD_FAB2(SCH_1):VR_PVCCIN_CPU0_PH4_OCSET
   2    GND      B @BASEBOARD_FAB2_LIB.BASEBOARD_FAB2(SCH_1):GND

CAP_A_0402V-0.1UF,16V,10%,X7R,A  I93  CT40
   1 VR_PVCCIN_CPU0_AIREF4      A @BASEBOARD_FAB2_LIB.BASEBOARD_FAB2(SCH_1):VR_PVCCIN_CPU0_AIREF4
   2    GND      B @BASEBOARD_FAB2_LIB.BASEBOARD_FAB2(SCH_1):GND

CAP_A_0402V-0.1UF,16V,10%,X7R,A  I96  CT39
   1 VR_PVCCIN_CPU0_AIREF3      A @BASEBOARD_FAB2_LIB.BASEBOARD_FAB2(SCH_1):VR_PVCCIN_CPU0_AIREF3
   2    GND      B @BASEBOARD_FAB2_LIB.BASEBOARD_FAB2(SCH_1):GND

CAP_0402LF-1000PF,50V,10%,X7R,A  I99  CT37
   1 A_TSENSE_PVCCIN_CPU0      A @BASEBOARD_FAB2_LIB.BASEBOARD_FAB2(SCH_1):A_TSENSE_PVCCIN_CPU0
   2    GND      B @BASEBOARD_FAB2_LIB.BASEBOARD_FAB2(SCH_1):GND

SC2K2P50V3KX-GP_SMD-BCG6-SC2K2A  I101  CT38
   1 VR_PVCCIN_CPU0_PHASE3      1 @BASEBOARD_FAB2_LIB.BASEBOARD_FAB2(SCH_1):VR_PVCCIN_CPU0_PHASE3
   2 UNNAMED_203_3D01R5F-GP_I102_2      2 @BASEBOARD_FAB2_LIB.BASEBOARD_FAB2(SCH_1):UNNAMED_203_3D01R5F-GP_I102_2

SC2K2P50V3KX-GP_SMD-BCG6-SC2K2A  I106  CT41
   1 VR_PVCCIN_CPU0_PHASE4      1 @BASEBOARD_FAB2_LIB.BASEBOARD_FAB2(SCH_1):VR_PVCCIN_CPU0_PHASE4
   2 UNNAMED_203_3D01R5F-GP_I105_2      2 @BASEBOARD_FAB2_LIB.BASEBOARD_FAB2(SCH_1):UNNAMED_203_3D01R5F-GP_I105_2

CAP_0402LF-1000PF,50V,10%,X7R,A  I108  CT42
   1 A_TSENSE_PVCCIN_CPU0      A @BASEBOARD_FAB2_LIB.BASEBOARD_FAB2(SCH_1):A_TSENSE_PVCCIN_CPU0
   2    GND      B @BASEBOARD_FAB2_LIB.BASEBOARD_FAB2(SCH_1):GND

3D01R5F-GP_SMD-RG5-3D01R5F-GP,A  I105  RT27
   1    GND      1 @BASEBOARD_FAB2_LIB.BASEBOARD_FAB2(SCH_1):GND
   2 UNNAMED_203_3D01R5F-GP_I105_2      2 @BASEBOARD_FAB2_LIB.BASEBOARD_FAB2(SCH_1):UNNAMED_203_3D01R5F-GP_I105_2

3D01R5F-GP_SMD-RG5-3D01R5F-GP,A  I102  RT26
   1    GND      1 @BASEBOARD_FAB2_LIB.BASEBOARD_FAB2(SCH_1):GND
   2 UNNAMED_203_3D01R5F-GP_I102_2      2 @BASEBOARD_FAB2_LIB.BASEBOARD_FAB2(SCH_1):UNNAMED_203_3D01R5F-GP_I102_2

RES_0402-0.0,5%,1/16W,CHIP,G21A  I110  RT25
   1 VR_PVCCIN_CPU0_PH3_BOOT      A @BASEBOARD_FAB2_LIB.BASEBOARD_FAB2(SCH_1):VR_PVCCIN_CPU0_PH3_BOOT
   2 VR_PVCCIN_CPU0_PH3_BOOT_R      B @BASEBOARD_FAB2_LIB.BASEBOARD_FAB2(SCH_1):VR_PVCCIN_CPU0_PH3_BOOT_R

RES_0402-0.0,5%,1/16W,CHIP,G21A  I111  RT28
   1 VR_PVCCIN_CPU0_PH4_BOOT      A @BASEBOARD_FAB2_LIB.BASEBOARD_FAB2(SCH_1):VR_PVCCIN_CPU0_PH4_BOOT
   2 VR_PVCCIN_CPU0_PH4_BOOT_R      B @BASEBOARD_FAB2_LIB.BASEBOARD_FAB2(SCH_1):VR_PVCCIN_CPU0_PH4_BOOT_R


DRAWING: @BASEBOARD_FAB2_LIB.BASEBOARD_FAB2(SCH_1):PAGE202 

INDUCTOR_SM-0.12UH,IND,D92183-A  I5  L4E1
   1 VR_PVCCIN_CPU0_PHASE1    INA @BASEBOARD_FAB2_LIB.BASEBOARD_FAB2(SCH_1):VR_PVCCIN_CPU0_PHASE1
   2 PVCCIN_CPU0    INB @BASEBOARD_FAB2_LIB.BASEBOARD_FAB2(SCH_1):PVCCIN_CPU0

CAP_A_0603V-22.0UF,4V,20%,X6S,A  I9  C6R7
   1 PVCCIN_CPU0      A @BASEBOARD_FAB2_LIB.BASEBOARD_FAB2(SCH_1):PVCCIN_CPU0
   2    GND      B @BASEBOARD_FAB2_LIB.BASEBOARD_FAB2(SCH_1):GND

CAP_0402-0.22UF,16V,10%,X7R,A3A  I18  C4E5
   1 P5V_STBY      A @BASEBOARD_FAB2_LIB.BASEBOARD_FAB2(SCH_1):P5V_STBY
   2    GND      B @BASEBOARD_FAB2_LIB.BASEBOARD_FAB2(SCH_1):GND

CAP_A_0402V-1.0UF,6.3V,10%,X6SA  I19  C4E6
   1 P5V_STBY      A @BASEBOARD_FAB2_LIB.BASEBOARD_FAB2(SCH_1):P5V_STBY
   2    GND      B @BASEBOARD_FAB2_LIB.BASEBOARD_FAB2(SCH_1):GND

CAP_0402-0.220UF,16V,10%,X7R,AA  I22  C4E17
   1 VR_PVCCIN_CPU0_PH1_BOOT      A @BASEBOARD_FAB2_LIB.BASEBOARD_FAB2(SCH_1):VR_PVCCIN_CPU0_PH1_BOOT
   2 VR_PVCCIN_CPU0_PH1_PHASE      B @BASEBOARD_FAB2_LIB.BASEBOARD_FAB2(SCH_1):VR_PVCCIN_CPU0_PH1_PHASE

CAP_0402-0.22UF,16V,10%,X7R,A3A  I24  C4E27
   1 P5V_STBY      A @BASEBOARD_FAB2_LIB.BASEBOARD_FAB2(SCH_1):P5V_STBY
   2    GND      B @BASEBOARD_FAB2_LIB.BASEBOARD_FAB2(SCH_1):GND

CAP_A_0402V-1.0UF,6.3V,10%,X6SA  I25  C4E25
   1 P5V_STBY      A @BASEBOARD_FAB2_LIB.BASEBOARD_FAB2(SCH_1):P5V_STBY
   2    GND      B @BASEBOARD_FAB2_LIB.BASEBOARD_FAB2(SCH_1):GND

CAP_A_0603V-22.0UF,4V,20%,X6S,A  I27  C4E11
   1 PVCCIN_CPU0      A @BASEBOARD_FAB2_LIB.BASEBOARD_FAB2(SCH_1):PVCCIN_CPU0
   2    GND      B @BASEBOARD_FAB2_LIB.BASEBOARD_FAB2(SCH_1):GND

INDUCTOR_SM-0.12UH,IND,D92183-A  I29  L4D3
   1 VR_PVCCIN_CPU0_PHASE2    INA @BASEBOARD_FAB2_LIB.BASEBOARD_FAB2(SCH_1):VR_PVCCIN_CPU0_PHASE2
   2 PVCCIN_CPU0    INB @BASEBOARD_FAB2_LIB.BASEBOARD_FAB2(SCH_1):PVCCIN_CPU0

CAP_0402-0.220UF,16V,10%,X7R,AA  I32  C4D50
   1 VR_PVCCIN_CPU0_PH2_BOOT      A @BASEBOARD_FAB2_LIB.BASEBOARD_FAB2(SCH_1):VR_PVCCIN_CPU0_PH2_BOOT
   2 VR_PVCCIN_CPU0_PH2_PHASE      B @BASEBOARD_FAB2_LIB.BASEBOARD_FAB2(SCH_1):VR_PVCCIN_CPU0_PH2_PHASE

RES_0402-1.0,1%,1/16W,CHIP,G21A  I33  R6R2
   1 VR_PVCCIN_CPU0_PH1_VCIN      A @BASEBOARD_FAB2_LIB.BASEBOARD_FAB2(SCH_1):VR_PVCCIN_CPU0_PH1_VCIN
   2 P5V_STBY      B @BASEBOARD_FAB2_LIB.BASEBOARD_FAB2(SCH_1):P5V_STBY

CAP_0402-1.0UF,16V,10%,X6S,D97A  I34  C4E10
   1 VR_PVCCIN_CPU0_PH1_VCIN      A @BASEBOARD_FAB2_LIB.BASEBOARD_FAB2(SCH_1):VR_PVCCIN_CPU0_PH1_VCIN
   2    GND      B @BASEBOARD_FAB2_LIB.BASEBOARD_FAB2(SCH_1):GND

CAP_A_0402V-0.1UF,16V,10%,X7R,A  I35  C4E20
   1 VR_FET_SW_P12V_STBY_PVCCIN_CPU0      A @BASEBOARD_FAB2_LIB.BASEBOARD_FAB2(SCH_1):VR_FET_SW_P12V_STBY_PVCCIN_CPU0
   2    GND      B @BASEBOARD_FAB2_LIB.BASEBOARD_FAB2(SCH_1):GND

CAP_0402-1.0UF,16V,10%,X6S,D97A  I36  C4E19
   1 VR_FET_SW_P12V_STBY_PVCCIN_CPU0      A @BASEBOARD_FAB2_LIB.BASEBOARD_FAB2(SCH_1):VR_FET_SW_P12V_STBY_PVCCIN_CPU0
   2    GND      B @BASEBOARD_FAB2_LIB.BASEBOARD_FAB2(SCH_1):GND

CAP_0805-10UF,16V,10%,X6S,C953A  I37  C6R11
   1 VR_FET_SW_P12V_STBY_PVCCIN_CPU0      A @BASEBOARD_FAB2_LIB.BASEBOARD_FAB2(SCH_1):VR_FET_SW_P12V_STBY_PVCCIN_CPU0
   2    GND      B @BASEBOARD_FAB2_LIB.BASEBOARD_FAB2(SCH_1):GND

CAP_0805-10UF,16V,10%,X6S,C953A  I38  C6P13
   1 VR_FET_SW_P12V_STBY_PVCCIN_CPU0      A @BASEBOARD_FAB2_LIB.BASEBOARD_FAB2(SCH_1):VR_FET_SW_P12V_STBY_PVCCIN_CPU0
   2    GND      B @BASEBOARD_FAB2_LIB.BASEBOARD_FAB2(SCH_1):GND

RES_0402-1.0,1%,1/16W,CHIP,G21A  I39  R6R6
   1 VR_PVCCIN_CPU0_PH2_VCIN      A @BASEBOARD_FAB2_LIB.BASEBOARD_FAB2(SCH_1):VR_PVCCIN_CPU0_PH2_VCIN
   2 P5V_STBY      B @BASEBOARD_FAB2_LIB.BASEBOARD_FAB2(SCH_1):P5V_STBY

CAP_0805-10UF,16V,10%,X6S,C953A  I42  C6R13
   1 VR_FET_SW_P12V_STBY_PVCCIN_CPU0      A @BASEBOARD_FAB2_LIB.BASEBOARD_FAB2(SCH_1):VR_FET_SW_P12V_STBY_PVCCIN_CPU0
   2    GND      B @BASEBOARD_FAB2_LIB.BASEBOARD_FAB2(SCH_1):GND

CAP_0402-1.0UF,16V,10%,X6S,D97A  I45  C4E26
   1 VR_PVCCIN_CPU0_PH2_VCIN      A @BASEBOARD_FAB2_LIB.BASEBOARD_FAB2(SCH_1):VR_PVCCIN_CPU0_PH2_VCIN
   2    GND      B @BASEBOARD_FAB2_LIB.BASEBOARD_FAB2(SCH_1):GND

CAP_A_0402V-0.1UF,16V,10%,X7R,A  I46  C4D49
   1 VR_FET_SW_P12V_STBY_PVCCIN_CPU0      A @BASEBOARD_FAB2_LIB.BASEBOARD_FAB2(SCH_1):VR_FET_SW_P12V_STBY_PVCCIN_CPU0
   2    GND      B @BASEBOARD_FAB2_LIB.BASEBOARD_FAB2(SCH_1):GND

CAP_0402-1.0UF,16V,10%,X6S,D97A  I47  C4D48
   1 VR_FET_SW_P12V_STBY_PVCCIN_CPU0      A @BASEBOARD_FAB2_LIB.BASEBOARD_FAB2(SCH_1):VR_FET_SW_P12V_STBY_PVCCIN_CPU0
   2    GND      B @BASEBOARD_FAB2_LIB.BASEBOARD_FAB2(SCH_1):GND

CAP_0805-10UF,16V,10%,X6S,C953A  I48  C6R4
   1 VR_FET_SW_P12V_STBY_PVCCIN_CPU0      A @BASEBOARD_FAB2_LIB.BASEBOARD_FAB2(SCH_1):VR_FET_SW_P12V_STBY_PVCCIN_CPU0
   2    GND      B @BASEBOARD_FAB2_LIB.BASEBOARD_FAB2(SCH_1):GND

CAP_0805-10UF,16V,10%,X6S,C953A  I49  C6P22
   1 VR_FET_SW_P12V_STBY_PVCCIN_CPU0      A @BASEBOARD_FAB2_LIB.BASEBOARD_FAB2(SCH_1):VR_FET_SW_P12V_STBY_PVCCIN_CPU0
   2    GND      B @BASEBOARD_FAB2_LIB.BASEBOARD_FAB2(SCH_1):GND

CAP_0805-10UF,16V,10%,X6S,C953A  I51  C6N8
   1 VR_FET_SW_P12V_STBY_PVCCIN_CPU0      A @BASEBOARD_FAB2_LIB.BASEBOARD_FAB2(SCH_1):VR_FET_SW_P12V_STBY_PVCCIN_CPU0
   2    GND      B @BASEBOARD_FAB2_LIB.BASEBOARD_FAB2(SCH_1):GND

CAP_A_0603V-22.0UF,4V,20%,X6S,A  I61  C4E3
   1 PVCCIN_CPU0      A @BASEBOARD_FAB2_LIB.BASEBOARD_FAB2(SCH_1):PVCCIN_CPU0
   2    GND      B @BASEBOARD_FAB2_LIB.BASEBOARD_FAB2(SCH_1):GND

CAP_A_0603V-22.0UF,4V,20%,X6S,A  I62  C6P16
   1 PVCCIN_CPU0      A @BASEBOARD_FAB2_LIB.BASEBOARD_FAB2(SCH_1):PVCCIN_CPU0
   2    GND      B @BASEBOARD_FAB2_LIB.BASEBOARD_FAB2(SCH_1):GND

IR354XX_SM-IR35411,IC,H73688-0A  I63  EU4E1
  33 VR_PVCCIN_CPU0_PH1_BOOT_R  BOOST @BASEBOARD_FAB2_LIB.BASEBOARD_FAB2(SCH_1):VR_PVCCIN_CPU0_PH1_BOOT_R
  35 P5V_STBY     EN @BASEBOARD_FAB2_LIB.BASEBOARD_FAB2(SCH_1):P5V_STBY
  41 TP_PVCCIN_CPU0_PH1_GL_1  GL<1> @BASEBOARD_FAB2_LIB.BASEBOARD_FAB2(SCH_1):TP_PVCCIN_CPU0_PH1_GL_1
   6 TP_PVCCIN_CPU0_PH1_GL_0  GL<0> @BASEBOARD_FAB2_LIB.BASEBOARD_FAB2(SCH_1):TP_PVCCIN_CPU0_PH1_GL_0
  38 ISENSE_PVCCIN_CPU0_PH1_IMON   IOUT @BASEBOARD_FAB2_LIB.BASEBOARD_FAB2(SCH_1):ISENSE_PVCCIN_CPU0_PH1_IMON
   2    GND   LGND @BASEBOARD_FAB2_LIB.BASEBOARD_FAB2(SCH_1):GND
  31 NC_PVCCIN_CPU0_PH1_P31     NC @BASEBOARD_FAB2_LIB.BASEBOARD_FAB2(SCH_1):NC_PVCCIN_CPU0_PH1_P31
  37 VR_PVCCIN_CPU0_PH1_OCSET  OCSET @BASEBOARD_FAB2_LIB.BASEBOARD_FAB2(SCH_1):VR_PVCCIN_CPU0_PH1_OCSET
  40    GND PGND<2> @BASEBOARD_FAB2_LIB.BASEBOARD_FAB2(SCH_1):GND
   7    GND PGND<1> @BASEBOARD_FAB2_LIB.BASEBOARD_FAB2(SCH_1):GND
   5    GND PGND<0> @BASEBOARD_FAB2_LIB.BASEBOARD_FAB2(SCH_1):GND
  32 VR_PVCCIN_CPU0_PH1_PHASE  PHASE @BASEBOARD_FAB2_LIB.BASEBOARD_FAB2(SCH_1):VR_PVCCIN_CPU0_PH1_PHASE
  34 VR_PVCCIN_CPU0_PWM1    PWM @BASEBOARD_FAB2_LIB.BASEBOARD_FAB2(SCH_1):VR_PVCCIN_CPU0_PWM1
  39 VR_PVCCIN_CPU0_AIREF1  REFIN @BASEBOARD_FAB2_LIB.BASEBOARD_FAB2(SCH_1):VR_PVCCIN_CPU0_AIREF1
  10 VR_PVCCIN_CPU0_PHASE1     SW @BASEBOARD_FAB2_LIB.BASEBOARD_FAB2(SCH_1):VR_PVCCIN_CPU0_PHASE1
  36 A_TSENSE_PVCCIN_CPU0 TOUT_FLT @BASEBOARD_FAB2_LIB.BASEBOARD_FAB2(SCH_1):A_TSENSE_PVCCIN_CPU0
   3 VR_PVCCIN_CPU0_PH1_VCIN    VCC @BASEBOARD_FAB2_LIB.BASEBOARD_FAB2(SCH_1):VR_PVCCIN_CPU0_PH1_VCIN
   4 P5V_STBY   VDRV @BASEBOARD_FAB2_LIB.BASEBOARD_FAB2(SCH_1):P5V_STBY
  30 VR_FET_SW_P12V_STBY_PVCCIN_CPU0 VIN<1> @BASEBOARD_FAB2_LIB.BASEBOARD_FAB2(SCH_1):VR_FET_SW_P12V_STBY_PVCCIN_CPU0
  25 VR_FET_SW_P12V_STBY_PVCCIN_CPU0 VIN<0> @BASEBOARD_FAB2_LIB.BASEBOARD_FAB2(SCH_1):VR_FET_SW_P12V_STBY_PVCCIN_CPU0
   1 PVCCIN_CPU0    VOS @BASEBOARD_FAB2_LIB.BASEBOARD_FAB2(SCH_1):PVCCIN_CPU0

IR354XX_SM-IR35411,IC,H73688-0A  I64  EU4D6
  33 VR_PVCCIN_CPU0_PH2_BOOT_R  BOOST @BASEBOARD_FAB2_LIB.BASEBOARD_FAB2(SCH_1):VR_PVCCIN_CPU0_PH2_BOOT_R
  35 P5V_STBY     EN @BASEBOARD_FAB2_LIB.BASEBOARD_FAB2(SCH_1):P5V_STBY
  41 TP_PVCCIN_CPU0_PH2_GL_1  GL<1> @BASEBOARD_FAB2_LIB.BASEBOARD_FAB2(SCH_1):TP_PVCCIN_CPU0_PH2_GL_1
   6 TP_PVCCIN_CPU0_PH2_GL_0  GL<0> @BASEBOARD_FAB2_LIB.BASEBOARD_FAB2(SCH_1):TP_PVCCIN_CPU0_PH2_GL_0
  38 ISENSE_PVCCIN_CPU0_PH2_IMON   IOUT @BASEBOARD_FAB2_LIB.BASEBOARD_FAB2(SCH_1):ISENSE_PVCCIN_CPU0_PH2_IMON
   2    GND   LGND @BASEBOARD_FAB2_LIB.BASEBOARD_FAB2(SCH_1):GND
  31 NC_PVCCIN_CPU0_PH2_P31     NC @BASEBOARD_FAB2_LIB.BASEBOARD_FAB2(SCH_1):NC_PVCCIN_CPU0_PH2_P31
  37 VR_PVCCIN_CPU0_PH2_OCSET  OCSET @BASEBOARD_FAB2_LIB.BASEBOARD_FAB2(SCH_1):VR_PVCCIN_CPU0_PH2_OCSET
  40    GND PGND<2> @BASEBOARD_FAB2_LIB.BASEBOARD_FAB2(SCH_1):GND
   7    GND PGND<1> @BASEBOARD_FAB2_LIB.BASEBOARD_FAB2(SCH_1):GND
   5    GND PGND<0> @BASEBOARD_FAB2_LIB.BASEBOARD_FAB2(SCH_1):GND
  32 VR_PVCCIN_CPU0_PH2_PHASE  PHASE @BASEBOARD_FAB2_LIB.BASEBOARD_FAB2(SCH_1):VR_PVCCIN_CPU0_PH2_PHASE
  34 VR_PVCCIN_CPU0_PWM2    PWM @BASEBOARD_FAB2_LIB.BASEBOARD_FAB2(SCH_1):VR_PVCCIN_CPU0_PWM2
  39 VR_PVCCIN_CPU0_AIREF2  REFIN @BASEBOARD_FAB2_LIB.BASEBOARD_FAB2(SCH_1):VR_PVCCIN_CPU0_AIREF2
  10 VR_PVCCIN_CPU0_PHASE2     SW @BASEBOARD_FAB2_LIB.BASEBOARD_FAB2(SCH_1):VR_PVCCIN_CPU0_PHASE2
  36 A_TSENSE_PVCCIN_CPU0 TOUT_FLT @BASEBOARD_FAB2_LIB.BASEBOARD_FAB2(SCH_1):A_TSENSE_PVCCIN_CPU0
   3 VR_PVCCIN_CPU0_PH2_VCIN    VCC @BASEBOARD_FAB2_LIB.BASEBOARD_FAB2(SCH_1):VR_PVCCIN_CPU0_PH2_VCIN
   4 P5V_STBY   VDRV @BASEBOARD_FAB2_LIB.BASEBOARD_FAB2(SCH_1):P5V_STBY
  30 VR_FET_SW_P12V_STBY_PVCCIN_CPU0 VIN<1> @BASEBOARD_FAB2_LIB.BASEBOARD_FAB2(SCH_1):VR_FET_SW_P12V_STBY_PVCCIN_CPU0
  25 VR_FET_SW_P12V_STBY_PVCCIN_CPU0 VIN<0> @BASEBOARD_FAB2_LIB.BASEBOARD_FAB2(SCH_1):VR_FET_SW_P12V_STBY_PVCCIN_CPU0
   1 PVCCIN_CPU0    VOS @BASEBOARD_FAB2_LIB.BASEBOARD_FAB2(SCH_1):PVCCIN_CPU0

RES_0402-68.1K,1%,1/16W,EMPTY,A  I65  R4E22
   1 VR_PVCCIN_CPU0_PH1_OCSET      A @BASEBOARD_FAB2_LIB.BASEBOARD_FAB2(SCH_1):VR_PVCCIN_CPU0_PH1_OCSET
   2    GND      B @BASEBOARD_FAB2_LIB.BASEBOARD_FAB2(SCH_1):GND

RES_0402-68.1K,1%,1/16W,EMPTY,A  I67  R4E19
   1 VR_PVCCIN_CPU0_PH2_OCSET      A @BASEBOARD_FAB2_LIB.BASEBOARD_FAB2(SCH_1):VR_PVCCIN_CPU0_PH2_OCSET
   2    GND      B @BASEBOARD_FAB2_LIB.BASEBOARD_FAB2(SCH_1):GND

CAP_A_0402V-0.1UF,16V,10%,X7R,A  I70  CT1
   1 VR_PVCCIN_CPU0_AIREF1      A @BASEBOARD_FAB2_LIB.BASEBOARD_FAB2(SCH_1):VR_PVCCIN_CPU0_AIREF1
   2    GND      B @BASEBOARD_FAB2_LIB.BASEBOARD_FAB2(SCH_1):GND

SC2K2P50V3KX-GP_SMD-BCG6-SC2K2A  I76  CT3
   1 VR_PVCCIN_CPU0_PHASE1      1 @BASEBOARD_FAB2_LIB.BASEBOARD_FAB2(SCH_1):VR_PVCCIN_CPU0_PHASE1
   2 UNNAMED_202_3D01R5F-GP_I75_2      2 @BASEBOARD_FAB2_LIB.BASEBOARD_FAB2(SCH_1):UNNAMED_202_3D01R5F-GP_I75_2

CAP_0402LF-1000PF,50V,10%,X7R,A  I78  CT2
   1 A_TSENSE_PVCCIN_CPU0      A @BASEBOARD_FAB2_LIB.BASEBOARD_FAB2(SCH_1):A_TSENSE_PVCCIN_CPU0
   2    GND      B @BASEBOARD_FAB2_LIB.BASEBOARD_FAB2(SCH_1):GND

CAP_A_0402V-0.1UF,16V,10%,X7R,A  I81  CT6
   1 VR_PVCCIN_CPU0_AIREF2      A @BASEBOARD_FAB2_LIB.BASEBOARD_FAB2(SCH_1):VR_PVCCIN_CPU0_AIREF2
   2    GND      B @BASEBOARD_FAB2_LIB.BASEBOARD_FAB2(SCH_1):GND

SC2K2P50V3KX-GP_SMD-BCG6-SC2K2A  I82  CT5
   1 VR_PVCCIN_CPU0_PHASE2      1 @BASEBOARD_FAB2_LIB.BASEBOARD_FAB2(SCH_1):VR_PVCCIN_CPU0_PHASE2
   2 UNNAMED_202_3D01R5F-GP_I83_2      2 @BASEBOARD_FAB2_LIB.BASEBOARD_FAB2(SCH_1):UNNAMED_202_3D01R5F-GP_I83_2

3D01R5F-GP_SMD-RG5-3D01R5F-GP,A  I83  RT4
   1    GND      1 @BASEBOARD_FAB2_LIB.BASEBOARD_FAB2(SCH_1):GND
   2 UNNAMED_202_3D01R5F-GP_I83_2      2 @BASEBOARD_FAB2_LIB.BASEBOARD_FAB2(SCH_1):UNNAMED_202_3D01R5F-GP_I83_2

3D01R5F-GP_SMD-RG5-3D01R5F-GP,A  I75  RT2
   1    GND      1 @BASEBOARD_FAB2_LIB.BASEBOARD_FAB2(SCH_1):GND
   2 UNNAMED_202_3D01R5F-GP_I75_2      2 @BASEBOARD_FAB2_LIB.BASEBOARD_FAB2(SCH_1):UNNAMED_202_3D01R5F-GP_I75_2

CAP_0402LF-1000PF,50V,10%,X7R,A  I87  CT4
   1 A_TSENSE_PVCCIN_CPU0      A @BASEBOARD_FAB2_LIB.BASEBOARD_FAB2(SCH_1):A_TSENSE_PVCCIN_CPU0
   2    GND      B @BASEBOARD_FAB2_LIB.BASEBOARD_FAB2(SCH_1):GND

RES_0402-0.0,5%,1/16W,CHIP,G21A  I88  RT1
   1 VR_PVCCIN_CPU0_PH1_BOOT      A @BASEBOARD_FAB2_LIB.BASEBOARD_FAB2(SCH_1):VR_PVCCIN_CPU0_PH1_BOOT
   2 VR_PVCCIN_CPU0_PH1_BOOT_R      B @BASEBOARD_FAB2_LIB.BASEBOARD_FAB2(SCH_1):VR_PVCCIN_CPU0_PH1_BOOT_R

RES_0402-0.0,5%,1/16W,CHIP,G21A  I89  RT3
   1 VR_PVCCIN_CPU0_PH2_BOOT      A @BASEBOARD_FAB2_LIB.BASEBOARD_FAB2(SCH_1):VR_PVCCIN_CPU0_PH2_BOOT
   2 VR_PVCCIN_CPU0_PH2_BOOT_R      B @BASEBOARD_FAB2_LIB.BASEBOARD_FAB2(SCH_1):VR_PVCCIN_CPU0_PH2_BOOT_R


DRAWING: @BASEBOARD_FAB2_LIB.BASEBOARD_FAB2(SCH_1):PAGE219 

CAP_0402-0.220UF,16V,10%,X7R,AA  I44  C7A12
   1 VR_PVDDQ_DEF_PH1_BOOT      A @BASEBOARD_FAB2_LIB.BASEBOARD_FAB2(SCH_1):VR_PVDDQ_DEF_PH1_BOOT
   2 VR_PVDDQ_DEF_PH1_PHASE      B @BASEBOARD_FAB2_LIB.BASEBOARD_FAB2(SCH_1):VR_PVDDQ_DEF_PH1_PHASE

CAP_0805-10UF,16V,10%,X6S,C953A  I45  C3L2
   1 VR_FET_SW_P12V_STBY_PVDDQ_DEF      A @BASEBOARD_FAB2_LIB.BASEBOARD_FAB2(SCH_1):VR_FET_SW_P12V_STBY_PVDDQ_DEF
   2    GND      B @BASEBOARD_FAB2_LIB.BASEBOARD_FAB2(SCH_1):GND

CAP_0805-10UF,16V,10%,X6S,C953A  I46  C3L4
   1 VR_FET_SW_P12V_STBY_PVDDQ_DEF      A @BASEBOARD_FAB2_LIB.BASEBOARD_FAB2(SCH_1):VR_FET_SW_P12V_STBY_PVDDQ_DEF
   2    GND      B @BASEBOARD_FAB2_LIB.BASEBOARD_FAB2(SCH_1):GND

CAP_0805-10UF,16V,10%,X6S,C953A  I47  C3L13
   1 VR_FET_SW_P12V_STBY_PVDDQ_DEF      A @BASEBOARD_FAB2_LIB.BASEBOARD_FAB2(SCH_1):VR_FET_SW_P12V_STBY_PVDDQ_DEF
   2    GND      B @BASEBOARD_FAB2_LIB.BASEBOARD_FAB2(SCH_1):GND

CAP_0402-1.0UF,16V,10%,X6S,D97A  I48  C7A11
   1 VR_FET_SW_P12V_STBY_PVDDQ_DEF      A @BASEBOARD_FAB2_LIB.BASEBOARD_FAB2(SCH_1):VR_FET_SW_P12V_STBY_PVDDQ_DEF
   2    GND      B @BASEBOARD_FAB2_LIB.BASEBOARD_FAB2(SCH_1):GND

CAP_0402-1.0UF,16V,10%,X6S,D97A  I50  C7A16
   1 VR_PVDDQ_DEF_PH1_VCIN      A @BASEBOARD_FAB2_LIB.BASEBOARD_FAB2(SCH_1):VR_PVDDQ_DEF_PH1_VCIN
   2    GND      B @BASEBOARD_FAB2_LIB.BASEBOARD_FAB2(SCH_1):GND

CAP_A_0402V-0.1UF,16V,10%,X7R,A  I51  C7A5
   1 VR_FET_SW_P12V_STBY_PVDDQ_DEF      A @BASEBOARD_FAB2_LIB.BASEBOARD_FAB2(SCH_1):VR_FET_SW_P12V_STBY_PVDDQ_DEF
   2    GND      B @BASEBOARD_FAB2_LIB.BASEBOARD_FAB2(SCH_1):GND

RES_0402-1.0,1%,1/16W,CHIP,G21A  I52  R3L6
   1 VR_PVDDQ_DEF_PH1_VCIN      A @BASEBOARD_FAB2_LIB.BASEBOARD_FAB2(SCH_1):VR_PVDDQ_DEF_PH1_VCIN
   2 P5V_STBY      B @BASEBOARD_FAB2_LIB.BASEBOARD_FAB2(SCH_1):P5V_STBY

CAP_A_0402V-1.0UF,6.3V,10%,X6SA  I53  C7A18
   1 P5V_STBY      A @BASEBOARD_FAB2_LIB.BASEBOARD_FAB2(SCH_1):P5V_STBY
   2    GND      B @BASEBOARD_FAB2_LIB.BASEBOARD_FAB2(SCH_1):GND

CAP_0402-0.22UF,16V,10%,X7R,A3A  I54  C7A17
   1 P5V_STBY      A @BASEBOARD_FAB2_LIB.BASEBOARD_FAB2(SCH_1):P5V_STBY
   2    GND      B @BASEBOARD_FAB2_LIB.BASEBOARD_FAB2(SCH_1):GND

INDUCTOR_SM-0.12UH,IND,D92183-A  I55  L7A1
   1 VR_PVDDQ_DEF_PH1_SW    INA @BASEBOARD_FAB2_LIB.BASEBOARD_FAB2(SCH_1):VR_PVDDQ_DEF_PH1_SW
   2 PVDDQ_DEF    INB @BASEBOARD_FAB2_LIB.BASEBOARD_FAB2(SCH_1):PVDDQ_DEF

INDUCTOR_SM-0.12UH,IND,D92183-A  I65  L7A3
   1 VR_PVDDQ_DEF_PH2_SW    INA @BASEBOARD_FAB2_LIB.BASEBOARD_FAB2(SCH_1):VR_PVDDQ_DEF_PH2_SW
   2 PVDDQ_DEF    INB @BASEBOARD_FAB2_LIB.BASEBOARD_FAB2(SCH_1):PVDDQ_DEF

CAP_0805LF-22UF,4V,20%,X6S,C95A  I68  C6A4
   1 PVDDQ_DEF      A @BASEBOARD_FAB2_LIB.BASEBOARD_FAB2(SCH_1):PVDDQ_DEF
   2    GND      B @BASEBOARD_FAB2_LIB.BASEBOARD_FAB2(SCH_1):GND

CAP_0402-0.22UF,16V,10%,X7R,A3A  I72  C7A25
   1 P5V_STBY      A @BASEBOARD_FAB2_LIB.BASEBOARD_FAB2(SCH_1):P5V_STBY
   2    GND      B @BASEBOARD_FAB2_LIB.BASEBOARD_FAB2(SCH_1):GND

CAP_A_0402V-1.0UF,6.3V,10%,X6SA  I73  C7A26
   1 P5V_STBY      A @BASEBOARD_FAB2_LIB.BASEBOARD_FAB2(SCH_1):P5V_STBY
   2    GND      B @BASEBOARD_FAB2_LIB.BASEBOARD_FAB2(SCH_1):GND

CAP_0402-0.220UF,16V,10%,X7R,AA  I75  C7A22
   1 VR_PVDDQ_DEF_PH2_BOOT      A @BASEBOARD_FAB2_LIB.BASEBOARD_FAB2(SCH_1):VR_PVDDQ_DEF_PH2_BOOT
   2 VR_PVDDQ_DEF_PH2_PHASE      B @BASEBOARD_FAB2_LIB.BASEBOARD_FAB2(SCH_1):VR_PVDDQ_DEF_PH2_PHASE

RES_0402-1.0,1%,1/16W,CHIP,G21A  I76  R3L8
   1 VR_PVDDQ_DEF_PH2_VCIN      A @BASEBOARD_FAB2_LIB.BASEBOARD_FAB2(SCH_1):VR_PVDDQ_DEF_PH2_VCIN
   2 P5V_STBY      B @BASEBOARD_FAB2_LIB.BASEBOARD_FAB2(SCH_1):P5V_STBY

CAP_0402-1.0UF,16V,10%,X6S,D97A  I77  C7A24
   1 VR_PVDDQ_DEF_PH2_VCIN      A @BASEBOARD_FAB2_LIB.BASEBOARD_FAB2(SCH_1):VR_PVDDQ_DEF_PH2_VCIN
   2    GND      B @BASEBOARD_FAB2_LIB.BASEBOARD_FAB2(SCH_1):GND

CAP_A_0402V-0.1UF,16V,10%,X7R,A  I78  C7A20
   1 VR_FET_SW_P12V_STBY_PVDDQ_DEF      A @BASEBOARD_FAB2_LIB.BASEBOARD_FAB2(SCH_1):VR_FET_SW_P12V_STBY_PVDDQ_DEF
   2    GND      B @BASEBOARD_FAB2_LIB.BASEBOARD_FAB2(SCH_1):GND

CAP_0402-1.0UF,16V,10%,X6S,D97A  I79  C7A21
   1 VR_FET_SW_P12V_STBY_PVDDQ_DEF      A @BASEBOARD_FAB2_LIB.BASEBOARD_FAB2(SCH_1):VR_FET_SW_P12V_STBY_PVDDQ_DEF
   2    GND      B @BASEBOARD_FAB2_LIB.BASEBOARD_FAB2(SCH_1):GND

CAP_0805-10UF,16V,10%,X6S,C953A  I80  C3L17
   1 VR_FET_SW_P12V_STBY_PVDDQ_DEF      A @BASEBOARD_FAB2_LIB.BASEBOARD_FAB2(SCH_1):VR_FET_SW_P12V_STBY_PVDDQ_DEF
   2    GND      B @BASEBOARD_FAB2_LIB.BASEBOARD_FAB2(SCH_1):GND

CAP_0805-10UF,16V,10%,X6S,C953A  I81  C3L16
   1 VR_FET_SW_P12V_STBY_PVDDQ_DEF      A @BASEBOARD_FAB2_LIB.BASEBOARD_FAB2(SCH_1):VR_FET_SW_P12V_STBY_PVDDQ_DEF
   2    GND      B @BASEBOARD_FAB2_LIB.BASEBOARD_FAB2(SCH_1):GND

CAP_0805-10UF,16V,10%,X6S,C953A  I84  C3L15
   1 VR_FET_SW_P12V_STBY_PVDDQ_DEF      A @BASEBOARD_FAB2_LIB.BASEBOARD_FAB2(SCH_1):VR_FET_SW_P12V_STBY_PVDDQ_DEF
   2    GND      B @BASEBOARD_FAB2_LIB.BASEBOARD_FAB2(SCH_1):GND

CAP_0805LF-22UF,4V,20%,X6S,C95A  I87  C6A1
   1 PVDDQ_DEF      A @BASEBOARD_FAB2_LIB.BASEBOARD_FAB2(SCH_1):PVDDQ_DEF
   2    GND      B @BASEBOARD_FAB2_LIB.BASEBOARD_FAB2(SCH_1):GND

IR354XX_SM-IR35411,IC,H73688-0A  I106  EU7A1
  33 VR_PVDDQ_DEF_PH1_BOOT_R  BOOST @BASEBOARD_FAB2_LIB.BASEBOARD_FAB2(SCH_1):VR_PVDDQ_DEF_PH1_BOOT_R
  35 P5V_STBY     EN @BASEBOARD_FAB2_LIB.BASEBOARD_FAB2(SCH_1):P5V_STBY
  41 TP_PVDDQ_DEF_PH1_GL_1  GL<1> @BASEBOARD_FAB2_LIB.BASEBOARD_FAB2(SCH_1):TP_PVDDQ_DEF_PH1_GL_1
   6 TP_PVDDQ_DEF_PH1_GL_0  GL<0> @BASEBOARD_FAB2_LIB.BASEBOARD_FAB2(SCH_1):TP_PVDDQ_DEF_PH1_GL_0
  38 ISENSE_PVDDQ_DEF_PH1_IMON   IOUT @BASEBOARD_FAB2_LIB.BASEBOARD_FAB2(SCH_1):ISENSE_PVDDQ_DEF_PH1_IMON
   2    GND   LGND @BASEBOARD_FAB2_LIB.BASEBOARD_FAB2(SCH_1):GND
  31 NC_PVDDQ_DEF_PH1_P31     NC @BASEBOARD_FAB2_LIB.BASEBOARD_FAB2(SCH_1):NC_PVDDQ_DEF_PH1_P31
  37 VR_PVDDQ_DEF_PH1_OCSET  OCSET @BASEBOARD_FAB2_LIB.BASEBOARD_FAB2(SCH_1):VR_PVDDQ_DEF_PH1_OCSET
  40    GND PGND<2> @BASEBOARD_FAB2_LIB.BASEBOARD_FAB2(SCH_1):GND
   7    GND PGND<1> @BASEBOARD_FAB2_LIB.BASEBOARD_FAB2(SCH_1):GND
   5    GND PGND<0> @BASEBOARD_FAB2_LIB.BASEBOARD_FAB2(SCH_1):GND
  32 VR_PVDDQ_DEF_PH1_PHASE  PHASE @BASEBOARD_FAB2_LIB.BASEBOARD_FAB2(SCH_1):VR_PVDDQ_DEF_PH1_PHASE
  34 VR_PVDDQ_DEF_PWM1    PWM @BASEBOARD_FAB2_LIB.BASEBOARD_FAB2(SCH_1):VR_PVDDQ_DEF_PWM1
  39 VR_PVDDQ_DEF_AIREF1  REFIN @BASEBOARD_FAB2_LIB.BASEBOARD_FAB2(SCH_1):VR_PVDDQ_DEF_AIREF1
  10 VR_PVDDQ_DEF_PH1_SW     SW @BASEBOARD_FAB2_LIB.BASEBOARD_FAB2(SCH_1):VR_PVDDQ_DEF_PH1_SW
  36 A_TSENSE_PVDDQ_DEF TOUT_FLT @BASEBOARD_FAB2_LIB.BASEBOARD_FAB2(SCH_1):A_TSENSE_PVDDQ_DEF
   3 VR_PVDDQ_DEF_PH1_VCIN    VCC @BASEBOARD_FAB2_LIB.BASEBOARD_FAB2(SCH_1):VR_PVDDQ_DEF_PH1_VCIN
   4 P5V_STBY   VDRV @BASEBOARD_FAB2_LIB.BASEBOARD_FAB2(SCH_1):P5V_STBY
  30 VR_FET_SW_P12V_STBY_PVDDQ_DEF VIN<1> @BASEBOARD_FAB2_LIB.BASEBOARD_FAB2(SCH_1):VR_FET_SW_P12V_STBY_PVDDQ_DEF
  25 VR_FET_SW_P12V_STBY_PVDDQ_DEF VIN<0> @BASEBOARD_FAB2_LIB.BASEBOARD_FAB2(SCH_1):VR_FET_SW_P12V_STBY_PVDDQ_DEF
   1 PVDDQ_DEF    VOS @BASEBOARD_FAB2_LIB.BASEBOARD_FAB2(SCH_1):PVDDQ_DEF

IR354XX_SM-IR35411,IC,H73688-0A  I107  EU7A4
  33 VR_PVDDQ_DEF_PH2_BOOT_R  BOOST @BASEBOARD_FAB2_LIB.BASEBOARD_FAB2(SCH_1):VR_PVDDQ_DEF_PH2_BOOT_R
  35 P5V_STBY     EN @BASEBOARD_FAB2_LIB.BASEBOARD_FAB2(SCH_1):P5V_STBY
  41 TP_PVDDQ_DEF_PH2_GL_1  GL<1> @BASEBOARD_FAB2_LIB.BASEBOARD_FAB2(SCH_1):TP_PVDDQ_DEF_PH2_GL_1
   6 TP_PVDDQ_DEF_PH2_GL_0  GL<0> @BASEBOARD_FAB2_LIB.BASEBOARD_FAB2(SCH_1):TP_PVDDQ_DEF_PH2_GL_0
  38 ISENSE_PVDDQ_DEF_PH2_IMON   IOUT @BASEBOARD_FAB2_LIB.BASEBOARD_FAB2(SCH_1):ISENSE_PVDDQ_DEF_PH2_IMON
   2    GND   LGND @BASEBOARD_FAB2_LIB.BASEBOARD_FAB2(SCH_1):GND
  31 NC_PVDDQ_DEF_PH2_P31     NC @BASEBOARD_FAB2_LIB.BASEBOARD_FAB2(SCH_1):NC_PVDDQ_DEF_PH2_P31
  37 VR_PVDDQ_DEF_PH2_OCSET  OCSET @BASEBOARD_FAB2_LIB.BASEBOARD_FAB2(SCH_1):VR_PVDDQ_DEF_PH2_OCSET
  40    GND PGND<2> @BASEBOARD_FAB2_LIB.BASEBOARD_FAB2(SCH_1):GND
   7    GND PGND<1> @BASEBOARD_FAB2_LIB.BASEBOARD_FAB2(SCH_1):GND
   5    GND PGND<0> @BASEBOARD_FAB2_LIB.BASEBOARD_FAB2(SCH_1):GND
  32 VR_PVDDQ_DEF_PH2_PHASE  PHASE @BASEBOARD_FAB2_LIB.BASEBOARD_FAB2(SCH_1):VR_PVDDQ_DEF_PH2_PHASE
  34 VR_PVDDQ_DEF_PWM2    PWM @BASEBOARD_FAB2_LIB.BASEBOARD_FAB2(SCH_1):VR_PVDDQ_DEF_PWM2
  39 VR_PVDDQ_DEF_AIREF2  REFIN @BASEBOARD_FAB2_LIB.BASEBOARD_FAB2(SCH_1):VR_PVDDQ_DEF_AIREF2
  10 VR_PVDDQ_DEF_PH2_SW     SW @BASEBOARD_FAB2_LIB.BASEBOARD_FAB2(SCH_1):VR_PVDDQ_DEF_PH2_SW
  36 A_TSENSE_PVDDQ_DEF TOUT_FLT @BASEBOARD_FAB2_LIB.BASEBOARD_FAB2(SCH_1):A_TSENSE_PVDDQ_DEF
   3 VR_PVDDQ_DEF_PH2_VCIN    VCC @BASEBOARD_FAB2_LIB.BASEBOARD_FAB2(SCH_1):VR_PVDDQ_DEF_PH2_VCIN
   4 P5V_STBY   VDRV @BASEBOARD_FAB2_LIB.BASEBOARD_FAB2(SCH_1):P5V_STBY
  30 VR_FET_SW_P12V_STBY_PVDDQ_DEF VIN<1> @BASEBOARD_FAB2_LIB.BASEBOARD_FAB2(SCH_1):VR_FET_SW_P12V_STBY_PVDDQ_DEF
  25 VR_FET_SW_P12V_STBY_PVDDQ_DEF VIN<0> @BASEBOARD_FAB2_LIB.BASEBOARD_FAB2(SCH_1):VR_FET_SW_P12V_STBY_PVDDQ_DEF
   1 PVDDQ_DEF    VOS @BASEBOARD_FAB2_LIB.BASEBOARD_FAB2(SCH_1):PVDDQ_DEF

RES_0402-68.1K,1%,1/16W,EMPTY,A  I108  R7A20
   1 VR_PVDDQ_DEF_PH1_OCSET      A @BASEBOARD_FAB2_LIB.BASEBOARD_FAB2(SCH_1):VR_PVDDQ_DEF_PH1_OCSET
   2    GND      B @BASEBOARD_FAB2_LIB.BASEBOARD_FAB2(SCH_1):GND

RES_0402-68.1K,1%,1/16W,EMPTY,A  I110  R7A21
   1 VR_PVDDQ_DEF_PH2_OCSET      A @BASEBOARD_FAB2_LIB.BASEBOARD_FAB2(SCH_1):VR_PVDDQ_DEF_PH2_OCSET
   2    GND      B @BASEBOARD_FAB2_LIB.BASEBOARD_FAB2(SCH_1):GND

CAP_A_0402V-0.1UF,16V,10%,X7R,A  I113  CT46
   1 VR_PVDDQ_DEF_AIREF2      A @BASEBOARD_FAB2_LIB.BASEBOARD_FAB2(SCH_1):VR_PVDDQ_DEF_AIREF2
   2    GND      B @BASEBOARD_FAB2_LIB.BASEBOARD_FAB2(SCH_1):GND

CAP_A_0402V-0.1UF,16V,10%,X7R,A  I116  CT45
   1 VR_PVDDQ_DEF_AIREF1      A @BASEBOARD_FAB2_LIB.BASEBOARD_FAB2(SCH_1):VR_PVDDQ_DEF_AIREF1
   2    GND      B @BASEBOARD_FAB2_LIB.BASEBOARD_FAB2(SCH_1):GND

CAP_0402LF-1000PF,50V,10%,X7R,A  I119  CT48
   1 A_TSENSE_PVDDQ_DEF      A @BASEBOARD_FAB2_LIB.BASEBOARD_FAB2(SCH_1):A_TSENSE_PVDDQ_DEF
   2    GND      B @BASEBOARD_FAB2_LIB.BASEBOARD_FAB2(SCH_1):GND

SC2K2P50V3KX-GP_SMD-BCG6-SC2K2A  I121  CT47
   1 VR_PVDDQ_DEF_PH2_SW      1 @BASEBOARD_FAB2_LIB.BASEBOARD_FAB2(SCH_1):VR_PVDDQ_DEF_PH2_SW
   2 UNNAMED_219_3D01R5F-GP_I123_2      2 @BASEBOARD_FAB2_LIB.BASEBOARD_FAB2(SCH_1):UNNAMED_219_3D01R5F-GP_I123_2

CAP_0402LF-1000PF,50V,10%,X7R,A  I124  CT43
   1 A_TSENSE_PVDDQ_DEF      A @BASEBOARD_FAB2_LIB.BASEBOARD_FAB2(SCH_1):A_TSENSE_PVDDQ_DEF
   2    GND      B @BASEBOARD_FAB2_LIB.BASEBOARD_FAB2(SCH_1):GND

SC2K2P50V3KX-GP_SMD-BCG6-SC2K2A  I127  CT44
   1 VR_PVDDQ_DEF_PH1_SW      1 @BASEBOARD_FAB2_LIB.BASEBOARD_FAB2(SCH_1):VR_PVDDQ_DEF_PH1_SW
   2 UNNAMED_219_3D01R5F-GP_I126_2      2 @BASEBOARD_FAB2_LIB.BASEBOARD_FAB2(SCH_1):UNNAMED_219_3D01R5F-GP_I126_2

3D01R5F-GP_SMD-RG5-3D01R5F-GP,A  I126  RT29
   1    GND      1 @BASEBOARD_FAB2_LIB.BASEBOARD_FAB2(SCH_1):GND
   2 UNNAMED_219_3D01R5F-GP_I126_2      2 @BASEBOARD_FAB2_LIB.BASEBOARD_FAB2(SCH_1):UNNAMED_219_3D01R5F-GP_I126_2

3D01R5F-GP_SMD-RG5-3D01R5F-GP,A  I123  RT32
   1    GND      1 @BASEBOARD_FAB2_LIB.BASEBOARD_FAB2(SCH_1):GND
   2 UNNAMED_219_3D01R5F-GP_I123_2      2 @BASEBOARD_FAB2_LIB.BASEBOARD_FAB2(SCH_1):UNNAMED_219_3D01R5F-GP_I123_2

RES_0402-0.0,5%,1/16W,CHIP,G21A  I129  RT30
   1 VR_PVDDQ_DEF_PH1_BOOT      A @BASEBOARD_FAB2_LIB.BASEBOARD_FAB2(SCH_1):VR_PVDDQ_DEF_PH1_BOOT
   2 VR_PVDDQ_DEF_PH1_BOOT_R      B @BASEBOARD_FAB2_LIB.BASEBOARD_FAB2(SCH_1):VR_PVDDQ_DEF_PH1_BOOT_R

RES_0402-0.0,5%,1/16W,CHIP,G21A  I130  RT31
   1 VR_PVDDQ_DEF_PH2_BOOT      A @BASEBOARD_FAB2_LIB.BASEBOARD_FAB2(SCH_1):VR_PVDDQ_DEF_PH2_BOOT
   2 VR_PVDDQ_DEF_PH2_BOOT_R      B @BASEBOARD_FAB2_LIB.BASEBOARD_FAB2(SCH_1):VR_PVDDQ_DEF_PH2_BOOT_R


DRAWING: @BASEBOARD_FAB2_LIB.BASEBOARD_FAB2(SCH_1):PAGE216 

CAP_0805LF-22UF,4V,20%,X6S,C95A  I6  C6G3
   1 PVDDQ_ABC      A @BASEBOARD_FAB2_LIB.BASEBOARD_FAB2(SCH_1):PVDDQ_ABC
   2    GND      B @BASEBOARD_FAB2_LIB.BASEBOARD_FAB2(SCH_1):GND

CAP_0402-0.220UF,16V,10%,X7R,AA  I44  C7G31
   1 VR_PVDDQ_ABC_PH1_BOOT      A @BASEBOARD_FAB2_LIB.BASEBOARD_FAB2(SCH_1):VR_PVDDQ_ABC_PH1_BOOT
   2 VR_PVDDQ_ABC_PH1_PHASE      B @BASEBOARD_FAB2_LIB.BASEBOARD_FAB2(SCH_1):VR_PVDDQ_ABC_PH1_PHASE

CAP_0805-10UF,16V,10%,X6S,C953A  I45  C3U2
   1 VR_FET_SW_P12V_STBY_PVDDQ_ABC      A @BASEBOARD_FAB2_LIB.BASEBOARD_FAB2(SCH_1):VR_FET_SW_P12V_STBY_PVDDQ_ABC
   2    GND      B @BASEBOARD_FAB2_LIB.BASEBOARD_FAB2(SCH_1):GND

CAP_0805-10UF,16V,10%,X6S,C953A  I46  C3U3
   1 VR_FET_SW_P12V_STBY_PVDDQ_ABC      A @BASEBOARD_FAB2_LIB.BASEBOARD_FAB2(SCH_1):VR_FET_SW_P12V_STBY_PVDDQ_ABC
   2    GND      B @BASEBOARD_FAB2_LIB.BASEBOARD_FAB2(SCH_1):GND

CAP_0805-10UF,16V,10%,X6S,C953A  I47  C3U4
   1 VR_FET_SW_P12V_STBY_PVDDQ_ABC      A @BASEBOARD_FAB2_LIB.BASEBOARD_FAB2(SCH_1):VR_FET_SW_P12V_STBY_PVDDQ_ABC
   2    GND      B @BASEBOARD_FAB2_LIB.BASEBOARD_FAB2(SCH_1):GND

CAP_0402-1.0UF,16V,10%,X6S,D97A  I48  C7G37
   1 VR_FET_SW_P12V_STBY_PVDDQ_ABC      A @BASEBOARD_FAB2_LIB.BASEBOARD_FAB2(SCH_1):VR_FET_SW_P12V_STBY_PVDDQ_ABC
   2    GND      B @BASEBOARD_FAB2_LIB.BASEBOARD_FAB2(SCH_1):GND

CAP_0402-1.0UF,16V,10%,X6S,D97A  I50  C7G33
   1 VR_PVDDQ_ABC_PH1_VCIN      A @BASEBOARD_FAB2_LIB.BASEBOARD_FAB2(SCH_1):VR_PVDDQ_ABC_PH1_VCIN
   2    GND      B @BASEBOARD_FAB2_LIB.BASEBOARD_FAB2(SCH_1):GND

CAP_A_0402V-0.1UF,16V,10%,X7R,A  I51  C7G29
   1 VR_FET_SW_P12V_STBY_PVDDQ_ABC      A @BASEBOARD_FAB2_LIB.BASEBOARD_FAB2(SCH_1):VR_FET_SW_P12V_STBY_PVDDQ_ABC
   2    GND      B @BASEBOARD_FAB2_LIB.BASEBOARD_FAB2(SCH_1):GND

RES_0402-1.0,1%,1/16W,CHIP,G21A  I52  R3U6
   1 VR_PVDDQ_ABC_PH1_VCIN      A @BASEBOARD_FAB2_LIB.BASEBOARD_FAB2(SCH_1):VR_PVDDQ_ABC_PH1_VCIN
   2 P5V_STBY      B @BASEBOARD_FAB2_LIB.BASEBOARD_FAB2(SCH_1):P5V_STBY

CAP_A_0402V-1.0UF,6.3V,10%,X6SA  I53  C7G35
   1 P5V_STBY      A @BASEBOARD_FAB2_LIB.BASEBOARD_FAB2(SCH_1):P5V_STBY
   2    GND      B @BASEBOARD_FAB2_LIB.BASEBOARD_FAB2(SCH_1):GND

CAP_0402-0.22UF,16V,10%,X7R,A3A  I54  C7G34
   1 P5V_STBY      A @BASEBOARD_FAB2_LIB.BASEBOARD_FAB2(SCH_1):P5V_STBY
   2    GND      B @BASEBOARD_FAB2_LIB.BASEBOARD_FAB2(SCH_1):GND

INDUCTOR_SM-0.12UH,IND,D92183-A  I65  L7G2
   1 VR_PVDDQ_ABC_PH2_SW    INA @BASEBOARD_FAB2_LIB.BASEBOARD_FAB2(SCH_1):VR_PVDDQ_ABC_PH2_SW
   2 PVDDQ_ABC    INB @BASEBOARD_FAB2_LIB.BASEBOARD_FAB2(SCH_1):PVDDQ_ABC

CAP_0805LF-22UF,4V,20%,X6S,C95A  I68  C7G27
   1 PVDDQ_ABC      A @BASEBOARD_FAB2_LIB.BASEBOARD_FAB2(SCH_1):PVDDQ_ABC
   2    GND      B @BASEBOARD_FAB2_LIB.BASEBOARD_FAB2(SCH_1):GND

CAP_0402-0.22UF,16V,10%,X7R,A3A  I72  C7G41
   1 P5V_STBY      A @BASEBOARD_FAB2_LIB.BASEBOARD_FAB2(SCH_1):P5V_STBY
   2    GND      B @BASEBOARD_FAB2_LIB.BASEBOARD_FAB2(SCH_1):GND

CAP_A_0402V-1.0UF,6.3V,10%,X6SA  I73  C7G42
   1 P5V_STBY      A @BASEBOARD_FAB2_LIB.BASEBOARD_FAB2(SCH_1):P5V_STBY
   2    GND      B @BASEBOARD_FAB2_LIB.BASEBOARD_FAB2(SCH_1):GND

RES_0402-1.0,1%,1/16W,CHIP,G21A  I76  R3U9
   1 VR_PVDDQ_ABC_PH2_VCIN      A @BASEBOARD_FAB2_LIB.BASEBOARD_FAB2(SCH_1):VR_PVDDQ_ABC_PH2_VCIN
   2 P5V_STBY      B @BASEBOARD_FAB2_LIB.BASEBOARD_FAB2(SCH_1):P5V_STBY

CAP_0402-1.0UF,16V,10%,X6S,D97A  I77  C7G40
   1 VR_PVDDQ_ABC_PH2_VCIN      A @BASEBOARD_FAB2_LIB.BASEBOARD_FAB2(SCH_1):VR_PVDDQ_ABC_PH2_VCIN
   2    GND      B @BASEBOARD_FAB2_LIB.BASEBOARD_FAB2(SCH_1):GND

CAP_A_0402V-0.1UF,16V,10%,X7R,A  I78  C7G36
   1 VR_FET_SW_P12V_STBY_PVDDQ_ABC      A @BASEBOARD_FAB2_LIB.BASEBOARD_FAB2(SCH_1):VR_FET_SW_P12V_STBY_PVDDQ_ABC
   2    GND      B @BASEBOARD_FAB2_LIB.BASEBOARD_FAB2(SCH_1):GND

CAP_0402-1.0UF,16V,10%,X6S,D97A  I79  C7G30
   1 VR_FET_SW_P12V_STBY_PVDDQ_ABC      A @BASEBOARD_FAB2_LIB.BASEBOARD_FAB2(SCH_1):VR_FET_SW_P12V_STBY_PVDDQ_ABC
   2    GND      B @BASEBOARD_FAB2_LIB.BASEBOARD_FAB2(SCH_1):GND

CAP_0805-10UF,16V,10%,X6S,C953A  I80  C3U9
   1 VR_FET_SW_P12V_STBY_PVDDQ_ABC      A @BASEBOARD_FAB2_LIB.BASEBOARD_FAB2(SCH_1):VR_FET_SW_P12V_STBY_PVDDQ_ABC
   2    GND      B @BASEBOARD_FAB2_LIB.BASEBOARD_FAB2(SCH_1):GND

CAP_0805-10UF,16V,10%,X6S,C953A  I81  C3U7
   1 VR_FET_SW_P12V_STBY_PVDDQ_ABC      A @BASEBOARD_FAB2_LIB.BASEBOARD_FAB2(SCH_1):VR_FET_SW_P12V_STBY_PVDDQ_ABC
   2    GND      B @BASEBOARD_FAB2_LIB.BASEBOARD_FAB2(SCH_1):GND

CAP_0805-10UF,16V,10%,X6S,C953A  I84  C3U6
   1 VR_FET_SW_P12V_STBY_PVDDQ_ABC      A @BASEBOARD_FAB2_LIB.BASEBOARD_FAB2(SCH_1):VR_FET_SW_P12V_STBY_PVDDQ_ABC
   2    GND      B @BASEBOARD_FAB2_LIB.BASEBOARD_FAB2(SCH_1):GND

IR354XX_SM-IR35411,IC,H73688-0A  I102  EU7G2
  33 VR_PVDDQ_ABC_PH1_BOOT_R  BOOST @BASEBOARD_FAB2_LIB.BASEBOARD_FAB2(SCH_1):VR_PVDDQ_ABC_PH1_BOOT_R
  35 P5V_STBY     EN @BASEBOARD_FAB2_LIB.BASEBOARD_FAB2(SCH_1):P5V_STBY
  41 TP_PVDDQ_ABC_PH1_GL_1  GL<1> @BASEBOARD_FAB2_LIB.BASEBOARD_FAB2(SCH_1):TP_PVDDQ_ABC_PH1_GL_1
   6 TP_PVDDQ_ABC_PH1_GL_0  GL<0> @BASEBOARD_FAB2_LIB.BASEBOARD_FAB2(SCH_1):TP_PVDDQ_ABC_PH1_GL_0
  38 ISENSE_PVDDQ_ABC_PH1_IMON   IOUT @BASEBOARD_FAB2_LIB.BASEBOARD_FAB2(SCH_1):ISENSE_PVDDQ_ABC_PH1_IMON
   2    GND   LGND @BASEBOARD_FAB2_LIB.BASEBOARD_FAB2(SCH_1):GND
  31 NC_PVDDQ_ABC_PH1_P31     NC @BASEBOARD_FAB2_LIB.BASEBOARD_FAB2(SCH_1):NC_PVDDQ_ABC_PH1_P31
  37 VR_PVDDQ_ABC_PH1_OCSET  OCSET @BASEBOARD_FAB2_LIB.BASEBOARD_FAB2(SCH_1):VR_PVDDQ_ABC_PH1_OCSET
  40    GND PGND<2> @BASEBOARD_FAB2_LIB.BASEBOARD_FAB2(SCH_1):GND
   7    GND PGND<1> @BASEBOARD_FAB2_LIB.BASEBOARD_FAB2(SCH_1):GND
   5    GND PGND<0> @BASEBOARD_FAB2_LIB.BASEBOARD_FAB2(SCH_1):GND
  32 VR_PVDDQ_ABC_PH1_PHASE  PHASE @BASEBOARD_FAB2_LIB.BASEBOARD_FAB2(SCH_1):VR_PVDDQ_ABC_PH1_PHASE
  34 VR_PVDDQ_ABC_PWM1    PWM @BASEBOARD_FAB2_LIB.BASEBOARD_FAB2(SCH_1):VR_PVDDQ_ABC_PWM1
  39 VR_PVDDQ_ABC_AIREF1  REFIN @BASEBOARD_FAB2_LIB.BASEBOARD_FAB2(SCH_1):VR_PVDDQ_ABC_AIREF1
  10 VR_PVDDQ_ABC_PH1_SW     SW @BASEBOARD_FAB2_LIB.BASEBOARD_FAB2(SCH_1):VR_PVDDQ_ABC_PH1_SW
  36 A_TSENSE_PVDDQ_ABC TOUT_FLT @BASEBOARD_FAB2_LIB.BASEBOARD_FAB2(SCH_1):A_TSENSE_PVDDQ_ABC
   3 VR_PVDDQ_ABC_PH1_VCIN    VCC @BASEBOARD_FAB2_LIB.BASEBOARD_FAB2(SCH_1):VR_PVDDQ_ABC_PH1_VCIN
   4 P5V_STBY   VDRV @BASEBOARD_FAB2_LIB.BASEBOARD_FAB2(SCH_1):P5V_STBY
  30 VR_FET_SW_P12V_STBY_PVDDQ_ABC VIN<1> @BASEBOARD_FAB2_LIB.BASEBOARD_FAB2(SCH_1):VR_FET_SW_P12V_STBY_PVDDQ_ABC
  25 VR_FET_SW_P12V_STBY_PVDDQ_ABC VIN<0> @BASEBOARD_FAB2_LIB.BASEBOARD_FAB2(SCH_1):VR_FET_SW_P12V_STBY_PVDDQ_ABC
   1 PVDDQ_ABC    VOS @BASEBOARD_FAB2_LIB.BASEBOARD_FAB2(SCH_1):PVDDQ_ABC

IR354XX_SM-IR35411,IC,H73688-0A  I103  EU7G3
  33 VR_PVDDQ_ABC_PH2_BOOT_R  BOOST @BASEBOARD_FAB2_LIB.BASEBOARD_FAB2(SCH_1):VR_PVDDQ_ABC_PH2_BOOT_R
  35 P5V_STBY     EN @BASEBOARD_FAB2_LIB.BASEBOARD_FAB2(SCH_1):P5V_STBY
  41 TP_PVDDQ_ABC_PH2_GL_1  GL<1> @BASEBOARD_FAB2_LIB.BASEBOARD_FAB2(SCH_1):TP_PVDDQ_ABC_PH2_GL_1
   6 TP_PVDDQ_ABC_PH2_GL_0  GL<0> @BASEBOARD_FAB2_LIB.BASEBOARD_FAB2(SCH_1):TP_PVDDQ_ABC_PH2_GL_0
  38 ISENSE_PVDDQ_ABC_PH2_IMON   IOUT @BASEBOARD_FAB2_LIB.BASEBOARD_FAB2(SCH_1):ISENSE_PVDDQ_ABC_PH2_IMON
   2    GND   LGND @BASEBOARD_FAB2_LIB.BASEBOARD_FAB2(SCH_1):GND
  31 NC_PVDDQ_ABC_PH2_P31     NC @BASEBOARD_FAB2_LIB.BASEBOARD_FAB2(SCH_1):NC_PVDDQ_ABC_PH2_P31
  37 VR_PVDDQ_ABC_PH2_OCSET  OCSET @BASEBOARD_FAB2_LIB.BASEBOARD_FAB2(SCH_1):VR_PVDDQ_ABC_PH2_OCSET
  40    GND PGND<2> @BASEBOARD_FAB2_LIB.BASEBOARD_FAB2(SCH_1):GND
   7    GND PGND<1> @BASEBOARD_FAB2_LIB.BASEBOARD_FAB2(SCH_1):GND
   5    GND PGND<0> @BASEBOARD_FAB2_LIB.BASEBOARD_FAB2(SCH_1):GND
  32 VR_PVDDQ_ABC_PH2_PHASE  PHASE @BASEBOARD_FAB2_LIB.BASEBOARD_FAB2(SCH_1):VR_PVDDQ_ABC_PH2_PHASE
  34 VR_PVDDQ_ABC_PWM2    PWM @BASEBOARD_FAB2_LIB.BASEBOARD_FAB2(SCH_1):VR_PVDDQ_ABC_PWM2
  39 VR_PVDDQ_ABC_AIREF2  REFIN @BASEBOARD_FAB2_LIB.BASEBOARD_FAB2(SCH_1):VR_PVDDQ_ABC_AIREF2
  10 VR_PVDDQ_ABC_PH2_SW     SW @BASEBOARD_FAB2_LIB.BASEBOARD_FAB2(SCH_1):VR_PVDDQ_ABC_PH2_SW
  36 A_TSENSE_PVDDQ_ABC TOUT_FLT @BASEBOARD_FAB2_LIB.BASEBOARD_FAB2(SCH_1):A_TSENSE_PVDDQ_ABC
   3 VR_PVDDQ_ABC_PH2_VCIN    VCC @BASEBOARD_FAB2_LIB.BASEBOARD_FAB2(SCH_1):VR_PVDDQ_ABC_PH2_VCIN
   4 P5V_STBY   VDRV @BASEBOARD_FAB2_LIB.BASEBOARD_FAB2(SCH_1):P5V_STBY
  30 VR_FET_SW_P12V_STBY_PVDDQ_ABC VIN<1> @BASEBOARD_FAB2_LIB.BASEBOARD_FAB2(SCH_1):VR_FET_SW_P12V_STBY_PVDDQ_ABC
  25 VR_FET_SW_P12V_STBY_PVDDQ_ABC VIN<0> @BASEBOARD_FAB2_LIB.BASEBOARD_FAB2(SCH_1):VR_FET_SW_P12V_STBY_PVDDQ_ABC
   1 PVDDQ_ABC    VOS @BASEBOARD_FAB2_LIB.BASEBOARD_FAB2(SCH_1):PVDDQ_ABC

RES_0402-68.1K,1%,1/16W,EMPTY,A  I104  R7G25
   1 VR_PVDDQ_ABC_PH1_OCSET      A @BASEBOARD_FAB2_LIB.BASEBOARD_FAB2(SCH_1):VR_PVDDQ_ABC_PH1_OCSET
   2    GND      B @BASEBOARD_FAB2_LIB.BASEBOARD_FAB2(SCH_1):GND

RES_0402-68.1K,1%,1/16W,EMPTY,A  I106  R7G30
   1 VR_PVDDQ_ABC_PH2_OCSET      A @BASEBOARD_FAB2_LIB.BASEBOARD_FAB2(SCH_1):VR_PVDDQ_ABC_PH2_OCSET
   2    GND      B @BASEBOARD_FAB2_LIB.BASEBOARD_FAB2(SCH_1):GND

CAP_A_0402V-0.1UF,16V,10%,X7R,A  I108  CT51
   1 VR_PVDDQ_ABC_AIREF1      A @BASEBOARD_FAB2_LIB.BASEBOARD_FAB2(SCH_1):VR_PVDDQ_ABC_AIREF1
   2    GND      B @BASEBOARD_FAB2_LIB.BASEBOARD_FAB2(SCH_1):GND

CAP_A_0402V-0.1UF,16V,10%,X7R,A  I111  CT52
   1 VR_PVDDQ_ABC_AIREF2      A @BASEBOARD_FAB2_LIB.BASEBOARD_FAB2(SCH_1):VR_PVDDQ_ABC_AIREF2
   2    GND      B @BASEBOARD_FAB2_LIB.BASEBOARD_FAB2(SCH_1):GND

CAP_0402LF-1000PF,50V,10%,X7R,A  I118  CT49
   1 A_TSENSE_PVDDQ_ABC      A @BASEBOARD_FAB2_LIB.BASEBOARD_FAB2(SCH_1):A_TSENSE_PVDDQ_ABC
   2    GND      B @BASEBOARD_FAB2_LIB.BASEBOARD_FAB2(SCH_1):GND

SC2K2P50V3KX-GP_SMD-BCG6-SC2K2A  I119  CT53
   1 VR_PVDDQ_ABC_PH2_SW      1 @BASEBOARD_FAB2_LIB.BASEBOARD_FAB2(SCH_1):VR_PVDDQ_ABC_PH2_SW
   2 UNNAMED_216_3D01R5F-GP_I123_2      2 @BASEBOARD_FAB2_LIB.BASEBOARD_FAB2(SCH_1):UNNAMED_216_3D01R5F-GP_I123_2

CAP_0402LF-1000PF,50V,10%,X7R,A  I121  CT54
   1 A_TSENSE_PVDDQ_ABC      A @BASEBOARD_FAB2_LIB.BASEBOARD_FAB2(SCH_1):A_TSENSE_PVDDQ_ABC
   2    GND      B @BASEBOARD_FAB2_LIB.BASEBOARD_FAB2(SCH_1):GND

SC2K2P50V3KX-GP_SMD-BCG6-SC2K2A  I124  CT50
   1 VR_PVDDQ_ABC_PH1_SW      1 @BASEBOARD_FAB2_LIB.BASEBOARD_FAB2(SCH_1):VR_PVDDQ_ABC_PH1_SW
   2 UNNAMED_216_3D01R5F-GP_I114_2      2 @BASEBOARD_FAB2_LIB.BASEBOARD_FAB2(SCH_1):UNNAMED_216_3D01R5F-GP_I114_2

INDUCTOR_SM-0.12UH,IND,D92183-A  I125  L7G1
   1 VR_PVDDQ_ABC_PH1_SW    INA @BASEBOARD_FAB2_LIB.BASEBOARD_FAB2(SCH_1):VR_PVDDQ_ABC_PH1_SW
   2 PVDDQ_ABC    INB @BASEBOARD_FAB2_LIB.BASEBOARD_FAB2(SCH_1):PVDDQ_ABC

3D01R5F-GP_SMD-RG5-3D01R5F-GP,A  I114  RT34
   1    GND      1 @BASEBOARD_FAB2_LIB.BASEBOARD_FAB2(SCH_1):GND
   2 UNNAMED_216_3D01R5F-GP_I114_2      2 @BASEBOARD_FAB2_LIB.BASEBOARD_FAB2(SCH_1):UNNAMED_216_3D01R5F-GP_I114_2

3D01R5F-GP_SMD-RG5-3D01R5F-GP,A  I123  RT35
   1    GND      1 @BASEBOARD_FAB2_LIB.BASEBOARD_FAB2(SCH_1):GND
   2 UNNAMED_216_3D01R5F-GP_I123_2      2 @BASEBOARD_FAB2_LIB.BASEBOARD_FAB2(SCH_1):UNNAMED_216_3D01R5F-GP_I123_2

RES_0402-0.0,5%,1/16W,CHIP,G21A  I126  RT33
   1 VR_PVDDQ_ABC_PH1_BOOT      A @BASEBOARD_FAB2_LIB.BASEBOARD_FAB2(SCH_1):VR_PVDDQ_ABC_PH1_BOOT
   2 VR_PVDDQ_ABC_PH1_BOOT_R      B @BASEBOARD_FAB2_LIB.BASEBOARD_FAB2(SCH_1):VR_PVDDQ_ABC_PH1_BOOT_R

RES_0402-0.0,5%,1/16W,CHIP,G21A  I127  RT36
   1 VR_PVDDQ_ABC_PH2_BOOT      A @BASEBOARD_FAB2_LIB.BASEBOARD_FAB2(SCH_1):VR_PVDDQ_ABC_PH2_BOOT
   2 VR_PVDDQ_ABC_PH2_BOOT_R      B @BASEBOARD_FAB2_LIB.BASEBOARD_FAB2(SCH_1):VR_PVDDQ_ABC_PH2_BOOT_R

CAP_0402-0.220UF,16V,10%,X7R,AA  I128  C7G38
   1 VR_PVDDQ_ABC_PH2_BOOT      A @BASEBOARD_FAB2_LIB.BASEBOARD_FAB2(SCH_1):VR_PVDDQ_ABC_PH2_BOOT
   2 VR_PVDDQ_ABC_PH2_PHASE      B @BASEBOARD_FAB2_LIB.BASEBOARD_FAB2(SCH_1):VR_PVDDQ_ABC_PH2_PHASE


DRAWING: @BASEBOARD_FAB2_LIB.BASEBOARD_FAB2(SCH_1):PAGE210 

CAP_A_0603V-22.0UF,4V,20%,X6S,A  I8  C1C19
   1 PVSA_CPU1      A @BASEBOARD_FAB2_LIB.BASEBOARD_FAB2(SCH_1):PVSA_CPU1
   2    GND      B @BASEBOARD_FAB2_LIB.BASEBOARD_FAB2(SCH_1):GND

INDUCTOR_SM-0.3UH,IND,D92183-0A  I10  L1C1
   1 VR_PVSA_CPU1_PHASE_SW    INA @BASEBOARD_FAB2_LIB.BASEBOARD_FAB2(SCH_1):VR_PVSA_CPU1_PHASE_SW
   2 PVSA_CPU1    INB @BASEBOARD_FAB2_LIB.BASEBOARD_FAB2(SCH_1):PVSA_CPU1

CAPP_3018-470UF,2.5V,20%,ALUM,A  I12  C9N11
   1 PVSA_CPU1      A @BASEBOARD_FAB2_LIB.BASEBOARD_FAB2(SCH_1):PVSA_CPU1
   2    GND      B @BASEBOARD_FAB2_LIB.BASEBOARD_FAB2(SCH_1):GND

CAPP_3018-470UF,2.5V,20%,ALUM,A  I14  C9N20
   1 PVSA_CPU1      A @BASEBOARD_FAB2_LIB.BASEBOARD_FAB2(SCH_1):PVSA_CPU1
   2    GND      B @BASEBOARD_FAB2_LIB.BASEBOARD_FAB2(SCH_1):GND

RES_0402-1.0,1%,1/16W,CHIP,G21A  I20  R9N3
   1 VR_PVSA_CPU1_VCIN      A @BASEBOARD_FAB2_LIB.BASEBOARD_FAB2(SCH_1):VR_PVSA_CPU1_VCIN
   2 P5V_STBY      B @BASEBOARD_FAB2_LIB.BASEBOARD_FAB2(SCH_1):P5V_STBY

CAP_0402-0.22UF,16V,10%,X7R,A3A  I22  C1C4
   1 P5V_STBY      A @BASEBOARD_FAB2_LIB.BASEBOARD_FAB2(SCH_1):P5V_STBY
   2    GND      B @BASEBOARD_FAB2_LIB.BASEBOARD_FAB2(SCH_1):GND

CAP_A_0402V-1.0UF,6.3V,10%,X6SA  I23  C1C3
   1 P5V_STBY      A @BASEBOARD_FAB2_LIB.BASEBOARD_FAB2(SCH_1):P5V_STBY
   2    GND      B @BASEBOARD_FAB2_LIB.BASEBOARD_FAB2(SCH_1):GND

CAP_0402-0.220UF,16V,10%,X7R,AA  I24  C1C12
   1 VR_PVSA_CPU1_BOOT      A @BASEBOARD_FAB2_LIB.BASEBOARD_FAB2(SCH_1):VR_PVSA_CPU1_BOOT
   2 VR_PVSA_CPU1_PHASE      B @BASEBOARD_FAB2_LIB.BASEBOARD_FAB2(SCH_1):VR_PVSA_CPU1_PHASE

CAP_0402-1.0UF,16V,10%,X6S,D97A  I26  C1C5
   1 VR_PVSA_CPU1_VCIN      A @BASEBOARD_FAB2_LIB.BASEBOARD_FAB2(SCH_1):VR_PVSA_CPU1_VCIN
   2    GND      B @BASEBOARD_FAB2_LIB.BASEBOARD_FAB2(SCH_1):GND

CAP_A_0402V-0.1UF,16V,10%,X7R,A  I27  C1C17
   1 VR_FET_SW_P12V_STBY_PVCCIN_CPU1      A @BASEBOARD_FAB2_LIB.BASEBOARD_FAB2(SCH_1):VR_FET_SW_P12V_STBY_PVCCIN_CPU1
   2    GND      B @BASEBOARD_FAB2_LIB.BASEBOARD_FAB2(SCH_1):GND

CAP_0402-1.0UF,16V,10%,X6S,D97A  I28  C1C15
   1 VR_FET_SW_P12V_STBY_PVCCIN_CPU1      A @BASEBOARD_FAB2_LIB.BASEBOARD_FAB2(SCH_1):VR_FET_SW_P12V_STBY_PVCCIN_CPU1
   2    GND      B @BASEBOARD_FAB2_LIB.BASEBOARD_FAB2(SCH_1):GND

RES_0402-100.0,1%,1/16W,CHIP,GA  I29  R1C12
   1 VSENSE_PVSA_CPU1_P      A @BASEBOARD_FAB2_LIB.BASEBOARD_FAB2(SCH_1):VSENSE_PVSA_CPU1_P
   2 PVSA_CPU1      B @BASEBOARD_FAB2_LIB.BASEBOARD_FAB2(SCH_1):PVSA_CPU1

RES_0402-0.0,5%,1/16W,CHIP,G21A  I31  R1C7
   1 VSENSE_PVSA_CPU1_P      A @BASEBOARD_FAB2_LIB.BASEBOARD_FAB2(SCH_1):VSENSE_PVSA_CPU1_P
   2 VSENSE_PVSA_CPU1_SKT_VSEN      B @BASEBOARD_FAB2_LIB.BASEBOARD_FAB2(SCH_1):VSENSE_PVSA_CPU1_SKT_VSEN

RES_0402-0.0,5%,1/16W,CHIP,G21A  I32  R1C5
   1 VSENSE_PVSA_CPU1_N      A @BASEBOARD_FAB2_LIB.BASEBOARD_FAB2(SCH_1):VSENSE_PVSA_CPU1_N
   2 VSENSE_PVSA_CPU1_SKT_VRTN      B @BASEBOARD_FAB2_LIB.BASEBOARD_FAB2(SCH_1):VSENSE_PVSA_CPU1_SKT_VRTN

RES_0402-100.0,1%,1/16W,CHIP,GA  I33  R1C4
   1 VSENSE_PVSA_CPU1_N      A @BASEBOARD_FAB2_LIB.BASEBOARD_FAB2(SCH_1):VSENSE_PVSA_CPU1_N
   2    GND      B @BASEBOARD_FAB2_LIB.BASEBOARD_FAB2(SCH_1):GND

RES_0402-1.00K,1%,1/16W,EMPTY,A  I34  R1C6
   1 VSENSE_PVSA_CPU1_P      A @BASEBOARD_FAB2_LIB.BASEBOARD_FAB2(SCH_1):VSENSE_PVSA_CPU1_P
   2 VSENSE_PVSA_CPU1_N      B @BASEBOARD_FAB2_LIB.BASEBOARD_FAB2(SCH_1):VSENSE_PVSA_CPU1_N

CAP_0805-10UF,16V,10%,X6S,C953A  I35  C9N13
   1 VR_FET_SW_P12V_STBY_PVCCIN_CPU1      A @BASEBOARD_FAB2_LIB.BASEBOARD_FAB2(SCH_1):VR_FET_SW_P12V_STBY_PVCCIN_CPU1
   2    GND      B @BASEBOARD_FAB2_LIB.BASEBOARD_FAB2(SCH_1):GND

CAP_0805-10UF,16V,10%,X6S,C953A  I36  C9N19
   1 VR_FET_SW_P12V_STBY_PVCCIN_CPU1      A @BASEBOARD_FAB2_LIB.BASEBOARD_FAB2(SCH_1):VR_FET_SW_P12V_STBY_PVCCIN_CPU1
   2    GND      B @BASEBOARD_FAB2_LIB.BASEBOARD_FAB2(SCH_1):GND

CAP_0805-10UF,16V,10%,X6S,C953A  I38  C9N21
   1 VR_FET_SW_P12V_STBY_PVCCIN_CPU1      A @BASEBOARD_FAB2_LIB.BASEBOARD_FAB2(SCH_1):VR_FET_SW_P12V_STBY_PVCCIN_CPU1
   2    GND      B @BASEBOARD_FAB2_LIB.BASEBOARD_FAB2(SCH_1):GND

CAP_A_0603V-22.0UF,4V,20%,X6S,A  I44  C9N22
   1 PVSA_CPU1      A @BASEBOARD_FAB2_LIB.BASEBOARD_FAB2(SCH_1):PVSA_CPU1
   2    GND      B @BASEBOARD_FAB2_LIB.BASEBOARD_FAB2(SCH_1):GND

RES_0402-51.1,1.0%,1/16W,CHIP,A  I45  R9N4
   1 PVSA_CPU1      A @BASEBOARD_FAB2_LIB.BASEBOARD_FAB2(SCH_1):PVSA_CPU1
   2    GND      B @BASEBOARD_FAB2_LIB.BASEBOARD_FAB2(SCH_1):GND

IR354XX_SM-IR35412,IC,H73684-0A  I51  EU1C1
  33 VR_PVSA_CPU1_BOOT_R  BOOST @BASEBOARD_FAB2_LIB.BASEBOARD_FAB2(SCH_1):VR_PVSA_CPU1_BOOT_R
  35 P5V_STBY     EN @BASEBOARD_FAB2_LIB.BASEBOARD_FAB2(SCH_1):P5V_STBY
  41 TP_PVSA_CPU1_GL_1  GL<1> @BASEBOARD_FAB2_LIB.BASEBOARD_FAB2(SCH_1):TP_PVSA_CPU1_GL_1
   6 TP_PVSA_CPU1_GL_0  GL<0> @BASEBOARD_FAB2_LIB.BASEBOARD_FAB2(SCH_1):TP_PVSA_CPU1_GL_0
  38 ISENSE_PVSA_CPU1_IMON   IOUT @BASEBOARD_FAB2_LIB.BASEBOARD_FAB2(SCH_1):ISENSE_PVSA_CPU1_IMON
   2    GND   LGND @BASEBOARD_FAB2_LIB.BASEBOARD_FAB2(SCH_1):GND
  31 NC_PVSA_CPU1_P31     NC @BASEBOARD_FAB2_LIB.BASEBOARD_FAB2(SCH_1):NC_PVSA_CPU1_P31
  37 VR_PVSA_CPU1_OCSET  OCSET @BASEBOARD_FAB2_LIB.BASEBOARD_FAB2(SCH_1):VR_PVSA_CPU1_OCSET
  40    GND PGND<2> @BASEBOARD_FAB2_LIB.BASEBOARD_FAB2(SCH_1):GND
   7    GND PGND<1> @BASEBOARD_FAB2_LIB.BASEBOARD_FAB2(SCH_1):GND
   5    GND PGND<0> @BASEBOARD_FAB2_LIB.BASEBOARD_FAB2(SCH_1):GND
  32 VR_PVSA_CPU1_PHASE  PHASE @BASEBOARD_FAB2_LIB.BASEBOARD_FAB2(SCH_1):VR_PVSA_CPU1_PHASE
  34 VR_PVSA_CPU1_PWM    PWM @BASEBOARD_FAB2_LIB.BASEBOARD_FAB2(SCH_1):VR_PVSA_CPU1_PWM
  39 VR_PVSA_CPU1_BIREF1  REFIN @BASEBOARD_FAB2_LIB.BASEBOARD_FAB2(SCH_1):VR_PVSA_CPU1_BIREF1
  10 VR_PVSA_CPU1_PHASE_SW     SW @BASEBOARD_FAB2_LIB.BASEBOARD_FAB2(SCH_1):VR_PVSA_CPU1_PHASE_SW
  36 A_TSENSE_PVSA_CPU1 TOUT_FLT @BASEBOARD_FAB2_LIB.BASEBOARD_FAB2(SCH_1):A_TSENSE_PVSA_CPU1
   3 VR_PVSA_CPU1_VCIN    VCC @BASEBOARD_FAB2_LIB.BASEBOARD_FAB2(SCH_1):VR_PVSA_CPU1_VCIN
   4 P5V_STBY   VDRV @BASEBOARD_FAB2_LIB.BASEBOARD_FAB2(SCH_1):P5V_STBY
  30 VR_FET_SW_P12V_STBY_PVCCIN_CPU1 VIN<1> @BASEBOARD_FAB2_LIB.BASEBOARD_FAB2(SCH_1):VR_FET_SW_P12V_STBY_PVCCIN_CPU1
  25 VR_FET_SW_P12V_STBY_PVCCIN_CPU1 VIN<0> @BASEBOARD_FAB2_LIB.BASEBOARD_FAB2(SCH_1):VR_FET_SW_P12V_STBY_PVCCIN_CPU1
   1 PVSA_CPU1    VOS @BASEBOARD_FAB2_LIB.BASEBOARD_FAB2(SCH_1):PVSA_CPU1

RES_0402-68.1K,1%,1/16W,EMPTY,A  I52  R1C37
   1 VR_PVSA_CPU1_OCSET      A @BASEBOARD_FAB2_LIB.BASEBOARD_FAB2(SCH_1):VR_PVSA_CPU1_OCSET
   2    GND      B @BASEBOARD_FAB2_LIB.BASEBOARD_FAB2(SCH_1):GND

CAP_A_0402V-0.1UF,16V,10%,X7R,A  I55  CT57
   1 VR_PVSA_CPU1_BIREF1      A @BASEBOARD_FAB2_LIB.BASEBOARD_FAB2(SCH_1):VR_PVSA_CPU1_BIREF1
   2    GND      B @BASEBOARD_FAB2_LIB.BASEBOARD_FAB2(SCH_1):GND

SC2K2P50V3KX-GP_SMD-BCG6-SC2K2A  I57  CT56
   1 VR_PVSA_CPU1_PHASE_SW      1 @BASEBOARD_FAB2_LIB.BASEBOARD_FAB2(SCH_1):VR_PVSA_CPU1_PHASE_SW
   2 UNNAMED_210_3D01R5F-GP_I59_2      2 @BASEBOARD_FAB2_LIB.BASEBOARD_FAB2(SCH_1):UNNAMED_210_3D01R5F-GP_I59_2

CAP_0402LF-1000PF,50V,10%,X7R,A  I60  CT55
   1 A_TSENSE_PVSA_CPU1      A @BASEBOARD_FAB2_LIB.BASEBOARD_FAB2(SCH_1):A_TSENSE_PVSA_CPU1
   2    GND      B @BASEBOARD_FAB2_LIB.BASEBOARD_FAB2(SCH_1):GND

3D01R5F-GP_SMD-RG5-3D01R5F-GP,A  I59  RT38
   1    GND      1 @BASEBOARD_FAB2_LIB.BASEBOARD_FAB2(SCH_1):GND
   2 UNNAMED_210_3D01R5F-GP_I59_2      2 @BASEBOARD_FAB2_LIB.BASEBOARD_FAB2(SCH_1):UNNAMED_210_3D01R5F-GP_I59_2

RES_0402-0.0,5%,1/16W,CHIP,G21A  I62  RT37
   1 VR_PVSA_CPU1_BOOT      A @BASEBOARD_FAB2_LIB.BASEBOARD_FAB2(SCH_1):VR_PVSA_CPU1_BOOT
   2 VR_PVSA_CPU1_BOOT_R      B @BASEBOARD_FAB2_LIB.BASEBOARD_FAB2(SCH_1):VR_PVSA_CPU1_BOOT_R


DRAWING: @BASEBOARD_FAB2_LIB.BASEBOARD_FAB2(SCH_1):PAGE205 

CAP_A_0603V-22.0UF,4V,20%,X6S,A  I5  C6N7
   1 PVSA_CPU0      A @BASEBOARD_FAB2_LIB.BASEBOARD_FAB2(SCH_1):PVSA_CPU0
   2    GND      B @BASEBOARD_FAB2_LIB.BASEBOARD_FAB2(SCH_1):GND

INDUCTOR_SM-0.3UH,IND,D92183-0A  I7  L4C2
   1 VR_PVSA_CPU0_PHASE_SW    INA @BASEBOARD_FAB2_LIB.BASEBOARD_FAB2(SCH_1):VR_PVSA_CPU0_PHASE_SW
   2 PVSA_CPU0    INB @BASEBOARD_FAB2_LIB.BASEBOARD_FAB2(SCH_1):PVSA_CPU0

CAPP_3018-470UF,2.5V,20%,ALUM,A  I12  C6N1
   1 PVSA_CPU0      A @BASEBOARD_FAB2_LIB.BASEBOARD_FAB2(SCH_1):PVSA_CPU0
   2    GND      B @BASEBOARD_FAB2_LIB.BASEBOARD_FAB2(SCH_1):GND

CAPP_3018-470UF,2.5V,20%,ALUM,A  I14  C6N4
   1 PVSA_CPU0      A @BASEBOARD_FAB2_LIB.BASEBOARD_FAB2(SCH_1):PVSA_CPU0
   2    GND      B @BASEBOARD_FAB2_LIB.BASEBOARD_FAB2(SCH_1):GND

CAP_0402-0.22UF,16V,10%,X7R,A3A  I16  C4C5
   1 P5V_STBY      A @BASEBOARD_FAB2_LIB.BASEBOARD_FAB2(SCH_1):P5V_STBY
   2    GND      B @BASEBOARD_FAB2_LIB.BASEBOARD_FAB2(SCH_1):GND

CAP_A_0402V-1.0UF,6.3V,10%,X6SA  I18  C4C4
   1 P5V_STBY      A @BASEBOARD_FAB2_LIB.BASEBOARD_FAB2(SCH_1):P5V_STBY
   2    GND      B @BASEBOARD_FAB2_LIB.BASEBOARD_FAB2(SCH_1):GND

RES_0402-1.0,1%,1/16W,CHIP,G21A  I19  R6N3
   1 VR_PVSA_CPU0_VCIN      A @BASEBOARD_FAB2_LIB.BASEBOARD_FAB2(SCH_1):VR_PVSA_CPU0_VCIN
   2 P5V_STBY      B @BASEBOARD_FAB2_LIB.BASEBOARD_FAB2(SCH_1):P5V_STBY

CAP_0402-1.0UF,16V,10%,X6S,D97A  I20  C4C6
   1 VR_PVSA_CPU0_VCIN      A @BASEBOARD_FAB2_LIB.BASEBOARD_FAB2(SCH_1):VR_PVSA_CPU0_VCIN
   2    GND      B @BASEBOARD_FAB2_LIB.BASEBOARD_FAB2(SCH_1):GND

RES_0402-100.0,1%,1/16W,CHIP,GA  I24  R4C5
   1 VSENSE_PVSA_CPU0_P      A @BASEBOARD_FAB2_LIB.BASEBOARD_FAB2(SCH_1):VSENSE_PVSA_CPU0_P
   2 PVSA_CPU0      B @BASEBOARD_FAB2_LIB.BASEBOARD_FAB2(SCH_1):PVSA_CPU0

CAP_0402-0.220UF,16V,10%,X7R,AA  I25  C4C8
   1 VR_PVSA_CPU0_BOOT      A @BASEBOARD_FAB2_LIB.BASEBOARD_FAB2(SCH_1):VR_PVSA_CPU0_BOOT
   2 VR_PVSA_CPU0_PHASE      B @BASEBOARD_FAB2_LIB.BASEBOARD_FAB2(SCH_1):VR_PVSA_CPU0_PHASE

RES_0402-0.0,5%,1/16W,CHIP,G21A  I26  R4C4
   1 VSENSE_PVSA_CPU0_P      A @BASEBOARD_FAB2_LIB.BASEBOARD_FAB2(SCH_1):VSENSE_PVSA_CPU0_P
   2 VSENSE_PVSA_CPU0_SKT_VSEN      B @BASEBOARD_FAB2_LIB.BASEBOARD_FAB2(SCH_1):VSENSE_PVSA_CPU0_SKT_VSEN

RES_0402-100.0,1%,1/16W,CHIP,GA  I29  R4C1
   1 VSENSE_PVSA_CPU0_N      A @BASEBOARD_FAB2_LIB.BASEBOARD_FAB2(SCH_1):VSENSE_PVSA_CPU0_N
   2    GND      B @BASEBOARD_FAB2_LIB.BASEBOARD_FAB2(SCH_1):GND

RES_0402-0.0,5%,1/16W,CHIP,G21A  I30  R4C2
   1 VSENSE_PVSA_CPU0_N      A @BASEBOARD_FAB2_LIB.BASEBOARD_FAB2(SCH_1):VSENSE_PVSA_CPU0_N
   2 VSENSE_PVSA_CPU0_SKT_VRTN      B @BASEBOARD_FAB2_LIB.BASEBOARD_FAB2(SCH_1):VSENSE_PVSA_CPU0_SKT_VRTN

CAP_A_0402V-0.1UF,16V,10%,X7R,A  I31  C4C10
   1 VR_FET_SW_P12V_STBY_PVCCIN_CPU0      A @BASEBOARD_FAB2_LIB.BASEBOARD_FAB2(SCH_1):VR_FET_SW_P12V_STBY_PVCCIN_CPU0
   2    GND      B @BASEBOARD_FAB2_LIB.BASEBOARD_FAB2(SCH_1):GND

CAP_0402-1.0UF,16V,10%,X6S,D97A  I32  C4C9
   1 VR_FET_SW_P12V_STBY_PVCCIN_CPU0      A @BASEBOARD_FAB2_LIB.BASEBOARD_FAB2(SCH_1):VR_FET_SW_P12V_STBY_PVCCIN_CPU0
   2    GND      B @BASEBOARD_FAB2_LIB.BASEBOARD_FAB2(SCH_1):GND

CAP_0805-10UF,16V,10%,X6S,C953A  I33  C6N2
   1 VR_FET_SW_P12V_STBY_PVCCIN_CPU0      A @BASEBOARD_FAB2_LIB.BASEBOARD_FAB2(SCH_1):VR_FET_SW_P12V_STBY_PVCCIN_CPU0
   2    GND      B @BASEBOARD_FAB2_LIB.BASEBOARD_FAB2(SCH_1):GND

CAP_0805-10UF,16V,10%,X6S,C953A  I34  C6N3
   1 VR_FET_SW_P12V_STBY_PVCCIN_CPU0      A @BASEBOARD_FAB2_LIB.BASEBOARD_FAB2(SCH_1):VR_FET_SW_P12V_STBY_PVCCIN_CPU0
   2    GND      B @BASEBOARD_FAB2_LIB.BASEBOARD_FAB2(SCH_1):GND

CAP_0805-10UF,16V,10%,X6S,C953A  I35  C6N6
   1 VR_FET_SW_P12V_STBY_PVCCIN_CPU0      A @BASEBOARD_FAB2_LIB.BASEBOARD_FAB2(SCH_1):VR_FET_SW_P12V_STBY_PVCCIN_CPU0
   2    GND      B @BASEBOARD_FAB2_LIB.BASEBOARD_FAB2(SCH_1):GND

RES_0402-1.00K,1%,1/16W,EMPTY,A  I37  R4C3
   1 VSENSE_PVSA_CPU0_P      A @BASEBOARD_FAB2_LIB.BASEBOARD_FAB2(SCH_1):VSENSE_PVSA_CPU0_P
   2 VSENSE_PVSA_CPU0_N      B @BASEBOARD_FAB2_LIB.BASEBOARD_FAB2(SCH_1):VSENSE_PVSA_CPU0_N

CAP_A_0603V-22.0UF,4V,20%,X6S,A  I43  C4C11
   1 PVSA_CPU0      A @BASEBOARD_FAB2_LIB.BASEBOARD_FAB2(SCH_1):PVSA_CPU0
   2    GND      B @BASEBOARD_FAB2_LIB.BASEBOARD_FAB2(SCH_1):GND

RES_0402-51.1,1.0%,1/16W,CHIP,A  I45  R6N4
   1 PVSA_CPU0      A @BASEBOARD_FAB2_LIB.BASEBOARD_FAB2(SCH_1):PVSA_CPU0
   2    GND      B @BASEBOARD_FAB2_LIB.BASEBOARD_FAB2(SCH_1):GND

IR354XX_SM-IR35412,IC,H73684-0A  I46  EU4C1
  33 VR_PVSA_CPU0_BOOT_R  BOOST @BASEBOARD_FAB2_LIB.BASEBOARD_FAB2(SCH_1):VR_PVSA_CPU0_BOOT_R
  35 P5V_STBY     EN @BASEBOARD_FAB2_LIB.BASEBOARD_FAB2(SCH_1):P5V_STBY
  41 TP_PVSA_CPU0_GL_1  GL<1> @BASEBOARD_FAB2_LIB.BASEBOARD_FAB2(SCH_1):TP_PVSA_CPU0_GL_1
   6 TP_PVSA_CPU0_GL_0  GL<0> @BASEBOARD_FAB2_LIB.BASEBOARD_FAB2(SCH_1):TP_PVSA_CPU0_GL_0
  38 ISENSE_PVSA_CPU0_IMON   IOUT @BASEBOARD_FAB2_LIB.BASEBOARD_FAB2(SCH_1):ISENSE_PVSA_CPU0_IMON
   2    GND   LGND @BASEBOARD_FAB2_LIB.BASEBOARD_FAB2(SCH_1):GND
  31 NC_PVSA_CPU0_P31     NC @BASEBOARD_FAB2_LIB.BASEBOARD_FAB2(SCH_1):NC_PVSA_CPU0_P31
  37 VR_PVSA_CPU0_OCSET  OCSET @BASEBOARD_FAB2_LIB.BASEBOARD_FAB2(SCH_1):VR_PVSA_CPU0_OCSET
  40    GND PGND<2> @BASEBOARD_FAB2_LIB.BASEBOARD_FAB2(SCH_1):GND
   7    GND PGND<1> @BASEBOARD_FAB2_LIB.BASEBOARD_FAB2(SCH_1):GND
   5    GND PGND<0> @BASEBOARD_FAB2_LIB.BASEBOARD_FAB2(SCH_1):GND
  32 VR_PVSA_CPU0_PHASE  PHASE @BASEBOARD_FAB2_LIB.BASEBOARD_FAB2(SCH_1):VR_PVSA_CPU0_PHASE
  34 VR_PVSA_CPU0_PWM    PWM @BASEBOARD_FAB2_LIB.BASEBOARD_FAB2(SCH_1):VR_PVSA_CPU0_PWM
  39 VR_PVSA_CPU0_BIREF1  REFIN @BASEBOARD_FAB2_LIB.BASEBOARD_FAB2(SCH_1):VR_PVSA_CPU0_BIREF1
  10 VR_PVSA_CPU0_PHASE_SW     SW @BASEBOARD_FAB2_LIB.BASEBOARD_FAB2(SCH_1):VR_PVSA_CPU0_PHASE_SW
  36 A_TSENSE_PVSA_CPU0 TOUT_FLT @BASEBOARD_FAB2_LIB.BASEBOARD_FAB2(SCH_1):A_TSENSE_PVSA_CPU0
   3 VR_PVSA_CPU0_VCIN    VCC @BASEBOARD_FAB2_LIB.BASEBOARD_FAB2(SCH_1):VR_PVSA_CPU0_VCIN
   4 P5V_STBY   VDRV @BASEBOARD_FAB2_LIB.BASEBOARD_FAB2(SCH_1):P5V_STBY
  30 VR_FET_SW_P12V_STBY_PVCCIN_CPU0 VIN<1> @BASEBOARD_FAB2_LIB.BASEBOARD_FAB2(SCH_1):VR_FET_SW_P12V_STBY_PVCCIN_CPU0
  25 VR_FET_SW_P12V_STBY_PVCCIN_CPU0 VIN<0> @BASEBOARD_FAB2_LIB.BASEBOARD_FAB2(SCH_1):VR_FET_SW_P12V_STBY_PVCCIN_CPU0
   1 PVSA_CPU0    VOS @BASEBOARD_FAB2_LIB.BASEBOARD_FAB2(SCH_1):PVSA_CPU0

RES_0402-68.1K,1%,1/16W,EMPTY,A  I62  R4C13
   1 VR_PVSA_CPU0_OCSET      A @BASEBOARD_FAB2_LIB.BASEBOARD_FAB2(SCH_1):VR_PVSA_CPU0_OCSET
   2    GND      B @BASEBOARD_FAB2_LIB.BASEBOARD_FAB2(SCH_1):GND

SC2K2P50V3KX-GP_SMD-BCG6-SC2K2A  I64  CT59
   1 VR_PVSA_CPU0_PHASE_SW      1 @BASEBOARD_FAB2_LIB.BASEBOARD_FAB2(SCH_1):VR_PVSA_CPU0_PHASE_SW
   2 UNNAMED_205_3D01R5F-GP_I68_2      2 @BASEBOARD_FAB2_LIB.BASEBOARD_FAB2(SCH_1):UNNAMED_205_3D01R5F-GP_I68_2

CAP_0402LF-1000PF,50V,10%,X7R,A  I65  CT58
   1 A_TSENSE_PVSA_CPU0      A @BASEBOARD_FAB2_LIB.BASEBOARD_FAB2(SCH_1):A_TSENSE_PVSA_CPU0
   2    GND      B @BASEBOARD_FAB2_LIB.BASEBOARD_FAB2(SCH_1):GND

CAP_A_0402V-0.1UF,16V,10%,X7R,A  I69  CT60
   1 VR_PVSA_CPU0_BIREF1      A @BASEBOARD_FAB2_LIB.BASEBOARD_FAB2(SCH_1):VR_PVSA_CPU0_BIREF1
   2    GND      B @BASEBOARD_FAB2_LIB.BASEBOARD_FAB2(SCH_1):GND

3D01R5F-GP_SMD-RG5-3D01R5F-GP,A  I68  RT39
   1    GND      1 @BASEBOARD_FAB2_LIB.BASEBOARD_FAB2(SCH_1):GND
   2 UNNAMED_205_3D01R5F-GP_I68_2      2 @BASEBOARD_FAB2_LIB.BASEBOARD_FAB2(SCH_1):UNNAMED_205_3D01R5F-GP_I68_2

RES_0402-0.0,5%,1/16W,CHIP,G21A  I72  RT40
   1 VR_PVSA_CPU0_BOOT      A @BASEBOARD_FAB2_LIB.BASEBOARD_FAB2(SCH_1):VR_PVSA_CPU0_BOOT
   2 VR_PVSA_CPU0_BOOT_R      B @BASEBOARD_FAB2_LIB.BASEBOARD_FAB2(SCH_1):VR_PVSA_CPU0_BOOT_R


DRAWING: @BASEBOARD_FAB2_LIB.BASEBOARD_FAB2(SCH_1):PAGE214 

CAP_1210-100UF,16V,20%,X5R,644A  I8  C4E9
   1 VR_FET_SW_P12V_STBY_PVCCIN_CPU0      A @BASEBOARD_FAB2_LIB.BASEBOARD_FAB2(SCH_1):VR_FET_SW_P12V_STBY_PVCCIN_CPU0
   2    GND      B @BASEBOARD_FAB2_LIB.BASEBOARD_FAB2(SCH_1):GND

CAPP_3018-470UF,2.5V,20%,ALUM,A  I20  C4E7
   1 PVCCIO_CPU1      A @BASEBOARD_FAB2_LIB.BASEBOARD_FAB2(SCH_1):PVCCIO_CPU1
   2    GND      B @BASEBOARD_FAB2_LIB.BASEBOARD_FAB2(SCH_1):GND

CAPP_3018-470UF,2.5V,20%,ALUM,A  I21  C6R12
   1 PVCCIO_CPU1      A @BASEBOARD_FAB2_LIB.BASEBOARD_FAB2(SCH_1):PVCCIO_CPU1
   2    GND      B @BASEBOARD_FAB2_LIB.BASEBOARD_FAB2(SCH_1):GND

CAPP_3018-470UF,2.5V,20%,ALUM,A  I24  C6R5
   1 PVCCIO_CPU1      A @BASEBOARD_FAB2_LIB.BASEBOARD_FAB2(SCH_1):PVCCIO_CPU1
   2    GND      B @BASEBOARD_FAB2_LIB.BASEBOARD_FAB2(SCH_1):GND

CAP_1210-100UF,16V,20%,X5R,644A  I29  C4E8
   1 VR_FET_SW_P12V_STBY_PVCCIN_CPU0      A @BASEBOARD_FAB2_LIB.BASEBOARD_FAB2(SCH_1):VR_FET_SW_P12V_STBY_PVCCIN_CPU0
   2    GND      B @BASEBOARD_FAB2_LIB.BASEBOARD_FAB2(SCH_1):GND

CAP_1210-100UF,16V,20%,X5R,644A  I31  C4E14
   1 VR_FET_SW_P12V_STBY_PVCCIN_CPU0      A @BASEBOARD_FAB2_LIB.BASEBOARD_FAB2(SCH_1):VR_FET_SW_P12V_STBY_PVCCIN_CPU0
   2    GND      B @BASEBOARD_FAB2_LIB.BASEBOARD_FAB2(SCH_1):GND

CAP_A_0603V-22.0UF,4V,20%,X6S,A  I65  C7R1
   1 PVCCIO_CPU1      A @BASEBOARD_FAB2_LIB.BASEBOARD_FAB2(SCH_1):PVCCIO_CPU1
   2    GND      B @BASEBOARD_FAB2_LIB.BASEBOARD_FAB2(SCH_1):GND

INDUCTOR_SM-150NH,IND,D92183-0A  I67  L4E2
   1 VR_PVCCIO_CPU1_PH1_SW    INA @BASEBOARD_FAB2_LIB.BASEBOARD_FAB2(SCH_1):VR_PVCCIO_CPU1_PH1_SW
   2 PVCCIO_CPU1    INB @BASEBOARD_FAB2_LIB.BASEBOARD_FAB2(SCH_1):PVCCIO_CPU1

RES_0402-1.0,1%,1/16W,CHIP,G21A  I71  R6R5
   1 VR_PVCCIO_CPU1_PH1_VCIN      A @BASEBOARD_FAB2_LIB.BASEBOARD_FAB2(SCH_1):VR_PVCCIO_CPU1_PH1_VCIN
   2 P5V_STBY      B @BASEBOARD_FAB2_LIB.BASEBOARD_FAB2(SCH_1):P5V_STBY

CAP_0402-0.22UF,16V,10%,X7R,A3A  I73  C4E23
   1 P5V_STBY      A @BASEBOARD_FAB2_LIB.BASEBOARD_FAB2(SCH_1):P5V_STBY
   2    GND      B @BASEBOARD_FAB2_LIB.BASEBOARD_FAB2(SCH_1):GND

CAP_A_0402V-1.0UF,6.3V,10%,X6SA  I74  C4E28
   1 P5V_STBY      A @BASEBOARD_FAB2_LIB.BASEBOARD_FAB2(SCH_1):P5V_STBY
   2    GND      B @BASEBOARD_FAB2_LIB.BASEBOARD_FAB2(SCH_1):GND

CAP_0402-1.0UF,16V,10%,X6S,D97A  I76  C4E22
   1 VR_PVCCIO_CPU1_PH1_VCIN      A @BASEBOARD_FAB2_LIB.BASEBOARD_FAB2(SCH_1):VR_PVCCIO_CPU1_PH1_VCIN
   2    GND      B @BASEBOARD_FAB2_LIB.BASEBOARD_FAB2(SCH_1):GND

CAP_A_0402V-0.1UF,16V,10%,X7R,A  I77  C4E13
   1 VR_FET_SW_P12V_STBY_PVCCIN_CPU0      A @BASEBOARD_FAB2_LIB.BASEBOARD_FAB2(SCH_1):VR_FET_SW_P12V_STBY_PVCCIN_CPU0
   2    GND      B @BASEBOARD_FAB2_LIB.BASEBOARD_FAB2(SCH_1):GND

CAP_0402-0.220UF,16V,10%,X7R,AA  I78  C4E18
   1 VR_PVCCIO_CPU1_PH1_BOOT      A @BASEBOARD_FAB2_LIB.BASEBOARD_FAB2(SCH_1):VR_PVCCIO_CPU1_PH1_BOOT
   2 VR_PVCCIO_CPU1_PH1_PHASE      B @BASEBOARD_FAB2_LIB.BASEBOARD_FAB2(SCH_1):VR_PVCCIO_CPU1_PH1_PHASE

CAP_0402-1.0UF,16V,10%,X6S,D97A  I79  C4E15
   1 VR_FET_SW_P12V_STBY_PVCCIN_CPU0      A @BASEBOARD_FAB2_LIB.BASEBOARD_FAB2(SCH_1):VR_FET_SW_P12V_STBY_PVCCIN_CPU0
   2    GND      B @BASEBOARD_FAB2_LIB.BASEBOARD_FAB2(SCH_1):GND

CAP_0805-10UF,16V,10%,X6S,C953A  I80  C6R14
   1 VR_FET_SW_P12V_STBY_PVCCIN_CPU0      A @BASEBOARD_FAB2_LIB.BASEBOARD_FAB2(SCH_1):VR_FET_SW_P12V_STBY_PVCCIN_CPU0
   2    GND      B @BASEBOARD_FAB2_LIB.BASEBOARD_FAB2(SCH_1):GND

CAP_0805-10UF,16V,10%,X6S,C953A  I81  C6R10
   1 VR_FET_SW_P12V_STBY_PVCCIN_CPU0      A @BASEBOARD_FAB2_LIB.BASEBOARD_FAB2(SCH_1):VR_FET_SW_P12V_STBY_PVCCIN_CPU0
   2    GND      B @BASEBOARD_FAB2_LIB.BASEBOARD_FAB2(SCH_1):GND

CAP_0805-10UF,16V,10%,X6S,C953A  I83  C6R8
   1 VR_FET_SW_P12V_STBY_PVCCIN_CPU0      A @BASEBOARD_FAB2_LIB.BASEBOARD_FAB2(SCH_1):VR_FET_SW_P12V_STBY_PVCCIN_CPU0
   2    GND      B @BASEBOARD_FAB2_LIB.BASEBOARD_FAB2(SCH_1):GND

CAP_A_0402V-0.1UF,16V,10%,EMPTA  I96  C3D27
   1 VSENSE_PVCCIO_CPU1_SKT_VSEN      A @BASEBOARD_FAB2_LIB.BASEBOARD_FAB2(SCH_1):VSENSE_PVCCIO_CPU1_SKT_VSEN
   2 VSENSE_PVCCIO_CPU1_SKT_VRTN      B @BASEBOARD_FAB2_LIB.BASEBOARD_FAB2(SCH_1):VSENSE_PVCCIO_CPU1_SKT_VRTN

RES_0402-100.0,1%,1/16W,CHIP,GA  I101  R3D28
   1 VSENSE_PVCCIO_CPU1_AVSN      A @BASEBOARD_FAB2_LIB.BASEBOARD_FAB2(SCH_1):VSENSE_PVCCIO_CPU1_AVSN
   2    GND      B @BASEBOARD_FAB2_LIB.BASEBOARD_FAB2(SCH_1):GND

RES_0402-100.0,1%,1/16W,CHIP,GA  I105  R3E1
   1 VSENSE_PVCCIO_CPU1_AVSP      A @BASEBOARD_FAB2_LIB.BASEBOARD_FAB2(SCH_1):VSENSE_PVCCIO_CPU1_AVSP
   2 PVCCIO_CPU1      B @BASEBOARD_FAB2_LIB.BASEBOARD_FAB2(SCH_1):PVCCIO_CPU1

CAP_A_0603V-22.0UF,4V,20%,X6S,A  I108  C3E1
   1 PVCCIO_CPU1      A @BASEBOARD_FAB2_LIB.BASEBOARD_FAB2(SCH_1):PVCCIO_CPU1
   2    GND      B @BASEBOARD_FAB2_LIB.BASEBOARD_FAB2(SCH_1):GND

RES_0402-51.1,1.0%,1/16W,CHIP,A  I109  R7R1
   1 PVCCIO_CPU1      A @BASEBOARD_FAB2_LIB.BASEBOARD_FAB2(SCH_1):PVCCIO_CPU1
   2    GND      B @BASEBOARD_FAB2_LIB.BASEBOARD_FAB2(SCH_1):GND

IR354XX_SM-IR35412,IC,H73684-0A  I126  EU4E2
  33 VR_PVCCIO_CPU1_PH1_BOOT_R  BOOST @BASEBOARD_FAB2_LIB.BASEBOARD_FAB2(SCH_1):VR_PVCCIO_CPU1_PH1_BOOT_R
  35 P5V_STBY     EN @BASEBOARD_FAB2_LIB.BASEBOARD_FAB2(SCH_1):P5V_STBY
  41 TP_PVCCIO_CPU1_GL_1  GL<1> @BASEBOARD_FAB2_LIB.BASEBOARD_FAB2(SCH_1):TP_PVCCIO_CPU1_GL_1
   6 TP_PVCCIO_CPU1_GL_0  GL<0> @BASEBOARD_FAB2_LIB.BASEBOARD_FAB2(SCH_1):TP_PVCCIO_CPU1_GL_0
  38 ISENSE_PVCCIO_CPU1_PH1_IMON   IOUT @BASEBOARD_FAB2_LIB.BASEBOARD_FAB2(SCH_1):ISENSE_PVCCIO_CPU1_PH1_IMON
   2    GND   LGND @BASEBOARD_FAB2_LIB.BASEBOARD_FAB2(SCH_1):GND
  31 NC_PVCCIO_CPU1_PH1_P31     NC @BASEBOARD_FAB2_LIB.BASEBOARD_FAB2(SCH_1):NC_PVCCIO_CPU1_PH1_P31
  37 VR_PVCCIO_CPU1_OCSET  OCSET @BASEBOARD_FAB2_LIB.BASEBOARD_FAB2(SCH_1):VR_PVCCIO_CPU1_OCSET
  40    GND PGND<2> @BASEBOARD_FAB2_LIB.BASEBOARD_FAB2(SCH_1):GND
   7    GND PGND<1> @BASEBOARD_FAB2_LIB.BASEBOARD_FAB2(SCH_1):GND
   5    GND PGND<0> @BASEBOARD_FAB2_LIB.BASEBOARD_FAB2(SCH_1):GND
  32 VR_PVCCIO_CPU1_PH1_PHASE  PHASE @BASEBOARD_FAB2_LIB.BASEBOARD_FAB2(SCH_1):VR_PVCCIO_CPU1_PH1_PHASE
  34 VR_PVCCIO_CPU1_PWM1    PWM @BASEBOARD_FAB2_LIB.BASEBOARD_FAB2(SCH_1):VR_PVCCIO_CPU1_PWM1
  39 VR_PVCCIO_CPU1_AIREF1  REFIN @BASEBOARD_FAB2_LIB.BASEBOARD_FAB2(SCH_1):VR_PVCCIO_CPU1_AIREF1
  10 VR_PVCCIO_CPU1_PH1_SW     SW @BASEBOARD_FAB2_LIB.BASEBOARD_FAB2(SCH_1):VR_PVCCIO_CPU1_PH1_SW
  36 A_TSENSE_PVCCIO_CPU1 TOUT_FLT @BASEBOARD_FAB2_LIB.BASEBOARD_FAB2(SCH_1):A_TSENSE_PVCCIO_CPU1
   3 VR_PVCCIO_CPU1_PH1_VCIN    VCC @BASEBOARD_FAB2_LIB.BASEBOARD_FAB2(SCH_1):VR_PVCCIO_CPU1_PH1_VCIN
   4 P5V_STBY   VDRV @BASEBOARD_FAB2_LIB.BASEBOARD_FAB2(SCH_1):P5V_STBY
  30 VR_FET_SW_P12V_STBY_PVCCIN_CPU0 VIN<1> @BASEBOARD_FAB2_LIB.BASEBOARD_FAB2(SCH_1):VR_FET_SW_P12V_STBY_PVCCIN_CPU0
  25 VR_FET_SW_P12V_STBY_PVCCIN_CPU0 VIN<0> @BASEBOARD_FAB2_LIB.BASEBOARD_FAB2(SCH_1):VR_FET_SW_P12V_STBY_PVCCIN_CPU0
   1 PVCCIO_CPU1    VOS @BASEBOARD_FAB2_LIB.BASEBOARD_FAB2(SCH_1):PVCCIO_CPU1

RES_0402-68.1K,1%,1/16W,EMPTY,A  I127  R4E21
   1 VR_PVCCIO_CPU1_OCSET      A @BASEBOARD_FAB2_LIB.BASEBOARD_FAB2(SCH_1):VR_PVCCIO_CPU1_OCSET
   2    GND      B @BASEBOARD_FAB2_LIB.BASEBOARD_FAB2(SCH_1):GND

SHUNT_SH0201-EMPTY,N_A  I129  SH3D2
   1 VSENSE_PVCCIO_CPU1_SKT_VSEN      A @BASEBOARD_FAB2_LIB.BASEBOARD_FAB2(SCH_1):VSENSE_PVCCIO_CPU1_SKT_VSEN
   2 VSENSE_PVCCIO_CPU1_AVSP      B @BASEBOARD_FAB2_LIB.BASEBOARD_FAB2(SCH_1):VSENSE_PVCCIO_CPU1_AVSP

SHUNT_SH0201-EMPTY,N_A  I130  SH3D1
   1 VSENSE_PVCCIO_CPU1_SKT_VRTN      A @BASEBOARD_FAB2_LIB.BASEBOARD_FAB2(SCH_1):VSENSE_PVCCIO_CPU1_SKT_VRTN
   2 VSENSE_PVCCIO_CPU1_AVSN      B @BASEBOARD_FAB2_LIB.BASEBOARD_FAB2(SCH_1):VSENSE_PVCCIO_CPU1_AVSN

SC2K2P50V3KX-GP_SMD-BCG6-SC2K2A  I131  CT62
   1 VR_PVCCIO_CPU1_PH1_SW      1 @BASEBOARD_FAB2_LIB.BASEBOARD_FAB2(SCH_1):VR_PVCCIO_CPU1_PH1_SW
   2 UNNAMED_214_3D01R5F-GP_I132_2      2 @BASEBOARD_FAB2_LIB.BASEBOARD_FAB2(SCH_1):UNNAMED_214_3D01R5F-GP_I132_2

CAP_0402LF-1000PF,50V,10%,X7R,A  I134  CT61
   1 A_TSENSE_PVCCIO_CPU1      A @BASEBOARD_FAB2_LIB.BASEBOARD_FAB2(SCH_1):A_TSENSE_PVCCIO_CPU1
   2    GND      B @BASEBOARD_FAB2_LIB.BASEBOARD_FAB2(SCH_1):GND

CAP_A_0402V-0.1UF,16V,10%,X7R,A  I137  CT63
   1 VR_PVCCIO_CPU1_AIREF1      A @BASEBOARD_FAB2_LIB.BASEBOARD_FAB2(SCH_1):VR_PVCCIO_CPU1_AIREF1
   2    GND      B @BASEBOARD_FAB2_LIB.BASEBOARD_FAB2(SCH_1):GND

3D01R5F-GP_SMD-RG5-3D01R5F-GP,A  I132  RT42
   1    GND      1 @BASEBOARD_FAB2_LIB.BASEBOARD_FAB2(SCH_1):GND
   2 UNNAMED_214_3D01R5F-GP_I132_2      2 @BASEBOARD_FAB2_LIB.BASEBOARD_FAB2(SCH_1):UNNAMED_214_3D01R5F-GP_I132_2

RES_0402-0.0,5%,1/16W,CHIP,G21A  I139  RT41
   1 VR_PVCCIO_CPU1_PH1_BOOT      A @BASEBOARD_FAB2_LIB.BASEBOARD_FAB2(SCH_1):VR_PVCCIO_CPU1_PH1_BOOT
   2 VR_PVCCIO_CPU1_PH1_BOOT_R      B @BASEBOARD_FAB2_LIB.BASEBOARD_FAB2(SCH_1):VR_PVCCIO_CPU1_PH1_BOOT_R


DRAWING: @BASEBOARD_FAB2_LIB.BASEBOARD_FAB2(SCH_1):PAGE236 

CAP_0805LF-22UF,4V,20%,X6S,C95A  I9  C7A30
   1 PVNN_PCH_STBY      A @BASEBOARD_FAB2_LIB.BASEBOARD_FAB2(SCH_1):PVNN_PCH_STBY
   2    GND      B @BASEBOARD_FAB2_LIB.BASEBOARD_FAB2(SCH_1):GND

INDUCTOR_SM-0.3UH,IND,D92183-0A  I10  L7A2
   1 VR_PVNN_PCH_PH1_PHASE_SW    INA @BASEBOARD_FAB2_LIB.BASEBOARD_FAB2(SCH_1):VR_PVNN_PCH_PH1_PHASE_SW
   2 PVNN_PCH_STBY    INB @BASEBOARD_FAB2_LIB.BASEBOARD_FAB2(SCH_1):PVNN_PCH_STBY

RES_0402-1.0,1%,1/16W,CHIP,G21A  I14  R3L1
   1 VR_PVNN_PCH_PH1_VCIN      A @BASEBOARD_FAB2_LIB.BASEBOARD_FAB2(SCH_1):VR_PVNN_PCH_PH1_VCIN
   2 P5V_STBY      B @BASEBOARD_FAB2_LIB.BASEBOARD_FAB2(SCH_1):P5V_STBY

CAP_0402-0.22UF,16V,10%,X7R,A3A  I16  C7A8
   1 P5V_STBY      A @BASEBOARD_FAB2_LIB.BASEBOARD_FAB2(SCH_1):P5V_STBY
   2    GND      B @BASEBOARD_FAB2_LIB.BASEBOARD_FAB2(SCH_1):GND

CAP_A_0402V-1.0UF,6.3V,10%,X6SA  I17  C3L1
   1 P5V_STBY      A @BASEBOARD_FAB2_LIB.BASEBOARD_FAB2(SCH_1):P5V_STBY
   2    GND      B @BASEBOARD_FAB2_LIB.BASEBOARD_FAB2(SCH_1):GND

CAP_0402-1.0UF,16V,10%,X6S,D97A  I19  C7A6
   1 VR_PVNN_PCH_PH1_VCIN      A @BASEBOARD_FAB2_LIB.BASEBOARD_FAB2(SCH_1):VR_PVNN_PCH_PH1_VCIN
   2    GND      B @BASEBOARD_FAB2_LIB.BASEBOARD_FAB2(SCH_1):GND

CAP_A_0402V-0.1UF,16V,10%,X7R,A  I20  C7A39
   1 VR_FET_SW_P12V_STBY_PVDDQ_DEF      A @BASEBOARD_FAB2_LIB.BASEBOARD_FAB2(SCH_1):VR_FET_SW_P12V_STBY_PVDDQ_DEF
   2    GND      B @BASEBOARD_FAB2_LIB.BASEBOARD_FAB2(SCH_1):GND

CAP_0402-0.220UF,16V,10%,X7R,AA  I21  C7A43
   1 VR_PVNN_PCH_PH1_BOOT      A @BASEBOARD_FAB2_LIB.BASEBOARD_FAB2(SCH_1):VR_PVNN_PCH_PH1_BOOT
   2 VR_PVNN_PCH_PH1_PHASE      B @BASEBOARD_FAB2_LIB.BASEBOARD_FAB2(SCH_1):VR_PVNN_PCH_PH1_PHASE

CAP_0402-1.0UF,16V,10%,X6S,D97A  I22  C7A7
   1 VR_FET_SW_P12V_STBY_PVDDQ_DEF      A @BASEBOARD_FAB2_LIB.BASEBOARD_FAB2(SCH_1):VR_FET_SW_P12V_STBY_PVDDQ_DEF
   2    GND      B @BASEBOARD_FAB2_LIB.BASEBOARD_FAB2(SCH_1):GND

CAP_0805-10UF,16V,10%,X6S,C953A  I23  C3L12
   1 VR_FET_SW_P12V_STBY_PVDDQ_DEF      A @BASEBOARD_FAB2_LIB.BASEBOARD_FAB2(SCH_1):VR_FET_SW_P12V_STBY_PVDDQ_DEF
   2    GND      B @BASEBOARD_FAB2_LIB.BASEBOARD_FAB2(SCH_1):GND

CAP_0805-10UF,16V,10%,X6S,C953A  I24  C3L11
   1 VR_FET_SW_P12V_STBY_PVDDQ_DEF      A @BASEBOARD_FAB2_LIB.BASEBOARD_FAB2(SCH_1):VR_FET_SW_P12V_STBY_PVDDQ_DEF
   2    GND      B @BASEBOARD_FAB2_LIB.BASEBOARD_FAB2(SCH_1):GND

CAP_0805-10UF,16V,10%,X6S,C953A  I26  C3L8
   1 VR_FET_SW_P12V_STBY_PVDDQ_DEF      A @BASEBOARD_FAB2_LIB.BASEBOARD_FAB2(SCH_1):VR_FET_SW_P12V_STBY_PVDDQ_DEF
   2    GND      B @BASEBOARD_FAB2_LIB.BASEBOARD_FAB2(SCH_1):GND

CAP_0805-10UF,16V,10%,X6S,C953A  I29  C3L9
   1 VR_FET_SW_P12V_STBY_PVDDQ_DEF      A @BASEBOARD_FAB2_LIB.BASEBOARD_FAB2(SCH_1):VR_FET_SW_P12V_STBY_PVDDQ_DEF
   2    GND      B @BASEBOARD_FAB2_LIB.BASEBOARD_FAB2(SCH_1):GND

CAP_0805-10UF,16V,10%,X6S,C953A  I31  C3L7
   1 VR_FET_SW_P12V_STBY_PVDDQ_DEF      A @BASEBOARD_FAB2_LIB.BASEBOARD_FAB2(SCH_1):VR_FET_SW_P12V_STBY_PVDDQ_DEF
   2    GND      B @BASEBOARD_FAB2_LIB.BASEBOARD_FAB2(SCH_1):GND

CAP_0805-10UF,16V,10%,X6S,C953A  I32  C3L10
   1 VR_FET_SW_P12V_STBY_PVDDQ_DEF      A @BASEBOARD_FAB2_LIB.BASEBOARD_FAB2(SCH_1):VR_FET_SW_P12V_STBY_PVDDQ_DEF
   2    GND      B @BASEBOARD_FAB2_LIB.BASEBOARD_FAB2(SCH_1):GND

CAP_0402-1.0UF,16V,10%,X6S,D97A  I33  C7A9
   1 VR_FET_SW_P12V_STBY_PVDDQ_DEF      A @BASEBOARD_FAB2_LIB.BASEBOARD_FAB2(SCH_1):VR_FET_SW_P12V_STBY_PVDDQ_DEF
   2    GND      B @BASEBOARD_FAB2_LIB.BASEBOARD_FAB2(SCH_1):GND

CAP_0402-0.220UF,16V,10%,X7R,AA  I34  C7A44
   1 VR_P1V05_PCH_STBY_PH1_BOOT      A @BASEBOARD_FAB2_LIB.BASEBOARD_FAB2(SCH_1):VR_P1V05_PCH_STBY_PH1_BOOT
   2 VR_P1V05_PCH_STBY_PH1_PHASE      B @BASEBOARD_FAB2_LIB.BASEBOARD_FAB2(SCH_1):VR_P1V05_PCH_STBY_PH1_PHASE

CAP_A_0402V-0.1UF,16V,10%,X7R,A  I35  C7A40
   1 VR_FET_SW_P12V_STBY_PVDDQ_DEF      A @BASEBOARD_FAB2_LIB.BASEBOARD_FAB2(SCH_1):VR_FET_SW_P12V_STBY_PVDDQ_DEF
   2    GND      B @BASEBOARD_FAB2_LIB.BASEBOARD_FAB2(SCH_1):GND

CAP_0402-1.0UF,16V,10%,X6S,D97A  I36  C7A10
   1 VR_P1V05_PCH_STBY_PH1_VCIN      A @BASEBOARD_FAB2_LIB.BASEBOARD_FAB2(SCH_1):VR_P1V05_PCH_STBY_PH1_VCIN
   2    GND      B @BASEBOARD_FAB2_LIB.BASEBOARD_FAB2(SCH_1):GND

CAP_A_0402V-1.0UF,6.3V,10%,X6SA  I38  C3L29
   1 P5V_STBY      A @BASEBOARD_FAB2_LIB.BASEBOARD_FAB2(SCH_1):P5V_STBY
   2    GND      B @BASEBOARD_FAB2_LIB.BASEBOARD_FAB2(SCH_1):GND

CAP_0402-0.22UF,16V,10%,X7R,A3A  I39  C7A41
   1 P5V_STBY      A @BASEBOARD_FAB2_LIB.BASEBOARD_FAB2(SCH_1):P5V_STBY
   2    GND      B @BASEBOARD_FAB2_LIB.BASEBOARD_FAB2(SCH_1):GND

RES_0402-1.0,1%,1/16W,CHIP,G21A  I41  R3L4
   1 VR_P1V05_PCH_STBY_PH1_VCIN      A @BASEBOARD_FAB2_LIB.BASEBOARD_FAB2(SCH_1):VR_P1V05_PCH_STBY_PH1_VCIN
   2 P5V_STBY      B @BASEBOARD_FAB2_LIB.BASEBOARD_FAB2(SCH_1):P5V_STBY

INDUCTOR_SM-0.3UH,IND,D92183-0A  I45  L7A4
   1 VR_P1V05_PCH_STBY_PH1_PHASE_SW    INA @BASEBOARD_FAB2_LIB.BASEBOARD_FAB2(SCH_1):VR_P1V05_PCH_STBY_PH1_PHASE_SW
   2 P1V05_PCH_STBY    INB @BASEBOARD_FAB2_LIB.BASEBOARD_FAB2(SCH_1):P1V05_PCH_STBY

CAP_0805LF-22UF,4V,20%,X6S,C95A  I46  C7A42
   1 P1V05_PCH_STBY      A @BASEBOARD_FAB2_LIB.BASEBOARD_FAB2(SCH_1):P1V05_PCH_STBY
   2    GND      B @BASEBOARD_FAB2_LIB.BASEBOARD_FAB2(SCH_1):GND

RES_0402-0.0,5%,1/16W,CHIP,G21A  I56  R8B14
   1 VSENSE_P1V05_PCH_STBY_AVSP      A @BASEBOARD_FAB2_LIB.BASEBOARD_FAB2(SCH_1):VSENSE_P1V05_PCH_STBY_AVSP
   2 P1V05_PCH_STBY      B @BASEBOARD_FAB2_LIB.BASEBOARD_FAB2(SCH_1):P1V05_PCH_STBY

RES_0402-100.0,1%,1/16W,EMPTY,A  I57  R8B15
   1 VSENSE_P1V05_PCH_STBY_AVSP      A @BASEBOARD_FAB2_LIB.BASEBOARD_FAB2(SCH_1):VSENSE_P1V05_PCH_STBY_AVSP
   2 VSENSE_P1V05_PCH_STBY_AVSN      B @BASEBOARD_FAB2_LIB.BASEBOARD_FAB2(SCH_1):VSENSE_P1V05_PCH_STBY_AVSN

RES_0402-0.0,5%,1/16W,CHIP,G21A  I59  R8B12
   1 VSENSE_P1V05_PCH_STBY_AVSN      A @BASEBOARD_FAB2_LIB.BASEBOARD_FAB2(SCH_1):VSENSE_P1V05_PCH_STBY_AVSN
   2    GND      B @BASEBOARD_FAB2_LIB.BASEBOARD_FAB2(SCH_1):GND

CAP_1210-100UF,16V,20%,X5R,644A  I63  C7A13
   1 VR_FET_SW_P12V_STBY_PVDDQ_DEF      A @BASEBOARD_FAB2_LIB.BASEBOARD_FAB2(SCH_1):VR_FET_SW_P12V_STBY_PVDDQ_DEF
   2    GND      B @BASEBOARD_FAB2_LIB.BASEBOARD_FAB2(SCH_1):GND

CAP_1210-100UF,16V,20%,X5R,644A  I65  C7A14
   1 VR_FET_SW_P12V_STBY_PVDDQ_DEF      A @BASEBOARD_FAB2_LIB.BASEBOARD_FAB2(SCH_1):VR_FET_SW_P12V_STBY_PVDDQ_DEF
   2    GND      B @BASEBOARD_FAB2_LIB.BASEBOARD_FAB2(SCH_1):GND

CAPP_SM-470UF,2V,20%,ALUM,6990A  I71  C3L18
   1 PVNN_PCH_STBY      A @BASEBOARD_FAB2_LIB.BASEBOARD_FAB2(SCH_1):PVNN_PCH_STBY
   2    GND      B @BASEBOARD_FAB2_LIB.BASEBOARD_FAB2(SCH_1):GND

CAPP_SM-470UF,2V,20%,ALUM,6990A  I73  C3L20
   1 PVNN_PCH_STBY      A @BASEBOARD_FAB2_LIB.BASEBOARD_FAB2(SCH_1):PVNN_PCH_STBY
   2    GND      B @BASEBOARD_FAB2_LIB.BASEBOARD_FAB2(SCH_1):GND

CAPP_SM-470UF,2V,20%,ALUM,6990A  I74  C3L21
   1 PVNN_PCH_STBY      A @BASEBOARD_FAB2_LIB.BASEBOARD_FAB2(SCH_1):PVNN_PCH_STBY
   2    GND      B @BASEBOARD_FAB2_LIB.BASEBOARD_FAB2(SCH_1):GND

CAPP_SM-470UF,2V,20%,ALUM,6990A  I75  C7A27
   1 PVNN_PCH_STBY      A @BASEBOARD_FAB2_LIB.BASEBOARD_FAB2(SCH_1):PVNN_PCH_STBY
   2    GND      B @BASEBOARD_FAB2_LIB.BASEBOARD_FAB2(SCH_1):GND

CAPP_SM-470UF,2V,20%,ALUM,6990A  I76  C3L19
   1 P1V05_PCH_STBY      A @BASEBOARD_FAB2_LIB.BASEBOARD_FAB2(SCH_1):P1V05_PCH_STBY
   2    GND      B @BASEBOARD_FAB2_LIB.BASEBOARD_FAB2(SCH_1):GND

CAPP_SM-470UF,2V,20%,ALUM,6990A  I77  C2L46
   1 P1V05_PCH_STBY      A @BASEBOARD_FAB2_LIB.BASEBOARD_FAB2(SCH_1):P1V05_PCH_STBY
   2    GND      B @BASEBOARD_FAB2_LIB.BASEBOARD_FAB2(SCH_1):GND

CAPP_SM-470UF,2V,20%,ALUM,6990A  I78  C8A15
   1 P1V05_PCH_STBY      A @BASEBOARD_FAB2_LIB.BASEBOARD_FAB2(SCH_1):P1V05_PCH_STBY
   2    GND      B @BASEBOARD_FAB2_LIB.BASEBOARD_FAB2(SCH_1):GND

CAPP_SM-470UF,2V,20%,ALUM,6990A  I79  C2L25
   1 P1V05_PCH_STBY      A @BASEBOARD_FAB2_LIB.BASEBOARD_FAB2(SCH_1):P1V05_PCH_STBY
   2    GND      B @BASEBOARD_FAB2_LIB.BASEBOARD_FAB2(SCH_1):GND

RES_0402-100.0,1%,1/16W,CHIP,GA  I90  R7A13
   1 VSENSE_PVNN_PCH_STBY_AVSP      A @BASEBOARD_FAB2_LIB.BASEBOARD_FAB2(SCH_1):VSENSE_PVNN_PCH_STBY_AVSP
   2 PVNN_PCH_STBY      B @BASEBOARD_FAB2_LIB.BASEBOARD_FAB2(SCH_1):PVNN_PCH_STBY

RES_0402-0.0,5%,1/16W,CHIP,G21A  I92  R7A18
   1    GND      A @BASEBOARD_FAB2_LIB.BASEBOARD_FAB2(SCH_1):GND
   2 VSENSE_PVNN_PCH_STBY_AVSN      B @BASEBOARD_FAB2_LIB.BASEBOARD_FAB2(SCH_1):VSENSE_PVNN_PCH_STBY_AVSN

RES_0402-10.0,1%,1/16W,CHIP,G2A  I93  R7A19
   1 VSENSE_PVNN_PCH_STBY_QAT      A @BASEBOARD_FAB2_LIB.BASEBOARD_FAB2(SCH_1):VSENSE_PVNN_PCH_STBY_QAT
   2 VSENSE_PVNN_PCH_STBY_AVSP      B @BASEBOARD_FAB2_LIB.BASEBOARD_FAB2(SCH_1):VSENSE_PVNN_PCH_STBY_AVSP

RES_0402-10.0,1%,1/16W,CHIP,G2A  I94  R7A14
   1 VSENSE_PVNN_PCH_STBY_FPK      A @BASEBOARD_FAB2_LIB.BASEBOARD_FAB2(SCH_1):VSENSE_PVNN_PCH_STBY_FPK
   2 VSENSE_PVNN_PCH_STBY_AVSP      B @BASEBOARD_FAB2_LIB.BASEBOARD_FAB2(SCH_1):VSENSE_PVNN_PCH_STBY_AVSP

IR354XX_SM-IR35412,IC,H73684-0A  I116  EU7A3
  33 VR_PVNN_PCH_PH1_BOOT_R  BOOST @BASEBOARD_FAB2_LIB.BASEBOARD_FAB2(SCH_1):VR_PVNN_PCH_PH1_BOOT_R
  35 P5V_STBY     EN @BASEBOARD_FAB2_LIB.BASEBOARD_FAB2(SCH_1):P5V_STBY
  41 TP_PVNN_PCH_GL_1  GL<1> @BASEBOARD_FAB2_LIB.BASEBOARD_FAB2(SCH_1):TP_PVNN_PCH_GL_1
   6 TP_PVNN_PCH_GL_0  GL<0> @BASEBOARD_FAB2_LIB.BASEBOARD_FAB2(SCH_1):TP_PVNN_PCH_GL_0
  38 ISENSE_PVNN_PCH_PH1_IMON   IOUT @BASEBOARD_FAB2_LIB.BASEBOARD_FAB2(SCH_1):ISENSE_PVNN_PCH_PH1_IMON
   2    GND   LGND @BASEBOARD_FAB2_LIB.BASEBOARD_FAB2(SCH_1):GND
  31 NC_PVNN_PCH_PH1_P31     NC @BASEBOARD_FAB2_LIB.BASEBOARD_FAB2(SCH_1):NC_PVNN_PCH_PH1_P31
  37 VR_PVNN_PCH_STBY_OCSET  OCSET @BASEBOARD_FAB2_LIB.BASEBOARD_FAB2(SCH_1):VR_PVNN_PCH_STBY_OCSET
  40    GND PGND<2> @BASEBOARD_FAB2_LIB.BASEBOARD_FAB2(SCH_1):GND
   7    GND PGND<1> @BASEBOARD_FAB2_LIB.BASEBOARD_FAB2(SCH_1):GND
   5    GND PGND<0> @BASEBOARD_FAB2_LIB.BASEBOARD_FAB2(SCH_1):GND
  32 VR_PVNN_PCH_PH1_PHASE  PHASE @BASEBOARD_FAB2_LIB.BASEBOARD_FAB2(SCH_1):VR_PVNN_PCH_PH1_PHASE
  34 VR_PVNN_PCH_PWM1    PWM @BASEBOARD_FAB2_LIB.BASEBOARD_FAB2(SCH_1):VR_PVNN_PCH_PWM1
  39 VR_PVNN_PCH_AIREF1  REFIN @BASEBOARD_FAB2_LIB.BASEBOARD_FAB2(SCH_1):VR_PVNN_PCH_AIREF1
  10 VR_PVNN_PCH_PH1_PHASE_SW     SW @BASEBOARD_FAB2_LIB.BASEBOARD_FAB2(SCH_1):VR_PVNN_PCH_PH1_PHASE_SW
  36 A_TSENSE_PVNN_PCH_TMON TOUT_FLT @BASEBOARD_FAB2_LIB.BASEBOARD_FAB2(SCH_1):A_TSENSE_PVNN_PCH_TMON
   3 VR_PVNN_PCH_PH1_VCIN    VCC @BASEBOARD_FAB2_LIB.BASEBOARD_FAB2(SCH_1):VR_PVNN_PCH_PH1_VCIN
   4 P5V_STBY   VDRV @BASEBOARD_FAB2_LIB.BASEBOARD_FAB2(SCH_1):P5V_STBY
  30 VR_FET_SW_P12V_STBY_PVDDQ_DEF VIN<1> @BASEBOARD_FAB2_LIB.BASEBOARD_FAB2(SCH_1):VR_FET_SW_P12V_STBY_PVDDQ_DEF
  25 VR_FET_SW_P12V_STBY_PVDDQ_DEF VIN<0> @BASEBOARD_FAB2_LIB.BASEBOARD_FAB2(SCH_1):VR_FET_SW_P12V_STBY_PVDDQ_DEF
   1 PVNN_PCH_STBY    VOS @BASEBOARD_FAB2_LIB.BASEBOARD_FAB2(SCH_1):PVNN_PCH_STBY

IR354XX_SM-IR35412,IC,H73684-0A  I117  EU7A2
  33 VR_P1V05_PCH_STBY_PH1_BOOT_R  BOOST @BASEBOARD_FAB2_LIB.BASEBOARD_FAB2(SCH_1):VR_P1V05_PCH_STBY_PH1_BOOT_R
  35 P5V_STBY     EN @BASEBOARD_FAB2_LIB.BASEBOARD_FAB2(SCH_1):P5V_STBY
  41 TP_P1V05_PCH_GL_1  GL<1> @BASEBOARD_FAB2_LIB.BASEBOARD_FAB2(SCH_1):TP_P1V05_PCH_GL_1
   6 TP_P1V05_PCH_GL_0  GL<0> @BASEBOARD_FAB2_LIB.BASEBOARD_FAB2(SCH_1):TP_P1V05_PCH_GL_0
  38 ISENSE_P1V05_PCH_STBY_PH1_IMON   IOUT @BASEBOARD_FAB2_LIB.BASEBOARD_FAB2(SCH_1):ISENSE_P1V05_PCH_STBY_PH1_IMON
   2    GND   LGND @BASEBOARD_FAB2_LIB.BASEBOARD_FAB2(SCH_1):GND
  31 NC_P1V05_PCH_STBY_PH1_P31     NC @BASEBOARD_FAB2_LIB.BASEBOARD_FAB2(SCH_1):NC_P1V05_PCH_STBY_PH1_P31
  37 VR_P1V05_PCH_STBY_OCSET  OCSET @BASEBOARD_FAB2_LIB.BASEBOARD_FAB2(SCH_1):VR_P1V05_PCH_STBY_OCSET
  40    GND PGND<2> @BASEBOARD_FAB2_LIB.BASEBOARD_FAB2(SCH_1):GND
   7    GND PGND<1> @BASEBOARD_FAB2_LIB.BASEBOARD_FAB2(SCH_1):GND
   5    GND PGND<0> @BASEBOARD_FAB2_LIB.BASEBOARD_FAB2(SCH_1):GND
  32 VR_P1V05_PCH_STBY_PH1_PHASE  PHASE @BASEBOARD_FAB2_LIB.BASEBOARD_FAB2(SCH_1):VR_P1V05_PCH_STBY_PH1_PHASE
  34 VR_P1V05_PCH_STBY_PWM1    PWM @BASEBOARD_FAB2_LIB.BASEBOARD_FAB2(SCH_1):VR_P1V05_PCH_STBY_PWM1
  39 VR_P1V05_PCH_BIREF1  REFIN @BASEBOARD_FAB2_LIB.BASEBOARD_FAB2(SCH_1):VR_P1V05_PCH_BIREF1
  10 VR_P1V05_PCH_STBY_PH1_PHASE_SW     SW @BASEBOARD_FAB2_LIB.BASEBOARD_FAB2(SCH_1):VR_P1V05_PCH_STBY_PH1_PHASE_SW
  36 A_TSENSE_P1V05_PCH_STBY_TMON TOUT_FLT @BASEBOARD_FAB2_LIB.BASEBOARD_FAB2(SCH_1):A_TSENSE_P1V05_PCH_STBY_TMON
   3 VR_P1V05_PCH_STBY_PH1_VCIN    VCC @BASEBOARD_FAB2_LIB.BASEBOARD_FAB2(SCH_1):VR_P1V05_PCH_STBY_PH1_VCIN
   4 P5V_STBY   VDRV @BASEBOARD_FAB2_LIB.BASEBOARD_FAB2(SCH_1):P5V_STBY
  30 VR_FET_SW_P12V_STBY_PVDDQ_DEF VIN<1> @BASEBOARD_FAB2_LIB.BASEBOARD_FAB2(SCH_1):VR_FET_SW_P12V_STBY_PVDDQ_DEF
  25 VR_FET_SW_P12V_STBY_PVDDQ_DEF VIN<0> @BASEBOARD_FAB2_LIB.BASEBOARD_FAB2(SCH_1):VR_FET_SW_P12V_STBY_PVDDQ_DEF
   1 P1V05_PCH_STBY    VOS @BASEBOARD_FAB2_LIB.BASEBOARD_FAB2(SCH_1):P1V05_PCH_STBY

RES_0402-68.1K,1%,1/16W,EMPTY,A  I118  R3L15
   1 VR_PVNN_PCH_STBY_OCSET      A @BASEBOARD_FAB2_LIB.BASEBOARD_FAB2(SCH_1):VR_PVNN_PCH_STBY_OCSET
   2    GND      B @BASEBOARD_FAB2_LIB.BASEBOARD_FAB2(SCH_1):GND

RES_0402-68.1K,1%,1/16W,EMPTY,A  I120  R3L14
   1 VR_P1V05_PCH_STBY_OCSET      A @BASEBOARD_FAB2_LIB.BASEBOARD_FAB2(SCH_1):VR_P1V05_PCH_STBY_OCSET
   2    GND      B @BASEBOARD_FAB2_LIB.BASEBOARD_FAB2(SCH_1):GND

CAP_A_0402V-0.1UF,16V,10%,X7R,A  I124  CT67
   1 VR_P1V05_PCH_BIREF1      A @BASEBOARD_FAB2_LIB.BASEBOARD_FAB2(SCH_1):VR_P1V05_PCH_BIREF1
   2    GND      B @BASEBOARD_FAB2_LIB.BASEBOARD_FAB2(SCH_1):GND

CAP_A_0402V-0.1UF,16V,10%,X7R,A  I127  CT66
   1 VR_PVNN_PCH_AIREF1      A @BASEBOARD_FAB2_LIB.BASEBOARD_FAB2(SCH_1):VR_PVNN_PCH_AIREF1
   2    GND      B @BASEBOARD_FAB2_LIB.BASEBOARD_FAB2(SCH_1):GND

SC2K2P50V3KX-GP_SMD-BCG6-SC2K2A  I131  CT65
   1 VR_PVNN_PCH_PH1_PHASE_SW      1 @BASEBOARD_FAB2_LIB.BASEBOARD_FAB2(SCH_1):VR_PVNN_PCH_PH1_PHASE_SW
   2 UNNAMED_236_3D01R5F-GP_I132_2      2 @BASEBOARD_FAB2_LIB.BASEBOARD_FAB2(SCH_1):UNNAMED_236_3D01R5F-GP_I132_2

CAP_0402LF-1000PF,50V,10%,X7R,A  I134  CT69
   1 A_TSENSE_P1V05_PCH_STBY_TMON      A @BASEBOARD_FAB2_LIB.BASEBOARD_FAB2(SCH_1):A_TSENSE_P1V05_PCH_STBY_TMON
   2    GND      B @BASEBOARD_FAB2_LIB.BASEBOARD_FAB2(SCH_1):GND

CAP_0402LF-1000PF,50V,10%,X7R,A  I136  CT64
   1 A_TSENSE_PVNN_PCH_TMON      A @BASEBOARD_FAB2_LIB.BASEBOARD_FAB2(SCH_1):A_TSENSE_PVNN_PCH_TMON
   2    GND      B @BASEBOARD_FAB2_LIB.BASEBOARD_FAB2(SCH_1):GND

SC2K2P50V3KX-GP_SMD-BCG6-SC2K2A  I140  CT68
   1 VR_P1V05_PCH_STBY_PH1_PHASE_SW      1 @BASEBOARD_FAB2_LIB.BASEBOARD_FAB2(SCH_1):VR_P1V05_PCH_STBY_PH1_PHASE_SW
   2 UNNAMED_236_3D01R5F-GP_I137_2      2 @BASEBOARD_FAB2_LIB.BASEBOARD_FAB2(SCH_1):UNNAMED_236_3D01R5F-GP_I137_2

3D01R5F-GP_SMD-RG5-3D01R5F-GP,A  I137  RT45
   1    GND      1 @BASEBOARD_FAB2_LIB.BASEBOARD_FAB2(SCH_1):GND
   2 UNNAMED_236_3D01R5F-GP_I137_2      2 @BASEBOARD_FAB2_LIB.BASEBOARD_FAB2(SCH_1):UNNAMED_236_3D01R5F-GP_I137_2

3D01R5F-GP_SMD-RG5-3D01R5F-GP,A  I132  RT43
   1    GND      1 @BASEBOARD_FAB2_LIB.BASEBOARD_FAB2(SCH_1):GND
   2 UNNAMED_236_3D01R5F-GP_I132_2      2 @BASEBOARD_FAB2_LIB.BASEBOARD_FAB2(SCH_1):UNNAMED_236_3D01R5F-GP_I132_2

RES_0402-0.0,5%,1/16W,CHIP,G21A  I141  RT44
   1 VR_PVNN_PCH_PH1_BOOT      A @BASEBOARD_FAB2_LIB.BASEBOARD_FAB2(SCH_1):VR_PVNN_PCH_PH1_BOOT
   2 VR_PVNN_PCH_PH1_BOOT_R      B @BASEBOARD_FAB2_LIB.BASEBOARD_FAB2(SCH_1):VR_PVNN_PCH_PH1_BOOT_R

RES_0402-0.0,5%,1/16W,CHIP,G21A  I142  RT46
   1 VR_P1V05_PCH_STBY_PH1_BOOT      A @BASEBOARD_FAB2_LIB.BASEBOARD_FAB2(SCH_1):VR_P1V05_PCH_STBY_PH1_BOOT
   2 VR_P1V05_PCH_STBY_PH1_BOOT_R      B @BASEBOARD_FAB2_LIB.BASEBOARD_FAB2(SCH_1):VR_P1V05_PCH_STBY_PH1_BOOT_R


DRAWING: @BASEBOARD_FAB2_LIB.BASEBOARD_FAB2(SCH_1):PAGE212 

CAPP_3018-470UF,2.5V,20%,ALUM,A  I16  C3N38
   1 PVCCIO_CPU0      A @BASEBOARD_FAB2_LIB.BASEBOARD_FAB2(SCH_1):PVCCIO_CPU0
   2    GND      B @BASEBOARD_FAB2_LIB.BASEBOARD_FAB2(SCH_1):GND

CAPP_3018-470UF,2.5V,20%,ALUM,A  I17  C3N26
   1 PVCCIO_CPU0      A @BASEBOARD_FAB2_LIB.BASEBOARD_FAB2(SCH_1):PVCCIO_CPU0
   2    GND      B @BASEBOARD_FAB2_LIB.BASEBOARD_FAB2(SCH_1):GND

CAPP_3018-470UF,2.5V,20%,ALUM,A  I18  C3N35
   1 PVCCIO_CPU0      A @BASEBOARD_FAB2_LIB.BASEBOARD_FAB2(SCH_1):PVCCIO_CPU0
   2    GND      B @BASEBOARD_FAB2_LIB.BASEBOARD_FAB2(SCH_1):GND

CAP_A_0603V-22.0UF,4V,20%,X6S,A  I23  C7C6
   1 PVCCIO_CPU0      A @BASEBOARD_FAB2_LIB.BASEBOARD_FAB2(SCH_1):PVCCIO_CPU0
   2    GND      B @BASEBOARD_FAB2_LIB.BASEBOARD_FAB2(SCH_1):GND

INDUCTOR_SM-150NH,IND,D92183-0A  I25  L7C2
   1 VR_PVCCIO_CPU0_PH1_SW    INA @BASEBOARD_FAB2_LIB.BASEBOARD_FAB2(SCH_1):VR_PVCCIO_CPU0_PH1_SW
   2 PVCCIO_CPU0    INB @BASEBOARD_FAB2_LIB.BASEBOARD_FAB2(SCH_1):PVCCIO_CPU0

RES_0402-1.0,1%,1/16W,CHIP,G21A  I32  R3N7
   1 VR_PVCCIO_CPU0_PH1_VCIN      A @BASEBOARD_FAB2_LIB.BASEBOARD_FAB2(SCH_1):VR_PVCCIO_CPU0_PH1_VCIN
   2 P5V_STBY      B @BASEBOARD_FAB2_LIB.BASEBOARD_FAB2(SCH_1):P5V_STBY

CAP_0402-0.22UF,16V,10%,X7R,A3A  I33  C7C18
   1 P5V_STBY      A @BASEBOARD_FAB2_LIB.BASEBOARD_FAB2(SCH_1):P5V_STBY
   2    GND      B @BASEBOARD_FAB2_LIB.BASEBOARD_FAB2(SCH_1):GND

CAP_A_0402V-1.0UF,6.3V,10%,X6SA  I34  C7C20
   1 P5V_STBY      A @BASEBOARD_FAB2_LIB.BASEBOARD_FAB2(SCH_1):P5V_STBY
   2    GND      B @BASEBOARD_FAB2_LIB.BASEBOARD_FAB2(SCH_1):GND

CAP_0402-1.0UF,16V,10%,X6S,D97A  I36  C7C17
   1 VR_PVCCIO_CPU0_PH1_VCIN      A @BASEBOARD_FAB2_LIB.BASEBOARD_FAB2(SCH_1):VR_PVCCIO_CPU0_PH1_VCIN
   2    GND      B @BASEBOARD_FAB2_LIB.BASEBOARD_FAB2(SCH_1):GND

CAP_0402-0.220UF,16V,10%,X7R,AA  I37  C7C14
   1 VR_PVCCIO_CPU0_PH1_BOOT      A @BASEBOARD_FAB2_LIB.BASEBOARD_FAB2(SCH_1):VR_PVCCIO_CPU0_PH1_BOOT
   2 VR_PVCCIO_CPU0_PH1_PHASE      B @BASEBOARD_FAB2_LIB.BASEBOARD_FAB2(SCH_1):VR_PVCCIO_CPU0_PH1_PHASE

CAP_A_0402V-0.1UF,16V,10%,X7R,A  I38  C7C11
   1 VR_FET_SW_P12V_STBY_PVCCIO_CPU0      A @BASEBOARD_FAB2_LIB.BASEBOARD_FAB2(SCH_1):VR_FET_SW_P12V_STBY_PVCCIO_CPU0
   2    GND      B @BASEBOARD_FAB2_LIB.BASEBOARD_FAB2(SCH_1):GND

CAP_0402-1.0UF,16V,10%,X6S,D97A  I39  C7C12
   1 VR_FET_SW_P12V_STBY_PVCCIO_CPU0      A @BASEBOARD_FAB2_LIB.BASEBOARD_FAB2(SCH_1):VR_FET_SW_P12V_STBY_PVCCIO_CPU0
   2    GND      B @BASEBOARD_FAB2_LIB.BASEBOARD_FAB2(SCH_1):GND

CAP_0805-10UF,16V,10%,X6S,C953A  I40  C3N36
   1 VR_FET_SW_P12V_STBY_PVCCIO_CPU0      A @BASEBOARD_FAB2_LIB.BASEBOARD_FAB2(SCH_1):VR_FET_SW_P12V_STBY_PVCCIO_CPU0
   2    GND      B @BASEBOARD_FAB2_LIB.BASEBOARD_FAB2(SCH_1):GND

CAP_0805-10UF,16V,10%,X6S,C953A  I41  C3N33
   1 VR_FET_SW_P12V_STBY_PVCCIO_CPU0      A @BASEBOARD_FAB2_LIB.BASEBOARD_FAB2(SCH_1):VR_FET_SW_P12V_STBY_PVCCIO_CPU0
   2    GND      B @BASEBOARD_FAB2_LIB.BASEBOARD_FAB2(SCH_1):GND

CAP_0805-10UF,16V,10%,X6S,C953A  I43  C3N34
   1 VR_FET_SW_P12V_STBY_PVCCIO_CPU0      A @BASEBOARD_FAB2_LIB.BASEBOARD_FAB2(SCH_1):VR_FET_SW_P12V_STBY_PVCCIO_CPU0
   2    GND      B @BASEBOARD_FAB2_LIB.BASEBOARD_FAB2(SCH_1):GND

CAP_1210-100UF,16V,20%,X5R,644A  I51  C7C8
   1 VR_FET_SW_P12V_STBY_PVCCIO_CPU0      A @BASEBOARD_FAB2_LIB.BASEBOARD_FAB2(SCH_1):VR_FET_SW_P12V_STBY_PVCCIO_CPU0
   2    GND      B @BASEBOARD_FAB2_LIB.BASEBOARD_FAB2(SCH_1):GND

CAP_1210-100UF,16V,20%,X5R,644A  I54  C7C7
   1 VR_FET_SW_P12V_STBY_PVCCIO_CPU0      A @BASEBOARD_FAB2_LIB.BASEBOARD_FAB2(SCH_1):VR_FET_SW_P12V_STBY_PVCCIO_CPU0
   2    GND      B @BASEBOARD_FAB2_LIB.BASEBOARD_FAB2(SCH_1):GND

INDUCTOR_SM-100NH,IND,D92183-0B  I56  L7C1
   1 P12V_STBY    INA @BASEBOARD_FAB2_LIB.BASEBOARD_FAB2(SCH_1):P12V_STBY
   2 VR_FET_SW_P12V_STBY_PVCCIO_CPU0    INB @BASEBOARD_FAB2_LIB.BASEBOARD_FAB2(SCH_1):VR_FET_SW_P12V_STBY_PVCCIO_CPU0

CAP_A_0402V-0.1UF,16V,10%,EMPTA  I60  C3P1
   1 VSENSE_PVCCIO_CPU0_SKT_VSEN      A @BASEBOARD_FAB2_LIB.BASEBOARD_FAB2(SCH_1):VSENSE_PVCCIO_CPU0_SKT_VSEN
   2 VSENSE_PVCCIO_CPU0_SKT_VRTN      B @BASEBOARD_FAB2_LIB.BASEBOARD_FAB2(SCH_1):VSENSE_PVCCIO_CPU0_SKT_VRTN

RES_0402-100.0,1%,1/16W,CHIP,GA  I68  R3N20
   1 VSENSE_PVCCIO_CPU0_AVSN      A @BASEBOARD_FAB2_LIB.BASEBOARD_FAB2(SCH_1):VSENSE_PVCCIO_CPU0_AVSN
   2    GND      B @BASEBOARD_FAB2_LIB.BASEBOARD_FAB2(SCH_1):GND

RES_0402-100.0,1%,1/16W,CHIP,GA  I74  R3N21
   1 VSENSE_PVCCIO_CPU0_AVSP      A @BASEBOARD_FAB2_LIB.BASEBOARD_FAB2(SCH_1):VSENSE_PVCCIO_CPU0_AVSP
   2 PVCCIO_CPU0      B @BASEBOARD_FAB2_LIB.BASEBOARD_FAB2(SCH_1):PVCCIO_CPU0

CAP_A_0603V-22.0UF,4V,20%,X6S,A  I77  C7C10
   1 PVCCIO_CPU0      A @BASEBOARD_FAB2_LIB.BASEBOARD_FAB2(SCH_1):PVCCIO_CPU0
   2    GND      B @BASEBOARD_FAB2_LIB.BASEBOARD_FAB2(SCH_1):GND

RES_0402-51.1,1.0%,1/16W,CHIP,A  I78  R7C3
   1 PVCCIO_CPU0      A @BASEBOARD_FAB2_LIB.BASEBOARD_FAB2(SCH_1):PVCCIO_CPU0
   2    GND      B @BASEBOARD_FAB2_LIB.BASEBOARD_FAB2(SCH_1):GND

IR354XX_SM-IR35412,IC,H73684-0A  I101  EU7C1
  33 VR_PVCCIO_CPU0_PH1_BOOT_R  BOOST @BASEBOARD_FAB2_LIB.BASEBOARD_FAB2(SCH_1):VR_PVCCIO_CPU0_PH1_BOOT_R
  35 P5V_STBY     EN @BASEBOARD_FAB2_LIB.BASEBOARD_FAB2(SCH_1):P5V_STBY
  41 TP_PVCCIO_CPU0_GL_1  GL<1> @BASEBOARD_FAB2_LIB.BASEBOARD_FAB2(SCH_1):TP_PVCCIO_CPU0_GL_1
   6 TP_PVCCIO_CPU0_GL_0  GL<0> @BASEBOARD_FAB2_LIB.BASEBOARD_FAB2(SCH_1):TP_PVCCIO_CPU0_GL_0
  38 ISENSE_PVCCIO_CPU0_PH1_IMON   IOUT @BASEBOARD_FAB2_LIB.BASEBOARD_FAB2(SCH_1):ISENSE_PVCCIO_CPU0_PH1_IMON
   2    GND   LGND @BASEBOARD_FAB2_LIB.BASEBOARD_FAB2(SCH_1):GND
  31 NC_PVCCIO_CPU0_PH1_P31     NC @BASEBOARD_FAB2_LIB.BASEBOARD_FAB2(SCH_1):NC_PVCCIO_CPU0_PH1_P31
  37 VR_PVCCIO_CPU0_OCSET  OCSET @BASEBOARD_FAB2_LIB.BASEBOARD_FAB2(SCH_1):VR_PVCCIO_CPU0_OCSET
  40    GND PGND<2> @BASEBOARD_FAB2_LIB.BASEBOARD_FAB2(SCH_1):GND
   7    GND PGND<1> @BASEBOARD_FAB2_LIB.BASEBOARD_FAB2(SCH_1):GND
   5    GND PGND<0> @BASEBOARD_FAB2_LIB.BASEBOARD_FAB2(SCH_1):GND
  32 VR_PVCCIO_CPU0_PH1_PHASE  PHASE @BASEBOARD_FAB2_LIB.BASEBOARD_FAB2(SCH_1):VR_PVCCIO_CPU0_PH1_PHASE
  34 VR_PVCCIO_CPU0_PWM1    PWM @BASEBOARD_FAB2_LIB.BASEBOARD_FAB2(SCH_1):VR_PVCCIO_CPU0_PWM1
  39 VR_PVCCIO_CPU0_AIREF1  REFIN @BASEBOARD_FAB2_LIB.BASEBOARD_FAB2(SCH_1):VR_PVCCIO_CPU0_AIREF1
  10 VR_PVCCIO_CPU0_PH1_SW     SW @BASEBOARD_FAB2_LIB.BASEBOARD_FAB2(SCH_1):VR_PVCCIO_CPU0_PH1_SW
  36 A_TSENSE_PVCCIO_CPU0 TOUT_FLT @BASEBOARD_FAB2_LIB.BASEBOARD_FAB2(SCH_1):A_TSENSE_PVCCIO_CPU0
   3 VR_PVCCIO_CPU0_PH1_VCIN    VCC @BASEBOARD_FAB2_LIB.BASEBOARD_FAB2(SCH_1):VR_PVCCIO_CPU0_PH1_VCIN
   4 P5V_STBY   VDRV @BASEBOARD_FAB2_LIB.BASEBOARD_FAB2(SCH_1):P5V_STBY
  30 VR_FET_SW_P12V_STBY_PVCCIO_CPU0 VIN<1> @BASEBOARD_FAB2_LIB.BASEBOARD_FAB2(SCH_1):VR_FET_SW_P12V_STBY_PVCCIO_CPU0
  25 VR_FET_SW_P12V_STBY_PVCCIO_CPU0 VIN<0> @BASEBOARD_FAB2_LIB.BASEBOARD_FAB2(SCH_1):VR_FET_SW_P12V_STBY_PVCCIO_CPU0
   1 PVCCIO_CPU0    VOS @BASEBOARD_FAB2_LIB.BASEBOARD_FAB2(SCH_1):PVCCIO_CPU0

RES_0402-68.1K,1%,1/16W,EMPTY,A  I103  R7C25
   1 VR_PVCCIO_CPU0_OCSET      A @BASEBOARD_FAB2_LIB.BASEBOARD_FAB2(SCH_1):VR_PVCCIO_CPU0_OCSET
   2    GND      B @BASEBOARD_FAB2_LIB.BASEBOARD_FAB2(SCH_1):GND

SHUNT_SH0201-EMPTY,N_A  I104  SH3P1
   1 VSENSE_PVCCIO_CPU0_SKT_VSEN      A @BASEBOARD_FAB2_LIB.BASEBOARD_FAB2(SCH_1):VSENSE_PVCCIO_CPU0_SKT_VSEN
   2 VSENSE_PVCCIO_CPU0_AVSP      B @BASEBOARD_FAB2_LIB.BASEBOARD_FAB2(SCH_1):VSENSE_PVCCIO_CPU0_AVSP

SHUNT_SH0201-EMPTY,N_A  I105  SH3P2
   1 VSENSE_PVCCIO_CPU0_SKT_VRTN      A @BASEBOARD_FAB2_LIB.BASEBOARD_FAB2(SCH_1):VSENSE_PVCCIO_CPU0_SKT_VRTN
   2 VSENSE_PVCCIO_CPU0_AVSN      B @BASEBOARD_FAB2_LIB.BASEBOARD_FAB2(SCH_1):VSENSE_PVCCIO_CPU0_AVSN

CAP_A_0402V-0.1UF,16V,10%,X7R,A  I106  CT70
   1 VR_PVCCIO_CPU0_AIREF1      A @BASEBOARD_FAB2_LIB.BASEBOARD_FAB2(SCH_1):VR_PVCCIO_CPU0_AIREF1
   2    GND      B @BASEBOARD_FAB2_LIB.BASEBOARD_FAB2(SCH_1):GND

CAP_0402LF-1000PF,50V,10%,X7R,A  I109  CT71
   1 A_TSENSE_PVCCIO_CPU0      A @BASEBOARD_FAB2_LIB.BASEBOARD_FAB2(SCH_1):A_TSENSE_PVCCIO_CPU0
   2    GND      B @BASEBOARD_FAB2_LIB.BASEBOARD_FAB2(SCH_1):GND

SC2K2P50V3KX-GP_SMD-BCG6-SC2K2A  I111  CT72
   1 VR_PVCCIO_CPU0_PH1_SW      1 @BASEBOARD_FAB2_LIB.BASEBOARD_FAB2(SCH_1):VR_PVCCIO_CPU0_PH1_SW
   2 UNNAMED_212_3D01R5F-GP_I112_2      2 @BASEBOARD_FAB2_LIB.BASEBOARD_FAB2(SCH_1):UNNAMED_212_3D01R5F-GP_I112_2

3D01R5F-GP_SMD-RG5-3D01R5F-GP,A  I112  RT48
   1    GND      1 @BASEBOARD_FAB2_LIB.BASEBOARD_FAB2(SCH_1):GND
   2 UNNAMED_212_3D01R5F-GP_I112_2      2 @BASEBOARD_FAB2_LIB.BASEBOARD_FAB2(SCH_1):UNNAMED_212_3D01R5F-GP_I112_2

RES_0402-0.0,5%,1/16W,CHIP,G21A  I114  RT47
   1 VR_PVCCIO_CPU0_PH1_BOOT      A @BASEBOARD_FAB2_LIB.BASEBOARD_FAB2(SCH_1):VR_PVCCIO_CPU0_PH1_BOOT
   2 VR_PVCCIO_CPU0_PH1_BOOT_R      B @BASEBOARD_FAB2_LIB.BASEBOARD_FAB2(SCH_1):VR_PVCCIO_CPU0_PH1_BOOT_R


DRAWING: @BASEBOARD_FAB2_LIB.BASEBOARD_FAB2(SCH_1):PAGE239 

CAP_0402LF-1000PF,50V,10%,X7R,A  I4  C9F10
   1 PWRGD_P1V538_BMC_STBY_R      A @BASEBOARD_FAB2_LIB.BASEBOARD_FAB2(SCH_1):PWRGD_P1V538_BMC_STBY_R
   2    GND      B @BASEBOARD_FAB2_LIB.BASEBOARD_FAB2(SCH_1):GND

RES_0402-10.0K,1%,1/16W,CHIP,GA  I6  R9F12
   1 P3V3_STBY      A @BASEBOARD_FAB2_LIB.BASEBOARD_FAB2(SCH_1):P3V3_STBY
   2 PWRGD_P1V538_BMC_STBY_R      B @BASEBOARD_FAB2_LIB.BASEBOARD_FAB2(SCH_1):PWRGD_P1V538_BMC_STBY_R

CAP_0805LF-22UF,4V,20%,X6S,C95A  I7  C9F13
   1 P1V2_AUX_BMC      A @BASEBOARD_FAB2_LIB.BASEBOARD_FAB2(SCH_1):P1V2_AUX_BMC
   2    GND      B @BASEBOARD_FAB2_LIB.BASEBOARD_FAB2(SCH_1):GND

CAP_0603-10UF,6.3V,20%,X6S,E15A  I12  C1T15
   1 P1V2_AUX_BMC      A @BASEBOARD_FAB2_LIB.BASEBOARD_FAB2(SCH_1):P1V2_AUX_BMC
   2    GND      B @BASEBOARD_FAB2_LIB.BASEBOARD_FAB2(SCH_1):GND

RES_0402-13K,1.0%,1/16W,CHIP,GA  I15  R9F32
   1    GND      A @BASEBOARD_FAB2_LIB.BASEBOARD_FAB2(SCH_1):GND
   2 VR_P1V538_BMC_STBY_FB      B @BASEBOARD_FAB2_LIB.BASEBOARD_FAB2(SCH_1):VR_P1V538_BMC_STBY_FB

CAP_0603-10UF,6.3V,20%,X6S,E15A  I22  C1T7
   1 P3V3_STBY      A @BASEBOARD_FAB2_LIB.BASEBOARD_FAB2(SCH_1):P3V3_STBY
   2    GND      B @BASEBOARD_FAB2_LIB.BASEBOARD_FAB2(SCH_1):GND

CAP_0402LF-1000PF,50V,10%,EMPTA  I30  C9F6
   1 PWRGD_P3V3_STBY      A @BASEBOARD_FAB2_LIB.BASEBOARD_FAB2(SCH_1):PWRGD_P3V3_STBY
   2    GND      B @BASEBOARD_FAB2_LIB.BASEBOARD_FAB2(SCH_1):GND

RT9059_DFN-IC,H65765-001  I70  EU9F2
   4 VR_P1V538_BMC_STBY_FB ADJ_NC @BASEBOARD_FAB2_LIB.BASEBOARD_FAB2(SCH_1):VR_P1V538_BMC_STBY_FB
   6 PWRGD_P3V3_STBY     EN @BASEBOARD_FAB2_LIB.BASEBOARD_FAB2(SCH_1):PWRGD_P3V3_STBY
  11    GND    GND @BASEBOARD_FAB2_LIB.BASEBOARD_FAB2(SCH_1):GND
   5 PWRGD_P1V538_BMC_STBY_R  PGOOD @BASEBOARD_FAB2_LIB.BASEBOARD_FAB2(SCH_1):PWRGD_P1V538_BMC_STBY_R
  10 P3V3_STBY    VDD @BASEBOARD_FAB2_LIB.BASEBOARD_FAB2(SCH_1):P3V3_STBY
   9 P3V3_STBY VIN<2> @BASEBOARD_FAB2_LIB.BASEBOARD_FAB2(SCH_1):P3V3_STBY
   8 P3V3_STBY VIN<1> @BASEBOARD_FAB2_LIB.BASEBOARD_FAB2(SCH_1):P3V3_STBY
   7 P3V3_STBY VIN<0> @BASEBOARD_FAB2_LIB.BASEBOARD_FAB2(SCH_1):P3V3_STBY
   3 P1V2_AUX_BMC VOUT<2> @BASEBOARD_FAB2_LIB.BASEBOARD_FAB2(SCH_1):P1V2_AUX_BMC
   2 P1V2_AUX_BMC VOUT<1> @BASEBOARD_FAB2_LIB.BASEBOARD_FAB2(SCH_1):P1V2_AUX_BMC
   1 P1V2_AUX_BMC VOUT<0> @BASEBOARD_FAB2_LIB.BASEBOARD_FAB2(SCH_1):P1V2_AUX_BMC

CAP_A_0402V-0.1UF,16V,10%,X7R,A  I71  C9F5
   1 P3V3_STBY      A @BASEBOARD_FAB2_LIB.BASEBOARD_FAB2(SCH_1):P3V3_STBY
   2    GND      B @BASEBOARD_FAB2_LIB.BASEBOARD_FAB2(SCH_1):GND

RES_0402-22.1,1.0%,1/16W,CHIP,A  I72  R1T9
   1 PWRGD_P1V538_BMC_STBY_R      A @BASEBOARD_FAB2_LIB.BASEBOARD_FAB2(SCH_1):PWRGD_P1V538_BMC_STBY_R
   2 PWRGD_P1V538_BMC_STBY      B @BASEBOARD_FAB2_LIB.BASEBOARD_FAB2(SCH_1):PWRGD_P1V538_BMC_STBY

RT9059_DFN-IC,H65765-001  I73  EU25F2
   4 UNNAMED_239_21K5R2F-GP_I99_2 ADJ_NC @BASEBOARD_FAB2_LIB.BASEBOARD_FAB2(SCH_1):UNNAMED_239_21K5R2F-GP_I99_2
   6 UNNAMED_239_CAP_I91_A     EN @BASEBOARD_FAB2_LIB.BASEBOARD_FAB2(SCH_1):UNNAMED_239_CAP_I91_A
  11    GND    GND @BASEBOARD_FAB2_LIB.BASEBOARD_FAB2(SCH_1):GND
   5 UNNAMED_239_CAP_I84_A  PGOOD @BASEBOARD_FAB2_LIB.BASEBOARD_FAB2(SCH_1):UNNAMED_239_CAP_I84_A
  10 P3V3_STBY    VDD @BASEBOARD_FAB2_LIB.BASEBOARD_FAB2(SCH_1):P3V3_STBY
   9 P3V3_STBY VIN<2> @BASEBOARD_FAB2_LIB.BASEBOARD_FAB2(SCH_1):P3V3_STBY
   8 P3V3_STBY VIN<1> @BASEBOARD_FAB2_LIB.BASEBOARD_FAB2(SCH_1):P3V3_STBY
   7 P3V3_STBY VIN<0> @BASEBOARD_FAB2_LIB.BASEBOARD_FAB2(SCH_1):P3V3_STBY
   3 P2V5_AUX_BMC VOUT<2> @BASEBOARD_FAB2_LIB.BASEBOARD_FAB2(SCH_1):P2V5_AUX_BMC
   2 P2V5_AUX_BMC VOUT<1> @BASEBOARD_FAB2_LIB.BASEBOARD_FAB2(SCH_1):P2V5_AUX_BMC
   1 P2V5_AUX_BMC VOUT<0> @BASEBOARD_FAB2_LIB.BASEBOARD_FAB2(SCH_1):P2V5_AUX_BMC

RES_0402-22.1,1.0%,1/16W,CHIP,A  I77  R1W9
   1 UNNAMED_239_CAP_I84_A      A @BASEBOARD_FAB2_LIB.BASEBOARD_FAB2(SCH_1):UNNAMED_239_CAP_I84_A
   2 UNNAMED_239_OFFPAGE_I76_A      B @BASEBOARD_FAB2_LIB.BASEBOARD_FAB2(SCH_1):UNNAMED_239_OFFPAGE_I76_A

RES_0402-10.0K,1%,1/16W,CHIP,GA  I79  R9W12
   1 P3V3_STBY      A @BASEBOARD_FAB2_LIB.BASEBOARD_FAB2(SCH_1):P3V3_STBY
   2 UNNAMED_239_CAP_I84_A      B @BASEBOARD_FAB2_LIB.BASEBOARD_FAB2(SCH_1):UNNAMED_239_CAP_I84_A

CAP_0805LF-22UF,4V,20%,X6S,C95A  I81  C9W13
   1 P2V5_AUX_BMC      A @BASEBOARD_FAB2_LIB.BASEBOARD_FAB2(SCH_1):P2V5_AUX_BMC
   2    GND      B @BASEBOARD_FAB2_LIB.BASEBOARD_FAB2(SCH_1):GND

CAP_0603-10UF,6.3V,20%,X6S,E15A  I83  C1W15
   1 P2V5_AUX_BMC      A @BASEBOARD_FAB2_LIB.BASEBOARD_FAB2(SCH_1):P2V5_AUX_BMC
   2    GND      B @BASEBOARD_FAB2_LIB.BASEBOARD_FAB2(SCH_1):GND

CAP_0402LF-1000PF,50V,10%,X7R,A  I84  C9W10
   1 UNNAMED_239_CAP_I84_A      A @BASEBOARD_FAB2_LIB.BASEBOARD_FAB2(SCH_1):UNNAMED_239_CAP_I84_A
   2    GND      B @BASEBOARD_FAB2_LIB.BASEBOARD_FAB2(SCH_1):GND

RES_0402-13K,1.0%,1/16W,CHIP,GA  I87  R9W32
   1    GND      A @BASEBOARD_FAB2_LIB.BASEBOARD_FAB2(SCH_1):GND
   2 UNNAMED_239_21K5R2F-GP_I99_2      B @BASEBOARD_FAB2_LIB.BASEBOARD_FAB2(SCH_1):UNNAMED_239_21K5R2F-GP_I99_2

CAP_A_0402V-0.1UF,16V,10%,X7R,A  I90  C9W5
   1 P3V3_STBY      A @BASEBOARD_FAB2_LIB.BASEBOARD_FAB2(SCH_1):P3V3_STBY
   2    GND      B @BASEBOARD_FAB2_LIB.BASEBOARD_FAB2(SCH_1):GND

CAP_0402LF-1000PF,50V,10%,EMPTA  I91  C9W6
   1 UNNAMED_239_CAP_I91_A      A @BASEBOARD_FAB2_LIB.BASEBOARD_FAB2(SCH_1):UNNAMED_239_CAP_I91_A
   2    GND      B @BASEBOARD_FAB2_LIB.BASEBOARD_FAB2(SCH_1):GND

CAP_0603-10UF,6.3V,20%,X6S,E15A  I92  C1W7
   1 P3V3_STBY      A @BASEBOARD_FAB2_LIB.BASEBOARD_FAB2(SCH_1):P3V3_STBY
   2    GND      B @BASEBOARD_FAB2_LIB.BASEBOARD_FAB2(SCH_1):GND

5K1R2F-2-GP_SMD-RG-5K1R2F-2-GPA  I98  R9F31
   1 P1V2_AUX_BMC      1 @BASEBOARD_FAB2_LIB.BASEBOARD_FAB2(SCH_1):P1V2_AUX_BMC
   2 VR_P1V538_BMC_STBY_FB      2 @BASEBOARD_FAB2_LIB.BASEBOARD_FAB2(SCH_1):VR_P1V538_BMC_STBY_FB

21K5R2F-GP_RCL_GP-21K5R2F-GP,6A  I99  R9W31
   1 P2V5_AUX_BMC      1 @BASEBOARD_FAB2_LIB.BASEBOARD_FAB2(SCH_1):P2V5_AUX_BMC
   2 UNNAMED_239_21K5R2F-GP_I99_2      2 @BASEBOARD_FAB2_LIB.BASEBOARD_FAB2(SCH_1):UNNAMED_239_21K5R2F-GP_I99_2


DRAWING: @BASEBOARD_FAB2_LIB.BASEBOARD_FAB2(SCH_1):PAGE21 

RES_0402-221,1.0%,1/16W,CHIP,GA  I149  R6N10
   1 SVID_ALERT0_CPU0_N      A @BASEBOARD_FAB2_LIB.BASEBOARD_FAB2(SCH_1):SVID_ALERT0_CPU0_N
   2 SVID_ALERT0_CPU0_R_N      B @BASEBOARD_FAB2_LIB.BASEBOARD_FAB2(SCH_1):SVID_ALERT0_CPU0_R_N

RES_0402-0.0,5%,1/16W,CHIP,G21A  I150  R6N12
   1 SVID_CLK0_CPU0      A @BASEBOARD_FAB2_LIB.BASEBOARD_FAB2(SCH_1):SVID_CLK0_CPU0
   2 SVID_CLK0_CPU0_R      B @BASEBOARD_FAB2_LIB.BASEBOARD_FAB2(SCH_1):SVID_CLK0_CPU0_R

RES_0402-0.0,5%,1/16W,CHIP,G21A  I151  R6N11
   1 SVID_DIO0_CPU0      A @BASEBOARD_FAB2_LIB.BASEBOARD_FAB2(SCH_1):SVID_DIO0_CPU0
   2 SVID_DIO0_CPU0_R      B @BASEBOARD_FAB2_LIB.BASEBOARD_FAB2(SCH_1):SVID_DIO0_CPU0_R

RES_0402-221,1.0%,1/16W,CHIP,GA  I152  R6B3
   1 SVID_ALERT1_CPU0_N      A @BASEBOARD_FAB2_LIB.BASEBOARD_FAB2(SCH_1):SVID_ALERT1_CPU0_N
   2 SVID_ALERT1_CPU0_R_N      B @BASEBOARD_FAB2_LIB.BASEBOARD_FAB2(SCH_1):SVID_ALERT1_CPU0_R_N

RES_0402-0.0,5%,1/16W,CHIP,G21A  I153  R6B5
   1 SVID_CLK1_CPU0      A @BASEBOARD_FAB2_LIB.BASEBOARD_FAB2(SCH_1):SVID_CLK1_CPU0
   2 SVID_CLK1_CPU0_R      B @BASEBOARD_FAB2_LIB.BASEBOARD_FAB2(SCH_1):SVID_CLK1_CPU0_R

RES_0402-0.0,5%,1/16W,CHIP,G21A  I154  R6B4
   1 SVID_DIO1_CPU0      A @BASEBOARD_FAB2_LIB.BASEBOARD_FAB2(SCH_1):SVID_DIO1_CPU0
   2 SVID_DIO1_CPU0_R      B @BASEBOARD_FAB2_LIB.BASEBOARD_FAB2(SCH_1):SVID_DIO1_CPU0_R

RES_0402-100.0,1%,1/16W,CHIP,GA  I159  R6B2
   1 PVCCIO_CPU0      A @BASEBOARD_FAB2_LIB.BASEBOARD_FAB2(SCH_1):PVCCIO_CPU0
   2 SVID_DIO1_CPU0_R      B @BASEBOARD_FAB2_LIB.BASEBOARD_FAB2(SCH_1):SVID_DIO1_CPU0_R

RES_0402-49.9,1%,1/16W,CHIP,G2A  I161  R6B1
   1 PVCCIO_CPU0      A @BASEBOARD_FAB2_LIB.BASEBOARD_FAB2(SCH_1):PVCCIO_CPU0
   2 SVID_ALERT1_CPU0_R_N      B @BASEBOARD_FAB2_LIB.BASEBOARD_FAB2(SCH_1):SVID_ALERT1_CPU0_R_N

RES_0402-100.0,1%,1/16W,CHIP,GA  I163  R6N2
   1 SVID_DIO0_CPU0_R      A @BASEBOARD_FAB2_LIB.BASEBOARD_FAB2(SCH_1):SVID_DIO0_CPU0_R
   2 PVCCIO_CPU0      B @BASEBOARD_FAB2_LIB.BASEBOARD_FAB2(SCH_1):PVCCIO_CPU0

RES_0402-49.9,1%,1/16W,CHIP,G2A  I164  R6N1
   1 SVID_ALERT0_CPU0_R_N      A @BASEBOARD_FAB2_LIB.BASEBOARD_FAB2(SCH_1):SVID_ALERT0_CPU0_R_N
   2 PVCCIO_CPU0      B @BASEBOARD_FAB2_LIB.BASEBOARD_FAB2(SCH_1):PVCCIO_CPU0

RES_0402-90.9,1%,1/16W,CHIP,G2A  I177  R5D1
   1 A_CPU0_DEF_RCOMP0      A @BASEBOARD_FAB2_LIB.BASEBOARD_FAB2(SCH_1):A_CPU0_DEF_RCOMP0
   2    GND      B @BASEBOARD_FAB2_LIB.BASEBOARD_FAB2(SCH_1):GND

RES_0402-90.9,1%,1/16W,CHIP,G2A  I178  R5D2
   1 A_CPU0_DEF_RCOMP1      A @BASEBOARD_FAB2_LIB.BASEBOARD_FAB2(SCH_1):A_CPU0_DEF_RCOMP1
   2    GND      B @BASEBOARD_FAB2_LIB.BASEBOARD_FAB2(SCH_1):GND

RES_0402-100.0,1%,1/16W,CHIP,GA  I179  R6D1
   1 A_CPU0_DEF_RCOMP2      A @BASEBOARD_FAB2_LIB.BASEBOARD_FAB2(SCH_1):A_CPU0_DEF_RCOMP2
   2    GND      B @BASEBOARD_FAB2_LIB.BASEBOARD_FAB2(SCH_1):GND

RES_0402-90.9,1%,1/16W,CHIP,G2A  I180  R4P8
   1 A_CPU0_ABC_RCOMP0      A @BASEBOARD_FAB2_LIB.BASEBOARD_FAB2(SCH_1):A_CPU0_ABC_RCOMP0
   2    GND      B @BASEBOARD_FAB2_LIB.BASEBOARD_FAB2(SCH_1):GND

RES_0402-90.9,1%,1/16W,CHIP,G2A  I181  R4P10
   1 A_CPU0_ABC_RCOMP1      A @BASEBOARD_FAB2_LIB.BASEBOARD_FAB2(SCH_1):A_CPU0_ABC_RCOMP1
   2    GND      B @BASEBOARD_FAB2_LIB.BASEBOARD_FAB2(SCH_1):GND

RES_0402-100.0,1%,1/16W,CHIP,GA  I182  R4P11
   1 A_CPU0_ABC_RCOMP2      A @BASEBOARD_FAB2_LIB.BASEBOARD_FAB2(SCH_1):A_CPU0_ABC_RCOMP2
   2    GND      B @BASEBOARD_FAB2_LIB.BASEBOARD_FAB2(SCH_1):GND

RES_0402-49.9,1%,1/16W,CHIP,G2A  I184  R6D11
   1 A_CPU0_UPI01_RBIAS      A @BASEBOARD_FAB2_LIB.BASEBOARD_FAB2(SCH_1):A_CPU0_UPI01_RBIAS
   2    GND      B @BASEBOARD_FAB2_LIB.BASEBOARD_FAB2(SCH_1):GND

RES_0402-49.9,1%,1/16W,CHIP,G2A  I186  R4P3
   1 A_CPU0_PE012_RBIAS      A @BASEBOARD_FAB2_LIB.BASEBOARD_FAB2(SCH_1):A_CPU0_PE012_RBIAS
   2    GND      B @BASEBOARD_FAB2_LIB.BASEBOARD_FAB2(SCH_1):GND

RES_0402-49.9,1%,1/16W,CHIP,G2A  I188  R4P2
   1 A_CPU0_PE3_RBIAS      A @BASEBOARD_FAB2_LIB.BASEBOARD_FAB2(SCH_1):A_CPU0_PE3_RBIAS
   2    GND      B @BASEBOARD_FAB2_LIB.BASEBOARD_FAB2(SCH_1):GND

RES_0402-49.9,1%,1/16W,CHIP,G2A  I189  R4P4
   1 A_CPU0_UPI2_RBIAS      A @BASEBOARD_FAB2_LIB.BASEBOARD_FAB2(SCH_1):A_CPU0_UPI2_RBIAS
   2    GND      B @BASEBOARD_FAB2_LIB.BASEBOARD_FAB2(SCH_1):GND

RES_0402-49.9,1%,1/16W,CHIP,G2A  I204  R6D2
   1 A_CPU0_MCP01_RBIAS      A @BASEBOARD_FAB2_LIB.BASEBOARD_FAB2(SCH_1):A_CPU0_MCP01_RBIAS
   2    GND      B @BASEBOARD_FAB2_LIB.BASEBOARD_FAB2(SCH_1):GND

SOCKET_P_MECH_A_RIGHT-P0,PLASTA  I216  XRU1
SOCKET_P_MECH_A_LEFT-P0,PLASTIA  I217  XLU1
RES_0402-49.9,1%,1/16W,CHIP,G2A  I219  R4P19
   1 H_PMSYNC_CLK_24M_CPU0      A @BASEBOARD_FAB2_LIB.BASEBOARD_FAB2(SCH_1):H_PMSYNC_CLK_24M_CPU0
   2 H_PMSYNC_CLK_24M      B @BASEBOARD_FAB2_LIB.BASEBOARD_FAB2(SCH_1):H_PMSYNC_CLK_24M

RES_0402-1.8K,1%,1/16W,CHIP,G2A  I227  R5N2
   1 P3V3_STBY      A @BASEBOARD_FAB2_LIB.BASEBOARD_FAB2(SCH_1):P3V3_STBY
   2 FM_CPU0_PROC_ID1      B @BASEBOARD_FAB2_LIB.BASEBOARD_FAB2(SCH_1):FM_CPU0_PROC_ID1

RES_0402-10.0K,1%,1/16W,CHIP,GA  I238  R5N1
   1 P3V3_STBY      A @BASEBOARD_FAB2_LIB.BASEBOARD_FAB2(SCH_1):P3V3_STBY
   2 FM_CPU0_PKGID0      B @BASEBOARD_FAB2_LIB.BASEBOARD_FAB2(SCH_1):FM_CPU0_PKGID0

RES_0402-10.0K,1%,1/16W,CHIP,GA  I239  R5N5
   1 P3V3_STBY      A @BASEBOARD_FAB2_LIB.BASEBOARD_FAB2(SCH_1):P3V3_STBY
   2 FM_CPU0_PKGID1      B @BASEBOARD_FAB2_LIB.BASEBOARD_FAB2(SCH_1):FM_CPU0_PKGID1

RES_0402-10.0K,1%,1/16W,CHIP,GA  I240  R5N3
   1 P3V3_STBY      A @BASEBOARD_FAB2_LIB.BASEBOARD_FAB2(SCH_1):P3V3_STBY
   2 FM_CPU0_PKGID2      B @BASEBOARD_FAB2_LIB.BASEBOARD_FAB2(SCH_1):FM_CPU0_PKGID2

RES_0402-1.8K,1%,1/16W,CHIP,G2A  I241  R5N4
   1 P3V3_STBY      A @BASEBOARD_FAB2_LIB.BASEBOARD_FAB2(SCH_1):P3V3_STBY
   2 FM_CPU0_PROC_ID0      B @BASEBOARD_FAB2_LIB.BASEBOARD_FAB2(SCH_1):FM_CPU0_PROC_ID0

RES_0402-49.9,1%,1/16W,CHIP,G2A  I244  R4P18
   1 H_PM_SYNC_GTL_R1      A @BASEBOARD_FAB2_LIB.BASEBOARD_FAB2(SCH_1):H_PM_SYNC_GTL_R1
   2 H_PM_SYNC_GTL      B @BASEBOARD_FAB2_LIB.BASEBOARD_FAB2(SCH_1):H_PM_SYNC_GTL

RES_0402-4.75K,1%,1/16W,CHIP,GA  I258  R4R5
   1 P3V3_STBY      A @BASEBOARD_FAB2_LIB.BASEBOARD_FAB2(SCH_1):P3V3_STBY
   2 FM_CPU0_SKTOCC_LVT3_N      B @BASEBOARD_FAB2_LIB.BASEBOARD_FAB2(SCH_1):FM_CPU0_SKTOCC_LVT3_N

SKX_EXT_B_BGA1-IC,TBD  I259  U5D1
AU24 CLK_100M_CPU0_BCLK0_DN BCLK0_DN @BASEBOARD_FAB2_LIB.BASEBOARD_FAB2(SCH_1):CLK_100M_CPU0_BCLK0_DN
AW24 CLK_100M_CPU0_BCLK0_DP BCLK0_DP @BASEBOARD_FAB2_LIB.BASEBOARD_FAB2(SCH_1):CLK_100M_CPU0_BCLK0_DP
CR26 CLK_100M_CPU0_BCLK1_DN BCLK1_DN @BASEBOARD_FAB2_LIB.BASEBOARD_FAB2(SCH_1):CLK_100M_CPU0_BCLK1_DN
CP27 CLK_100M_CPU0_BCLK1_DP BCLK1_DP @BASEBOARD_FAB2_LIB.BASEBOARD_FAB2(SCH_1):CLK_100M_CPU0_BCLK1_DP
CT25 CLK_100M_CPU0_BCLK2_DN BCLK2_DN @BASEBOARD_FAB2_LIB.BASEBOARD_FAB2(SCH_1):CLK_100M_CPU0_BCLK2_DN
CU26 CLK_100M_CPU0_BCLK2_DP BCLK2_DP @BASEBOARD_FAB2_LIB.BASEBOARD_FAB2(SCH_1):CLK_100M_CPU0_BCLK2_DP
BA20 PD_CPU0_BIST_ENABLE BIST_ENABLE @BASEBOARD_FAB2_LIB.BASEBOARD_FAB2(SCH_1):PD_CPU0_BIST_ENABLE
BD23 H_CPU0_BMCINIT BMCINIT @BASEBOARD_FAB2_LIB.BASEBOARD_FAB2(SCH_1):H_CPU0_BMCINIT
AC12 XDP_CPU_OBSFN_B1_MBP7_N BPM_N<7> @BASEBOARD_FAB2_LIB.BASEBOARD_FAB2(SCH_1):XDP_CPU_OBSFN_B1_MBP7_N
AE12 XDP_CPU_OBSFN_B0_MBP6_N BPM_N<6> @BASEBOARD_FAB2_LIB.BASEBOARD_FAB2(SCH_1):XDP_CPU_OBSFN_B0_MBP6_N
 Y11 TP_XDP_CPU0_OBSDATA_A3_MBP5_N BPM_N<5> @BASEBOARD_FAB2_LIB.BASEBOARD_FAB2(SCH_1):TP_XDP_CPU0_OBSDATA_A3_MBP5_N
AA12 TP_XDP_CPU0_OBSDATA_A2_MBP4_N BPM_N<4> @BASEBOARD_FAB2_LIB.BASEBOARD_FAB2(SCH_1):TP_XDP_CPU0_OBSDATA_A2_MBP4_N
AF11 TP_XDP_CPU0_OBSDATA_A1_MBP3_N BPM_N<3> @BASEBOARD_FAB2_LIB.BASEBOARD_FAB2(SCH_1):TP_XDP_CPU0_OBSDATA_A1_MBP3_N
AG10 TP_XDP_CPU0_OBSDATA_A0_MBP2_N BPM_N<2> @BASEBOARD_FAB2_LIB.BASEBOARD_FAB2(SCH_1):TP_XDP_CPU0_OBSDATA_A0_MBP2_N
AH11 XDP_CPU_MBP1_N BPM_N<1> @BASEBOARD_FAB2_LIB.BASEBOARD_FAB2(SCH_1):XDP_CPU_MBP1_N
AJ10 XDP_CPU_MBP0_N BPM_N<0> @BASEBOARD_FAB2_LIB.BASEBOARD_FAB2(SCH_1):XDP_CPU_MBP0_N
AL14 H_CPU0_CATERR_G_N CATERR_N @BASEBOARD_FAB2_LIB.BASEBOARD_FAB2(SCH_1):H_CPU0_CATERR_G_N
AN30 PWRGD_CPU0_DRAMPWROK_ABC_G DDR012_DRAM_PWR_OK @BASEBOARD_FAB2_LIB.BASEBOARD_FAB2(SCH_1):PWRGD_CPU0_DRAMPWROK_ABC_G
AC42 A_CPU0_ABC_RCOMP2 DDR012_RCOMP<2> @BASEBOARD_FAB2_LIB.BASEBOARD_FAB2(SCH_1):A_CPU0_ABC_RCOMP2
AB43 A_CPU0_ABC_RCOMP1 DDR012_RCOMP<1> @BASEBOARD_FAB2_LIB.BASEBOARD_FAB2(SCH_1):A_CPU0_ABC_RCOMP1
 Y43 A_CPU0_ABC_RCOMP0 DDR012_RCOMP<0> @BASEBOARD_FAB2_LIB.BASEBOARD_FAB2(SCH_1):A_CPU0_ABC_RCOMP0
 U64 M_ABC_RST_N DDR012_RESET_N @BASEBOARD_FAB2_LIB.BASEBOARD_FAB2(SCH_1):M_ABC_RST_N
AJ18 SMB_DDR_ABC_SCL_G_R DDR012_SPDSCL @BASEBOARD_FAB2_LIB.BASEBOARD_FAB2(SCH_1):SMB_DDR_ABC_SCL_G_R
AF17 SMB_DDR_ABC_SDA_G_R DDR012_SPDSDA @BASEBOARD_FAB2_LIB.BASEBOARD_FAB2(SCH_1):SMB_DDR_ABC_SDA_G_R
AJ64 M_A_CPU_VREF DDR0_CAVREF @BASEBOARD_FAB2_LIB.BASEBOARD_FAB2(SCH_1):M_A_CPU_VREF
AK63 M_B_CPU_VREF DDR1_CAVREF @BASEBOARD_FAB2_LIB.BASEBOARD_FAB2(SCH_1):M_B_CPU_VREF
AH63 M_C_CPU_VREF DDR2_CAVREF @BASEBOARD_FAB2_LIB.BASEBOARD_FAB2(SCH_1):M_C_CPU_VREF
CR28 PWRGD_CPU0_DRAMPWROK_DEF_G DDR345_DRAM_PWR_OK @BASEBOARD_FAB2_LIB.BASEBOARD_FAB2(SCH_1):PWRGD_CPU0_DRAMPWROK_DEF_G
DD49 A_CPU0_DEF_RCOMP2 DDR345_RCOMP<2> @BASEBOARD_FAB2_LIB.BASEBOARD_FAB2(SCH_1):A_CPU0_DEF_RCOMP2
DD47 A_CPU0_DEF_RCOMP1 DDR345_RCOMP<1> @BASEBOARD_FAB2_LIB.BASEBOARD_FAB2(SCH_1):A_CPU0_DEF_RCOMP1
DC48 A_CPU0_DEF_RCOMP0 DDR345_RCOMP<0> @BASEBOARD_FAB2_LIB.BASEBOARD_FAB2(SCH_1):A_CPU0_DEF_RCOMP0
DV63 M_DEF_RST_N DDR345_RESET_N @BASEBOARD_FAB2_LIB.BASEBOARD_FAB2(SCH_1):M_DEF_RST_N
AE18 SMB_DDR_DEF_SCL_G_R DDR345_SPDSCL @BASEBOARD_FAB2_LIB.BASEBOARD_FAB2(SCH_1):SMB_DDR_DEF_SCL_G_R
AD17 SMB_DDR_DEF_SDA_G_R DDR345_SPDSDA @BASEBOARD_FAB2_LIB.BASEBOARD_FAB2(SCH_1):SMB_DDR_DEF_SDA_G_R
CP61 M_D_CPU_VREF DDR3_CAVREF @BASEBOARD_FAB2_LIB.BASEBOARD_FAB2(SCH_1):M_D_CPU_VREF
CT61 M_E_CPU_VREF DDR4_CAVREF @BASEBOARD_FAB2_LIB.BASEBOARD_FAB2(SCH_1):M_E_CPU_VREF
CV61 M_F_CPU_VREF DDR5_CAVREF @BASEBOARD_FAB2_LIB.BASEBOARD_FAB2(SCH_1):M_F_CPU_VREF
AJ14 PU_CPU0_EAR_N  EAR_N @BASEBOARD_FAB2_LIB.BASEBOARD_FAB2(SCH_1):PU_CPU0_EAR_N
AL12 H_CPU0_ERR2_G_N ERROR_N<2> @BASEBOARD_FAB2_LIB.BASEBOARD_FAB2(SCH_1):H_CPU0_ERR2_G_N
AK11 H_CPU0_ERR1_G_N ERROR_N<1> @BASEBOARD_FAB2_LIB.BASEBOARD_FAB2(SCH_1):H_CPU0_ERR1_G_N
AJ12 H_CPU0_ERR0_G_N ERROR_N<0> @BASEBOARD_FAB2_LIB.BASEBOARD_FAB2(SCH_1):H_CPU0_ERR0_G_N
AV17 PU_CPU0_FRMAGENT FRMAGENT @BASEBOARD_FAB2_LIB.BASEBOARD_FAB2(SCH_1):PU_CPU0_FRMAGENT
AE20 PU_CPU0_LEGACY_SKT LEGACY_SKT @BASEBOARD_FAB2_LIB.BASEBOARD_FAB2(SCH_1):PU_CPU0_LEGACY_SKT
CT31 A_CPU0_MCP01_RBIAS MCP01_RBIAS<1> @BASEBOARD_FAB2_LIB.BASEBOARD_FAB2(SCH_1):A_CPU0_MCP01_RBIAS
CU32 A_CPU0_MCP01_RBIAS MCP01_RBIAS<0> @BASEBOARD_FAB2_LIB.BASEBOARD_FAB2(SCH_1):A_CPU0_MCP01_RBIAS
AH13 H_CPU0_MEMABC_MEMHOT_G_N MEM_HOT_C012_N @BASEBOARD_FAB2_LIB.BASEBOARD_FAB2(SCH_1):H_CPU0_MEMABC_MEMHOT_G_N
AF13 H_CPU0_MEMDEF_MEMHOT_G_N MEM_HOT_C345_N @BASEBOARD_FAB2_LIB.BASEBOARD_FAB2(SCH_1):H_CPU0_MEMDEF_MEMHOT_G_N
AN20 H_CPU0_MSMI_G_N MSMI_N @BASEBOARD_FAB2_LIB.BASEBOARD_FAB2(SCH_1):H_CPU0_MSMI_G_N
AP11 TP_NMI_CPU0    NMI @BASEBOARD_FAB2_LIB.BASEBOARD_FAB2(SCH_1):TP_NMI_CPU0
CL30 A_CPU0_PE012_RBIAS PE012_RBIAS<1> @BASEBOARD_FAB2_LIB.BASEBOARD_FAB2(SCH_1):A_CPU0_PE012_RBIAS
CN30 A_CPU0_PE012_RBIAS PE012_RBIAS<0> @BASEBOARD_FAB2_LIB.BASEBOARD_FAB2(SCH_1):A_CPU0_PE012_RBIAS
CR30 A_CPU0_PE3_RBIAS PE3_RBIAS<1> @BASEBOARD_FAB2_LIB.BASEBOARD_FAB2(SCH_1):A_CPU0_PE3_RBIAS
CP29 A_CPU0_PE3_RBIAS PE3_RBIAS<0> @BASEBOARD_FAB2_LIB.BASEBOARD_FAB2(SCH_1):A_CPU0_PE3_RBIAS
AU12 PECI_CPU_G   PECI @BASEBOARD_FAB2_LIB.BASEBOARD_FAB2(SCH_1):PECI_CPU_G
AM19 TP_CPU0_PE_HP_SCL PE_HP_SCL @BASEBOARD_FAB2_LIB.BASEBOARD_FAB2(SCH_1):TP_CPU0_PE_HP_SCL
AL18 TP_CPU0_PE_HP_SDA PE_HP_SDA @BASEBOARD_FAB2_LIB.BASEBOARD_FAB2(SCH_1):TP_CPU0_PE_HP_SDA
CW56 PD_PIROM_CPU0_ADDR2 PIROM_ADDR<2> @BASEBOARD_FAB2_LIB.BASEBOARD_FAB2(SCH_1):PD_PIROM_CPU0_ADDR2
CV57 PD_PIROM_CPU0_ADDR1 PIROM_ADDR<1> @BASEBOARD_FAB2_LIB.BASEBOARD_FAB2(SCH_1):PD_PIROM_CPU0_ADDR1
CU58 PD_PIROM_CPU0_ADDR0 PIROM_ADDR<0> @BASEBOARD_FAB2_LIB.BASEBOARD_FAB2(SCH_1):PD_PIROM_CPU0_ADDR0
DA72 FM_CPU0_PKGID2 PKGID<2> @BASEBOARD_FAB2_LIB.BASEBOARD_FAB2(SCH_1):FM_CPU0_PKGID2
CW72 FM_CPU0_PKGID1 PKGID<1> @BASEBOARD_FAB2_LIB.BASEBOARD_FAB2(SCH_1):FM_CPU0_PKGID1
DC72 FM_CPU0_PKGID0 PKGID<0> @BASEBOARD_FAB2_LIB.BASEBOARD_FAB2(SCH_1):FM_CPU0_PKGID0
AR14 H_PM_SYNC_GTL_R1 PMSYNC @BASEBOARD_FAB2_LIB.BASEBOARD_FAB2(SCH_1):H_PM_SYNC_GTL_R1
AT19 H_PMSYNC_CLK_24M_CPU0 PMSYNC_CLK @BASEBOARD_FAB2_LIB.BASEBOARD_FAB2(SCH_1):H_PMSYNC_CLK_24M_CPU0
AF15 H_CPU0_FAST_WAKE_N PM_FAST_WAKE_N @BASEBOARD_FAB2_LIB.BASEBOARD_FAB2(SCH_1):H_CPU0_FAST_WAKE_N
AG16 XDP_CPU_PRDY_N PRDY_N @BASEBOARD_FAB2_LIB.BASEBOARD_FAB2(SCH_1):XDP_CPU_PRDY_N
AR12 XDP_CPU_PREQ_N PREQ_N @BASEBOARD_FAB2_LIB.BASEBOARD_FAB2(SCH_1):XDP_CPU_PREQ_N
AB17 TP_CPU0_PROCDIS_G_N PROCDIS_N @BASEBOARD_FAB2_LIB.BASEBOARD_FAB2(SCH_1):TP_CPU0_PROCDIS_G_N
AC16 H_CPU0_PROCHOT_G_N PROCHOT_N @BASEBOARD_FAB2_LIB.BASEBOARD_FAB2(SCH_1):H_CPU0_PROCHOT_G_N
DB71 FM_CPU0_PROC_ID1 PROC_ID<1> @BASEBOARD_FAB2_LIB.BASEBOARD_FAB2(SCH_1):FM_CPU0_PROC_ID1
CY71 FM_CPU0_PROC_ID0 PROC_ID<0> @BASEBOARD_FAB2_LIB.BASEBOARD_FAB2(SCH_1):FM_CPU0_PROC_ID0
BC24 PWRGD_CPU0_G PWRGOOD @BASEBOARD_FAB2_LIB.BASEBOARD_FAB2(SCH_1):PWRGD_CPU0_G
AP21 RST_CPU0_G_N RESET_N @BASEBOARD_FAB2_LIB.BASEBOARD_FAB2(SCH_1):RST_CPU0_G_N
AR18 PU_CPU0_SAFE_MODE_BOOT SAFE_MODE_BOOT @BASEBOARD_FAB2_LIB.BASEBOARD_FAB2(SCH_1):PU_CPU0_SAFE_MODE_BOOT
AB13 FM_CPU0_SKTOCC_LVT3_N SKTOCC_N @BASEBOARD_FAB2_LIB.BASEBOARD_FAB2(SCH_1):FM_CPU0_SKTOCC_LVT3_N
CT59 SMB_PIROM_CPU0_SCL SMBCLK @BASEBOARD_FAB2_LIB.BASEBOARD_FAB2(SCH_1):SMB_PIROM_CPU0_SCL
CW58 SMB_PIROM_CPU0_SDA SMBDAT @BASEBOARD_FAB2_LIB.BASEBOARD_FAB2(SCH_1):SMB_PIROM_CPU0_SDA
CV59 FM_CPU0_SM_WP  SM_WP @BASEBOARD_FAB2_LIB.BASEBOARD_FAB2(SCH_1):FM_CPU0_SM_WP
AU20 TP_CPU0_SOCKET_ID_2 SOCKET_ID<2> @BASEBOARD_FAB2_LIB.BASEBOARD_FAB2(SCH_1):TP_CPU0_SOCKET_ID_2
AU16 PU_CPU0_SOCKET_ID_1 SOCKET_ID<1> @BASEBOARD_FAB2_LIB.BASEBOARD_FAB2(SCH_1):PU_CPU0_SOCKET_ID_1
AU22 PU_CPU0_SOCKET_ID_0 SOCKET_ID<0> @BASEBOARD_FAB2_LIB.BASEBOARD_FAB2(SCH_1):PU_CPU0_SOCKET_ID_0
DL44 SVID_ALERT1_CPU0_N SVIDALERT_N<1> @BASEBOARD_FAB2_LIB.BASEBOARD_FAB2(SCH_1):SVID_ALERT1_CPU0_N
DE44 SVID_ALERT0_CPU0_N SVIDALERT_N<0> @BASEBOARD_FAB2_LIB.BASEBOARD_FAB2(SCH_1):SVID_ALERT0_CPU0_N
DG44 SVID_CLK1_CPU0 SVIDCLK<1> @BASEBOARD_FAB2_LIB.BASEBOARD_FAB2(SCH_1):SVID_CLK1_CPU0
DC44 SVID_CLK0_CPU0 SVIDCLK<0> @BASEBOARD_FAB2_LIB.BASEBOARD_FAB2(SCH_1):SVID_CLK0_CPU0
DJ44 SVID_DIO1_CPU0 SVIDDATA<1> @BASEBOARD_FAB2_LIB.BASEBOARD_FAB2(SCH_1):SVID_DIO1_CPU0
DB45 SVID_DIO0_CPU0 SVIDDATA<0> @BASEBOARD_FAB2_LIB.BASEBOARD_FAB2(SCH_1):SVID_DIO0_CPU0
AA14 XDP_CPU_TCK0    TCK @BASEBOARD_FAB2_LIB.BASEBOARD_FAB2(SCH_1):XDP_CPU_TCK0
AC14 XDP_CPU_TDI    TDI @BASEBOARD_FAB2_LIB.BASEBOARD_FAB2(SCH_1):XDP_CPU_TDI
AE14 XDP_CPU0_TDO    TDO @BASEBOARD_FAB2_LIB.BASEBOARD_FAB2(SCH_1):XDP_CPU0_TDO
AY19 PD_CPU0_TEST12 TEST_12 @BASEBOARD_FAB2_LIB.BASEBOARD_FAB2(SCH_1):PD_CPU0_TEST12
DB51 PD_CPU0_TEST13 TEST_13 @BASEBOARD_FAB2_LIB.BASEBOARD_FAB2(SCH_1):PD_CPU0_TEST13
DC50 PD_CPU0_TEST14 TEST_14 @BASEBOARD_FAB2_LIB.BASEBOARD_FAB2(SCH_1):PD_CPU0_TEST14
AW14 PD_CPU0_KSFC_DIS TEST_15 @BASEBOARD_FAB2_LIB.BASEBOARD_FAB2(SCH_1):PD_CPU0_KSFC_DIS
AB15 H_CPU0_THERMTRIP_G_N THERMTRIP_N @BASEBOARD_FAB2_LIB.BASEBOARD_FAB2(SCH_1):H_CPU0_THERMTRIP_G_N
 W14 XDP_CPU_TMS    TMS @BASEBOARD_FAB2_LIB.BASEBOARD_FAB2(SCH_1):XDP_CPU_TMS
 Y13 XDP_CPU_TRST_N TRST_N @BASEBOARD_FAB2_LIB.BASEBOARD_FAB2(SCH_1):XDP_CPU_TRST_N
AM11 PU_CPU0_TSC_SYNC TSC_SYNC @BASEBOARD_FAB2_LIB.BASEBOARD_FAB2(SCH_1):PU_CPU0_TSC_SYNC
AW18 PU_CPU0_TXT_AGENT TXT_AGENT @BASEBOARD_FAB2_LIB.BASEBOARD_FAB2(SCH_1):PU_CPU0_TXT_AGENT
AV15 PD_CPU0_TXT_PLTEN TXT_PLTEN @BASEBOARD_FAB2_LIB.BASEBOARD_FAB2(SCH_1):PD_CPU0_TXT_PLTEN
AP29 A_CPU0_UPI01_RBIAS UPI01_RBIAS<1> @BASEBOARD_FAB2_LIB.BASEBOARD_FAB2(SCH_1):A_CPU0_UPI01_RBIAS
AT29 A_CPU0_UPI01_RBIAS UPI01_RBIAS<0> @BASEBOARD_FAB2_LIB.BASEBOARD_FAB2(SCH_1):A_CPU0_UPI01_RBIAS
CK29 A_CPU0_UPI2_RBIAS UPI2_RBIAS<1> @BASEBOARD_FAB2_LIB.BASEBOARD_FAB2(SCH_1):A_CPU0_UPI2_RBIAS
CL28 A_CPU0_UPI2_RBIAS UPI2_RBIAS<0> @BASEBOARD_FAB2_LIB.BASEBOARD_FAB2(SCH_1):A_CPU0_UPI2_RBIAS


DRAWING: @BASEBOARD_FAB2_LIB.BASEBOARD_FAB2(SCH_1):PAGE22 

RES_0402-49.9,1%,1/16W,CHIP,G2A  I188  R5R1
   1 PD_CPU0_RSVD_TEST_1      A @BASEBOARD_FAB2_LIB.BASEBOARD_FAB2(SCH_1):PD_CPU0_RSVD_TEST_1
   2    GND      B @BASEBOARD_FAB2_LIB.BASEBOARD_FAB2(SCH_1):GND

RES_0402-49.9,1%,1/16W,CHIP,G2A  I190  R5P4
   1 PD_CPU0_RSVD_TEST_2      A @BASEBOARD_FAB2_LIB.BASEBOARD_FAB2(SCH_1):PD_CPU0_RSVD_TEST_2
   2    GND      B @BASEBOARD_FAB2_LIB.BASEBOARD_FAB2(SCH_1):GND

SKX_EXT_B_BGA1-IC,TBD  I204  U5D1
AV21 XDP_PRESENT_N DEBUG_EN_N @BASEBOARD_FAB2_LIB.BASEBOARD_FAB2(SCH_1):XDP_PRESENT_N
AW12 PD_CPU0_DMIMODE_OVERRIDE DMIMODE_OVERRIDE @BASEBOARD_FAB2_LIB.BASEBOARD_FAB2(SCH_1):PD_CPU0_DMIMODE_OVERRIDE
AU14 H_CPU0_FIVR_FAULT_G FIVR_FAULT @BASEBOARD_FAB2_LIB.BASEBOARD_FAB2(SCH_1):H_CPU0_FIVR_FAULT_G
AP17 XDP_CPU_PWR_DEBUG_N PWR_DEBUG_N @BASEBOARD_FAB2_LIB.BASEBOARD_FAB2(SCH_1):XDP_CPU_PWR_DEBUG_N
  A4 TP_CPU0_RSVD_304 RSVD<304> @BASEBOARD_FAB2_LIB.BASEBOARD_FAB2(SCH_1):TP_CPU0_RSVD_304
  A6 TP_CPU0_RSVD_303 RSVD<303> @BASEBOARD_FAB2_LIB.BASEBOARD_FAB2(SCH_1):TP_CPU0_RSVD_303
 A14 P1V8_MCP_CPU0 RSVD<302> @BASEBOARD_FAB2_LIB.BASEBOARD_FAB2(SCH_1):P1V8_MCP_CPU0
 A16 P1V8_MCP_CPU0 RSVD<301> @BASEBOARD_FAB2_LIB.BASEBOARD_FAB2(SCH_1):P1V8_MCP_CPU0
 A24 TP_CPU0_RSVD_300 RSVD<300> @BASEBOARD_FAB2_LIB.BASEBOARD_FAB2(SCH_1):TP_CPU0_RSVD_300
  B3 TP_CPU0_RSVD_299 RSVD<299> @BASEBOARD_FAB2_LIB.BASEBOARD_FAB2(SCH_1):TP_CPU0_RSVD_299
  B7 TP_CPU0_RSVD_298 RSVD<298> @BASEBOARD_FAB2_LIB.BASEBOARD_FAB2(SCH_1):TP_CPU0_RSVD_298
 B13 P1V8_MCP_CPU0 RSVD<296> @BASEBOARD_FAB2_LIB.BASEBOARD_FAB2(SCH_1):P1V8_MCP_CPU0
 B15 P1V8_MCP_CPU0 RSVD<295> @BASEBOARD_FAB2_LIB.BASEBOARD_FAB2(SCH_1):P1V8_MCP_CPU0
 B17 P1V8_MCP_CPU0 RSVD<294> @BASEBOARD_FAB2_LIB.BASEBOARD_FAB2(SCH_1):P1V8_MCP_CPU0
 B77 TP_CPU0_RSVD_293 RSVD<293> @BASEBOARD_FAB2_LIB.BASEBOARD_FAB2(SCH_1):TP_CPU0_RSVD_293
 B81 TP_CPU0_RSVD_292 RSVD<292> @BASEBOARD_FAB2_LIB.BASEBOARD_FAB2(SCH_1):TP_CPU0_RSVD_292
  C6 TP_CPU0_RSVD_291 RSVD<291> @BASEBOARD_FAB2_LIB.BASEBOARD_FAB2(SCH_1):TP_CPU0_RSVD_291
 C18 TP_CPU0_RSVD_290 RSVD<290> @BASEBOARD_FAB2_LIB.BASEBOARD_FAB2(SCH_1):TP_CPU0_RSVD_290
 C24 TP_CPU0_RSVD_289 RSVD<289> @BASEBOARD_FAB2_LIB.BASEBOARD_FAB2(SCH_1):TP_CPU0_RSVD_289
 C82 TP_CPU0_RSVD_288 RSVD<288> @BASEBOARD_FAB2_LIB.BASEBOARD_FAB2(SCH_1):TP_CPU0_RSVD_288
  D5 TP_CPU0_RSVD_287 RSVD<287> @BASEBOARD_FAB2_LIB.BASEBOARD_FAB2(SCH_1):TP_CPU0_RSVD_287
 D17 TP_CPU0_RSVD_286 RSVD<286> @BASEBOARD_FAB2_LIB.BASEBOARD_FAB2(SCH_1):TP_CPU0_RSVD_286
 D65 TP_CPU0_RSVD_285 RSVD<285> @BASEBOARD_FAB2_LIB.BASEBOARD_FAB2(SCH_1):TP_CPU0_RSVD_285
 D83 TP_CPU0_RSVD_284 RSVD<284> @BASEBOARD_FAB2_LIB.BASEBOARD_FAB2(SCH_1):TP_CPU0_RSVD_284
  E2 TP_CPU0_RSVD_283 RSVD<283> @BASEBOARD_FAB2_LIB.BASEBOARD_FAB2(SCH_1):TP_CPU0_RSVD_283
  E4 TP_CPU0_RSVD_282 RSVD<282> @BASEBOARD_FAB2_LIB.BASEBOARD_FAB2(SCH_1):TP_CPU0_RSVD_282
 E24 TP_CPU0_RSVD_281 RSVD<281> @BASEBOARD_FAB2_LIB.BASEBOARD_FAB2(SCH_1):TP_CPU0_RSVD_281
 E84 TP_CPU0_RSVD_280 RSVD<280> @BASEBOARD_FAB2_LIB.BASEBOARD_FAB2(SCH_1):TP_CPU0_RSVD_280
  F3 TP_CPU0_RSVD_279 RSVD<279> @BASEBOARD_FAB2_LIB.BASEBOARD_FAB2(SCH_1):TP_CPU0_RSVD_279
 F23 TP_CPU0_RSVD_278 RSVD<278> @BASEBOARD_FAB2_LIB.BASEBOARD_FAB2(SCH_1):TP_CPU0_RSVD_278
 F65 TP_CPU0_RSVD_277 RSVD<277> @BASEBOARD_FAB2_LIB.BASEBOARD_FAB2(SCH_1):TP_CPU0_RSVD_277
 F83 TP_CPU0_RSVD_276 RSVD<276> @BASEBOARD_FAB2_LIB.BASEBOARD_FAB2(SCH_1):TP_CPU0_RSVD_276
  G2 TP_CPU0_RSVD_275 RSVD<275> @BASEBOARD_FAB2_LIB.BASEBOARD_FAB2(SCH_1):TP_CPU0_RSVD_275
 G64 TP_CPU0_RSVD_274 RSVD<274> @BASEBOARD_FAB2_LIB.BASEBOARD_FAB2(SCH_1):TP_CPU0_RSVD_274
 G84 TP_CPU0_RSVD_273 RSVD<273> @BASEBOARD_FAB2_LIB.BASEBOARD_FAB2(SCH_1):TP_CPU0_RSVD_273
  H1 TP_CPU0_RSVD_272 RSVD<272> @BASEBOARD_FAB2_LIB.BASEBOARD_FAB2(SCH_1):TP_CPU0_RSVD_272
 H83 TP_CPU0_RSVD_271 RSVD<271> @BASEBOARD_FAB2_LIB.BASEBOARD_FAB2(SCH_1):TP_CPU0_RSVD_271
 H85 TP_CPU0_RSVD_270 RSVD<270> @BASEBOARD_FAB2_LIB.BASEBOARD_FAB2(SCH_1):TP_CPU0_RSVD_270
 J46 TP_CPU0_RSVD_269 RSVD<269> @BASEBOARD_FAB2_LIB.BASEBOARD_FAB2(SCH_1):TP_CPU0_RSVD_269
 J62 TP_CPU0_RSVD_268 RSVD<268> @BASEBOARD_FAB2_LIB.BASEBOARD_FAB2(SCH_1):TP_CPU0_RSVD_268
 K61 TP_CPU0_RSVD_267 RSVD<267> @BASEBOARD_FAB2_LIB.BASEBOARD_FAB2(SCH_1):TP_CPU0_RSVD_267
 M63 TP_CPU0_RSVD_266 RSVD<266> @BASEBOARD_FAB2_LIB.BASEBOARD_FAB2(SCH_1):TP_CPU0_RSVD_266
 P65 TP_CPU0_RSVD_265 RSVD<265> @BASEBOARD_FAB2_LIB.BASEBOARD_FAB2(SCH_1):TP_CPU0_RSVD_265
 R62 TP_CPU0_RSVD_264 RSVD<264> @BASEBOARD_FAB2_LIB.BASEBOARD_FAB2(SCH_1):TP_CPU0_RSVD_264
 R66 TP_CPU0_RSVD_263 RSVD<263> @BASEBOARD_FAB2_LIB.BASEBOARD_FAB2(SCH_1):TP_CPU0_RSVD_263
 T67 TP_CPU0_RSVD_262 RSVD<262> @BASEBOARD_FAB2_LIB.BASEBOARD_FAB2(SCH_1):TP_CPU0_RSVD_262
 U66 TP_CPU0_RSVD_261 RSVD<261> @BASEBOARD_FAB2_LIB.BASEBOARD_FAB2(SCH_1):TP_CPU0_RSVD_261
 V65 TP_CPU0_RSVD_260 RSVD<260> @BASEBOARD_FAB2_LIB.BASEBOARD_FAB2(SCH_1):TP_CPU0_RSVD_260
 V67 TP_CPU0_RSVD_259 RSVD<259> @BASEBOARD_FAB2_LIB.BASEBOARD_FAB2(SCH_1):TP_CPU0_RSVD_259
 W66 TP_CPU0_RSVD_258 RSVD<258> @BASEBOARD_FAB2_LIB.BASEBOARD_FAB2(SCH_1):TP_CPU0_RSVD_258
 Y23 FM_CPU0_RC_ERROR_N RSVD<257> @BASEBOARD_FAB2_LIB.BASEBOARD_FAB2(SCH_1):FM_CPU0_RC_ERROR_N
 Y65 TP_CPU0_RSVD_256 RSVD<256> @BASEBOARD_FAB2_LIB.BASEBOARD_FAB2(SCH_1):TP_CPU0_RSVD_256
AD47 TP_CPU0_RSVD_254 RSVD<254> @BASEBOARD_FAB2_LIB.BASEBOARD_FAB2(SCH_1):TP_CPU0_RSVD_254
AD49 TP_CPU0_RSVD_253 RSVD<253> @BASEBOARD_FAB2_LIB.BASEBOARD_FAB2(SCH_1):TP_CPU0_RSVD_253
AD51 TP_CPU0_RSVD_252 RSVD<252> @BASEBOARD_FAB2_LIB.BASEBOARD_FAB2(SCH_1):TP_CPU0_RSVD_252
AE46 TP_CPU0_RSVD_251 RSVD<251> @BASEBOARD_FAB2_LIB.BASEBOARD_FAB2(SCH_1):TP_CPU0_RSVD_251
AE48 TP_CPU0_RSVD_250 RSVD<250> @BASEBOARD_FAB2_LIB.BASEBOARD_FAB2(SCH_1):TP_CPU0_RSVD_250
AE50 TP_CPU0_RSVD_249 RSVD<249> @BASEBOARD_FAB2_LIB.BASEBOARD_FAB2(SCH_1):TP_CPU0_RSVD_249
AE52 TP_CPU0_RSVD_248 RSVD<248> @BASEBOARD_FAB2_LIB.BASEBOARD_FAB2(SCH_1):TP_CPU0_RSVD_248
AE72 TP_CPU0_RSVD_247 RSVD<247> @BASEBOARD_FAB2_LIB.BASEBOARD_FAB2(SCH_1):TP_CPU0_RSVD_247
AF19 TP_CPU0_RSVD_246 RSVD<246> @BASEBOARD_FAB2_LIB.BASEBOARD_FAB2(SCH_1):TP_CPU0_RSVD_246
AF47 TP_CPU0_RSVD_245 RSVD<245> @BASEBOARD_FAB2_LIB.BASEBOARD_FAB2(SCH_1):TP_CPU0_RSVD_245
AF49 TP_CPU0_RSVD_244 RSVD<244> @BASEBOARD_FAB2_LIB.BASEBOARD_FAB2(SCH_1):TP_CPU0_RSVD_244
AF51 TP_CPU0_RSVD_243 RSVD<243> @BASEBOARD_FAB2_LIB.BASEBOARD_FAB2(SCH_1):TP_CPU0_RSVD_243
AF53 TP_CPU0_RSVD_242 RSVD<242> @BASEBOARD_FAB2_LIB.BASEBOARD_FAB2(SCH_1):TP_CPU0_RSVD_242
AF71 TP_CPU0_RSVD_241 RSVD<241> @BASEBOARD_FAB2_LIB.BASEBOARD_FAB2(SCH_1):TP_CPU0_RSVD_241
AG20 TP_CPU0_RSVD_240 RSVD<240> @BASEBOARD_FAB2_LIB.BASEBOARD_FAB2(SCH_1):TP_CPU0_RSVD_240
AG48 TP_CPU0_RSVD_239 RSVD<239> @BASEBOARD_FAB2_LIB.BASEBOARD_FAB2(SCH_1):TP_CPU0_RSVD_239
AG50 TP_CPU0_RSVD_238 RSVD<238> @BASEBOARD_FAB2_LIB.BASEBOARD_FAB2(SCH_1):TP_CPU0_RSVD_238
AG52 TP_CPU0_RSVD_237 RSVD<237> @BASEBOARD_FAB2_LIB.BASEBOARD_FAB2(SCH_1):TP_CPU0_RSVD_237
AG54 TP_CPU0_RSVD_236 RSVD<236> @BASEBOARD_FAB2_LIB.BASEBOARD_FAB2(SCH_1):TP_CPU0_RSVD_236
AG56 TP_CPU0_RSVD_235 RSVD<235> @BASEBOARD_FAB2_LIB.BASEBOARD_FAB2(SCH_1):TP_CPU0_RSVD_235
AG72 TP_CPU0_RSVD_234 RSVD<234> @BASEBOARD_FAB2_LIB.BASEBOARD_FAB2(SCH_1):TP_CPU0_RSVD_234
AH15 TP_CPU0_RSVD_233 RSVD<233> @BASEBOARD_FAB2_LIB.BASEBOARD_FAB2(SCH_1):TP_CPU0_RSVD_233
AH19 TP_CPU0_RSVD_232 RSVD<232> @BASEBOARD_FAB2_LIB.BASEBOARD_FAB2(SCH_1):TP_CPU0_RSVD_232
AH55 TP_CPU0_RSVD_231 RSVD<231> @BASEBOARD_FAB2_LIB.BASEBOARD_FAB2(SCH_1):TP_CPU0_RSVD_231
AH57 TP_CPU0_RSVD_230 RSVD<230> @BASEBOARD_FAB2_LIB.BASEBOARD_FAB2(SCH_1):TP_CPU0_RSVD_230
AH71 TP_CPU0_RSVD_229 RSVD<229> @BASEBOARD_FAB2_LIB.BASEBOARD_FAB2(SCH_1):TP_CPU0_RSVD_229
AH73 TP_CPU0_RSVD_228 RSVD<228> @BASEBOARD_FAB2_LIB.BASEBOARD_FAB2(SCH_1):TP_CPU0_RSVD_228
AJ20 TP_CPU0_RSVD_227 RSVD<227> @BASEBOARD_FAB2_LIB.BASEBOARD_FAB2(SCH_1):TP_CPU0_RSVD_227
AJ56 TP_CPU0_RSVD_226 RSVD<226> @BASEBOARD_FAB2_LIB.BASEBOARD_FAB2(SCH_1):TP_CPU0_RSVD_226
AJ58 TP_CPU0_RSVD_225 RSVD<225> @BASEBOARD_FAB2_LIB.BASEBOARD_FAB2(SCH_1):TP_CPU0_RSVD_225
AJ60 TP_CPU0_RSVD_224 RSVD<224> @BASEBOARD_FAB2_LIB.BASEBOARD_FAB2(SCH_1):TP_CPU0_RSVD_224
AJ62 TP_CPU0_RSVD_223 RSVD<223> @BASEBOARD_FAB2_LIB.BASEBOARD_FAB2(SCH_1):TP_CPU0_RSVD_223
AJ70 TP_CPU0_RSVD_222 RSVD<222> @BASEBOARD_FAB2_LIB.BASEBOARD_FAB2(SCH_1):TP_CPU0_RSVD_222
AK21 VSENSE_P1V8MCP_CPU0_SKT_VSEN RSVD<221> @BASEBOARD_FAB2_LIB.BASEBOARD_FAB2(SCH_1):VSENSE_P1V8MCP_CPU0_SKT_VSEN
AK27 CLK_322M_OSC_CPU0_RC_DP RSVD<220> @BASEBOARD_FAB2_LIB.BASEBOARD_FAB2(SCH_1):CLK_322M_OSC_CPU0_RC_DP
AK57 TP_CPU0_RSVD_219 RSVD<219> @BASEBOARD_FAB2_LIB.BASEBOARD_FAB2(SCH_1):TP_CPU0_RSVD_219
AK59 TP_CPU0_RSVD_218 RSVD<218> @BASEBOARD_FAB2_LIB.BASEBOARD_FAB2(SCH_1):TP_CPU0_RSVD_218
AK61 TP_CPU0_RSVD_217 RSVD<217> @BASEBOARD_FAB2_LIB.BASEBOARD_FAB2(SCH_1):TP_CPU0_RSVD_217
AK69 TP_CPU0_RSVD_216 RSVD<216> @BASEBOARD_FAB2_LIB.BASEBOARD_FAB2(SCH_1):TP_CPU0_RSVD_216
AL20 VSENSE_P1V8MCP_CPU0_SKT_VRTN RSVD<215> @BASEBOARD_FAB2_LIB.BASEBOARD_FAB2(SCH_1):VSENSE_P1V8MCP_CPU0_SKT_VRTN
AL22 TP_CPU0_RSVD_214 RSVD<214> @BASEBOARD_FAB2_LIB.BASEBOARD_FAB2(SCH_1):TP_CPU0_RSVD_214
AL26 CLK_322M_OSC_CPU0_RC_DN RSVD<213> @BASEBOARD_FAB2_LIB.BASEBOARD_FAB2(SCH_1):CLK_322M_OSC_CPU0_RC_DN
AL58 TP_CPU0_RSVD_212 RSVD<212> @BASEBOARD_FAB2_LIB.BASEBOARD_FAB2(SCH_1):TP_CPU0_RSVD_212
AL60 TP_CPU0_RSVD_211 RSVD<211> @BASEBOARD_FAB2_LIB.BASEBOARD_FAB2(SCH_1):TP_CPU0_RSVD_211
AL62 TP_CPU0_RSVD_210 RSVD<210> @BASEBOARD_FAB2_LIB.BASEBOARD_FAB2(SCH_1):TP_CPU0_RSVD_210
AM21 PVCCMCP_CPU0 RSVD<209> @BASEBOARD_FAB2_LIB.BASEBOARD_FAB2(SCH_1):PVCCMCP_CPU0
AM23 TP_CPU0_RSVD_208 RSVD<208> @BASEBOARD_FAB2_LIB.BASEBOARD_FAB2(SCH_1):TP_CPU0_RSVD_208
AM25 PVCCMCP_CPU0 RSVD<207> @BASEBOARD_FAB2_LIB.BASEBOARD_FAB2(SCH_1):PVCCMCP_CPU0
AM27 CLK_100M_CPU0_RC_REFCLK0_DP RSVD<206> @BASEBOARD_FAB2_LIB.BASEBOARD_FAB2(SCH_1):CLK_100M_CPU0_RC_REFCLK0_DP
AM59 TP_CPU0_RSVD_205 RSVD<205> @BASEBOARD_FAB2_LIB.BASEBOARD_FAB2(SCH_1):TP_CPU0_RSVD_205
AM61 TP_CPU0_RSVD_204 RSVD<204> @BASEBOARD_FAB2_LIB.BASEBOARD_FAB2(SCH_1):TP_CPU0_RSVD_204
AN18 PVCCMCP_CPU0 RSVD<203> @BASEBOARD_FAB2_LIB.BASEBOARD_FAB2(SCH_1):PVCCMCP_CPU0
AN22 PVCCMCP_CPU0 RSVD<202> @BASEBOARD_FAB2_LIB.BASEBOARD_FAB2(SCH_1):PVCCMCP_CPU0
AN24 PVCCMCP_CPU0 RSVD<201> @BASEBOARD_FAB2_LIB.BASEBOARD_FAB2(SCH_1):PVCCMCP_CPU0
AN26 PVCCMCP_CPU0 RSVD<200> @BASEBOARD_FAB2_LIB.BASEBOARD_FAB2(SCH_1):PVCCMCP_CPU0
AN60 TP_CPU0_RSVD_199 RSVD<199> @BASEBOARD_FAB2_LIB.BASEBOARD_FAB2(SCH_1):TP_CPU0_RSVD_199
AN62 TP_CPU0_RSVD_198 RSVD<198> @BASEBOARD_FAB2_LIB.BASEBOARD_FAB2(SCH_1):TP_CPU0_RSVD_198
AP23 PVCCMCP_CPU0 RSVD<197> @BASEBOARD_FAB2_LIB.BASEBOARD_FAB2(SCH_1):PVCCMCP_CPU0
AP25 PVCCMCP_CPU0 RSVD<196> @BASEBOARD_FAB2_LIB.BASEBOARD_FAB2(SCH_1):PVCCMCP_CPU0
AP27 CLK_100M_CPU0_RC_REFCLK0_DN RSVD<195> @BASEBOARD_FAB2_LIB.BASEBOARD_FAB2(SCH_1):CLK_100M_CPU0_RC_REFCLK0_DN
AP61 TP_CPU0_RSVD_194 RSVD<194> @BASEBOARD_FAB2_LIB.BASEBOARD_FAB2(SCH_1):TP_CPU0_RSVD_194
AF45 PD_CPU0_RSVD_TEST_1 TEST_1 @BASEBOARD_FAB2_LIB.BASEBOARD_FAB2(SCH_1):PD_CPU0_RSVD_TEST_1
AY13 TP_CPU0_RSVD_TEST_11 TEST_11 @BASEBOARD_FAB2_LIB.BASEBOARD_FAB2(SCH_1):TP_CPU0_RSVD_TEST_11
AG46 PD_CPU0_RSVD_TEST_2 TEST_2 @BASEBOARD_FAB2_LIB.BASEBOARD_FAB2(SCH_1):PD_CPU0_RSVD_TEST_2
AM13 TP_CPU0_RSVD_TEST_3 TEST_3 @BASEBOARD_FAB2_LIB.BASEBOARD_FAB2(SCH_1):TP_CPU0_RSVD_TEST_3
AN12 TP_CPU0_RSVD_TEST_4 TEST_4 @BASEBOARD_FAB2_LIB.BASEBOARD_FAB2(SCH_1):TP_CPU0_RSVD_TEST_4
AN14 TP_CPU0_RSVD_TEST_5 TEST_5 @BASEBOARD_FAB2_LIB.BASEBOARD_FAB2(SCH_1):TP_CPU0_RSVD_TEST_5


DRAWING: @BASEBOARD_FAB2_LIB.BASEBOARD_FAB2(SCH_1):PAGE23 

SKX_EXT_B_BGA1-IC,TBD  I172  U5D1
 J60 M_A_ACT_N DDR0_ACT_N @BASEBOARD_FAB2_LIB.BASEBOARD_FAB2(SCH_1):M_A_ACT_N
 B61 M_A_ALERT_N DDR0_ALERT_N @BASEBOARD_FAB2_LIB.BASEBOARD_FAB2(SCH_1):M_A_ALERT_N
 G54 M_A_BA<1> DDR0_BA<1> @BASEBOARD_FAB2_LIB.BASEBOARD_FAB2(SCH_1):M_A_BA(1)
 C52 M_A_BA<0> DDR0_BA<0> @BASEBOARD_FAB2_LIB.BASEBOARD_FAB2(SCH_1):M_A_BA(0)
 F63 M_A_BG<1> DDR0_BG<1> @BASEBOARD_FAB2_LIB.BASEBOARD_FAB2(SCH_1):M_A_BG(1)
 D61 M_A_BG<0> DDR0_BG<0> @BASEBOARD_FAB2_LIB.BASEBOARD_FAB2(SCH_1):M_A_BG(0)
 G46 M_A_C<2> DDR0_CID<2> @BASEBOARD_FAB2_LIB.BASEBOARD_FAB2(SCH_1):M_A_C(2)
 D63 M_A_CKE<3> DDR0_CKE<3> @BASEBOARD_FAB2_LIB.BASEBOARD_FAB2(SCH_1):M_A_CKE(3)
 B63 M_A_CKE<2> DDR0_CKE<2> @BASEBOARD_FAB2_LIB.BASEBOARD_FAB2(SCH_1):M_A_CKE(2)
 C64 M_A_CKE<1> DDR0_CKE<1> @BASEBOARD_FAB2_LIB.BASEBOARD_FAB2(SCH_1):M_A_CKE(1)
 C62 M_A_CKE<0> DDR0_CKE<0> @BASEBOARD_FAB2_LIB.BASEBOARD_FAB2(SCH_1):M_A_CKE(0)
 C56 M_A_CLK_DN<3> DDR0_CLK_DN<3> @BASEBOARD_FAB2_LIB.BASEBOARD_FAB2(SCH_1):M_A_CLK_DN(3)
 J56 M_A_CLK_DN<2> DDR0_CLK_DN<2> @BASEBOARD_FAB2_LIB.BASEBOARD_FAB2(SCH_1):M_A_CLK_DN(2)
 C54 M_A_CLK_DN<1> DDR0_CLK_DN<1> @BASEBOARD_FAB2_LIB.BASEBOARD_FAB2(SCH_1):M_A_CLK_DN(1)
 F55 M_A_CLK_DN<0> DDR0_CLK_DN<0> @BASEBOARD_FAB2_LIB.BASEBOARD_FAB2(SCH_1):M_A_CLK_DN(0)
 B57 M_A_CLK_DP<3> DDR0_CLK_DP<3> @BASEBOARD_FAB2_LIB.BASEBOARD_FAB2(SCH_1):M_A_CLK_DP(3)
 G56 M_A_CLK_DP<2> DDR0_CLK_DP<2> @BASEBOARD_FAB2_LIB.BASEBOARD_FAB2(SCH_1):M_A_CLK_DP(2)
 B55 M_A_CLK_DP<1> DDR0_CLK_DP<1> @BASEBOARD_FAB2_LIB.BASEBOARD_FAB2(SCH_1):M_A_CLK_DP(1)
 D55 M_A_CLK_DP<0> DDR0_CLK_DP<0> @BASEBOARD_FAB2_LIB.BASEBOARD_FAB2(SCH_1):M_A_CLK_DP(0)
 K45 M_A_CS_N<7> DDR0_CS_N<7> @BASEBOARD_FAB2_LIB.BASEBOARD_FAB2(SCH_1):M_A_CS_N(7)
 F45 M_A_CS_N<6> DDR0_CS_N<6> @BASEBOARD_FAB2_LIB.BASEBOARD_FAB2(SCH_1):M_A_CS_N(6)
 D49 M_A_CS_N<5> DDR0_CS_N<5> @BASEBOARD_FAB2_LIB.BASEBOARD_FAB2(SCH_1):M_A_CS_N(5)
 B51 M_A_CS_N<4> DDR0_CS_N<4> @BASEBOARD_FAB2_LIB.BASEBOARD_FAB2(SCH_1):M_A_CS_N(4)
 F47 M_A_CS_N<3> DDR0_CS_N<3> @BASEBOARD_FAB2_LIB.BASEBOARD_FAB2(SCH_1):M_A_CS_N(3)
 D47 M_A_CS_N<2> DDR0_CS_N<2> @BASEBOARD_FAB2_LIB.BASEBOARD_FAB2(SCH_1):M_A_CS_N(2)
 F49 M_A_CS_N<1> DDR0_CS_N<1> @BASEBOARD_FAB2_LIB.BASEBOARD_FAB2(SCH_1):M_A_CS_N(1)
 G52 M_A_CS_N<0> DDR0_CS_N<0> @BASEBOARD_FAB2_LIB.BASEBOARD_FAB2(SCH_1):M_A_CS_N(0)
 K23 M_A_DQ<63> DDR0_DQ<63> @BASEBOARD_FAB2_LIB.BASEBOARD_FAB2(SCH_1):M_A_DQ(63)
 H23 M_A_DQ<62> DDR0_DQ<62> @BASEBOARD_FAB2_LIB.BASEBOARD_FAB2(SCH_1):M_A_DQ(62)
 N26 M_A_DQ<61> DDR0_DQ<61> @BASEBOARD_FAB2_LIB.BASEBOARD_FAB2(SCH_1):M_A_DQ(61)
 L26 M_A_DQ<60> DDR0_DQ<60> @BASEBOARD_FAB2_LIB.BASEBOARD_FAB2(SCH_1):M_A_DQ(60)
 T23 M_A_DQ<59> DDR0_DQ<59> @BASEBOARD_FAB2_LIB.BASEBOARD_FAB2(SCH_1):M_A_DQ(59)
 P23 M_A_DQ<58> DDR0_DQ<58> @BASEBOARD_FAB2_LIB.BASEBOARD_FAB2(SCH_1):M_A_DQ(58)
 P25 M_A_DQ<57> DDR0_DQ<57> @BASEBOARD_FAB2_LIB.BASEBOARD_FAB2(SCH_1):M_A_DQ(57)
 K25 M_A_DQ<56> DDR0_DQ<56> @BASEBOARD_FAB2_LIB.BASEBOARD_FAB2(SCH_1):M_A_DQ(56)
 P29 M_A_DQ<55> DDR0_DQ<55> @BASEBOARD_FAB2_LIB.BASEBOARD_FAB2(SCH_1):M_A_DQ(55)
 K29 M_A_DQ<54> DDR0_DQ<54> @BASEBOARD_FAB2_LIB.BASEBOARD_FAB2(SCH_1):M_A_DQ(54)
 N32 M_A_DQ<53> DDR0_DQ<53> @BASEBOARD_FAB2_LIB.BASEBOARD_FAB2(SCH_1):M_A_DQ(53)
 L32 M_A_DQ<52> DDR0_DQ<52> @BASEBOARD_FAB2_LIB.BASEBOARD_FAB2(SCH_1):M_A_DQ(52)
 N28 M_A_DQ<51> DDR0_DQ<51> @BASEBOARD_FAB2_LIB.BASEBOARD_FAB2(SCH_1):M_A_DQ(51)
 L28 M_A_DQ<50> DDR0_DQ<50> @BASEBOARD_FAB2_LIB.BASEBOARD_FAB2(SCH_1):M_A_DQ(50)
 P31 M_A_DQ<49> DDR0_DQ<49> @BASEBOARD_FAB2_LIB.BASEBOARD_FAB2(SCH_1):M_A_DQ(49)
 K31 M_A_DQ<48> DDR0_DQ<48> @BASEBOARD_FAB2_LIB.BASEBOARD_FAB2(SCH_1):M_A_DQ(48)
 P35 M_A_DQ<47> DDR0_DQ<47> @BASEBOARD_FAB2_LIB.BASEBOARD_FAB2(SCH_1):M_A_DQ(47)
 K35 M_A_DQ<46> DDR0_DQ<46> @BASEBOARD_FAB2_LIB.BASEBOARD_FAB2(SCH_1):M_A_DQ(46)
 N38 M_A_DQ<45> DDR0_DQ<45> @BASEBOARD_FAB2_LIB.BASEBOARD_FAB2(SCH_1):M_A_DQ(45)
 L38 M_A_DQ<44> DDR0_DQ<44> @BASEBOARD_FAB2_LIB.BASEBOARD_FAB2(SCH_1):M_A_DQ(44)
 N34 M_A_DQ<43> DDR0_DQ<43> @BASEBOARD_FAB2_LIB.BASEBOARD_FAB2(SCH_1):M_A_DQ(43)
 L34 M_A_DQ<42> DDR0_DQ<42> @BASEBOARD_FAB2_LIB.BASEBOARD_FAB2(SCH_1):M_A_DQ(42)
 P37 M_A_DQ<41> DDR0_DQ<41> @BASEBOARD_FAB2_LIB.BASEBOARD_FAB2(SCH_1):M_A_DQ(41)
 K37 M_A_DQ<40> DDR0_DQ<40> @BASEBOARD_FAB2_LIB.BASEBOARD_FAB2(SCH_1):M_A_DQ(40)
 F39 M_A_DQ<39> DDR0_DQ<39> @BASEBOARD_FAB2_LIB.BASEBOARD_FAB2(SCH_1):M_A_DQ(39)
 B39 M_A_DQ<38> DDR0_DQ<38> @BASEBOARD_FAB2_LIB.BASEBOARD_FAB2(SCH_1):M_A_DQ(38)
 F41 M_A_DQ<37> DDR0_DQ<37> @BASEBOARD_FAB2_LIB.BASEBOARD_FAB2(SCH_1):M_A_DQ(37)
 E42 M_A_DQ<36> DDR0_DQ<36> @BASEBOARD_FAB2_LIB.BASEBOARD_FAB2(SCH_1):M_A_DQ(36)
 E38 M_A_DQ<35> DDR0_DQ<35> @BASEBOARD_FAB2_LIB.BASEBOARD_FAB2(SCH_1):M_A_DQ(35)
 C38 M_A_DQ<34> DDR0_DQ<34> @BASEBOARD_FAB2_LIB.BASEBOARD_FAB2(SCH_1):M_A_DQ(34)
 B41 M_A_DQ<33> DDR0_DQ<33> @BASEBOARD_FAB2_LIB.BASEBOARD_FAB2(SCH_1):M_A_DQ(33)
 C42 M_A_DQ<32> DDR0_DQ<32> @BASEBOARD_FAB2_LIB.BASEBOARD_FAB2(SCH_1):M_A_DQ(32)
 R74 M_A_DQ<31> DDR0_DQ<31> @BASEBOARD_FAB2_LIB.BASEBOARD_FAB2(SCH_1):M_A_DQ(31)
 L74 M_A_DQ<30> DDR0_DQ<30> @BASEBOARD_FAB2_LIB.BASEBOARD_FAB2(SCH_1):M_A_DQ(30)
 P77 M_A_DQ<29> DDR0_DQ<29> @BASEBOARD_FAB2_LIB.BASEBOARD_FAB2(SCH_1):M_A_DQ(29)
 M77 M_A_DQ<28> DDR0_DQ<28> @BASEBOARD_FAB2_LIB.BASEBOARD_FAB2(SCH_1):M_A_DQ(28)
 P73 M_A_DQ<27> DDR0_DQ<27> @BASEBOARD_FAB2_LIB.BASEBOARD_FAB2(SCH_1):M_A_DQ(27)
 M73 M_A_DQ<26> DDR0_DQ<26> @BASEBOARD_FAB2_LIB.BASEBOARD_FAB2(SCH_1):M_A_DQ(26)
 R76 M_A_DQ<25> DDR0_DQ<25> @BASEBOARD_FAB2_LIB.BASEBOARD_FAB2(SCH_1):M_A_DQ(25)
 L76 M_A_DQ<24> DDR0_DQ<24> @BASEBOARD_FAB2_LIB.BASEBOARD_FAB2(SCH_1):M_A_DQ(24)
 N80 M_A_DQ<23> DDR0_DQ<23> @BASEBOARD_FAB2_LIB.BASEBOARD_FAB2(SCH_1):M_A_DQ(23)
 R82 M_A_DQ<22> DDR0_DQ<22> @BASEBOARD_FAB2_LIB.BASEBOARD_FAB2(SCH_1):M_A_DQ(22)
 V79 M_A_DQ<21> DDR0_DQ<21> @BASEBOARD_FAB2_LIB.BASEBOARD_FAB2(SCH_1):M_A_DQ(21)
 W80 M_A_DQ<20> DDR0_DQ<20> @BASEBOARD_FAB2_LIB.BASEBOARD_FAB2(SCH_1):M_A_DQ(20)
 M81 M_A_DQ<19> DDR0_DQ<19> @BASEBOARD_FAB2_LIB.BASEBOARD_FAB2(SCH_1):M_A_DQ(19)
 N82 M_A_DQ<18> DDR0_DQ<18> @BASEBOARD_FAB2_LIB.BASEBOARD_FAB2(SCH_1):M_A_DQ(18)
 T79 M_A_DQ<17> DDR0_DQ<17> @BASEBOARD_FAB2_LIB.BASEBOARD_FAB2(SCH_1):M_A_DQ(17)
 V81 M_A_DQ<16> DDR0_DQ<16> @BASEBOARD_FAB2_LIB.BASEBOARD_FAB2(SCH_1):M_A_DQ(16)
 N84 M_A_DQ<15> DDR0_DQ<15> @BASEBOARD_FAB2_LIB.BASEBOARD_FAB2(SCH_1):M_A_DQ(15)
 N86 M_A_DQ<14> DDR0_DQ<14> @BASEBOARD_FAB2_LIB.BASEBOARD_FAB2(SCH_1):M_A_DQ(14)
AA84 M_A_DQ<13> DDR0_DQ<13> @BASEBOARD_FAB2_LIB.BASEBOARD_FAB2(SCH_1):M_A_DQ(13)
AA86 M_A_DQ<12> DDR0_DQ<12> @BASEBOARD_FAB2_LIB.BASEBOARD_FAB2(SCH_1):M_A_DQ(12)
 L84 M_A_DQ<11> DDR0_DQ<11> @BASEBOARD_FAB2_LIB.BASEBOARD_FAB2(SCH_1):M_A_DQ(11)
 L86 M_A_DQ<10> DDR0_DQ<10> @BASEBOARD_FAB2_LIB.BASEBOARD_FAB2(SCH_1):M_A_DQ(10)
 W84 M_A_DQ<9> DDR0_DQ<9> @BASEBOARD_FAB2_LIB.BASEBOARD_FAB2(SCH_1):M_A_DQ(9)
 W86 M_A_DQ<8> DDR0_DQ<8> @BASEBOARD_FAB2_LIB.BASEBOARD_FAB2(SCH_1):M_A_DQ(8)
AG84 M_A_DQ<7> DDR0_DQ<7> @BASEBOARD_FAB2_LIB.BASEBOARD_FAB2(SCH_1):M_A_DQ(7)
AG86 M_A_DQ<6> DDR0_DQ<6> @BASEBOARD_FAB2_LIB.BASEBOARD_FAB2(SCH_1):M_A_DQ(6)
AR84 M_A_DQ<5> DDR0_DQ<5> @BASEBOARD_FAB2_LIB.BASEBOARD_FAB2(SCH_1):M_A_DQ(5)
AR86 M_A_DQ<4> DDR0_DQ<4> @BASEBOARD_FAB2_LIB.BASEBOARD_FAB2(SCH_1):M_A_DQ(4)
AE84 M_A_DQ<3> DDR0_DQ<3> @BASEBOARD_FAB2_LIB.BASEBOARD_FAB2(SCH_1):M_A_DQ(3)
AE86 M_A_DQ<2> DDR0_DQ<2> @BASEBOARD_FAB2_LIB.BASEBOARD_FAB2(SCH_1):M_A_DQ(2)
AN84 M_A_DQ<1> DDR0_DQ<1> @BASEBOARD_FAB2_LIB.BASEBOARD_FAB2(SCH_1):M_A_DQ(1)
AN86 M_A_DQ<0> DDR0_DQ<0> @BASEBOARD_FAB2_LIB.BASEBOARD_FAB2(SCH_1):M_A_DQ(0)
AB67 M_A_DQS_DN<17> DDR0_DQS_DN<17> @BASEBOARD_FAB2_LIB.BASEBOARD_FAB2(SCH_1):M_A_DQS_DN(17)
 J24 M_A_DQS_DN<16> DDR0_DQS_DN<16> @BASEBOARD_FAB2_LIB.BASEBOARD_FAB2(SCH_1):M_A_DQS_DN(16)
 J30 M_A_DQS_DN<15> DDR0_DQS_DN<15> @BASEBOARD_FAB2_LIB.BASEBOARD_FAB2(SCH_1):M_A_DQS_DN(15)
 J36 M_A_DQS_DN<14> DDR0_DQS_DN<14> @BASEBOARD_FAB2_LIB.BASEBOARD_FAB2(SCH_1):M_A_DQS_DN(14)
 A40 M_A_DQS_DN<13> DDR0_DQS_DN<13> @BASEBOARD_FAB2_LIB.BASEBOARD_FAB2(SCH_1):M_A_DQS_DN(13)
 K75 M_A_DQS_DN<12> DDR0_DQS_DN<12> @BASEBOARD_FAB2_LIB.BASEBOARD_FAB2(SCH_1):M_A_DQS_DN(12)
 U82 M_A_DQS_DN<11> DDR0_DQS_DN<11> @BASEBOARD_FAB2_LIB.BASEBOARD_FAB2(SCH_1):M_A_DQS_DN(11)
 U84 M_A_DQS_DN<10> DDR0_DQS_DN<10> @BASEBOARD_FAB2_LIB.BASEBOARD_FAB2(SCH_1):M_A_DQS_DN(10)
AL84 M_A_DQS_DN<9> DDR0_DQS_DN<9> @BASEBOARD_FAB2_LIB.BASEBOARD_FAB2(SCH_1):M_A_DQS_DN(9)
AH67 M_A_DQS_DN<8> DDR0_DQS_DN<8> @BASEBOARD_FAB2_LIB.BASEBOARD_FAB2(SCH_1):M_A_DQS_DN(8)
 N24 M_A_DQS_DN<7> DDR0_DQS_DN<7> @BASEBOARD_FAB2_LIB.BASEBOARD_FAB2(SCH_1):M_A_DQS_DN(7)
 R30 M_A_DQS_DN<6> DDR0_DQS_DN<6> @BASEBOARD_FAB2_LIB.BASEBOARD_FAB2(SCH_1):M_A_DQS_DN(6)
 R36 M_A_DQS_DN<5> DDR0_DQS_DN<5> @BASEBOARD_FAB2_LIB.BASEBOARD_FAB2(SCH_1):M_A_DQS_DN(5)
 G40 M_A_DQS_DN<4> DDR0_DQS_DN<4> @BASEBOARD_FAB2_LIB.BASEBOARD_FAB2(SCH_1):M_A_DQS_DN(4)
 T75 M_A_DQS_DN<3> DDR0_DQS_DN<3> @BASEBOARD_FAB2_LIB.BASEBOARD_FAB2(SCH_1):M_A_DQS_DN(3)
 P79 M_A_DQS_DN<2> DDR0_DQS_DN<2> @BASEBOARD_FAB2_LIB.BASEBOARD_FAB2(SCH_1):M_A_DQS_DN(2)
 R84 M_A_DQS_DN<1> DDR0_DQS_DN<1> @BASEBOARD_FAB2_LIB.BASEBOARD_FAB2(SCH_1):M_A_DQS_DN(1)
AJ84 M_A_DQS_DN<0> DDR0_DQS_DN<0> @BASEBOARD_FAB2_LIB.BASEBOARD_FAB2(SCH_1):M_A_DQS_DN(0)
AD67 M_A_DQS_DP<17> DDR0_DQS_DP<17> @BASEBOARD_FAB2_LIB.BASEBOARD_FAB2(SCH_1):M_A_DQS_DP(17)
 L24 M_A_DQS_DP<16> DDR0_DQS_DP<16> @BASEBOARD_FAB2_LIB.BASEBOARD_FAB2(SCH_1):M_A_DQS_DP(16)
 L30 M_A_DQS_DP<15> DDR0_DQS_DP<15> @BASEBOARD_FAB2_LIB.BASEBOARD_FAB2(SCH_1):M_A_DQS_DP(15)
 L36 M_A_DQS_DP<14> DDR0_DQS_DP<14> @BASEBOARD_FAB2_LIB.BASEBOARD_FAB2(SCH_1):M_A_DQS_DP(14)
 C40 M_A_DQS_DP<13> DDR0_DQS_DP<13> @BASEBOARD_FAB2_LIB.BASEBOARD_FAB2(SCH_1):M_A_DQS_DP(13)
 M75 M_A_DQS_DP<12> DDR0_DQS_DP<12> @BASEBOARD_FAB2_LIB.BASEBOARD_FAB2(SCH_1):M_A_DQS_DP(12)
 T81 M_A_DQS_DP<11> DDR0_DQS_DP<11> @BASEBOARD_FAB2_LIB.BASEBOARD_FAB2(SCH_1):M_A_DQS_DP(11)
 V85 M_A_DQS_DP<10> DDR0_DQS_DP<10> @BASEBOARD_FAB2_LIB.BASEBOARD_FAB2(SCH_1):M_A_DQS_DP(10)
AM85 M_A_DQS_DP<9> DDR0_DQS_DP<9> @BASEBOARD_FAB2_LIB.BASEBOARD_FAB2(SCH_1):M_A_DQS_DP(9)
AF67 M_A_DQS_DP<8> DDR0_DQS_DP<8> @BASEBOARD_FAB2_LIB.BASEBOARD_FAB2(SCH_1):M_A_DQS_DP(8)
 R24 M_A_DQS_DP<7> DDR0_DQS_DP<7> @BASEBOARD_FAB2_LIB.BASEBOARD_FAB2(SCH_1):M_A_DQS_DP(7)
 N30 M_A_DQS_DP<6> DDR0_DQS_DP<6> @BASEBOARD_FAB2_LIB.BASEBOARD_FAB2(SCH_1):M_A_DQS_DP(6)
 N36 M_A_DQS_DP<5> DDR0_DQS_DP<5> @BASEBOARD_FAB2_LIB.BASEBOARD_FAB2(SCH_1):M_A_DQS_DP(5)
 E40 M_A_DQS_DP<4> DDR0_DQS_DP<4> @BASEBOARD_FAB2_LIB.BASEBOARD_FAB2(SCH_1):M_A_DQS_DP(4)
 P75 M_A_DQS_DP<3> DDR0_DQS_DP<3> @BASEBOARD_FAB2_LIB.BASEBOARD_FAB2(SCH_1):M_A_DQS_DP(3)
 R80 M_A_DQS_DP<2> DDR0_DQS_DP<2> @BASEBOARD_FAB2_LIB.BASEBOARD_FAB2(SCH_1):M_A_DQS_DP(2)
 P85 M_A_DQS_DP<1> DDR0_DQS_DP<1> @BASEBOARD_FAB2_LIB.BASEBOARD_FAB2(SCH_1):M_A_DQS_DP(1)
AH85 M_A_DQS_DP<0> DDR0_DQS_DP<0> @BASEBOARD_FAB2_LIB.BASEBOARD_FAB2(SCH_1):M_A_DQS_DP(0)
AG66 M_A_ECC<7> DDR0_ECC<7> @BASEBOARD_FAB2_LIB.BASEBOARD_FAB2(SCH_1):M_A_ECC(7)
AC66 M_A_ECC<6> DDR0_ECC<6> @BASEBOARD_FAB2_LIB.BASEBOARD_FAB2(SCH_1):M_A_ECC(6)
AF69 M_A_ECC<5> DDR0_ECC<5> @BASEBOARD_FAB2_LIB.BASEBOARD_FAB2(SCH_1):M_A_ECC(5)
AD69 M_A_ECC<4> DDR0_ECC<4> @BASEBOARD_FAB2_LIB.BASEBOARD_FAB2(SCH_1):M_A_ECC(4)
AF65 M_A_ECC<3> DDR0_ECC<3> @BASEBOARD_FAB2_LIB.BASEBOARD_FAB2(SCH_1):M_A_ECC(3)
AD65 M_A_ECC<2> DDR0_ECC<2> @BASEBOARD_FAB2_LIB.BASEBOARD_FAB2(SCH_1):M_A_ECC(2)
AG68 M_A_ECC<1> DDR0_ECC<1> @BASEBOARD_FAB2_LIB.BASEBOARD_FAB2(SCH_1):M_A_ECC(1)
AC68 M_A_ECC<0> DDR0_ECC<0> @BASEBOARD_FAB2_LIB.BASEBOARD_FAB2(SCH_1):M_A_ECC(0)
 K47 M_A_MA<17> DDR0_MA<17> @BASEBOARD_FAB2_LIB.BASEBOARD_FAB2(SCH_1):M_A_MA(17)
 D51 M_A_MA<16> DDR0_MA<16> @BASEBOARD_FAB2_LIB.BASEBOARD_FAB2(SCH_1):M_A_MA(16)
 K49 M_A_MA<15> DDR0_MA<15> @BASEBOARD_FAB2_LIB.BASEBOARD_FAB2(SCH_1):M_A_MA(15)
 F51 M_A_MA<14> DDR0_MA<14> @BASEBOARD_FAB2_LIB.BASEBOARD_FAB2(SCH_1):M_A_MA(14)
 J48 M_A_MA<13> DDR0_MA<13> @BASEBOARD_FAB2_LIB.BASEBOARD_FAB2(SCH_1):M_A_MA(13)
 J64 M_A_MA<12> DDR0_MA<12> @BASEBOARD_FAB2_LIB.BASEBOARD_FAB2(SCH_1):M_A_MA(12)
 G62 M_A_MA<11> DDR0_MA<11> @BASEBOARD_FAB2_LIB.BASEBOARD_FAB2(SCH_1):M_A_MA(11)
 J54 M_A_MA<10> DDR0_MA<10> @BASEBOARD_FAB2_LIB.BASEBOARD_FAB2(SCH_1):M_A_MA(10)
 F61 M_A_MA<9> DDR0_MA<9> @BASEBOARD_FAB2_LIB.BASEBOARD_FAB2(SCH_1):M_A_MA(9)
 C60 M_A_MA<8> DDR0_MA<8> @BASEBOARD_FAB2_LIB.BASEBOARD_FAB2(SCH_1):M_A_MA(8)
 G60 M_A_MA<7> DDR0_MA<7> @BASEBOARD_FAB2_LIB.BASEBOARD_FAB2(SCH_1):M_A_MA(7)
 D59 M_A_MA<6> DDR0_MA<6> @BASEBOARD_FAB2_LIB.BASEBOARD_FAB2(SCH_1):M_A_MA(6)
 F59 M_A_MA<5> DDR0_MA<5> @BASEBOARD_FAB2_LIB.BASEBOARD_FAB2(SCH_1):M_A_MA(5)
 G58 M_A_MA<4> DDR0_MA<4> @BASEBOARD_FAB2_LIB.BASEBOARD_FAB2(SCH_1):M_A_MA(4)
 C58 M_A_MA<3> DDR0_MA<3> @BASEBOARD_FAB2_LIB.BASEBOARD_FAB2(SCH_1):M_A_MA(3)
 D57 M_A_MA<2> DDR0_MA<2> @BASEBOARD_FAB2_LIB.BASEBOARD_FAB2(SCH_1):M_A_MA(2)
 F57 M_A_MA<1> DDR0_MA<1> @BASEBOARD_FAB2_LIB.BASEBOARD_FAB2(SCH_1):M_A_MA(1)
 F53 M_A_MA<0> DDR0_MA<0> @BASEBOARD_FAB2_LIB.BASEBOARD_FAB2(SCH_1):M_A_MA(0)
 G48 M_A_ODT<3> DDR0_ODT<3> @BASEBOARD_FAB2_LIB.BASEBOARD_FAB2(SCH_1):M_A_ODT(3)
 G50 M_A_ODT<2> DDR0_ODT<2> @BASEBOARD_FAB2_LIB.BASEBOARD_FAB2(SCH_1):M_A_ODT(2)
 C48 M_A_ODT<1> DDR0_ODT<1> @BASEBOARD_FAB2_LIB.BASEBOARD_FAB2(SCH_1):M_A_ODT(1)
 C50 M_A_ODT<0> DDR0_ODT<0> @BASEBOARD_FAB2_LIB.BASEBOARD_FAB2(SCH_1):M_A_ODT(0)
 D53 M_A_PAR DDR0_PAR @BASEBOARD_FAB2_LIB.BASEBOARD_FAB2(SCH_1):M_A_PAR


DRAWING: @BASEBOARD_FAB2_LIB.BASEBOARD_FAB2(SCH_1):PAGE24 

SKX_EXT_B_BGA1-IC,TBD  I172  U5D1
 T63 M_B_ACT_N DDR1_ACT_N @BASEBOARD_FAB2_LIB.BASEBOARD_FAB2(SCH_1):M_B_ACT_N
 W62 M_B_ALERT_N DDR1_ALERT_N @BASEBOARD_FAB2_LIB.BASEBOARD_FAB2(SCH_1):M_B_ALERT_N
 K55 M_B_BA<1> DDR1_BA<1> @BASEBOARD_FAB2_LIB.BASEBOARD_FAB2(SCH_1):M_B_BA(1)
 T53 M_B_BA<0> DDR1_BA<0> @BASEBOARD_FAB2_LIB.BASEBOARD_FAB2(SCH_1):M_B_BA(0)
 N60 M_B_BG<1> DDR1_BG<1> @BASEBOARD_FAB2_LIB.BASEBOARD_FAB2(SCH_1):M_B_BG(1)
 M61 M_B_BG<0> DDR1_BG<0> @BASEBOARD_FAB2_LIB.BASEBOARD_FAB2(SCH_1):M_B_BG(0)
 M47 M_B_C<2> DDR1_CID<2> @BASEBOARD_FAB2_LIB.BASEBOARD_FAB2(SCH_1):M_B_C(2)
 L64 M_B_CKE<3> DDR1_CKE<3> @BASEBOARD_FAB2_LIB.BASEBOARD_FAB2(SCH_1):M_B_CKE(3)
 K63 M_B_CKE<2> DDR1_CKE<2> @BASEBOARD_FAB2_LIB.BASEBOARD_FAB2(SCH_1):M_B_CKE(2)
 R64 M_B_CKE<1> DDR1_CKE<1> @BASEBOARD_FAB2_LIB.BASEBOARD_FAB2(SCH_1):M_B_CKE(1)
 N62 M_B_CKE<0> DDR1_CKE<0> @BASEBOARD_FAB2_LIB.BASEBOARD_FAB2(SCH_1):M_B_CKE(0)
 R56 M_B_CLK_DN<3> DDR1_CLK_DN<3> @BASEBOARD_FAB2_LIB.BASEBOARD_FAB2(SCH_1):M_B_CLK_DN(3)
 N56 M_B_CLK_DN<2> DDR1_CLK_DN<2> @BASEBOARD_FAB2_LIB.BASEBOARD_FAB2(SCH_1):M_B_CLK_DN(2)
 R54 M_B_CLK_DN<1> DDR1_CLK_DN<1> @BASEBOARD_FAB2_LIB.BASEBOARD_FAB2(SCH_1):M_B_CLK_DN(1)
 M53 M_B_CLK_DN<0> DDR1_CLK_DN<0> @BASEBOARD_FAB2_LIB.BASEBOARD_FAB2(SCH_1):M_B_CLK_DN(0)
 T57 M_B_CLK_DP<3> DDR1_CLK_DP<3> @BASEBOARD_FAB2_LIB.BASEBOARD_FAB2(SCH_1):M_B_CLK_DP(3)
 M57 M_B_CLK_DP<2> DDR1_CLK_DP<2> @BASEBOARD_FAB2_LIB.BASEBOARD_FAB2(SCH_1):M_B_CLK_DP(2)
 T55 M_B_CLK_DP<1> DDR1_CLK_DP<1> @BASEBOARD_FAB2_LIB.BASEBOARD_FAB2(SCH_1):M_B_CLK_DP(1)
 N54 M_B_CLK_DP<0> DDR1_CLK_DP<0> @BASEBOARD_FAB2_LIB.BASEBOARD_FAB2(SCH_1):M_B_CLK_DP(0)
 R46 M_B_CS_N<7> DDR1_CS_N<7> @BASEBOARD_FAB2_LIB.BASEBOARD_FAB2(SCH_1):M_B_CS_N(7)
 M45 M_B_CS_N<6> DDR1_CS_N<6> @BASEBOARD_FAB2_LIB.BASEBOARD_FAB2(SCH_1):M_B_CS_N(6)
 T49 M_B_CS_N<5> DDR1_CS_N<5> @BASEBOARD_FAB2_LIB.BASEBOARD_FAB2(SCH_1):M_B_CS_N(5)
 J50 M_B_CS_N<4> DDR1_CS_N<4> @BASEBOARD_FAB2_LIB.BASEBOARD_FAB2(SCH_1):M_B_CS_N(4)
 V47 M_B_CS_N<3> DDR1_CS_N<3> @BASEBOARD_FAB2_LIB.BASEBOARD_FAB2(SCH_1):M_B_CS_N(3)
 N46 M_B_CS_N<2> DDR1_CS_N<2> @BASEBOARD_FAB2_LIB.BASEBOARD_FAB2(SCH_1):M_B_CS_N(2)
 R50 M_B_CS_N<1> DDR1_CS_N<1> @BASEBOARD_FAB2_LIB.BASEBOARD_FAB2(SCH_1):M_B_CS_N(1)
 K51 M_B_CS_N<0> DDR1_CS_N<0> @BASEBOARD_FAB2_LIB.BASEBOARD_FAB2(SCH_1):M_B_CS_N(0)
AA26 M_B_DQ<63> DDR1_DQ<63> @BASEBOARD_FAB2_LIB.BASEBOARD_FAB2(SCH_1):M_B_DQ(63)
 U26 M_B_DQ<62> DDR1_DQ<62> @BASEBOARD_FAB2_LIB.BASEBOARD_FAB2(SCH_1):M_B_DQ(62)
 Y29 M_B_DQ<61> DDR1_DQ<61> @BASEBOARD_FAB2_LIB.BASEBOARD_FAB2(SCH_1):M_B_DQ(61)
 V29 M_B_DQ<60> DDR1_DQ<60> @BASEBOARD_FAB2_LIB.BASEBOARD_FAB2(SCH_1):M_B_DQ(60)
 Y25 M_B_DQ<59> DDR1_DQ<59> @BASEBOARD_FAB2_LIB.BASEBOARD_FAB2(SCH_1):M_B_DQ(59)
 V25 M_B_DQ<58> DDR1_DQ<58> @BASEBOARD_FAB2_LIB.BASEBOARD_FAB2(SCH_1):M_B_DQ(58)
AA28 M_B_DQ<57> DDR1_DQ<57> @BASEBOARD_FAB2_LIB.BASEBOARD_FAB2(SCH_1):M_B_DQ(57)
 U28 M_B_DQ<56> DDR1_DQ<56> @BASEBOARD_FAB2_LIB.BASEBOARD_FAB2(SCH_1):M_B_DQ(56)
 F27 M_B_DQ<55> DDR1_DQ<55> @BASEBOARD_FAB2_LIB.BASEBOARD_FAB2(SCH_1):M_B_DQ(55)
 B27 M_B_DQ<54> DDR1_DQ<54> @BASEBOARD_FAB2_LIB.BASEBOARD_FAB2(SCH_1):M_B_DQ(54)
 F29 M_B_DQ<53> DDR1_DQ<53> @BASEBOARD_FAB2_LIB.BASEBOARD_FAB2(SCH_1):M_B_DQ(53)
 E30 M_B_DQ<52> DDR1_DQ<52> @BASEBOARD_FAB2_LIB.BASEBOARD_FAB2(SCH_1):M_B_DQ(52)
 E26 M_B_DQ<51> DDR1_DQ<51> @BASEBOARD_FAB2_LIB.BASEBOARD_FAB2(SCH_1):M_B_DQ(51)
 C26 M_B_DQ<50> DDR1_DQ<50> @BASEBOARD_FAB2_LIB.BASEBOARD_FAB2(SCH_1):M_B_DQ(50)
 B29 M_B_DQ<49> DDR1_DQ<49> @BASEBOARD_FAB2_LIB.BASEBOARD_FAB2(SCH_1):M_B_DQ(49)
 C30 M_B_DQ<48> DDR1_DQ<48> @BASEBOARD_FAB2_LIB.BASEBOARD_FAB2(SCH_1):M_B_DQ(48)
 F33 M_B_DQ<47> DDR1_DQ<47> @BASEBOARD_FAB2_LIB.BASEBOARD_FAB2(SCH_1):M_B_DQ(47)
 B33 M_B_DQ<46> DDR1_DQ<46> @BASEBOARD_FAB2_LIB.BASEBOARD_FAB2(SCH_1):M_B_DQ(46)
 F35 M_B_DQ<45> DDR1_DQ<45> @BASEBOARD_FAB2_LIB.BASEBOARD_FAB2(SCH_1):M_B_DQ(45)
 E36 M_B_DQ<44> DDR1_DQ<44> @BASEBOARD_FAB2_LIB.BASEBOARD_FAB2(SCH_1):M_B_DQ(44)
 E32 M_B_DQ<43> DDR1_DQ<43> @BASEBOARD_FAB2_LIB.BASEBOARD_FAB2(SCH_1):M_B_DQ(43)
 C32 M_B_DQ<42> DDR1_DQ<42> @BASEBOARD_FAB2_LIB.BASEBOARD_FAB2(SCH_1):M_B_DQ(42)
 B35 M_B_DQ<41> DDR1_DQ<41> @BASEBOARD_FAB2_LIB.BASEBOARD_FAB2(SCH_1):M_B_DQ(41)
 C36 M_B_DQ<40> DDR1_DQ<40> @BASEBOARD_FAB2_LIB.BASEBOARD_FAB2(SCH_1):M_B_DQ(40)
 P41 M_B_DQ<39> DDR1_DQ<39> @BASEBOARD_FAB2_LIB.BASEBOARD_FAB2(SCH_1):M_B_DQ(39)
 K41 M_B_DQ<38> DDR1_DQ<38> @BASEBOARD_FAB2_LIB.BASEBOARD_FAB2(SCH_1):M_B_DQ(38)
 T43 M_B_DQ<37> DDR1_DQ<37> @BASEBOARD_FAB2_LIB.BASEBOARD_FAB2(SCH_1):M_B_DQ(37)
 P43 M_B_DQ<36> DDR1_DQ<36> @BASEBOARD_FAB2_LIB.BASEBOARD_FAB2(SCH_1):M_B_DQ(36)
 N40 M_B_DQ<35> DDR1_DQ<35> @BASEBOARD_FAB2_LIB.BASEBOARD_FAB2(SCH_1):M_B_DQ(35)
 L40 M_B_DQ<34> DDR1_DQ<34> @BASEBOARD_FAB2_LIB.BASEBOARD_FAB2(SCH_1):M_B_DQ(34)
 H43 M_B_DQ<33> DDR1_DQ<33> @BASEBOARD_FAB2_LIB.BASEBOARD_FAB2(SCH_1):M_B_DQ(33)
 K43 M_B_DQ<32> DDR1_DQ<32> @BASEBOARD_FAB2_LIB.BASEBOARD_FAB2(SCH_1):M_B_DQ(32)
 G72 M_B_DQ<31> DDR1_DQ<31> @BASEBOARD_FAB2_LIB.BASEBOARD_FAB2(SCH_1):M_B_DQ(31)
 C72 M_B_DQ<30> DDR1_DQ<30> @BASEBOARD_FAB2_LIB.BASEBOARD_FAB2(SCH_1):M_B_DQ(30)
 G74 M_B_DQ<29> DDR1_DQ<29> @BASEBOARD_FAB2_LIB.BASEBOARD_FAB2(SCH_1):M_B_DQ(29)
 F75 M_B_DQ<28> DDR1_DQ<28> @BASEBOARD_FAB2_LIB.BASEBOARD_FAB2(SCH_1):M_B_DQ(28)
 F71 M_B_DQ<27> DDR1_DQ<27> @BASEBOARD_FAB2_LIB.BASEBOARD_FAB2(SCH_1):M_B_DQ(27)
 D71 M_B_DQ<26> DDR1_DQ<26> @BASEBOARD_FAB2_LIB.BASEBOARD_FAB2(SCH_1):M_B_DQ(26)
 C74 M_B_DQ<25> DDR1_DQ<25> @BASEBOARD_FAB2_LIB.BASEBOARD_FAB2(SCH_1):M_B_DQ(25)
 D75 M_B_DQ<24> DDR1_DQ<24> @BASEBOARD_FAB2_LIB.BASEBOARD_FAB2(SCH_1):M_B_DQ(24)
 J78 M_B_DQ<23> DDR1_DQ<23> @BASEBOARD_FAB2_LIB.BASEBOARD_FAB2(SCH_1):M_B_DQ(23)
 E78 M_B_DQ<22> DDR1_DQ<22> @BASEBOARD_FAB2_LIB.BASEBOARD_FAB2(SCH_1):M_B_DQ(22)
 H81 M_B_DQ<21> DDR1_DQ<21> @BASEBOARD_FAB2_LIB.BASEBOARD_FAB2(SCH_1):M_B_DQ(21)
 F81 M_B_DQ<20> DDR1_DQ<20> @BASEBOARD_FAB2_LIB.BASEBOARD_FAB2(SCH_1):M_B_DQ(20)
 H77 M_B_DQ<19> DDR1_DQ<19> @BASEBOARD_FAB2_LIB.BASEBOARD_FAB2(SCH_1):M_B_DQ(19)
 F77 M_B_DQ<18> DDR1_DQ<18> @BASEBOARD_FAB2_LIB.BASEBOARD_FAB2(SCH_1):M_B_DQ(18)
 J80 M_B_DQ<17> DDR1_DQ<17> @BASEBOARD_FAB2_LIB.BASEBOARD_FAB2(SCH_1):M_B_DQ(17)
 E80 M_B_DQ<16> DDR1_DQ<16> @BASEBOARD_FAB2_LIB.BASEBOARD_FAB2(SCH_1):M_B_DQ(16)
AC80 M_B_DQ<15> DDR1_DQ<15> @BASEBOARD_FAB2_LIB.BASEBOARD_FAB2(SCH_1):M_B_DQ(15)
AE82 M_B_DQ<14> DDR1_DQ<14> @BASEBOARD_FAB2_LIB.BASEBOARD_FAB2(SCH_1):M_B_DQ(14)
AH79 M_B_DQ<13> DDR1_DQ<13> @BASEBOARD_FAB2_LIB.BASEBOARD_FAB2(SCH_1):M_B_DQ(13)
AJ80 M_B_DQ<12> DDR1_DQ<12> @BASEBOARD_FAB2_LIB.BASEBOARD_FAB2(SCH_1):M_B_DQ(12)
AB81 M_B_DQ<11> DDR1_DQ<11> @BASEBOARD_FAB2_LIB.BASEBOARD_FAB2(SCH_1):M_B_DQ(11)
AC82 M_B_DQ<10> DDR1_DQ<10> @BASEBOARD_FAB2_LIB.BASEBOARD_FAB2(SCH_1):M_B_DQ(10)
AF79 M_B_DQ<9> DDR1_DQ<9> @BASEBOARD_FAB2_LIB.BASEBOARD_FAB2(SCH_1):M_B_DQ(9)
AH81 M_B_DQ<8> DDR1_DQ<8> @BASEBOARD_FAB2_LIB.BASEBOARD_FAB2(SCH_1):M_B_DQ(8)
AN80 M_B_DQ<7> DDR1_DQ<7> @BASEBOARD_FAB2_LIB.BASEBOARD_FAB2(SCH_1):M_B_DQ(7)
AR82 M_B_DQ<6> DDR1_DQ<6> @BASEBOARD_FAB2_LIB.BASEBOARD_FAB2(SCH_1):M_B_DQ(6)
AV79 M_B_DQ<5> DDR1_DQ<5> @BASEBOARD_FAB2_LIB.BASEBOARD_FAB2(SCH_1):M_B_DQ(5)
AW80 M_B_DQ<4> DDR1_DQ<4> @BASEBOARD_FAB2_LIB.BASEBOARD_FAB2(SCH_1):M_B_DQ(4)
AM81 M_B_DQ<3> DDR1_DQ<3> @BASEBOARD_FAB2_LIB.BASEBOARD_FAB2(SCH_1):M_B_DQ(3)
AN82 M_B_DQ<2> DDR1_DQ<2> @BASEBOARD_FAB2_LIB.BASEBOARD_FAB2(SCH_1):M_B_DQ(2)
AT79 M_B_DQ<1> DDR1_DQ<1> @BASEBOARD_FAB2_LIB.BASEBOARD_FAB2(SCH_1):M_B_DQ(1)
AV81 M_B_DQ<0> DDR1_DQ<0> @BASEBOARD_FAB2_LIB.BASEBOARD_FAB2(SCH_1):M_B_DQ(0)
 G68 M_B_DQS_DN<17> DDR1_DQS_DN<17> @BASEBOARD_FAB2_LIB.BASEBOARD_FAB2(SCH_1):M_B_DQS_DN(17)
 T27 M_B_DQS_DN<16> DDR1_DQS_DN<16> @BASEBOARD_FAB2_LIB.BASEBOARD_FAB2(SCH_1):M_B_DQS_DN(16)
 A28 M_B_DQS_DN<15> DDR1_DQS_DN<15> @BASEBOARD_FAB2_LIB.BASEBOARD_FAB2(SCH_1):M_B_DQS_DN(15)
 A34 M_B_DQS_DN<14> DDR1_DQS_DN<14> @BASEBOARD_FAB2_LIB.BASEBOARD_FAB2(SCH_1):M_B_DQS_DN(14)
 J42 M_B_DQS_DN<13> DDR1_DQS_DN<13> @BASEBOARD_FAB2_LIB.BASEBOARD_FAB2(SCH_1):M_B_DQS_DN(13)
 B73 M_B_DQS_DN<12> DDR1_DQS_DN<12> @BASEBOARD_FAB2_LIB.BASEBOARD_FAB2(SCH_1):M_B_DQS_DN(12)
 D79 M_B_DQS_DN<11> DDR1_DQS_DN<11> @BASEBOARD_FAB2_LIB.BASEBOARD_FAB2(SCH_1):M_B_DQS_DN(11)
AG82 M_B_DQS_DN<10> DDR1_DQS_DN<10> @BASEBOARD_FAB2_LIB.BASEBOARD_FAB2(SCH_1):M_B_DQS_DN(10)
AU82 M_B_DQS_DN<9> DDR1_DQS_DN<9> @BASEBOARD_FAB2_LIB.BASEBOARD_FAB2(SCH_1):M_B_DQS_DN(9)
 N68 M_B_DQS_DN<8> DDR1_DQS_DN<8> @BASEBOARD_FAB2_LIB.BASEBOARD_FAB2(SCH_1):M_B_DQS_DN(8)
AB27 M_B_DQS_DN<7> DDR1_DQS_DN<7> @BASEBOARD_FAB2_LIB.BASEBOARD_FAB2(SCH_1):M_B_DQS_DN(7)
 G28 M_B_DQS_DN<6> DDR1_DQS_DN<6> @BASEBOARD_FAB2_LIB.BASEBOARD_FAB2(SCH_1):M_B_DQS_DN(6)
 G34 M_B_DQS_DN<5> DDR1_DQS_DN<5> @BASEBOARD_FAB2_LIB.BASEBOARD_FAB2(SCH_1):M_B_DQS_DN(5)
 N42 M_B_DQS_DN<4> DDR1_DQS_DN<4> @BASEBOARD_FAB2_LIB.BASEBOARD_FAB2(SCH_1):M_B_DQS_DN(4)
 H73 M_B_DQS_DN<3> DDR1_DQS_DN<3> @BASEBOARD_FAB2_LIB.BASEBOARD_FAB2(SCH_1):M_B_DQS_DN(3)
 K79 M_B_DQS_DN<2> DDR1_DQS_DN<2> @BASEBOARD_FAB2_LIB.BASEBOARD_FAB2(SCH_1):M_B_DQS_DN(2)
AD79 M_B_DQS_DN<1> DDR1_DQS_DN<1> @BASEBOARD_FAB2_LIB.BASEBOARD_FAB2(SCH_1):M_B_DQS_DN(1)
AP79 M_B_DQS_DN<0> DDR1_DQS_DN<0> @BASEBOARD_FAB2_LIB.BASEBOARD_FAB2(SCH_1):M_B_DQS_DN(0)
 J68 M_B_DQS_DP<17> DDR1_DQS_DP<17> @BASEBOARD_FAB2_LIB.BASEBOARD_FAB2(SCH_1):M_B_DQS_DP(17)
 V27 M_B_DQS_DP<16> DDR1_DQS_DP<16> @BASEBOARD_FAB2_LIB.BASEBOARD_FAB2(SCH_1):M_B_DQS_DP(16)
 C28 M_B_DQS_DP<15> DDR1_DQS_DP<15> @BASEBOARD_FAB2_LIB.BASEBOARD_FAB2(SCH_1):M_B_DQS_DP(15)
 C34 M_B_DQS_DP<14> DDR1_DQS_DP<14> @BASEBOARD_FAB2_LIB.BASEBOARD_FAB2(SCH_1):M_B_DQS_DP(14)
 L42 M_B_DQS_DP<13> DDR1_DQS_DP<13> @BASEBOARD_FAB2_LIB.BASEBOARD_FAB2(SCH_1):M_B_DQS_DP(13)
 D73 M_B_DQS_DP<12> DDR1_DQS_DP<12> @BASEBOARD_FAB2_LIB.BASEBOARD_FAB2(SCH_1):M_B_DQS_DP(12)
 F79 M_B_DQS_DP<11> DDR1_DQS_DP<11> @BASEBOARD_FAB2_LIB.BASEBOARD_FAB2(SCH_1):M_B_DQS_DP(11)
AF81 M_B_DQS_DP<10> DDR1_DQS_DP<10> @BASEBOARD_FAB2_LIB.BASEBOARD_FAB2(SCH_1):M_B_DQS_DP(10)
AT81 M_B_DQS_DP<9> DDR1_DQS_DP<9> @BASEBOARD_FAB2_LIB.BASEBOARD_FAB2(SCH_1):M_B_DQS_DP(9)
 L68 M_B_DQS_DP<8> DDR1_DQS_DP<8> @BASEBOARD_FAB2_LIB.BASEBOARD_FAB2(SCH_1):M_B_DQS_DP(8)
 Y27 M_B_DQS_DP<7> DDR1_DQS_DP<7> @BASEBOARD_FAB2_LIB.BASEBOARD_FAB2(SCH_1):M_B_DQS_DP(7)
 E28 M_B_DQS_DP<6> DDR1_DQS_DP<6> @BASEBOARD_FAB2_LIB.BASEBOARD_FAB2(SCH_1):M_B_DQS_DP(6)
 E34 M_B_DQS_DP<5> DDR1_DQS_DP<5> @BASEBOARD_FAB2_LIB.BASEBOARD_FAB2(SCH_1):M_B_DQS_DP(5)
 R42 M_B_DQS_DP<4> DDR1_DQS_DP<4> @BASEBOARD_FAB2_LIB.BASEBOARD_FAB2(SCH_1):M_B_DQS_DP(4)
 F73 M_B_DQS_DP<3> DDR1_DQS_DP<3> @BASEBOARD_FAB2_LIB.BASEBOARD_FAB2(SCH_1):M_B_DQS_DP(3)
 H79 M_B_DQS_DP<2> DDR1_DQS_DP<2> @BASEBOARD_FAB2_LIB.BASEBOARD_FAB2(SCH_1):M_B_DQS_DP(2)
AE80 M_B_DQS_DP<1> DDR1_DQS_DP<1> @BASEBOARD_FAB2_LIB.BASEBOARD_FAB2(SCH_1):M_B_DQS_DP(1)
AR80 M_B_DQS_DP<0> DDR1_DQS_DP<0> @BASEBOARD_FAB2_LIB.BASEBOARD_FAB2(SCH_1):M_B_DQS_DP(0)
 M67 M_B_ECC<7> DDR1_ECC<7> @BASEBOARD_FAB2_LIB.BASEBOARD_FAB2(SCH_1):M_B_ECC(7)
 H67 M_B_ECC<6> DDR1_ECC<6> @BASEBOARD_FAB2_LIB.BASEBOARD_FAB2(SCH_1):M_B_ECC(6)
 M69 M_B_ECC<5> DDR1_ECC<5> @BASEBOARD_FAB2_LIB.BASEBOARD_FAB2(SCH_1):M_B_ECC(5)
 L70 M_B_ECC<4> DDR1_ECC<4> @BASEBOARD_FAB2_LIB.BASEBOARD_FAB2(SCH_1):M_B_ECC(4)
 L66 M_B_ECC<3> DDR1_ECC<3> @BASEBOARD_FAB2_LIB.BASEBOARD_FAB2(SCH_1):M_B_ECC(3)
 J66 M_B_ECC<2> DDR1_ECC<2> @BASEBOARD_FAB2_LIB.BASEBOARD_FAB2(SCH_1):M_B_ECC(2)
 H69 M_B_ECC<1> DDR1_ECC<1> @BASEBOARD_FAB2_LIB.BASEBOARD_FAB2(SCH_1):M_B_ECC(1)
 J70 M_B_ECC<0> DDR1_ECC<0> @BASEBOARD_FAB2_LIB.BASEBOARD_FAB2(SCH_1):M_B_ECC(0)
 N48 M_B_MA<17> DDR1_MA<17> @BASEBOARD_FAB2_LIB.BASEBOARD_FAB2(SCH_1):M_B_MA(17)
 R52 M_B_MA<16> DDR1_MA<16> @BASEBOARD_FAB2_LIB.BASEBOARD_FAB2(SCH_1):M_B_MA(16)
 N52 M_B_MA<15> DDR1_MA<15> @BASEBOARD_FAB2_LIB.BASEBOARD_FAB2(SCH_1):M_B_MA(15)
 T51 M_B_MA<14> DDR1_MA<14> @BASEBOARD_FAB2_LIB.BASEBOARD_FAB2(SCH_1):M_B_MA(14)
 M51 M_B_MA<13> DDR1_MA<13> @BASEBOARD_FAB2_LIB.BASEBOARD_FAB2(SCH_1):M_B_MA(13)
 T61 M_B_MA<12> DDR1_MA<12> @BASEBOARD_FAB2_LIB.BASEBOARD_FAB2(SCH_1):M_B_MA(12)
 R60 M_B_MA<11> DDR1_MA<11> @BASEBOARD_FAB2_LIB.BASEBOARD_FAB2(SCH_1):M_B_MA(11)
 M55 M_B_MA<10> DDR1_MA<10> @BASEBOARD_FAB2_LIB.BASEBOARD_FAB2(SCH_1):M_B_MA(10)
 K59 M_B_MA<9> DDR1_MA<9> @BASEBOARD_FAB2_LIB.BASEBOARD_FAB2(SCH_1):M_B_MA(9)
 W60 M_B_MA<8> DDR1_MA<8> @BASEBOARD_FAB2_LIB.BASEBOARD_FAB2(SCH_1):M_B_MA(8)
 V61 M_B_MA<7> DDR1_MA<7> @BASEBOARD_FAB2_LIB.BASEBOARD_FAB2(SCH_1):M_B_MA(7)
 T59 M_B_MA<6> DDR1_MA<6> @BASEBOARD_FAB2_LIB.BASEBOARD_FAB2(SCH_1):M_B_MA(6)
 R58 M_B_MA<5> DDR1_MA<5> @BASEBOARD_FAB2_LIB.BASEBOARD_FAB2(SCH_1):M_B_MA(5)
 M59 M_B_MA<4> DDR1_MA<4> @BASEBOARD_FAB2_LIB.BASEBOARD_FAB2(SCH_1):M_B_MA(4)
 N58 M_B_MA<3> DDR1_MA<3> @BASEBOARD_FAB2_LIB.BASEBOARD_FAB2(SCH_1):M_B_MA(3)
 K57 M_B_MA<2> DDR1_MA<2> @BASEBOARD_FAB2_LIB.BASEBOARD_FAB2(SCH_1):M_B_MA(2)
 J58 M_B_MA<1> DDR1_MA<1> @BASEBOARD_FAB2_LIB.BASEBOARD_FAB2(SCH_1):M_B_MA(1)
 J52 M_B_MA<0> DDR1_MA<0> @BASEBOARD_FAB2_LIB.BASEBOARD_FAB2(SCH_1):M_B_MA(0)
 T47 M_B_ODT<3> DDR1_ODT<3> @BASEBOARD_FAB2_LIB.BASEBOARD_FAB2(SCH_1):M_B_ODT(3)
 M49 M_B_ODT<2> DDR1_ODT<2> @BASEBOARD_FAB2_LIB.BASEBOARD_FAB2(SCH_1):M_B_ODT(2)
 R48 M_B_ODT<1> DDR1_ODT<1> @BASEBOARD_FAB2_LIB.BASEBOARD_FAB2(SCH_1):M_B_ODT(1)
 N50 M_B_ODT<0> DDR1_ODT<0> @BASEBOARD_FAB2_LIB.BASEBOARD_FAB2(SCH_1):M_B_ODT(0)
 K53 M_B_PAR DDR1_PAR @BASEBOARD_FAB2_LIB.BASEBOARD_FAB2(SCH_1):M_B_PAR


DRAWING: @BASEBOARD_FAB2_LIB.BASEBOARD_FAB2(SCH_1):PAGE25 

SKX_EXT_B_BGA1-IC,TBD  I172  U5D1
AB61 M_C_ACT_N DDR2_ACT_N @BASEBOARD_FAB2_LIB.BASEBOARD_FAB2(SCH_1):M_C_ACT_N
AD61 M_C_ALERT_N DDR2_ALERT_N @BASEBOARD_FAB2_LIB.BASEBOARD_FAB2(SCH_1):M_C_ALERT_N
AE56 M_C_BA<1> DDR2_BA<1> @BASEBOARD_FAB2_LIB.BASEBOARD_FAB2(SCH_1):M_C_BA(1)
 W52 M_C_BA<0> DDR2_BA<0> @BASEBOARD_FAB2_LIB.BASEBOARD_FAB2(SCH_1):M_C_BA(0)
AE62 M_C_BG<1> DDR2_BG<1> @BASEBOARD_FAB2_LIB.BASEBOARD_FAB2(SCH_1):M_C_BG(1)
AA60 M_C_BG<0> DDR2_BG<0> @BASEBOARD_FAB2_LIB.BASEBOARD_FAB2(SCH_1):M_C_BG(0)
AB45 M_C_C<2> DDR2_CID<2> @BASEBOARD_FAB2_LIB.BASEBOARD_FAB2(SCH_1):M_C_C(2)
AB63 M_C_CKE<3> DDR2_CKE<3> @BASEBOARD_FAB2_LIB.BASEBOARD_FAB2(SCH_1):M_C_CKE(3)
 V63 M_C_CKE<2> DDR2_CKE<2> @BASEBOARD_FAB2_LIB.BASEBOARD_FAB2(SCH_1):M_C_CKE(2)
AD63 M_C_CKE<1> DDR2_CKE<1> @BASEBOARD_FAB2_LIB.BASEBOARD_FAB2(SCH_1):M_C_CKE(1)
AA62 M_C_CKE<0> DDR2_CKE<0> @BASEBOARD_FAB2_LIB.BASEBOARD_FAB2(SCH_1):M_C_CKE(0)
 W56 M_C_CLK_DN<3> DDR2_CLK_DN<3> @BASEBOARD_FAB2_LIB.BASEBOARD_FAB2(SCH_1):M_C_CLK_DN(3)
AA56 M_C_CLK_DN<2> DDR2_CLK_DN<2> @BASEBOARD_FAB2_LIB.BASEBOARD_FAB2(SCH_1):M_C_CLK_DN(2)
 W54 M_C_CLK_DN<1> DDR2_CLK_DN<1> @BASEBOARD_FAB2_LIB.BASEBOARD_FAB2(SCH_1):M_C_CLK_DN(1)
AA54 M_C_CLK_DN<0> DDR2_CLK_DN<0> @BASEBOARD_FAB2_LIB.BASEBOARD_FAB2(SCH_1):M_C_CLK_DN(0)
 V57 M_C_CLK_DP<3> DDR2_CLK_DP<3> @BASEBOARD_FAB2_LIB.BASEBOARD_FAB2(SCH_1):M_C_CLK_DP(3)
AB57 M_C_CLK_DP<2> DDR2_CLK_DP<2> @BASEBOARD_FAB2_LIB.BASEBOARD_FAB2(SCH_1):M_C_CLK_DP(2)
 V55 M_C_CLK_DP<1> DDR2_CLK_DP<1> @BASEBOARD_FAB2_LIB.BASEBOARD_FAB2(SCH_1):M_C_CLK_DP(1)
AB55 M_C_CLK_DP<0> DDR2_CLK_DP<0> @BASEBOARD_FAB2_LIB.BASEBOARD_FAB2(SCH_1):M_C_CLK_DP(0)
 V45 M_C_CS_N<7> DDR2_CS_N<7> @BASEBOARD_FAB2_LIB.BASEBOARD_FAB2(SCH_1):M_C_CS_N(7)
 T45 M_C_CS_N<6> DDR2_CS_N<6> @BASEBOARD_FAB2_LIB.BASEBOARD_FAB2(SCH_1):M_C_CS_N(6)
 W48 M_C_CS_N<5> DDR2_CS_N<5> @BASEBOARD_FAB2_LIB.BASEBOARD_FAB2(SCH_1):M_C_CS_N(5)
AB51 M_C_CS_N<4> DDR2_CS_N<4> @BASEBOARD_FAB2_LIB.BASEBOARD_FAB2(SCH_1):M_C_CS_N(4)
AA46 M_C_CS_N<3> DDR2_CS_N<3> @BASEBOARD_FAB2_LIB.BASEBOARD_FAB2(SCH_1):M_C_CS_N(3)
 W46 M_C_CS_N<2> DDR2_CS_N<2> @BASEBOARD_FAB2_LIB.BASEBOARD_FAB2(SCH_1):M_C_CS_N(2)
AB49 M_C_CS_N<1> DDR2_CS_N<1> @BASEBOARD_FAB2_LIB.BASEBOARD_FAB2(SCH_1):M_C_CS_N(1)
 V51 M_C_CS_N<0> DDR2_CS_N<0> @BASEBOARD_FAB2_LIB.BASEBOARD_FAB2(SCH_1):M_C_CS_N(0)
AH23 M_C_DQ<63> DDR2_DQ<63> @BASEBOARD_FAB2_LIB.BASEBOARD_FAB2(SCH_1):M_C_DQ(63)
AD23 M_C_DQ<62> DDR2_DQ<62> @BASEBOARD_FAB2_LIB.BASEBOARD_FAB2(SCH_1):M_C_DQ(62)
AG26 M_C_DQ<61> DDR2_DQ<61> @BASEBOARD_FAB2_LIB.BASEBOARD_FAB2(SCH_1):M_C_DQ(61)
AE26 M_C_DQ<60> DDR2_DQ<60> @BASEBOARD_FAB2_LIB.BASEBOARD_FAB2(SCH_1):M_C_DQ(60)
AG22 M_C_DQ<59> DDR2_DQ<59> @BASEBOARD_FAB2_LIB.BASEBOARD_FAB2(SCH_1):M_C_DQ(59)
AE22 M_C_DQ<58> DDR2_DQ<58> @BASEBOARD_FAB2_LIB.BASEBOARD_FAB2(SCH_1):M_C_DQ(58)
AH25 M_C_DQ<57> DDR2_DQ<57> @BASEBOARD_FAB2_LIB.BASEBOARD_FAB2(SCH_1):M_C_DQ(57)
AD25 M_C_DQ<56> DDR2_DQ<56> @BASEBOARD_FAB2_LIB.BASEBOARD_FAB2(SCH_1):M_C_DQ(56)
AH29 M_C_DQ<55> DDR2_DQ<55> @BASEBOARD_FAB2_LIB.BASEBOARD_FAB2(SCH_1):M_C_DQ(55)
AD29 M_C_DQ<54> DDR2_DQ<54> @BASEBOARD_FAB2_LIB.BASEBOARD_FAB2(SCH_1):M_C_DQ(54)
AG32 M_C_DQ<53> DDR2_DQ<53> @BASEBOARD_FAB2_LIB.BASEBOARD_FAB2(SCH_1):M_C_DQ(53)
AE32 M_C_DQ<52> DDR2_DQ<52> @BASEBOARD_FAB2_LIB.BASEBOARD_FAB2(SCH_1):M_C_DQ(52)
AG28 M_C_DQ<51> DDR2_DQ<51> @BASEBOARD_FAB2_LIB.BASEBOARD_FAB2(SCH_1):M_C_DQ(51)
AE28 M_C_DQ<50> DDR2_DQ<50> @BASEBOARD_FAB2_LIB.BASEBOARD_FAB2(SCH_1):M_C_DQ(50)
AH31 M_C_DQ<49> DDR2_DQ<49> @BASEBOARD_FAB2_LIB.BASEBOARD_FAB2(SCH_1):M_C_DQ(49)
AD31 M_C_DQ<48> DDR2_DQ<48> @BASEBOARD_FAB2_LIB.BASEBOARD_FAB2(SCH_1):M_C_DQ(48)
AA32 M_C_DQ<47> DDR2_DQ<47> @BASEBOARD_FAB2_LIB.BASEBOARD_FAB2(SCH_1):M_C_DQ(47)
 U32 M_C_DQ<46> DDR2_DQ<46> @BASEBOARD_FAB2_LIB.BASEBOARD_FAB2(SCH_1):M_C_DQ(46)
 Y35 M_C_DQ<45> DDR2_DQ<45> @BASEBOARD_FAB2_LIB.BASEBOARD_FAB2(SCH_1):M_C_DQ(45)
 V35 M_C_DQ<44> DDR2_DQ<44> @BASEBOARD_FAB2_LIB.BASEBOARD_FAB2(SCH_1):M_C_DQ(44)
 Y31 M_C_DQ<43> DDR2_DQ<43> @BASEBOARD_FAB2_LIB.BASEBOARD_FAB2(SCH_1):M_C_DQ(43)
 V31 M_C_DQ<42> DDR2_DQ<42> @BASEBOARD_FAB2_LIB.BASEBOARD_FAB2(SCH_1):M_C_DQ(42)
AA34 M_C_DQ<41> DDR2_DQ<41> @BASEBOARD_FAB2_LIB.BASEBOARD_FAB2(SCH_1):M_C_DQ(41)
 U34 M_C_DQ<40> DDR2_DQ<40> @BASEBOARD_FAB2_LIB.BASEBOARD_FAB2(SCH_1):M_C_DQ(40)
AA38 M_C_DQ<39> DDR2_DQ<39> @BASEBOARD_FAB2_LIB.BASEBOARD_FAB2(SCH_1):M_C_DQ(39)
 U38 M_C_DQ<38> DDR2_DQ<38> @BASEBOARD_FAB2_LIB.BASEBOARD_FAB2(SCH_1):M_C_DQ(38)
 Y41 M_C_DQ<37> DDR2_DQ<37> @BASEBOARD_FAB2_LIB.BASEBOARD_FAB2(SCH_1):M_C_DQ(37)
 V41 M_C_DQ<36> DDR2_DQ<36> @BASEBOARD_FAB2_LIB.BASEBOARD_FAB2(SCH_1):M_C_DQ(36)
 Y37 M_C_DQ<35> DDR2_DQ<35> @BASEBOARD_FAB2_LIB.BASEBOARD_FAB2(SCH_1):M_C_DQ(35)
 V37 M_C_DQ<34> DDR2_DQ<34> @BASEBOARD_FAB2_LIB.BASEBOARD_FAB2(SCH_1):M_C_DQ(34)
AA40 M_C_DQ<33> DDR2_DQ<33> @BASEBOARD_FAB2_LIB.BASEBOARD_FAB2(SCH_1):M_C_DQ(33)
 U40 M_C_DQ<32> DDR2_DQ<32> @BASEBOARD_FAB2_LIB.BASEBOARD_FAB2(SCH_1):M_C_DQ(32)
AT65 M_C_DQ<31> DDR2_DQ<31> @BASEBOARD_FAB2_LIB.BASEBOARD_FAB2(SCH_1):M_C_DQ(31)
AM65 M_C_DQ<30> DDR2_DQ<30> @BASEBOARD_FAB2_LIB.BASEBOARD_FAB2(SCH_1):M_C_DQ(30)
AR68 M_C_DQ<29> DDR2_DQ<29> @BASEBOARD_FAB2_LIB.BASEBOARD_FAB2(SCH_1):M_C_DQ(29)
AN68 M_C_DQ<28> DDR2_DQ<28> @BASEBOARD_FAB2_LIB.BASEBOARD_FAB2(SCH_1):M_C_DQ(28)
AR64 M_C_DQ<27> DDR2_DQ<27> @BASEBOARD_FAB2_LIB.BASEBOARD_FAB2(SCH_1):M_C_DQ(27)
AN64 M_C_DQ<26> DDR2_DQ<26> @BASEBOARD_FAB2_LIB.BASEBOARD_FAB2(SCH_1):M_C_DQ(26)
AT67 M_C_DQ<25> DDR2_DQ<25> @BASEBOARD_FAB2_LIB.BASEBOARD_FAB2(SCH_1):M_C_DQ(25)
AM67 M_C_DQ<24> DDR2_DQ<24> @BASEBOARD_FAB2_LIB.BASEBOARD_FAB2(SCH_1):M_C_DQ(24)
 V69 M_C_DQ<23> DDR2_DQ<23> @BASEBOARD_FAB2_LIB.BASEBOARD_FAB2(SCH_1):M_C_DQ(23)
 T71 M_C_DQ<22> DDR2_DQ<22> @BASEBOARD_FAB2_LIB.BASEBOARD_FAB2(SCH_1):M_C_DQ(22)
AB71 M_C_DQ<21> DDR2_DQ<21> @BASEBOARD_FAB2_LIB.BASEBOARD_FAB2(SCH_1):M_C_DQ(21)
AA72 M_C_DQ<20> DDR2_DQ<20> @BASEBOARD_FAB2_LIB.BASEBOARD_FAB2(SCH_1):M_C_DQ(20)
 T69 M_C_DQ<19> DDR2_DQ<19> @BASEBOARD_FAB2_LIB.BASEBOARD_FAB2(SCH_1):M_C_DQ(19)
 R70 M_C_DQ<18> DDR2_DQ<18> @BASEBOARD_FAB2_LIB.BASEBOARD_FAB2(SCH_1):M_C_DQ(18)
AA70 M_C_DQ<17> DDR2_DQ<17> @BASEBOARD_FAB2_LIB.BASEBOARD_FAB2(SCH_1):M_C_DQ(17)
 W72 M_C_DQ<16> DDR2_DQ<16> @BASEBOARD_FAB2_LIB.BASEBOARD_FAB2(SCH_1):M_C_DQ(16)
 Y75 M_C_DQ<15> DDR2_DQ<15> @BASEBOARD_FAB2_LIB.BASEBOARD_FAB2(SCH_1):M_C_DQ(15)
AB77 M_C_DQ<14> DDR2_DQ<14> @BASEBOARD_FAB2_LIB.BASEBOARD_FAB2(SCH_1):M_C_DQ(14)
AE74 M_C_DQ<13> DDR2_DQ<13> @BASEBOARD_FAB2_LIB.BASEBOARD_FAB2(SCH_1):M_C_DQ(13)
AF75 M_C_DQ<12> DDR2_DQ<12> @BASEBOARD_FAB2_LIB.BASEBOARD_FAB2(SCH_1):M_C_DQ(12)
 W76 M_C_DQ<11> DDR2_DQ<11> @BASEBOARD_FAB2_LIB.BASEBOARD_FAB2(SCH_1):M_C_DQ(11)
 Y77 M_C_DQ<10> DDR2_DQ<10> @BASEBOARD_FAB2_LIB.BASEBOARD_FAB2(SCH_1):M_C_DQ(10)
AC74 M_C_DQ<9> DDR2_DQ<9> @BASEBOARD_FAB2_LIB.BASEBOARD_FAB2(SCH_1):M_C_DQ(9)
AE76 M_C_DQ<8> DDR2_DQ<8> @BASEBOARD_FAB2_LIB.BASEBOARD_FAB2(SCH_1):M_C_DQ(8)
AK75 M_C_DQ<7> DDR2_DQ<7> @BASEBOARD_FAB2_LIB.BASEBOARD_FAB2(SCH_1):M_C_DQ(7)
AM77 M_C_DQ<6> DDR2_DQ<6> @BASEBOARD_FAB2_LIB.BASEBOARD_FAB2(SCH_1):M_C_DQ(6)
AR74 M_C_DQ<5> DDR2_DQ<5> @BASEBOARD_FAB2_LIB.BASEBOARD_FAB2(SCH_1):M_C_DQ(5)
AT75 M_C_DQ<4> DDR2_DQ<4> @BASEBOARD_FAB2_LIB.BASEBOARD_FAB2(SCH_1):M_C_DQ(4)
AJ76 M_C_DQ<3> DDR2_DQ<3> @BASEBOARD_FAB2_LIB.BASEBOARD_FAB2(SCH_1):M_C_DQ(3)
AK77 M_C_DQ<2> DDR2_DQ<2> @BASEBOARD_FAB2_LIB.BASEBOARD_FAB2(SCH_1):M_C_DQ(2)
AN74 M_C_DQ<1> DDR2_DQ<1> @BASEBOARD_FAB2_LIB.BASEBOARD_FAB2(SCH_1):M_C_DQ(1)
AR76 M_C_DQ<0> DDR2_DQ<0> @BASEBOARD_FAB2_LIB.BASEBOARD_FAB2(SCH_1):M_C_DQ(0)
AT71 M_C_DQS_DN<17> DDR2_DQS_DN<17> @BASEBOARD_FAB2_LIB.BASEBOARD_FAB2(SCH_1):M_C_DQS_DN(17)
AC24 M_C_DQS_DN<16> DDR2_DQS_DN<16> @BASEBOARD_FAB2_LIB.BASEBOARD_FAB2(SCH_1):M_C_DQS_DN(16)
AC30 M_C_DQS_DN<15> DDR2_DQS_DN<15> @BASEBOARD_FAB2_LIB.BASEBOARD_FAB2(SCH_1):M_C_DQS_DN(15)
 T33 M_C_DQS_DN<14> DDR2_DQS_DN<14> @BASEBOARD_FAB2_LIB.BASEBOARD_FAB2(SCH_1):M_C_DQS_DN(14)
 T39 M_C_DQS_DN<13> DDR2_DQS_DN<13> @BASEBOARD_FAB2_LIB.BASEBOARD_FAB2(SCH_1):M_C_DQS_DN(13)
AL66 M_C_DQS_DN<12> DDR2_DQS_DN<12> @BASEBOARD_FAB2_LIB.BASEBOARD_FAB2(SCH_1):M_C_DQS_DN(12)
 U72 M_C_DQS_DN<11> DDR2_DQS_DN<11> @BASEBOARD_FAB2_LIB.BASEBOARD_FAB2(SCH_1):M_C_DQS_DN(11)
AD77 M_C_DQS_DN<10> DDR2_DQS_DN<10> @BASEBOARD_FAB2_LIB.BASEBOARD_FAB2(SCH_1):M_C_DQS_DN(10)
AP77 M_C_DQS_DN<9> DDR2_DQS_DN<9> @BASEBOARD_FAB2_LIB.BASEBOARD_FAB2(SCH_1):M_C_DQS_DN(9)
BB71 M_C_DQS_DN<8> DDR2_DQS_DN<8> @BASEBOARD_FAB2_LIB.BASEBOARD_FAB2(SCH_1):M_C_DQS_DN(8)
AJ24 M_C_DQS_DN<7> DDR2_DQS_DN<7> @BASEBOARD_FAB2_LIB.BASEBOARD_FAB2(SCH_1):M_C_DQS_DN(7)
AJ30 M_C_DQS_DN<6> DDR2_DQS_DN<6> @BASEBOARD_FAB2_LIB.BASEBOARD_FAB2(SCH_1):M_C_DQS_DN(6)
AB33 M_C_DQS_DN<5> DDR2_DQS_DN<5> @BASEBOARD_FAB2_LIB.BASEBOARD_FAB2(SCH_1):M_C_DQS_DN(5)
AB39 M_C_DQS_DN<4> DDR2_DQS_DN<4> @BASEBOARD_FAB2_LIB.BASEBOARD_FAB2(SCH_1):M_C_DQS_DN(4)
AU66 M_C_DQS_DN<3> DDR2_DQS_DN<3> @BASEBOARD_FAB2_LIB.BASEBOARD_FAB2(SCH_1):M_C_DQS_DN(3)
 Y69 M_C_DQS_DN<2> DDR2_DQS_DN<2> @BASEBOARD_FAB2_LIB.BASEBOARD_FAB2(SCH_1):M_C_DQS_DN(2)
AA74 M_C_DQS_DN<1> DDR2_DQS_DN<1> @BASEBOARD_FAB2_LIB.BASEBOARD_FAB2(SCH_1):M_C_DQS_DN(1)
AL74 M_C_DQS_DN<0> DDR2_DQS_DN<0> @BASEBOARD_FAB2_LIB.BASEBOARD_FAB2(SCH_1):M_C_DQS_DN(0)
AV71 M_C_DQS_DP<17> DDR2_DQS_DP<17> @BASEBOARD_FAB2_LIB.BASEBOARD_FAB2(SCH_1):M_C_DQS_DP(17)
AE24 M_C_DQS_DP<16> DDR2_DQS_DP<16> @BASEBOARD_FAB2_LIB.BASEBOARD_FAB2(SCH_1):M_C_DQS_DP(16)
AE30 M_C_DQS_DP<15> DDR2_DQS_DP<15> @BASEBOARD_FAB2_LIB.BASEBOARD_FAB2(SCH_1):M_C_DQS_DP(15)
 V33 M_C_DQS_DP<14> DDR2_DQS_DP<14> @BASEBOARD_FAB2_LIB.BASEBOARD_FAB2(SCH_1):M_C_DQS_DP(14)
 V39 M_C_DQS_DP<13> DDR2_DQS_DP<13> @BASEBOARD_FAB2_LIB.BASEBOARD_FAB2(SCH_1):M_C_DQS_DP(13)
AN66 M_C_DQS_DP<12> DDR2_DQS_DP<12> @BASEBOARD_FAB2_LIB.BASEBOARD_FAB2(SCH_1):M_C_DQS_DP(12)
 V71 M_C_DQS_DP<11> DDR2_DQS_DP<11> @BASEBOARD_FAB2_LIB.BASEBOARD_FAB2(SCH_1):M_C_DQS_DP(11)
AC76 M_C_DQS_DP<10> DDR2_DQS_DP<10> @BASEBOARD_FAB2_LIB.BASEBOARD_FAB2(SCH_1):M_C_DQS_DP(10)
AN76 M_C_DQS_DP<9> DDR2_DQS_DP<9> @BASEBOARD_FAB2_LIB.BASEBOARD_FAB2(SCH_1):M_C_DQS_DP(9)
AY71 M_C_DQS_DP<8> DDR2_DQS_DP<8> @BASEBOARD_FAB2_LIB.BASEBOARD_FAB2(SCH_1):M_C_DQS_DP(8)
AG24 M_C_DQS_DP<7> DDR2_DQS_DP<7> @BASEBOARD_FAB2_LIB.BASEBOARD_FAB2(SCH_1):M_C_DQS_DP(7)
AG30 M_C_DQS_DP<6> DDR2_DQS_DP<6> @BASEBOARD_FAB2_LIB.BASEBOARD_FAB2(SCH_1):M_C_DQS_DP(6)
 Y33 M_C_DQS_DP<5> DDR2_DQS_DP<5> @BASEBOARD_FAB2_LIB.BASEBOARD_FAB2(SCH_1):M_C_DQS_DP(5)
 Y39 M_C_DQS_DP<4> DDR2_DQS_DP<4> @BASEBOARD_FAB2_LIB.BASEBOARD_FAB2(SCH_1):M_C_DQS_DP(4)
AR66 M_C_DQS_DP<3> DDR2_DQS_DP<3> @BASEBOARD_FAB2_LIB.BASEBOARD_FAB2(SCH_1):M_C_DQS_DP(3)
 W70 M_C_DQS_DP<2> DDR2_DQS_DP<2> @BASEBOARD_FAB2_LIB.BASEBOARD_FAB2(SCH_1):M_C_DQS_DP(2)
AB75 M_C_DQS_DP<1> DDR2_DQS_DP<1> @BASEBOARD_FAB2_LIB.BASEBOARD_FAB2(SCH_1):M_C_DQS_DP(1)
AM75 M_C_DQS_DP<0> DDR2_DQS_DP<0> @BASEBOARD_FAB2_LIB.BASEBOARD_FAB2(SCH_1):M_C_DQS_DP(0)
BA70 M_C_ECC<7> DDR2_ECC<7> @BASEBOARD_FAB2_LIB.BASEBOARD_FAB2(SCH_1):M_C_ECC(7)
AU70 M_C_ECC<6> DDR2_ECC<6> @BASEBOARD_FAB2_LIB.BASEBOARD_FAB2(SCH_1):M_C_ECC(6)
AY73 M_C_ECC<5> DDR2_ECC<5> @BASEBOARD_FAB2_LIB.BASEBOARD_FAB2(SCH_1):M_C_ECC(5)
AV73 M_C_ECC<4> DDR2_ECC<4> @BASEBOARD_FAB2_LIB.BASEBOARD_FAB2(SCH_1):M_C_ECC(4)
AY69 M_C_ECC<3> DDR2_ECC<3> @BASEBOARD_FAB2_LIB.BASEBOARD_FAB2(SCH_1):M_C_ECC(3)
AV69 M_C_ECC<2> DDR2_ECC<2> @BASEBOARD_FAB2_LIB.BASEBOARD_FAB2(SCH_1):M_C_ECC(2)
BA72 M_C_ECC<1> DDR2_ECC<1> @BASEBOARD_FAB2_LIB.BASEBOARD_FAB2(SCH_1):M_C_ECC(1)
AU72 M_C_ECC<0> DDR2_ECC<0> @BASEBOARD_FAB2_LIB.BASEBOARD_FAB2(SCH_1):M_C_ECC(0)
AC46 M_C_MA<17> DDR2_MA<17> @BASEBOARD_FAB2_LIB.BASEBOARD_FAB2(SCH_1):M_C_MA(17)
AA52 M_C_MA<16> DDR2_MA<16> @BASEBOARD_FAB2_LIB.BASEBOARD_FAB2(SCH_1):M_C_MA(16)
AE54 M_C_MA<15> DDR2_MA<15> @BASEBOARD_FAB2_LIB.BASEBOARD_FAB2(SCH_1):M_C_MA(15)
 W50 M_C_MA<14> DDR2_MA<14> @BASEBOARD_FAB2_LIB.BASEBOARD_FAB2(SCH_1):M_C_MA(14)
AD53 M_C_MA<13> DDR2_MA<13> @BASEBOARD_FAB2_LIB.BASEBOARD_FAB2(SCH_1):M_C_MA(13)
AG62 M_C_MA<12> DDR2_MA<12> @BASEBOARD_FAB2_LIB.BASEBOARD_FAB2(SCH_1):M_C_MA(12)
AG60 M_C_MA<11> DDR2_MA<11> @BASEBOARD_FAB2_LIB.BASEBOARD_FAB2(SCH_1):M_C_MA(11)
AD55 M_C_MA<10> DDR2_MA<10> @BASEBOARD_FAB2_LIB.BASEBOARD_FAB2(SCH_1):M_C_MA(10)
AG58 M_C_MA<9> DDR2_MA<9> @BASEBOARD_FAB2_LIB.BASEBOARD_FAB2(SCH_1):M_C_MA(9)
AD59 M_C_MA<8> DDR2_MA<8> @BASEBOARD_FAB2_LIB.BASEBOARD_FAB2(SCH_1):M_C_MA(8)
AE60 M_C_MA<7> DDR2_MA<7> @BASEBOARD_FAB2_LIB.BASEBOARD_FAB2(SCH_1):M_C_MA(7)
AB59 M_C_MA<6> DDR2_MA<6> @BASEBOARD_FAB2_LIB.BASEBOARD_FAB2(SCH_1):M_C_MA(6)
 V59 M_C_MA<5> DDR2_MA<5> @BASEBOARD_FAB2_LIB.BASEBOARD_FAB2(SCH_1):M_C_MA(5)
AA58 M_C_MA<4> DDR2_MA<4> @BASEBOARD_FAB2_LIB.BASEBOARD_FAB2(SCH_1):M_C_MA(4)
 W58 M_C_MA<3> DDR2_MA<3> @BASEBOARD_FAB2_LIB.BASEBOARD_FAB2(SCH_1):M_C_MA(3)
AD57 M_C_MA<2> DDR2_MA<2> @BASEBOARD_FAB2_LIB.BASEBOARD_FAB2(SCH_1):M_C_MA(2)
AE58 M_C_MA<1> DDR2_MA<1> @BASEBOARD_FAB2_LIB.BASEBOARD_FAB2(SCH_1):M_C_MA(1)
AB53 M_C_MA<0> DDR2_MA<0> @BASEBOARD_FAB2_LIB.BASEBOARD_FAB2(SCH_1):M_C_MA(0)
AB47 M_C_ODT<3> DDR2_ODT<3> @BASEBOARD_FAB2_LIB.BASEBOARD_FAB2(SCH_1):M_C_ODT(3)
 V49 M_C_ODT<2> DDR2_ODT<2> @BASEBOARD_FAB2_LIB.BASEBOARD_FAB2(SCH_1):M_C_ODT(2)
AA48 M_C_ODT<1> DDR2_ODT<1> @BASEBOARD_FAB2_LIB.BASEBOARD_FAB2(SCH_1):M_C_ODT(1)
AA50 M_C_ODT<0> DDR2_ODT<0> @BASEBOARD_FAB2_LIB.BASEBOARD_FAB2(SCH_1):M_C_ODT(0)
 V53 M_C_PAR DDR2_PAR @BASEBOARD_FAB2_LIB.BASEBOARD_FAB2(SCH_1):M_C_PAR


DRAWING: @BASEBOARD_FAB2_LIB.BASEBOARD_FAB2(SCH_1):PAGE26 

SKX_EXT_B_BGA1-IC,TBD  I172  U5D1
DW60 M_D_ACT_N DDR3_ACT_N @BASEBOARD_FAB2_LIB.BASEBOARD_FAB2(SCH_1):M_D_ACT_N
ED63 M_D_ALERT_N DDR3_ALERT_N @BASEBOARD_FAB2_LIB.BASEBOARD_FAB2(SCH_1):M_D_ALERT_N
EA54 M_D_BA<1> DDR3_BA<1> @BASEBOARD_FAB2_LIB.BASEBOARD_FAB2(SCH_1):M_D_BA(1)
EE52 M_D_BA<0> DDR3_BA<0> @BASEBOARD_FAB2_LIB.BASEBOARD_FAB2(SCH_1):M_D_BA(0)
DW62 M_D_BG<1> DDR3_BG<1> @BASEBOARD_FAB2_LIB.BASEBOARD_FAB2(SCH_1):M_D_BG(1)
ED61 M_D_BG<0> DDR3_BG<0> @BASEBOARD_FAB2_LIB.BASEBOARD_FAB2(SCH_1):M_D_BG(0)
DV47 M_D_C<2> DDR3_CID<2> @BASEBOARD_FAB2_LIB.BASEBOARD_FAB2(SCH_1):M_D_C(2)
EB63 M_D_CKE<3> DDR3_CKE<3> @BASEBOARD_FAB2_LIB.BASEBOARD_FAB2(SCH_1):M_D_CKE(3)
EA62 M_D_CKE<2> DDR3_CKE<2> @BASEBOARD_FAB2_LIB.BASEBOARD_FAB2(SCH_1):M_D_CKE(2)
EF63 M_D_CKE<1> DDR3_CKE<1> @BASEBOARD_FAB2_LIB.BASEBOARD_FAB2(SCH_1):M_D_CKE(1)
EE62 M_D_CKE<0> DDR3_CKE<0> @BASEBOARD_FAB2_LIB.BASEBOARD_FAB2(SCH_1):M_D_CKE(0)
EF57 M_D_CLK_DN<3> DDR3_CLK_DN<3> @BASEBOARD_FAB2_LIB.BASEBOARD_FAB2(SCH_1):M_D_CLK_DN(3)
DW56 M_D_CLK_DN<2> DDR3_CLK_DN<2> @BASEBOARD_FAB2_LIB.BASEBOARD_FAB2(SCH_1):M_D_CLK_DN(2)
EF55 M_D_CLK_DN<1> DDR3_CLK_DN<1> @BASEBOARD_FAB2_LIB.BASEBOARD_FAB2(SCH_1):M_D_CLK_DN(1)
ED55 M_D_CLK_DN<0> DDR3_CLK_DN<0> @BASEBOARD_FAB2_LIB.BASEBOARD_FAB2(SCH_1):M_D_CLK_DN(0)
EE56 M_D_CLK_DP<3> DDR3_CLK_DP<3> @BASEBOARD_FAB2_LIB.BASEBOARD_FAB2(SCH_1):M_D_CLK_DP(3)
EA56 M_D_CLK_DP<2> DDR3_CLK_DP<2> @BASEBOARD_FAB2_LIB.BASEBOARD_FAB2(SCH_1):M_D_CLK_DP(2)
EE54 M_D_CLK_DP<1> DDR3_CLK_DP<1> @BASEBOARD_FAB2_LIB.BASEBOARD_FAB2(SCH_1):M_D_CLK_DP(1)
EB55 M_D_CLK_DP<0> DDR3_CLK_DP<0> @BASEBOARD_FAB2_LIB.BASEBOARD_FAB2(SCH_1):M_D_CLK_DP(0)
EB45 M_D_CS_N<7> DDR3_CS_N<7> @BASEBOARD_FAB2_LIB.BASEBOARD_FAB2(SCH_1):M_D_CS_N(7)
DV45 M_D_CS_N<6> DDR3_CS_N<6> @BASEBOARD_FAB2_LIB.BASEBOARD_FAB2(SCH_1):M_D_CS_N(6)
EB49 M_D_CS_N<5> DDR3_CS_N<5> @BASEBOARD_FAB2_LIB.BASEBOARD_FAB2(SCH_1):M_D_CS_N(5)
EB51 M_D_CS_N<4> DDR3_CS_N<4> @BASEBOARD_FAB2_LIB.BASEBOARD_FAB2(SCH_1):M_D_CS_N(4)
EB47 M_D_CS_N<3> DDR3_CS_N<3> @BASEBOARD_FAB2_LIB.BASEBOARD_FAB2(SCH_1):M_D_CS_N(3)
ED47 M_D_CS_N<2> DDR3_CS_N<2> @BASEBOARD_FAB2_LIB.BASEBOARD_FAB2(SCH_1):M_D_CS_N(2)
ED49 M_D_CS_N<1> DDR3_CS_N<1> @BASEBOARD_FAB2_LIB.BASEBOARD_FAB2(SCH_1):M_D_CS_N(1)
EF51 M_D_CS_N<0> DDR3_CS_N<0> @BASEBOARD_FAB2_LIB.BASEBOARD_FAB2(SCH_1):M_D_CS_N(0)
DW22 M_D_DQ<63> DDR3_DQ<63> @BASEBOARD_FAB2_LIB.BASEBOARD_FAB2(SCH_1):M_D_DQ(63)
EC22 M_D_DQ<62> DDR3_DQ<62> @BASEBOARD_FAB2_LIB.BASEBOARD_FAB2(SCH_1):M_D_DQ(62)
DT25 M_D_DQ<61> DDR3_DQ<61> @BASEBOARD_FAB2_LIB.BASEBOARD_FAB2(SCH_1):M_D_DQ(61)
DP25 M_D_DQ<60> DDR3_DQ<60> @BASEBOARD_FAB2_LIB.BASEBOARD_FAB2(SCH_1):M_D_DQ(60)
EB21 M_D_DQ<59> DDR3_DQ<59> @BASEBOARD_FAB2_LIB.BASEBOARD_FAB2(SCH_1):M_D_DQ(59)
DY21 M_D_DQ<58> DDR3_DQ<58> @BASEBOARD_FAB2_LIB.BASEBOARD_FAB2(SCH_1):M_D_DQ(58)
DU24 M_D_DQ<57> DDR3_DQ<57> @BASEBOARD_FAB2_LIB.BASEBOARD_FAB2(SCH_1):M_D_DQ(57)
DN24 M_D_DQ<56> DDR3_DQ<56> @BASEBOARD_FAB2_LIB.BASEBOARD_FAB2(SCH_1):M_D_DQ(56)
DU28 M_D_DQ<55> DDR3_DQ<55> @BASEBOARD_FAB2_LIB.BASEBOARD_FAB2(SCH_1):M_D_DQ(55)
DN28 M_D_DQ<54> DDR3_DQ<54> @BASEBOARD_FAB2_LIB.BASEBOARD_FAB2(SCH_1):M_D_DQ(54)
DT31 M_D_DQ<53> DDR3_DQ<53> @BASEBOARD_FAB2_LIB.BASEBOARD_FAB2(SCH_1):M_D_DQ(53)
DP31 M_D_DQ<52> DDR3_DQ<52> @BASEBOARD_FAB2_LIB.BASEBOARD_FAB2(SCH_1):M_D_DQ(52)
DT27 M_D_DQ<51> DDR3_DQ<51> @BASEBOARD_FAB2_LIB.BASEBOARD_FAB2(SCH_1):M_D_DQ(51)
DP27 M_D_DQ<50> DDR3_DQ<50> @BASEBOARD_FAB2_LIB.BASEBOARD_FAB2(SCH_1):M_D_DQ(50)
DU30 M_D_DQ<49> DDR3_DQ<49> @BASEBOARD_FAB2_LIB.BASEBOARD_FAB2(SCH_1):M_D_DQ(49)
DN30 M_D_DQ<48> DDR3_DQ<48> @BASEBOARD_FAB2_LIB.BASEBOARD_FAB2(SCH_1):M_D_DQ(48)
DU34 M_D_DQ<47> DDR3_DQ<47> @BASEBOARD_FAB2_LIB.BASEBOARD_FAB2(SCH_1):M_D_DQ(47)
DN34 M_D_DQ<46> DDR3_DQ<46> @BASEBOARD_FAB2_LIB.BASEBOARD_FAB2(SCH_1):M_D_DQ(46)
DT37 M_D_DQ<45> DDR3_DQ<45> @BASEBOARD_FAB2_LIB.BASEBOARD_FAB2(SCH_1):M_D_DQ(45)
DP37 M_D_DQ<44> DDR3_DQ<44> @BASEBOARD_FAB2_LIB.BASEBOARD_FAB2(SCH_1):M_D_DQ(44)
DT33 M_D_DQ<43> DDR3_DQ<43> @BASEBOARD_FAB2_LIB.BASEBOARD_FAB2(SCH_1):M_D_DQ(43)
DP33 M_D_DQ<42> DDR3_DQ<42> @BASEBOARD_FAB2_LIB.BASEBOARD_FAB2(SCH_1):M_D_DQ(42)
DU36 M_D_DQ<41> DDR3_DQ<41> @BASEBOARD_FAB2_LIB.BASEBOARD_FAB2(SCH_1):M_D_DQ(41)
DN36 M_D_DQ<40> DDR3_DQ<40> @BASEBOARD_FAB2_LIB.BASEBOARD_FAB2(SCH_1):M_D_DQ(40)
ED37 M_D_DQ<39> DDR3_DQ<39> @BASEBOARD_FAB2_LIB.BASEBOARD_FAB2(SCH_1):M_D_DQ(39)
DY37 M_D_DQ<38> DDR3_DQ<38> @BASEBOARD_FAB2_LIB.BASEBOARD_FAB2(SCH_1):M_D_DQ(38)
EA40 M_D_DQ<37> DDR3_DQ<37> @BASEBOARD_FAB2_LIB.BASEBOARD_FAB2(SCH_1):M_D_DQ(37)
DY39 M_D_DQ<36> DDR3_DQ<36> @BASEBOARD_FAB2_LIB.BASEBOARD_FAB2(SCH_1):M_D_DQ(36)
EC36 M_D_DQ<35> DDR3_DQ<35> @BASEBOARD_FAB2_LIB.BASEBOARD_FAB2(SCH_1):M_D_DQ(35)
EA36 M_D_DQ<34> DDR3_DQ<34> @BASEBOARD_FAB2_LIB.BASEBOARD_FAB2(SCH_1):M_D_DQ(34)
ED39 M_D_DQ<33> DDR3_DQ<33> @BASEBOARD_FAB2_LIB.BASEBOARD_FAB2(SCH_1):M_D_DQ(33)
EC40 M_D_DQ<32> DDR3_DQ<32> @BASEBOARD_FAB2_LIB.BASEBOARD_FAB2(SCH_1):M_D_DQ(32)
DU74 M_D_DQ<31> DDR3_DQ<31> @BASEBOARD_FAB2_LIB.BASEBOARD_FAB2(SCH_1):M_D_DQ(31)
DN74 M_D_DQ<30> DDR3_DQ<30> @BASEBOARD_FAB2_LIB.BASEBOARD_FAB2(SCH_1):M_D_DQ(30)
DT77 M_D_DQ<29> DDR3_DQ<29> @BASEBOARD_FAB2_LIB.BASEBOARD_FAB2(SCH_1):M_D_DQ(29)
DP77 M_D_DQ<28> DDR3_DQ<28> @BASEBOARD_FAB2_LIB.BASEBOARD_FAB2(SCH_1):M_D_DQ(28)
DT73 M_D_DQ<27> DDR3_DQ<27> @BASEBOARD_FAB2_LIB.BASEBOARD_FAB2(SCH_1):M_D_DQ(27)
DP73 M_D_DQ<26> DDR3_DQ<26> @BASEBOARD_FAB2_LIB.BASEBOARD_FAB2(SCH_1):M_D_DQ(26)
DU76 M_D_DQ<25> DDR3_DQ<25> @BASEBOARD_FAB2_LIB.BASEBOARD_FAB2(SCH_1):M_D_DQ(25)
DN76 M_D_DQ<24> DDR3_DQ<24> @BASEBOARD_FAB2_LIB.BASEBOARD_FAB2(SCH_1):M_D_DQ(24)
DN82 M_D_DQ<23> DDR3_DQ<23> @BASEBOARD_FAB2_LIB.BASEBOARD_FAB2(SCH_1):M_D_DQ(23)
DR80 M_D_DQ<22> DDR3_DQ<22> @BASEBOARD_FAB2_LIB.BASEBOARD_FAB2(SCH_1):M_D_DQ(22)
DJ80 M_D_DQ<21> DDR3_DQ<21> @BASEBOARD_FAB2_LIB.BASEBOARD_FAB2(SCH_1):M_D_DQ(21)
DK79 M_D_DQ<20> DDR3_DQ<20> @BASEBOARD_FAB2_LIB.BASEBOARD_FAB2(SCH_1):M_D_DQ(20)
DR82 M_D_DQ<19> DDR3_DQ<19> @BASEBOARD_FAB2_LIB.BASEBOARD_FAB2(SCH_1):M_D_DQ(19)
DT81 M_D_DQ<18> DDR3_DQ<18> @BASEBOARD_FAB2_LIB.BASEBOARD_FAB2(SCH_1):M_D_DQ(18)
DK81 M_D_DQ<17> DDR3_DQ<17> @BASEBOARD_FAB2_LIB.BASEBOARD_FAB2(SCH_1):M_D_DQ(17)
DM79 M_D_DQ<16> DDR3_DQ<16> @BASEBOARD_FAB2_LIB.BASEBOARD_FAB2(SCH_1):M_D_DQ(16)
DV85 M_D_DQ<15> DDR3_DQ<15> @BASEBOARD_FAB2_LIB.BASEBOARD_FAB2(SCH_1):M_D_DQ(15)
DR84 M_D_DQ<14> DDR3_DQ<14> @BASEBOARD_FAB2_LIB.BASEBOARD_FAB2(SCH_1):M_D_DQ(14)
DE84 M_D_DQ<13> DDR3_DQ<13> @BASEBOARD_FAB2_LIB.BASEBOARD_FAB2(SCH_1):M_D_DQ(13)
DD85 M_D_DQ<12> DDR3_DQ<12> @BASEBOARD_FAB2_LIB.BASEBOARD_FAB2(SCH_1):M_D_DQ(12)
DY83 M_D_DQ<11> DDR3_DQ<11> @BASEBOARD_FAB2_LIB.BASEBOARD_FAB2(SCH_1):M_D_DQ(11)
DV83 M_D_DQ<10> DDR3_DQ<10> @BASEBOARD_FAB2_LIB.BASEBOARD_FAB2(SCH_1):M_D_DQ(10)
DH85 M_D_DQ<9> DDR3_DQ<9> @BASEBOARD_FAB2_LIB.BASEBOARD_FAB2(SCH_1):M_D_DQ(9)
DG84 M_D_DQ<8> DDR3_DQ<8> @BASEBOARD_FAB2_LIB.BASEBOARD_FAB2(SCH_1):M_D_DQ(8)
CW84 M_D_DQ<7> DDR3_DQ<7> @BASEBOARD_FAB2_LIB.BASEBOARD_FAB2(SCH_1):M_D_DQ(7)
CW86 M_D_DQ<6> DDR3_DQ<6> @BASEBOARD_FAB2_LIB.BASEBOARD_FAB2(SCH_1):M_D_DQ(6)
CL86 M_D_DQ<5> DDR3_DQ<5> @BASEBOARD_FAB2_LIB.BASEBOARD_FAB2(SCH_1):M_D_DQ(5)
CL84 M_D_DQ<4> DDR3_DQ<4> @BASEBOARD_FAB2_LIB.BASEBOARD_FAB2(SCH_1):M_D_DQ(4)
DA84 M_D_DQ<3> DDR3_DQ<3> @BASEBOARD_FAB2_LIB.BASEBOARD_FAB2(SCH_1):M_D_DQ(3)
DA86 M_D_DQ<2> DDR3_DQ<2> @BASEBOARD_FAB2_LIB.BASEBOARD_FAB2(SCH_1):M_D_DQ(2)
CN86 M_D_DQ<1> DDR3_DQ<1> @BASEBOARD_FAB2_LIB.BASEBOARD_FAB2(SCH_1):M_D_DQ(1)
CN84 M_D_DQ<0> DDR3_DQ<0> @BASEBOARD_FAB2_LIB.BASEBOARD_FAB2(SCH_1):M_D_DQ(0)
DB67 M_D_DQS_DN<17> DDR3_DQS_DN<17> @BASEBOARD_FAB2_LIB.BASEBOARD_FAB2(SCH_1):M_D_DQS_DN(17)
DM23 M_D_DQS_DN<16> DDR3_DQS_DN<16> @BASEBOARD_FAB2_LIB.BASEBOARD_FAB2(SCH_1):M_D_DQS_DN(16)
DM29 M_D_DQS_DN<15> DDR3_DQS_DN<15> @BASEBOARD_FAB2_LIB.BASEBOARD_FAB2(SCH_1):M_D_DQS_DN(15)
DP35 M_D_DQS_DN<14> DDR3_DQS_DN<14> @BASEBOARD_FAB2_LIB.BASEBOARD_FAB2(SCH_1):M_D_DQS_DN(14)
EA38 M_D_DQS_DN<13> DDR3_DQS_DN<13> @BASEBOARD_FAB2_LIB.BASEBOARD_FAB2(SCH_1):M_D_DQS_DN(13)
DP75 M_D_DQS_DN<12> DDR3_DQS_DN<12> @BASEBOARD_FAB2_LIB.BASEBOARD_FAB2(SCH_1):M_D_DQS_DN(12)
DN80 M_D_DQS_DN<11> DDR3_DQS_DN<11> @BASEBOARD_FAB2_LIB.BASEBOARD_FAB2(SCH_1):M_D_DQS_DN(11)
DM85 M_D_DQS_DN<10> DDR3_DQS_DN<10> @BASEBOARD_FAB2_LIB.BASEBOARD_FAB2(SCH_1):M_D_DQS_DN(10)
CR84 M_D_DQS_DN<9> DDR3_DQS_DN<9> @BASEBOARD_FAB2_LIB.BASEBOARD_FAB2(SCH_1):M_D_DQS_DN(9)
DF67 M_D_DQS_DN<8> DDR3_DQS_DN<8> @BASEBOARD_FAB2_LIB.BASEBOARD_FAB2(SCH_1):M_D_DQS_DN(8)
DV23 M_D_DQS_DN<7> DDR3_DQS_DN<7> @BASEBOARD_FAB2_LIB.BASEBOARD_FAB2(SCH_1):M_D_DQS_DN(7)
DV29 M_D_DQS_DN<6> DDR3_DQS_DN<6> @BASEBOARD_FAB2_LIB.BASEBOARD_FAB2(SCH_1):M_D_DQS_DN(6)
DV35 M_D_DQS_DN<5> DDR3_DQS_DN<5> @BASEBOARD_FAB2_LIB.BASEBOARD_FAB2(SCH_1):M_D_DQS_DN(5)
EE38 M_D_DQS_DN<4> DDR3_DQS_DN<4> @BASEBOARD_FAB2_LIB.BASEBOARD_FAB2(SCH_1):M_D_DQS_DN(4)
DV75 M_D_DQS_DN<3> DDR3_DQS_DN<3> @BASEBOARD_FAB2_LIB.BASEBOARD_FAB2(SCH_1):M_D_DQS_DN(3)
DL82 M_D_DQS_DN<2> DDR3_DQS_DN<2> @BASEBOARD_FAB2_LIB.BASEBOARD_FAB2(SCH_1):M_D_DQS_DN(2)
DN84 M_D_DQS_DN<1> DDR3_DQS_DN<1> @BASEBOARD_FAB2_LIB.BASEBOARD_FAB2(SCH_1):M_D_DQS_DN(1)
CU84 M_D_DQS_DN<0> DDR3_DQS_DN<0> @BASEBOARD_FAB2_LIB.BASEBOARD_FAB2(SCH_1):M_D_DQS_DN(0)
CY67 M_D_DQS_DP<17> DDR3_DQS_DP<17> @BASEBOARD_FAB2_LIB.BASEBOARD_FAB2(SCH_1):M_D_DQS_DP(17)
DP23 M_D_DQS_DP<16> DDR3_DQS_DP<16> @BASEBOARD_FAB2_LIB.BASEBOARD_FAB2(SCH_1):M_D_DQS_DP(16)
DP29 M_D_DQS_DP<15> DDR3_DQS_DP<15> @BASEBOARD_FAB2_LIB.BASEBOARD_FAB2(SCH_1):M_D_DQS_DP(15)
DM35 M_D_DQS_DP<14> DDR3_DQS_DP<14> @BASEBOARD_FAB2_LIB.BASEBOARD_FAB2(SCH_1):M_D_DQS_DP(14)
DW38 M_D_DQS_DP<13> DDR3_DQS_DP<13> @BASEBOARD_FAB2_LIB.BASEBOARD_FAB2(SCH_1):M_D_DQS_DP(13)
DM75 M_D_DQS_DP<12> DDR3_DQS_DP<12> @BASEBOARD_FAB2_LIB.BASEBOARD_FAB2(SCH_1):M_D_DQS_DP(12)
DP79 M_D_DQS_DP<11> DDR3_DQS_DP<11> @BASEBOARD_FAB2_LIB.BASEBOARD_FAB2(SCH_1):M_D_DQS_DP(11)
DL84 M_D_DQS_DP<10> DDR3_DQS_DP<10> @BASEBOARD_FAB2_LIB.BASEBOARD_FAB2(SCH_1):M_D_DQS_DP(10)
CP85 M_D_DQS_DP<9> DDR3_DQS_DP<9> @BASEBOARD_FAB2_LIB.BASEBOARD_FAB2(SCH_1):M_D_DQS_DP(9)
DD67 M_D_DQS_DP<8> DDR3_DQS_DP<8> @BASEBOARD_FAB2_LIB.BASEBOARD_FAB2(SCH_1):M_D_DQS_DP(8)
DT23 M_D_DQS_DP<7> DDR3_DQS_DP<7> @BASEBOARD_FAB2_LIB.BASEBOARD_FAB2(SCH_1):M_D_DQS_DP(7)
DT29 M_D_DQS_DP<6> DDR3_DQS_DP<6> @BASEBOARD_FAB2_LIB.BASEBOARD_FAB2(SCH_1):M_D_DQS_DP(6)
DT35 M_D_DQS_DP<5> DDR3_DQS_DP<5> @BASEBOARD_FAB2_LIB.BASEBOARD_FAB2(SCH_1):M_D_DQS_DP(5)
EC38 M_D_DQS_DP<4> DDR3_DQS_DP<4> @BASEBOARD_FAB2_LIB.BASEBOARD_FAB2(SCH_1):M_D_DQS_DP(4)
DT75 M_D_DQS_DP<3> DDR3_DQS_DP<3> @BASEBOARD_FAB2_LIB.BASEBOARD_FAB2(SCH_1):M_D_DQS_DP(3)
DM81 M_D_DQS_DP<2> DDR3_DQS_DP<2> @BASEBOARD_FAB2_LIB.BASEBOARD_FAB2(SCH_1):M_D_DQS_DP(2)
DP85 M_D_DQS_DP<1> DDR3_DQS_DP<1> @BASEBOARD_FAB2_LIB.BASEBOARD_FAB2(SCH_1):M_D_DQS_DP(1)
CV85 M_D_DQS_DP<0> DDR3_DQS_DP<0> @BASEBOARD_FAB2_LIB.BASEBOARD_FAB2(SCH_1):M_D_DQS_DP(0)
DE66 M_D_ECC<7> DDR3_ECC<7> @BASEBOARD_FAB2_LIB.BASEBOARD_FAB2(SCH_1):M_D_ECC(7)
DA66 M_D_ECC<6> DDR3_ECC<6> @BASEBOARD_FAB2_LIB.BASEBOARD_FAB2(SCH_1):M_D_ECC(6)
DD69 M_D_ECC<5> DDR3_ECC<5> @BASEBOARD_FAB2_LIB.BASEBOARD_FAB2(SCH_1):M_D_ECC(5)
DB69 M_D_ECC<4> DDR3_ECC<4> @BASEBOARD_FAB2_LIB.BASEBOARD_FAB2(SCH_1):M_D_ECC(4)
DD65 M_D_ECC<3> DDR3_ECC<3> @BASEBOARD_FAB2_LIB.BASEBOARD_FAB2(SCH_1):M_D_ECC(3)
DB65 M_D_ECC<2> DDR3_ECC<2> @BASEBOARD_FAB2_LIB.BASEBOARD_FAB2(SCH_1):M_D_ECC(2)
DE68 M_D_ECC<1> DDR3_ECC<1> @BASEBOARD_FAB2_LIB.BASEBOARD_FAB2(SCH_1):M_D_ECC(1)
DA68 M_D_ECC<0> DDR3_ECC<0> @BASEBOARD_FAB2_LIB.BASEBOARD_FAB2(SCH_1):M_D_ECC(0)
EA46 M_D_MA<17> DDR3_MA<17> @BASEBOARD_FAB2_LIB.BASEBOARD_FAB2(SCH_1):M_D_MA(17)
EA52 M_D_MA<16> DDR3_MA<16> @BASEBOARD_FAB2_LIB.BASEBOARD_FAB2(SCH_1):M_D_MA(16)
DV49 M_D_MA<15> DDR3_MA<15> @BASEBOARD_FAB2_LIB.BASEBOARD_FAB2(SCH_1):M_D_MA(15)
ED51 M_D_MA<14> DDR3_MA<14> @BASEBOARD_FAB2_LIB.BASEBOARD_FAB2(SCH_1):M_D_MA(14)
DW48 M_D_MA<13> DDR3_MA<13> @BASEBOARD_FAB2_LIB.BASEBOARD_FAB2(SCH_1):M_D_MA(13)
DT63 M_D_MA<12> DDR3_MA<12> @BASEBOARD_FAB2_LIB.BASEBOARD_FAB2(SCH_1):M_D_MA(12)
EB61 M_D_MA<11> DDR3_MA<11> @BASEBOARD_FAB2_LIB.BASEBOARD_FAB2(SCH_1):M_D_MA(11)
DW54 M_D_MA<10> DDR3_MA<10> @BASEBOARD_FAB2_LIB.BASEBOARD_FAB2(SCH_1):M_D_MA(10)
EF61 M_D_MA<9> DDR3_MA<9> @BASEBOARD_FAB2_LIB.BASEBOARD_FAB2(SCH_1):M_D_MA(9)
EB59 M_D_MA<8> DDR3_MA<8> @BASEBOARD_FAB2_LIB.BASEBOARD_FAB2(SCH_1):M_D_MA(8)
EA60 M_D_MA<7> DDR3_MA<7> @BASEBOARD_FAB2_LIB.BASEBOARD_FAB2(SCH_1):M_D_MA(7)
EE60 M_D_MA<6> DDR3_MA<6> @BASEBOARD_FAB2_LIB.BASEBOARD_FAB2(SCH_1):M_D_MA(6)
EA58 M_D_MA<5> DDR3_MA<5> @BASEBOARD_FAB2_LIB.BASEBOARD_FAB2(SCH_1):M_D_MA(5)
ED59 M_D_MA<4> DDR3_MA<4> @BASEBOARD_FAB2_LIB.BASEBOARD_FAB2(SCH_1):M_D_MA(4)
EB57 M_D_MA<3> DDR3_MA<3> @BASEBOARD_FAB2_LIB.BASEBOARD_FAB2(SCH_1):M_D_MA(3)
EE58 M_D_MA<2> DDR3_MA<2> @BASEBOARD_FAB2_LIB.BASEBOARD_FAB2(SCH_1):M_D_MA(2)
ED57 M_D_MA<1> DDR3_MA<1> @BASEBOARD_FAB2_LIB.BASEBOARD_FAB2(SCH_1):M_D_MA(1)
EB53 M_D_MA<0> DDR3_MA<0> @BASEBOARD_FAB2_LIB.BASEBOARD_FAB2(SCH_1):M_D_MA(0)
EA48 M_D_ODT<3> DDR3_ODT<3> @BASEBOARD_FAB2_LIB.BASEBOARD_FAB2(SCH_1):M_D_ODT(3)
EA50 M_D_ODT<2> DDR3_ODT<2> @BASEBOARD_FAB2_LIB.BASEBOARD_FAB2(SCH_1):M_D_ODT(2)
EE48 M_D_ODT<1> DDR3_ODT<1> @BASEBOARD_FAB2_LIB.BASEBOARD_FAB2(SCH_1):M_D_ODT(1)
EE50 M_D_ODT<0> DDR3_ODT<0> @BASEBOARD_FAB2_LIB.BASEBOARD_FAB2(SCH_1):M_D_ODT(0)
ED53 M_D_PAR DDR3_PAR @BASEBOARD_FAB2_LIB.BASEBOARD_FAB2(SCH_1):M_D_PAR


DRAWING: @BASEBOARD_FAB2_LIB.BASEBOARD_FAB2(SCH_1):PAGE27 

SKX_EXT_B_BGA1-IC,TBD  I172  U5D1
DR62 M_E_ACT_N DDR4_ACT_N @BASEBOARD_FAB2_LIB.BASEBOARD_FAB2(SCH_1):M_E_ACT_N
DT61 M_E_ALERT_N DDR4_ALERT_N @BASEBOARD_FAB2_LIB.BASEBOARD_FAB2(SCH_1):M_E_ALERT_N
DV55 M_E_BA<1> DDR4_BA<1> @BASEBOARD_FAB2_LIB.BASEBOARD_FAB2(SCH_1):M_E_BA(1)
DM53 M_E_BA<0> DDR4_BA<0> @BASEBOARD_FAB2_LIB.BASEBOARD_FAB2(SCH_1):M_E_BA(0)
DM61 M_E_BG<1> DDR4_BG<1> @BASEBOARD_FAB2_LIB.BASEBOARD_FAB2(SCH_1):M_E_BG(1)
DJ62 M_E_BG<0> DDR4_BG<0> @BASEBOARD_FAB2_LIB.BASEBOARD_FAB2(SCH_1):M_E_BG(0)
DT47 M_E_C<2> DDR4_CID<2> @BASEBOARD_FAB2_LIB.BASEBOARD_FAB2(SCH_1):M_E_C(2)
DR64 M_E_CKE<3> DDR4_CKE<3> @BASEBOARD_FAB2_LIB.BASEBOARD_FAB2(SCH_1):M_E_CKE(3)
DL64 M_E_CKE<2> DDR4_CKE<2> @BASEBOARD_FAB2_LIB.BASEBOARD_FAB2(SCH_1):M_E_CKE(2)
DN64 M_E_CKE<1> DDR4_CKE<1> @BASEBOARD_FAB2_LIB.BASEBOARD_FAB2(SCH_1):M_E_CKE(1)
DM63 M_E_CKE<0> DDR4_CKE<0> @BASEBOARD_FAB2_LIB.BASEBOARD_FAB2(SCH_1):M_E_CKE(0)
DT57 M_E_CLK_DN<3> DDR4_CLK_DN<3> @BASEBOARD_FAB2_LIB.BASEBOARD_FAB2(SCH_1):M_E_CLK_DN(3)
DM57 M_E_CLK_DN<2> DDR4_CLK_DN<2> @BASEBOARD_FAB2_LIB.BASEBOARD_FAB2(SCH_1):M_E_CLK_DN(2)
DR54 M_E_CLK_DN<1> DDR4_CLK_DN<1> @BASEBOARD_FAB2_LIB.BASEBOARD_FAB2(SCH_1):M_E_CLK_DN(1)
DM55 M_E_CLK_DN<0> DDR4_CLK_DN<0> @BASEBOARD_FAB2_LIB.BASEBOARD_FAB2(SCH_1):M_E_CLK_DN(0)
DR56 M_E_CLK_DP<3> DDR4_CLK_DP<3> @BASEBOARD_FAB2_LIB.BASEBOARD_FAB2(SCH_1):M_E_CLK_DP(3)
DN56 M_E_CLK_DP<2> DDR4_CLK_DP<2> @BASEBOARD_FAB2_LIB.BASEBOARD_FAB2(SCH_1):M_E_CLK_DP(2)
DT53 M_E_CLK_DP<1> DDR4_CLK_DP<1> @BASEBOARD_FAB2_LIB.BASEBOARD_FAB2(SCH_1):M_E_CLK_DP(1)
DN54 M_E_CLK_DP<0> DDR4_CLK_DP<0> @BASEBOARD_FAB2_LIB.BASEBOARD_FAB2(SCH_1):M_E_CLK_DP(0)
DN46 M_E_CS_N<7> DDR4_CS_N<7> @BASEBOARD_FAB2_LIB.BASEBOARD_FAB2(SCH_1):M_E_CS_N(7)
DT45 M_E_CS_N<6> DDR4_CS_N<6> @BASEBOARD_FAB2_LIB.BASEBOARD_FAB2(SCH_1):M_E_CS_N(6)
DM49 M_E_CS_N<5> DDR4_CS_N<5> @BASEBOARD_FAB2_LIB.BASEBOARD_FAB2(SCH_1):M_E_CS_N(5)
DW50 M_E_CS_N<4> DDR4_CS_N<4> @BASEBOARD_FAB2_LIB.BASEBOARD_FAB2(SCH_1):M_E_CS_N(4)
DK47 M_E_CS_N<3> DDR4_CS_N<3> @BASEBOARD_FAB2_LIB.BASEBOARD_FAB2(SCH_1):M_E_CS_N(3)
DR46 M_E_CS_N<2> DDR4_CS_N<2> @BASEBOARD_FAB2_LIB.BASEBOARD_FAB2(SCH_1):M_E_CS_N(2)
DN50 M_E_CS_N<1> DDR4_CS_N<1> @BASEBOARD_FAB2_LIB.BASEBOARD_FAB2(SCH_1):M_E_CS_N(1)
DV51 M_E_CS_N<0> DDR4_CS_N<0> @BASEBOARD_FAB2_LIB.BASEBOARD_FAB2(SCH_1):M_E_CS_N(0)
DK25 M_E_DQ<63> DDR4_DQ<63> @BASEBOARD_FAB2_LIB.BASEBOARD_FAB2(SCH_1):M_E_DQ(63)
DF25 M_E_DQ<62> DDR4_DQ<62> @BASEBOARD_FAB2_LIB.BASEBOARD_FAB2(SCH_1):M_E_DQ(62)
DJ28 M_E_DQ<61> DDR4_DQ<61> @BASEBOARD_FAB2_LIB.BASEBOARD_FAB2(SCH_1):M_E_DQ(61)
DG28 M_E_DQ<60> DDR4_DQ<60> @BASEBOARD_FAB2_LIB.BASEBOARD_FAB2(SCH_1):M_E_DQ(60)
DJ24 M_E_DQ<59> DDR4_DQ<59> @BASEBOARD_FAB2_LIB.BASEBOARD_FAB2(SCH_1):M_E_DQ(59)
DD25 M_E_DQ<58> DDR4_DQ<58> @BASEBOARD_FAB2_LIB.BASEBOARD_FAB2(SCH_1):M_E_DQ(58)
DK27 M_E_DQ<57> DDR4_DQ<57> @BASEBOARD_FAB2_LIB.BASEBOARD_FAB2(SCH_1):M_E_DQ(57)
DF27 M_E_DQ<56> DDR4_DQ<56> @BASEBOARD_FAB2_LIB.BASEBOARD_FAB2(SCH_1):M_E_DQ(56)
ED25 M_E_DQ<55> DDR4_DQ<55> @BASEBOARD_FAB2_LIB.BASEBOARD_FAB2(SCH_1):M_E_DQ(55)
DY25 M_E_DQ<54> DDR4_DQ<54> @BASEBOARD_FAB2_LIB.BASEBOARD_FAB2(SCH_1):M_E_DQ(54)
EA28 M_E_DQ<53> DDR4_DQ<53> @BASEBOARD_FAB2_LIB.BASEBOARD_FAB2(SCH_1):M_E_DQ(53)
DY27 M_E_DQ<52> DDR4_DQ<52> @BASEBOARD_FAB2_LIB.BASEBOARD_FAB2(SCH_1):M_E_DQ(52)
EC24 M_E_DQ<51> DDR4_DQ<51> @BASEBOARD_FAB2_LIB.BASEBOARD_FAB2(SCH_1):M_E_DQ(51)
EA24 M_E_DQ<50> DDR4_DQ<50> @BASEBOARD_FAB2_LIB.BASEBOARD_FAB2(SCH_1):M_E_DQ(50)
ED27 M_E_DQ<49> DDR4_DQ<49> @BASEBOARD_FAB2_LIB.BASEBOARD_FAB2(SCH_1):M_E_DQ(49)
EC28 M_E_DQ<48> DDR4_DQ<48> @BASEBOARD_FAB2_LIB.BASEBOARD_FAB2(SCH_1):M_E_DQ(48)
ED31 M_E_DQ<47> DDR4_DQ<47> @BASEBOARD_FAB2_LIB.BASEBOARD_FAB2(SCH_1):M_E_DQ(47)
DY31 M_E_DQ<46> DDR4_DQ<46> @BASEBOARD_FAB2_LIB.BASEBOARD_FAB2(SCH_1):M_E_DQ(46)
EA34 M_E_DQ<45> DDR4_DQ<45> @BASEBOARD_FAB2_LIB.BASEBOARD_FAB2(SCH_1):M_E_DQ(45)
DY33 M_E_DQ<44> DDR4_DQ<44> @BASEBOARD_FAB2_LIB.BASEBOARD_FAB2(SCH_1):M_E_DQ(44)
EC30 M_E_DQ<43> DDR4_DQ<43> @BASEBOARD_FAB2_LIB.BASEBOARD_FAB2(SCH_1):M_E_DQ(43)
EA30 M_E_DQ<42> DDR4_DQ<42> @BASEBOARD_FAB2_LIB.BASEBOARD_FAB2(SCH_1):M_E_DQ(42)
ED33 M_E_DQ<41> DDR4_DQ<41> @BASEBOARD_FAB2_LIB.BASEBOARD_FAB2(SCH_1):M_E_DQ(41)
EC34 M_E_DQ<40> DDR4_DQ<40> @BASEBOARD_FAB2_LIB.BASEBOARD_FAB2(SCH_1):M_E_DQ(40)
DU40 M_E_DQ<39> DDR4_DQ<39> @BASEBOARD_FAB2_LIB.BASEBOARD_FAB2(SCH_1):M_E_DQ(39)
DN40 M_E_DQ<38> DDR4_DQ<38> @BASEBOARD_FAB2_LIB.BASEBOARD_FAB2(SCH_1):M_E_DQ(38)
DN42 M_E_DQ<37> DDR4_DQ<37> @BASEBOARD_FAB2_LIB.BASEBOARD_FAB2(SCH_1):M_E_DQ(37)
DL42 M_E_DQ<36> DDR4_DQ<36> @BASEBOARD_FAB2_LIB.BASEBOARD_FAB2(SCH_1):M_E_DQ(36)
DT39 M_E_DQ<35> DDR4_DQ<35> @BASEBOARD_FAB2_LIB.BASEBOARD_FAB2(SCH_1):M_E_DQ(35)
DP39 M_E_DQ<34> DDR4_DQ<34> @BASEBOARD_FAB2_LIB.BASEBOARD_FAB2(SCH_1):M_E_DQ(34)
DW42 M_E_DQ<33> DDR4_DQ<33> @BASEBOARD_FAB2_LIB.BASEBOARD_FAB2(SCH_1):M_E_DQ(33)
DU42 M_E_DQ<32> DDR4_DQ<32> @BASEBOARD_FAB2_LIB.BASEBOARD_FAB2(SCH_1):M_E_DQ(32)
EE72 M_E_DQ<31> DDR4_DQ<31> @BASEBOARD_FAB2_LIB.BASEBOARD_FAB2(SCH_1):M_E_DQ(31)
EA72 M_E_DQ<30> DDR4_DQ<30> @BASEBOARD_FAB2_LIB.BASEBOARD_FAB2(SCH_1):M_E_DQ(30)
EB75 M_E_DQ<29> DDR4_DQ<29> @BASEBOARD_FAB2_LIB.BASEBOARD_FAB2(SCH_1):M_E_DQ(29)
EA74 M_E_DQ<28> DDR4_DQ<28> @BASEBOARD_FAB2_LIB.BASEBOARD_FAB2(SCH_1):M_E_DQ(28)
ED71 M_E_DQ<27> DDR4_DQ<27> @BASEBOARD_FAB2_LIB.BASEBOARD_FAB2(SCH_1):M_E_DQ(27)
EB71 M_E_DQ<26> DDR4_DQ<26> @BASEBOARD_FAB2_LIB.BASEBOARD_FAB2(SCH_1):M_E_DQ(26)
EE74 M_E_DQ<25> DDR4_DQ<25> @BASEBOARD_FAB2_LIB.BASEBOARD_FAB2(SCH_1):M_E_DQ(25)
ED75 M_E_DQ<24> DDR4_DQ<24> @BASEBOARD_FAB2_LIB.BASEBOARD_FAB2(SCH_1):M_E_DQ(24)
EC78 M_E_DQ<23> DDR4_DQ<23> @BASEBOARD_FAB2_LIB.BASEBOARD_FAB2(SCH_1):M_E_DQ(23)
DW78 M_E_DQ<22> DDR4_DQ<22> @BASEBOARD_FAB2_LIB.BASEBOARD_FAB2(SCH_1):M_E_DQ(22)
EB81 M_E_DQ<21> DDR4_DQ<21> @BASEBOARD_FAB2_LIB.BASEBOARD_FAB2(SCH_1):M_E_DQ(21)
DY81 M_E_DQ<20> DDR4_DQ<20> @BASEBOARD_FAB2_LIB.BASEBOARD_FAB2(SCH_1):M_E_DQ(20)
EB77 M_E_DQ<19> DDR4_DQ<19> @BASEBOARD_FAB2_LIB.BASEBOARD_FAB2(SCH_1):M_E_DQ(19)
DY77 M_E_DQ<18> DDR4_DQ<18> @BASEBOARD_FAB2_LIB.BASEBOARD_FAB2(SCH_1):M_E_DQ(18)
EC80 M_E_DQ<17> DDR4_DQ<17> @BASEBOARD_FAB2_LIB.BASEBOARD_FAB2(SCH_1):M_E_DQ(17)
DW80 M_E_DQ<16> DDR4_DQ<16> @BASEBOARD_FAB2_LIB.BASEBOARD_FAB2(SCH_1):M_E_DQ(16)
DE82 M_E_DQ<15> DDR4_DQ<15> @BASEBOARD_FAB2_LIB.BASEBOARD_FAB2(SCH_1):M_E_DQ(15)
DC82 M_E_DQ<14> DDR4_DQ<14> @BASEBOARD_FAB2_LIB.BASEBOARD_FAB2(SCH_1):M_E_DQ(14)
CW80 M_E_DQ<13> DDR4_DQ<13> @BASEBOARD_FAB2_LIB.BASEBOARD_FAB2(SCH_1):M_E_DQ(13)
CY79 M_E_DQ<12> DDR4_DQ<12> @BASEBOARD_FAB2_LIB.BASEBOARD_FAB2(SCH_1):M_E_DQ(12)
DF81 M_E_DQ<11> DDR4_DQ<11> @BASEBOARD_FAB2_LIB.BASEBOARD_FAB2(SCH_1):M_E_DQ(11)
DE80 M_E_DQ<10> DDR4_DQ<10> @BASEBOARD_FAB2_LIB.BASEBOARD_FAB2(SCH_1):M_E_DQ(10)
CY81 M_E_DQ<9> DDR4_DQ<9> @BASEBOARD_FAB2_LIB.BASEBOARD_FAB2(SCH_1):M_E_DQ(9)
DB79 M_E_DQ<8> DDR4_DQ<8> @BASEBOARD_FAB2_LIB.BASEBOARD_FAB2(SCH_1):M_E_DQ(8)
CN82 M_E_DQ<7> DDR4_DQ<7> @BASEBOARD_FAB2_LIB.BASEBOARD_FAB2(SCH_1):M_E_DQ(7)
CR80 M_E_DQ<6> DDR4_DQ<6> @BASEBOARD_FAB2_LIB.BASEBOARD_FAB2(SCH_1):M_E_DQ(6)
CJ80 M_E_DQ<5> DDR4_DQ<5> @BASEBOARD_FAB2_LIB.BASEBOARD_FAB2(SCH_1):M_E_DQ(5)
CK79 M_E_DQ<4> DDR4_DQ<4> @BASEBOARD_FAB2_LIB.BASEBOARD_FAB2(SCH_1):M_E_DQ(4)
CR82 M_E_DQ<3> DDR4_DQ<3> @BASEBOARD_FAB2_LIB.BASEBOARD_FAB2(SCH_1):M_E_DQ(3)
CT81 M_E_DQ<2> DDR4_DQ<2> @BASEBOARD_FAB2_LIB.BASEBOARD_FAB2(SCH_1):M_E_DQ(2)
CK81 M_E_DQ<1> DDR4_DQ<1> @BASEBOARD_FAB2_LIB.BASEBOARD_FAB2(SCH_1):M_E_DQ(1)
CM79 M_E_DQ<0> DDR4_DQ<0> @BASEBOARD_FAB2_LIB.BASEBOARD_FAB2(SCH_1):M_E_DQ(0)
DV67 M_E_DQS_DN<17> DDR4_DQS_DN<17> @BASEBOARD_FAB2_LIB.BASEBOARD_FAB2(SCH_1):M_E_DQS_DN(17)
DG26 M_E_DQS_DN<16> DDR4_DQS_DN<16> @BASEBOARD_FAB2_LIB.BASEBOARD_FAB2(SCH_1):M_E_DQS_DN(16)
EA26 M_E_DQS_DN<15> DDR4_DQS_DN<15> @BASEBOARD_FAB2_LIB.BASEBOARD_FAB2(SCH_1):M_E_DQS_DN(15)
EA32 M_E_DQS_DN<14> DDR4_DQS_DN<14> @BASEBOARD_FAB2_LIB.BASEBOARD_FAB2(SCH_1):M_E_DQS_DN(14)
DP41 M_E_DQS_DN<13> DDR4_DQS_DN<13> @BASEBOARD_FAB2_LIB.BASEBOARD_FAB2(SCH_1):M_E_DQS_DN(13)
EB73 M_E_DQS_DN<12> DDR4_DQS_DN<12> @BASEBOARD_FAB2_LIB.BASEBOARD_FAB2(SCH_1):M_E_DQS_DN(12)
DY79 M_E_DQS_DN<11> DDR4_DQS_DN<11> @BASEBOARD_FAB2_LIB.BASEBOARD_FAB2(SCH_1):M_E_DQS_DN(11)
DC80 M_E_DQS_DN<10> DDR4_DQS_DN<10> @BASEBOARD_FAB2_LIB.BASEBOARD_FAB2(SCH_1):M_E_DQS_DN(10)
CN80 M_E_DQS_DN<9> DDR4_DQS_DN<9> @BASEBOARD_FAB2_LIB.BASEBOARD_FAB2(SCH_1):M_E_DQS_DN(9)
EB67 M_E_DQS_DN<8> DDR4_DQS_DN<8> @BASEBOARD_FAB2_LIB.BASEBOARD_FAB2(SCH_1):M_E_DQS_DN(8)
DL26 M_E_DQS_DN<7> DDR4_DQS_DN<7> @BASEBOARD_FAB2_LIB.BASEBOARD_FAB2(SCH_1):M_E_DQS_DN(7)
EE26 M_E_DQS_DN<6> DDR4_DQS_DN<6> @BASEBOARD_FAB2_LIB.BASEBOARD_FAB2(SCH_1):M_E_DQS_DN(6)
EE32 M_E_DQS_DN<5> DDR4_DQS_DN<5> @BASEBOARD_FAB2_LIB.BASEBOARD_FAB2(SCH_1):M_E_DQS_DN(5)
DV41 M_E_DQS_DN<4> DDR4_DQS_DN<4> @BASEBOARD_FAB2_LIB.BASEBOARD_FAB2(SCH_1):M_E_DQS_DN(4)
EF73 M_E_DQS_DN<3> DDR4_DQS_DN<3> @BASEBOARD_FAB2_LIB.BASEBOARD_FAB2(SCH_1):M_E_DQS_DN(3)
ED79 M_E_DQS_DN<2> DDR4_DQS_DN<2> @BASEBOARD_FAB2_LIB.BASEBOARD_FAB2(SCH_1):M_E_DQS_DN(2)
DA82 M_E_DQS_DN<1> DDR4_DQS_DN<1> @BASEBOARD_FAB2_LIB.BASEBOARD_FAB2(SCH_1):M_E_DQS_DN(1)
CL82 M_E_DQS_DN<0> DDR4_DQS_DN<0> @BASEBOARD_FAB2_LIB.BASEBOARD_FAB2(SCH_1):M_E_DQS_DN(0)
DT67 M_E_DQS_DP<17> DDR4_DQS_DP<17> @BASEBOARD_FAB2_LIB.BASEBOARD_FAB2(SCH_1):M_E_DQS_DP(17)
DE26 M_E_DQS_DP<16> DDR4_DQS_DP<16> @BASEBOARD_FAB2_LIB.BASEBOARD_FAB2(SCH_1):M_E_DQS_DP(16)
DW26 M_E_DQS_DP<15> DDR4_DQS_DP<15> @BASEBOARD_FAB2_LIB.BASEBOARD_FAB2(SCH_1):M_E_DQS_DP(15)
DW32 M_E_DQS_DP<14> DDR4_DQS_DP<14> @BASEBOARD_FAB2_LIB.BASEBOARD_FAB2(SCH_1):M_E_DQS_DP(14)
DM41 M_E_DQS_DP<13> DDR4_DQS_DP<13> @BASEBOARD_FAB2_LIB.BASEBOARD_FAB2(SCH_1):M_E_DQS_DP(13)
DY73 M_E_DQS_DP<12> DDR4_DQS_DP<12> @BASEBOARD_FAB2_LIB.BASEBOARD_FAB2(SCH_1):M_E_DQS_DP(12)
DV79 M_E_DQS_DP<11> DDR4_DQS_DP<11> @BASEBOARD_FAB2_LIB.BASEBOARD_FAB2(SCH_1):M_E_DQS_DP(11)
DD79 M_E_DQS_DP<10> DDR4_DQS_DP<10> @BASEBOARD_FAB2_LIB.BASEBOARD_FAB2(SCH_1):M_E_DQS_DP(10)
CP79 M_E_DQS_DP<9> DDR4_DQS_DP<9> @BASEBOARD_FAB2_LIB.BASEBOARD_FAB2(SCH_1):M_E_DQS_DP(9)
DY67 M_E_DQS_DP<8> DDR4_DQS_DP<8> @BASEBOARD_FAB2_LIB.BASEBOARD_FAB2(SCH_1):M_E_DQS_DP(8)
DJ26 M_E_DQS_DP<7> DDR4_DQS_DP<7> @BASEBOARD_FAB2_LIB.BASEBOARD_FAB2(SCH_1):M_E_DQS_DP(7)
EC26 M_E_DQS_DP<6> DDR4_DQS_DP<6> @BASEBOARD_FAB2_LIB.BASEBOARD_FAB2(SCH_1):M_E_DQS_DP(6)
EC32 M_E_DQS_DP<5> DDR4_DQS_DP<5> @BASEBOARD_FAB2_LIB.BASEBOARD_FAB2(SCH_1):M_E_DQS_DP(5)
DT41 M_E_DQS_DP<4> DDR4_DQS_DP<4> @BASEBOARD_FAB2_LIB.BASEBOARD_FAB2(SCH_1):M_E_DQS_DP(4)
ED73 M_E_DQS_DP<3> DDR4_DQS_DP<3> @BASEBOARD_FAB2_LIB.BASEBOARD_FAB2(SCH_1):M_E_DQS_DP(3)
EB79 M_E_DQS_DP<2> DDR4_DQS_DP<2> @BASEBOARD_FAB2_LIB.BASEBOARD_FAB2(SCH_1):M_E_DQS_DP(2)
DB81 M_E_DQS_DP<1> DDR4_DQS_DP<1> @BASEBOARD_FAB2_LIB.BASEBOARD_FAB2(SCH_1):M_E_DQS_DP(1)
CM81 M_E_DQS_DP<0> DDR4_DQS_DP<0> @BASEBOARD_FAB2_LIB.BASEBOARD_FAB2(SCH_1):M_E_DQS_DP(0)
EA66 M_E_ECC<7> DDR4_ECC<7> @BASEBOARD_FAB2_LIB.BASEBOARD_FAB2(SCH_1):M_E_ECC(7)
DU66 M_E_ECC<6> DDR4_ECC<6> @BASEBOARD_FAB2_LIB.BASEBOARD_FAB2(SCH_1):M_E_ECC(6)
DV69 M_E_ECC<5> DDR4_ECC<5> @BASEBOARD_FAB2_LIB.BASEBOARD_FAB2(SCH_1):M_E_ECC(5)
DU68 M_E_ECC<4> DDR4_ECC<4> @BASEBOARD_FAB2_LIB.BASEBOARD_FAB2(SCH_1):M_E_ECC(4)
DY65 M_E_ECC<3> DDR4_ECC<3> @BASEBOARD_FAB2_LIB.BASEBOARD_FAB2(SCH_1):M_E_ECC(3)
DV65 M_E_ECC<2> DDR4_ECC<2> @BASEBOARD_FAB2_LIB.BASEBOARD_FAB2(SCH_1):M_E_ECC(2)
EA68 M_E_ECC<1> DDR4_ECC<1> @BASEBOARD_FAB2_LIB.BASEBOARD_FAB2(SCH_1):M_E_ECC(1)
DY69 M_E_ECC<0> DDR4_ECC<0> @BASEBOARD_FAB2_LIB.BASEBOARD_FAB2(SCH_1):M_E_ECC(0)
DR48 M_E_MA<17> DDR4_MA<17> @BASEBOARD_FAB2_LIB.BASEBOARD_FAB2(SCH_1):M_E_MA(17)
DN52 M_E_MA<16> DDR4_MA<16> @BASEBOARD_FAB2_LIB.BASEBOARD_FAB2(SCH_1):M_E_MA(16)
DR52 M_E_MA<15> DDR4_MA<15> @BASEBOARD_FAB2_LIB.BASEBOARD_FAB2(SCH_1):M_E_MA(15)
DM51 M_E_MA<14> DDR4_MA<14> @BASEBOARD_FAB2_LIB.BASEBOARD_FAB2(SCH_1):M_E_MA(14)
DT51 M_E_MA<13> DDR4_MA<13> @BASEBOARD_FAB2_LIB.BASEBOARD_FAB2(SCH_1):M_E_MA(13)
DN60 M_E_MA<12> DDR4_MA<12> @BASEBOARD_FAB2_LIB.BASEBOARD_FAB2(SCH_1):M_E_MA(12)
DR60 M_E_MA<11> DDR4_MA<11> @BASEBOARD_FAB2_LIB.BASEBOARD_FAB2(SCH_1):M_E_MA(11)
DT55 M_E_MA<10> DDR4_MA<10> @BASEBOARD_FAB2_LIB.BASEBOARD_FAB2(SCH_1):M_E_MA(10)
DV59 M_E_MA<9> DDR4_MA<9> @BASEBOARD_FAB2_LIB.BASEBOARD_FAB2(SCH_1):M_E_MA(9)
DJ60 M_E_MA<8> DDR4_MA<8> @BASEBOARD_FAB2_LIB.BASEBOARD_FAB2(SCH_1):M_E_MA(8)
DK61 M_E_MA<7> DDR4_MA<7> @BASEBOARD_FAB2_LIB.BASEBOARD_FAB2(SCH_1):M_E_MA(7)
DM59 M_E_MA<6> DDR4_MA<6> @BASEBOARD_FAB2_LIB.BASEBOARD_FAB2(SCH_1):M_E_MA(6)
DN58 M_E_MA<5> DDR4_MA<5> @BASEBOARD_FAB2_LIB.BASEBOARD_FAB2(SCH_1):M_E_MA(5)
DT59 M_E_MA<4> DDR4_MA<4> @BASEBOARD_FAB2_LIB.BASEBOARD_FAB2(SCH_1):M_E_MA(4)
DR58 M_E_MA<3> DDR4_MA<3> @BASEBOARD_FAB2_LIB.BASEBOARD_FAB2(SCH_1):M_E_MA(3)
DV57 M_E_MA<2> DDR4_MA<2> @BASEBOARD_FAB2_LIB.BASEBOARD_FAB2(SCH_1):M_E_MA(2)
DW58 M_E_MA<1> DDR4_MA<1> @BASEBOARD_FAB2_LIB.BASEBOARD_FAB2(SCH_1):M_E_MA(1)
DW52 M_E_MA<0> DDR4_MA<0> @BASEBOARD_FAB2_LIB.BASEBOARD_FAB2(SCH_1):M_E_MA(0)
DM47 M_E_ODT<3> DDR4_ODT<3> @BASEBOARD_FAB2_LIB.BASEBOARD_FAB2(SCH_1):M_E_ODT(3)
DT49 M_E_ODT<2> DDR4_ODT<2> @BASEBOARD_FAB2_LIB.BASEBOARD_FAB2(SCH_1):M_E_ODT(2)
DN48 M_E_ODT<1> DDR4_ODT<1> @BASEBOARD_FAB2_LIB.BASEBOARD_FAB2(SCH_1):M_E_ODT(1)
DR50 M_E_ODT<0> DDR4_ODT<0> @BASEBOARD_FAB2_LIB.BASEBOARD_FAB2(SCH_1):M_E_ODT(0)
DV53 M_E_PAR DDR4_PAR @BASEBOARD_FAB2_LIB.BASEBOARD_FAB2(SCH_1):M_E_PAR


DRAWING: @BASEBOARD_FAB2_LIB.BASEBOARD_FAB2(SCH_1):PAGE28 

SKX_EXT_B_BGA1-IC,TBD  I172  U5D1
DC62 M_F_ACT_N DDR5_ACT_N @BASEBOARD_FAB2_LIB.BASEBOARD_FAB2(SCH_1):M_F_ACT_N
DD61 M_F_ALERT_N DDR5_ALERT_N @BASEBOARD_FAB2_LIB.BASEBOARD_FAB2(SCH_1):M_F_ALERT_N
DC56 M_F_BA<1> DDR5_BA<1> @BASEBOARD_FAB2_LIB.BASEBOARD_FAB2(SCH_1):M_F_BA(1)
DJ52 M_F_BA<0> DDR5_BA<0> @BASEBOARD_FAB2_LIB.BASEBOARD_FAB2(SCH_1):M_F_BA(0)
DF61 M_F_BG<1> DDR5_BG<1> @BASEBOARD_FAB2_LIB.BASEBOARD_FAB2(SCH_1):M_F_BG(1)
DA62 M_F_BG<0> DDR5_BG<0> @BASEBOARD_FAB2_LIB.BASEBOARD_FAB2(SCH_1):M_F_BG(0)
DF45 M_F_C<2> DDR5_CID<2> @BASEBOARD_FAB2_LIB.BASEBOARD_FAB2(SCH_1):M_F_C(2)
DF63 M_F_CKE<3> DDR5_CKE<3> @BASEBOARD_FAB2_LIB.BASEBOARD_FAB2(SCH_1):M_F_CKE(3)
DK63 M_F_CKE<2> DDR5_CKE<2> @BASEBOARD_FAB2_LIB.BASEBOARD_FAB2(SCH_1):M_F_CKE(2)
DD63 M_F_CKE<1> DDR5_CKE<1> @BASEBOARD_FAB2_LIB.BASEBOARD_FAB2(SCH_1):M_F_CKE(1)
DG62 M_F_CKE<0> DDR5_CKE<0> @BASEBOARD_FAB2_LIB.BASEBOARD_FAB2(SCH_1):M_F_CKE(0)
DF57 M_F_CLK_DN<3> DDR5_CLK_DN<3> @BASEBOARD_FAB2_LIB.BASEBOARD_FAB2(SCH_1):M_F_CLK_DN(3)
DK57 M_F_CLK_DN<2> DDR5_CLK_DN<2> @BASEBOARD_FAB2_LIB.BASEBOARD_FAB2(SCH_1):M_F_CLK_DN(2)
DF55 M_F_CLK_DN<1> DDR5_CLK_DN<1> @BASEBOARD_FAB2_LIB.BASEBOARD_FAB2(SCH_1):M_F_CLK_DN(1)
DK55 M_F_CLK_DN<0> DDR5_CLK_DN<0> @BASEBOARD_FAB2_LIB.BASEBOARD_FAB2(SCH_1):M_F_CLK_DN(0)
DG56 M_F_CLK_DP<3> DDR5_CLK_DP<3> @BASEBOARD_FAB2_LIB.BASEBOARD_FAB2(SCH_1):M_F_CLK_DP(3)
DJ56 M_F_CLK_DP<2> DDR5_CLK_DP<2> @BASEBOARD_FAB2_LIB.BASEBOARD_FAB2(SCH_1):M_F_CLK_DP(2)
DG54 M_F_CLK_DP<1> DDR5_CLK_DP<1> @BASEBOARD_FAB2_LIB.BASEBOARD_FAB2(SCH_1):M_F_CLK_DP(1)
DJ54 M_F_CLK_DP<0> DDR5_CLK_DP<0> @BASEBOARD_FAB2_LIB.BASEBOARD_FAB2(SCH_1):M_F_CLK_DP(0)
DK45 M_F_CS_N<7> DDR5_CS_N<7> @BASEBOARD_FAB2_LIB.BASEBOARD_FAB2(SCH_1):M_F_CS_N(7)
DM45 M_F_CS_N<6> DDR5_CS_N<6> @BASEBOARD_FAB2_LIB.BASEBOARD_FAB2(SCH_1):M_F_CS_N(6)
DJ48 M_F_CS_N<5> DDR5_CS_N<5> @BASEBOARD_FAB2_LIB.BASEBOARD_FAB2(SCH_1):M_F_CS_N(5)
DF51 M_F_CS_N<4> DDR5_CS_N<4> @BASEBOARD_FAB2_LIB.BASEBOARD_FAB2(SCH_1):M_F_CS_N(4)
DG46 M_F_CS_N<3> DDR5_CS_N<3> @BASEBOARD_FAB2_LIB.BASEBOARD_FAB2(SCH_1):M_F_CS_N(3)
DJ46 M_F_CS_N<2> DDR5_CS_N<2> @BASEBOARD_FAB2_LIB.BASEBOARD_FAB2(SCH_1):M_F_CS_N(2)
DF49 M_F_CS_N<1> DDR5_CS_N<1> @BASEBOARD_FAB2_LIB.BASEBOARD_FAB2(SCH_1):M_F_CS_N(1)
DK51 M_F_CS_N<0> DDR5_CS_N<0> @BASEBOARD_FAB2_LIB.BASEBOARD_FAB2(SCH_1):M_F_CS_N(0)
DC28 M_F_DQ<63> DDR5_DQ<63> @BASEBOARD_FAB2_LIB.BASEBOARD_FAB2(SCH_1):M_F_DQ(63)
CW28 M_F_DQ<62> DDR5_DQ<62> @BASEBOARD_FAB2_LIB.BASEBOARD_FAB2(SCH_1):M_F_DQ(62)
DB31 M_F_DQ<61> DDR5_DQ<61> @BASEBOARD_FAB2_LIB.BASEBOARD_FAB2(SCH_1):M_F_DQ(61)
CY31 M_F_DQ<60> DDR5_DQ<60> @BASEBOARD_FAB2_LIB.BASEBOARD_FAB2(SCH_1):M_F_DQ(60)
DB27 M_F_DQ<59> DDR5_DQ<59> @BASEBOARD_FAB2_LIB.BASEBOARD_FAB2(SCH_1):M_F_DQ(59)
CY27 M_F_DQ<58> DDR5_DQ<58> @BASEBOARD_FAB2_LIB.BASEBOARD_FAB2(SCH_1):M_F_DQ(58)
DC30 M_F_DQ<57> DDR5_DQ<57> @BASEBOARD_FAB2_LIB.BASEBOARD_FAB2(SCH_1):M_F_DQ(57)
CW30 M_F_DQ<56> DDR5_DQ<56> @BASEBOARD_FAB2_LIB.BASEBOARD_FAB2(SCH_1):M_F_DQ(56)
DC34 M_F_DQ<55> DDR5_DQ<55> @BASEBOARD_FAB2_LIB.BASEBOARD_FAB2(SCH_1):M_F_DQ(55)
CW34 M_F_DQ<54> DDR5_DQ<54> @BASEBOARD_FAB2_LIB.BASEBOARD_FAB2(SCH_1):M_F_DQ(54)
DB37 M_F_DQ<53> DDR5_DQ<53> @BASEBOARD_FAB2_LIB.BASEBOARD_FAB2(SCH_1):M_F_DQ(53)
CY37 M_F_DQ<52> DDR5_DQ<52> @BASEBOARD_FAB2_LIB.BASEBOARD_FAB2(SCH_1):M_F_DQ(52)
DB33 M_F_DQ<51> DDR5_DQ<51> @BASEBOARD_FAB2_LIB.BASEBOARD_FAB2(SCH_1):M_F_DQ(51)
CY33 M_F_DQ<50> DDR5_DQ<50> @BASEBOARD_FAB2_LIB.BASEBOARD_FAB2(SCH_1):M_F_DQ(50)
DC36 M_F_DQ<49> DDR5_DQ<49> @BASEBOARD_FAB2_LIB.BASEBOARD_FAB2(SCH_1):M_F_DQ(49)
CW36 M_F_DQ<48> DDR5_DQ<48> @BASEBOARD_FAB2_LIB.BASEBOARD_FAB2(SCH_1):M_F_DQ(48)
DK31 M_F_DQ<47> DDR5_DQ<47> @BASEBOARD_FAB2_LIB.BASEBOARD_FAB2(SCH_1):M_F_DQ(47)
DF31 M_F_DQ<46> DDR5_DQ<46> @BASEBOARD_FAB2_LIB.BASEBOARD_FAB2(SCH_1):M_F_DQ(46)
DJ34 M_F_DQ<45> DDR5_DQ<45> @BASEBOARD_FAB2_LIB.BASEBOARD_FAB2(SCH_1):M_F_DQ(45)
DG34 M_F_DQ<44> DDR5_DQ<44> @BASEBOARD_FAB2_LIB.BASEBOARD_FAB2(SCH_1):M_F_DQ(44)
DJ30 M_F_DQ<43> DDR5_DQ<43> @BASEBOARD_FAB2_LIB.BASEBOARD_FAB2(SCH_1):M_F_DQ(43)
DG30 M_F_DQ<42> DDR5_DQ<42> @BASEBOARD_FAB2_LIB.BASEBOARD_FAB2(SCH_1):M_F_DQ(42)
DK33 M_F_DQ<41> DDR5_DQ<41> @BASEBOARD_FAB2_LIB.BASEBOARD_FAB2(SCH_1):M_F_DQ(41)
DF33 M_F_DQ<40> DDR5_DQ<40> @BASEBOARD_FAB2_LIB.BASEBOARD_FAB2(SCH_1):M_F_DQ(40)
DH39 M_F_DQ<39> DDR5_DQ<39> @BASEBOARD_FAB2_LIB.BASEBOARD_FAB2(SCH_1):M_F_DQ(39)
DD39 M_F_DQ<38> DDR5_DQ<38> @BASEBOARD_FAB2_LIB.BASEBOARD_FAB2(SCH_1):M_F_DQ(38)
DE42 M_F_DQ<37> DDR5_DQ<37> @BASEBOARD_FAB2_LIB.BASEBOARD_FAB2(SCH_1):M_F_DQ(37)
DA42 M_F_DQ<36> DDR5_DQ<36> @BASEBOARD_FAB2_LIB.BASEBOARD_FAB2(SCH_1):M_F_DQ(36)
DG38 M_F_DQ<35> DDR5_DQ<35> @BASEBOARD_FAB2_LIB.BASEBOARD_FAB2(SCH_1):M_F_DQ(35)
DE38 M_F_DQ<34> DDR5_DQ<34> @BASEBOARD_FAB2_LIB.BASEBOARD_FAB2(SCH_1):M_F_DQ(34)
DG42 M_F_DQ<33> DDR5_DQ<33> @BASEBOARD_FAB2_LIB.BASEBOARD_FAB2(SCH_1):M_F_DQ(33)
DD41 M_F_DQ<32> DDR5_DQ<32> @BASEBOARD_FAB2_LIB.BASEBOARD_FAB2(SCH_1):M_F_DQ(32)
CU64 M_F_DQ<31> DDR5_DQ<31> @BASEBOARD_FAB2_LIB.BASEBOARD_FAB2(SCH_1):M_F_DQ(31)
CN64 M_F_DQ<30> DDR5_DQ<30> @BASEBOARD_FAB2_LIB.BASEBOARD_FAB2(SCH_1):M_F_DQ(30)
CT67 M_F_DQ<29> DDR5_DQ<29> @BASEBOARD_FAB2_LIB.BASEBOARD_FAB2(SCH_1):M_F_DQ(29)
CP67 M_F_DQ<28> DDR5_DQ<28> @BASEBOARD_FAB2_LIB.BASEBOARD_FAB2(SCH_1):M_F_DQ(28)
CT63 M_F_DQ<27> DDR5_DQ<27> @BASEBOARD_FAB2_LIB.BASEBOARD_FAB2(SCH_1):M_F_DQ(27)
CP63 M_F_DQ<26> DDR5_DQ<26> @BASEBOARD_FAB2_LIB.BASEBOARD_FAB2(SCH_1):M_F_DQ(26)
CU66 M_F_DQ<25> DDR5_DQ<25> @BASEBOARD_FAB2_LIB.BASEBOARD_FAB2(SCH_1):M_F_DQ(25)
CN66 M_F_DQ<24> DDR5_DQ<24> @BASEBOARD_FAB2_LIB.BASEBOARD_FAB2(SCH_1):M_F_DQ(24)
DM71 M_F_DQ<23> DDR5_DQ<23> @BASEBOARD_FAB2_LIB.BASEBOARD_FAB2(SCH_1):M_F_DQ(23)
DK69 M_F_DQ<22> DDR5_DQ<22> @BASEBOARD_FAB2_LIB.BASEBOARD_FAB2(SCH_1):M_F_DQ(22)
DG72 M_F_DQ<21> DDR5_DQ<21> @BASEBOARD_FAB2_LIB.BASEBOARD_FAB2(SCH_1):M_F_DQ(21)
DF71 M_F_DQ<20> DDR5_DQ<20> @BASEBOARD_FAB2_LIB.BASEBOARD_FAB2(SCH_1):M_F_DQ(20)
DN70 M_F_DQ<19> DDR5_DQ<19> @BASEBOARD_FAB2_LIB.BASEBOARD_FAB2(SCH_1):M_F_DQ(19)
DM69 M_F_DQ<18> DDR5_DQ<18> @BASEBOARD_FAB2_LIB.BASEBOARD_FAB2(SCH_1):M_F_DQ(18)
DJ72 M_F_DQ<17> DDR5_DQ<17> @BASEBOARD_FAB2_LIB.BASEBOARD_FAB2(SCH_1):M_F_DQ(17)
DG70 M_F_DQ<16> DDR5_DQ<16> @BASEBOARD_FAB2_LIB.BASEBOARD_FAB2(SCH_1):M_F_DQ(16)
DH77 M_F_DQ<15> DDR5_DQ<15> @BASEBOARD_FAB2_LIB.BASEBOARD_FAB2(SCH_1):M_F_DQ(15)
DF77 M_F_DQ<14> DDR5_DQ<14> @BASEBOARD_FAB2_LIB.BASEBOARD_FAB2(SCH_1):M_F_DQ(14)
DB75 M_F_DQ<13> DDR5_DQ<13> @BASEBOARD_FAB2_LIB.BASEBOARD_FAB2(SCH_1):M_F_DQ(13)
DC74 M_F_DQ<12> DDR5_DQ<12> @BASEBOARD_FAB2_LIB.BASEBOARD_FAB2(SCH_1):M_F_DQ(12)
DJ76 M_F_DQ<11> DDR5_DQ<11> @BASEBOARD_FAB2_LIB.BASEBOARD_FAB2(SCH_1):M_F_DQ(11)
DH75 M_F_DQ<10> DDR5_DQ<10> @BASEBOARD_FAB2_LIB.BASEBOARD_FAB2(SCH_1):M_F_DQ(10)
DC76 M_F_DQ<9> DDR5_DQ<9> @BASEBOARD_FAB2_LIB.BASEBOARD_FAB2(SCH_1):M_F_DQ(9)
DE74 M_F_DQ<8> DDR5_DQ<8> @BASEBOARD_FAB2_LIB.BASEBOARD_FAB2(SCH_1):M_F_DQ(8)
CT77 M_F_DQ<7> DDR5_DQ<7> @BASEBOARD_FAB2_LIB.BASEBOARD_FAB2(SCH_1):M_F_DQ(7)
CV75 M_F_DQ<6> DDR5_DQ<6> @BASEBOARD_FAB2_LIB.BASEBOARD_FAB2(SCH_1):M_F_DQ(6)
CM75 M_F_DQ<5> DDR5_DQ<5> @BASEBOARD_FAB2_LIB.BASEBOARD_FAB2(SCH_1):M_F_DQ(5)
CN74 M_F_DQ<4> DDR5_DQ<4> @BASEBOARD_FAB2_LIB.BASEBOARD_FAB2(SCH_1):M_F_DQ(4)
CV77 M_F_DQ<3> DDR5_DQ<3> @BASEBOARD_FAB2_LIB.BASEBOARD_FAB2(SCH_1):M_F_DQ(3)
CW76 M_F_DQ<2> DDR5_DQ<2> @BASEBOARD_FAB2_LIB.BASEBOARD_FAB2(SCH_1):M_F_DQ(2)
CN76 M_F_DQ<1> DDR5_DQ<1> @BASEBOARD_FAB2_LIB.BASEBOARD_FAB2(SCH_1):M_F_DQ(1)
CR74 M_F_DQ<0> DDR5_DQ<0> @BASEBOARD_FAB2_LIB.BASEBOARD_FAB2(SCH_1):M_F_DQ(0)
CJ70 M_F_DQS_DN<17> DDR5_DQS_DN<17> @BASEBOARD_FAB2_LIB.BASEBOARD_FAB2(SCH_1):M_F_DQS_DN(17)
CY29 M_F_DQS_DN<16> DDR5_DQS_DN<16> @BASEBOARD_FAB2_LIB.BASEBOARD_FAB2(SCH_1):M_F_DQS_DN(16)
CY35 M_F_DQS_DN<15> DDR5_DQS_DN<15> @BASEBOARD_FAB2_LIB.BASEBOARD_FAB2(SCH_1):M_F_DQS_DN(15)
DG32 M_F_DQS_DN<14> DDR5_DQS_DN<14> @BASEBOARD_FAB2_LIB.BASEBOARD_FAB2(SCH_1):M_F_DQS_DN(14)
DE40 M_F_DQS_DN<13> DDR5_DQS_DN<13> @BASEBOARD_FAB2_LIB.BASEBOARD_FAB2(SCH_1):M_F_DQS_DN(13)
CP65 M_F_DQS_DN<12> DDR5_DQS_DN<12> @BASEBOARD_FAB2_LIB.BASEBOARD_FAB2(SCH_1):M_F_DQS_DN(12)
DJ70 M_F_DQS_DN<11> DDR5_DQS_DN<11> @BASEBOARD_FAB2_LIB.BASEBOARD_FAB2(SCH_1):M_F_DQS_DN(11)
DF75 M_F_DQS_DN<10> DDR5_DQS_DN<10> @BASEBOARD_FAB2_LIB.BASEBOARD_FAB2(SCH_1):M_F_DQS_DN(10)
CT75 M_F_DQS_DN<9> DDR5_DQS_DN<9> @BASEBOARD_FAB2_LIB.BASEBOARD_FAB2(SCH_1):M_F_DQS_DN(9)
CN70 M_F_DQS_DN<8> DDR5_DQS_DN<8> @BASEBOARD_FAB2_LIB.BASEBOARD_FAB2(SCH_1):M_F_DQS_DN(8)
DD29 M_F_DQS_DN<7> DDR5_DQS_DN<7> @BASEBOARD_FAB2_LIB.BASEBOARD_FAB2(SCH_1):M_F_DQS_DN(7)
DD35 M_F_DQS_DN<6> DDR5_DQS_DN<6> @BASEBOARD_FAB2_LIB.BASEBOARD_FAB2(SCH_1):M_F_DQS_DN(6)
DL32 M_F_DQS_DN<5> DDR5_DQS_DN<5> @BASEBOARD_FAB2_LIB.BASEBOARD_FAB2(SCH_1):M_F_DQS_DN(5)
DG40 M_F_DQS_DN<4> DDR5_DQS_DN<4> @BASEBOARD_FAB2_LIB.BASEBOARD_FAB2(SCH_1):M_F_DQS_DN(4)
CV65 M_F_DQS_DN<3> DDR5_DQS_DN<3> @BASEBOARD_FAB2_LIB.BASEBOARD_FAB2(SCH_1):M_F_DQS_DN(3)
DL72 M_F_DQS_DN<2> DDR5_DQS_DN<2> @BASEBOARD_FAB2_LIB.BASEBOARD_FAB2(SCH_1):M_F_DQS_DN(2)
DD77 M_F_DQS_DN<1> DDR5_DQS_DN<1> @BASEBOARD_FAB2_LIB.BASEBOARD_FAB2(SCH_1):M_F_DQS_DN(1)
CP77 M_F_DQS_DN<0> DDR5_DQS_DN<0> @BASEBOARD_FAB2_LIB.BASEBOARD_FAB2(SCH_1):M_F_DQS_DN(0)
CG70 M_F_DQS_DP<17> DDR5_DQS_DP<17> @BASEBOARD_FAB2_LIB.BASEBOARD_FAB2(SCH_1):M_F_DQS_DP(17)
CV29 M_F_DQS_DP<16> DDR5_DQS_DP<16> @BASEBOARD_FAB2_LIB.BASEBOARD_FAB2(SCH_1):M_F_DQS_DP(16)
CV35 M_F_DQS_DP<15> DDR5_DQS_DP<15> @BASEBOARD_FAB2_LIB.BASEBOARD_FAB2(SCH_1):M_F_DQS_DP(15)
DE32 M_F_DQS_DP<14> DDR5_DQS_DP<14> @BASEBOARD_FAB2_LIB.BASEBOARD_FAB2(SCH_1):M_F_DQS_DP(14)
DC40 M_F_DQS_DP<13> DDR5_DQS_DP<13> @BASEBOARD_FAB2_LIB.BASEBOARD_FAB2(SCH_1):M_F_DQS_DP(13)
CM65 M_F_DQS_DP<12> DDR5_DQS_DP<12> @BASEBOARD_FAB2_LIB.BASEBOARD_FAB2(SCH_1):M_F_DQS_DP(12)
DH69 M_F_DQS_DP<11> DDR5_DQS_DP<11> @BASEBOARD_FAB2_LIB.BASEBOARD_FAB2(SCH_1):M_F_DQS_DP(11)
DG74 M_F_DQS_DP<10> DDR5_DQS_DP<10> @BASEBOARD_FAB2_LIB.BASEBOARD_FAB2(SCH_1):M_F_DQS_DP(10)
CU74 M_F_DQS_DP<9> DDR5_DQS_DP<9> @BASEBOARD_FAB2_LIB.BASEBOARD_FAB2(SCH_1):M_F_DQS_DP(9)
CL70 M_F_DQS_DP<8> DDR5_DQS_DP<8> @BASEBOARD_FAB2_LIB.BASEBOARD_FAB2(SCH_1):M_F_DQS_DP(8)
DB29 M_F_DQS_DP<7> DDR5_DQS_DP<7> @BASEBOARD_FAB2_LIB.BASEBOARD_FAB2(SCH_1):M_F_DQS_DP(7)
DB35 M_F_DQS_DP<6> DDR5_DQS_DP<6> @BASEBOARD_FAB2_LIB.BASEBOARD_FAB2(SCH_1):M_F_DQS_DP(6)
DJ32 M_F_DQS_DP<5> DDR5_DQS_DP<5> @BASEBOARD_FAB2_LIB.BASEBOARD_FAB2(SCH_1):M_F_DQS_DP(5)
DJ40 M_F_DQS_DP<4> DDR5_DQS_DP<4> @BASEBOARD_FAB2_LIB.BASEBOARD_FAB2(SCH_1):M_F_DQS_DP(4)
CT65 M_F_DQS_DP<3> DDR5_DQS_DP<3> @BASEBOARD_FAB2_LIB.BASEBOARD_FAB2(SCH_1):M_F_DQS_DP(3)
DK71 M_F_DQS_DP<2> DDR5_DQS_DP<2> @BASEBOARD_FAB2_LIB.BASEBOARD_FAB2(SCH_1):M_F_DQS_DP(2)
DE76 M_F_DQS_DP<1> DDR5_DQS_DP<1> @BASEBOARD_FAB2_LIB.BASEBOARD_FAB2(SCH_1):M_F_DQS_DP(1)
CR76 M_F_DQS_DP<0> DDR5_DQS_DP<0> @BASEBOARD_FAB2_LIB.BASEBOARD_FAB2(SCH_1):M_F_DQS_DP(0)
CM69 M_F_ECC<7> DDR5_ECC<7> @BASEBOARD_FAB2_LIB.BASEBOARD_FAB2(SCH_1):M_F_ECC(7)
CH69 M_F_ECC<6> DDR5_ECC<6> @BASEBOARD_FAB2_LIB.BASEBOARD_FAB2(SCH_1):M_F_ECC(6)
CL72 M_F_ECC<5> DDR5_ECC<5> @BASEBOARD_FAB2_LIB.BASEBOARD_FAB2(SCH_1):M_F_ECC(5)
CJ72 M_F_ECC<4> DDR5_ECC<4> @BASEBOARD_FAB2_LIB.BASEBOARD_FAB2(SCH_1):M_F_ECC(4)
CL68 M_F_ECC<3> DDR5_ECC<3> @BASEBOARD_FAB2_LIB.BASEBOARD_FAB2(SCH_1):M_F_ECC(3)
CJ68 M_F_ECC<2> DDR5_ECC<2> @BASEBOARD_FAB2_LIB.BASEBOARD_FAB2(SCH_1):M_F_ECC(2)
CM71 M_F_ECC<1> DDR5_ECC<1> @BASEBOARD_FAB2_LIB.BASEBOARD_FAB2(SCH_1):M_F_ECC(1)
CH71 M_F_ECC<0> DDR5_ECC<0> @BASEBOARD_FAB2_LIB.BASEBOARD_FAB2(SCH_1):M_F_ECC(0)
DE46 M_F_MA<17> DDR5_MA<17> @BASEBOARD_FAB2_LIB.BASEBOARD_FAB2(SCH_1):M_F_MA(17)
DG52 M_F_MA<16> DDR5_MA<16> @BASEBOARD_FAB2_LIB.BASEBOARD_FAB2(SCH_1):M_F_MA(16)
DC54 M_F_MA<15> DDR5_MA<15> @BASEBOARD_FAB2_LIB.BASEBOARD_FAB2(SCH_1):M_F_MA(15)
DJ50 M_F_MA<14> DDR5_MA<14> @BASEBOARD_FAB2_LIB.BASEBOARD_FAB2(SCH_1):M_F_MA(14)
DD53 M_F_MA<13> DDR5_MA<13> @BASEBOARD_FAB2_LIB.BASEBOARD_FAB2(SCH_1):M_F_MA(13)
DG60 M_F_MA<12> DDR5_MA<12> @BASEBOARD_FAB2_LIB.BASEBOARD_FAB2(SCH_1):M_F_MA(12)
DA60 M_F_MA<11> DDR5_MA<11> @BASEBOARD_FAB2_LIB.BASEBOARD_FAB2(SCH_1):M_F_MA(11)
DD55 M_F_MA<10> DDR5_MA<10> @BASEBOARD_FAB2_LIB.BASEBOARD_FAB2(SCH_1):M_F_MA(10)
DA58 M_F_MA<9> DDR5_MA<9> @BASEBOARD_FAB2_LIB.BASEBOARD_FAB2(SCH_1):M_F_MA(9)
DD59 M_F_MA<8> DDR5_MA<8> @BASEBOARD_FAB2_LIB.BASEBOARD_FAB2(SCH_1):M_F_MA(8)
DC60 M_F_MA<7> DDR5_MA<7> @BASEBOARD_FAB2_LIB.BASEBOARD_FAB2(SCH_1):M_F_MA(7)
DK59 M_F_MA<6> DDR5_MA<6> @BASEBOARD_FAB2_LIB.BASEBOARD_FAB2(SCH_1):M_F_MA(6)
DF59 M_F_MA<5> DDR5_MA<5> @BASEBOARD_FAB2_LIB.BASEBOARD_FAB2(SCH_1):M_F_MA(5)
DJ58 M_F_MA<4> DDR5_MA<4> @BASEBOARD_FAB2_LIB.BASEBOARD_FAB2(SCH_1):M_F_MA(4)
DG58 M_F_MA<3> DDR5_MA<3> @BASEBOARD_FAB2_LIB.BASEBOARD_FAB2(SCH_1):M_F_MA(3)
DD57 M_F_MA<2> DDR5_MA<2> @BASEBOARD_FAB2_LIB.BASEBOARD_FAB2(SCH_1):M_F_MA(2)
DC58 M_F_MA<1> DDR5_MA<1> @BASEBOARD_FAB2_LIB.BASEBOARD_FAB2(SCH_1):M_F_MA(1)
DF53 M_F_MA<0> DDR5_MA<0> @BASEBOARD_FAB2_LIB.BASEBOARD_FAB2(SCH_1):M_F_MA(0)
DF47 M_F_ODT<3> DDR5_ODT<3> @BASEBOARD_FAB2_LIB.BASEBOARD_FAB2(SCH_1):M_F_ODT(3)
DK49 M_F_ODT<2> DDR5_ODT<2> @BASEBOARD_FAB2_LIB.BASEBOARD_FAB2(SCH_1):M_F_ODT(2)
DG48 M_F_ODT<1> DDR5_ODT<1> @BASEBOARD_FAB2_LIB.BASEBOARD_FAB2(SCH_1):M_F_ODT(1)
DG50 M_F_ODT<0> DDR5_ODT<0> @BASEBOARD_FAB2_LIB.BASEBOARD_FAB2(SCH_1):M_F_ODT(0)
DK53 M_F_PAR DDR5_PAR @BASEBOARD_FAB2_LIB.BASEBOARD_FAB2(SCH_1):M_F_PAR


DRAWING: @BASEBOARD_FAB2_LIB.BASEBOARD_FAB2(SCH_1):PAGE29 

SKX_EXT_B_BGA1-IC,TBD  I61  U5D1
BN22 SMB_HFI0_CPU0_LVC2_SCL CD_HFI0_I2CCLK @BASEBOARD_FAB2_LIB.BASEBOARD_FAB2(SCH_1):SMB_HFI0_CPU0_LVC2_SCL
BP23 SMB_HFI0_CPU0_LVC2_SDA CD_HFI0_I2CDAT @BASEBOARD_FAB2_LIB.BASEBOARD_FAB2(SCH_1):SMB_HFI0_CPU0_LVC2_SDA
BP19 IRQ_HFI0_CPU0_LVT2_N CD_HFI0_INT_N @BASEBOARD_FAB2_LIB.BASEBOARD_FAB2(SCH_1):IRQ_HFI0_CPU0_LVT2_N
BK21 LED_HFI0_CPU0_N CD_HFI0_LED_N @BASEBOARD_FAB2_LIB.BASEBOARD_FAB2(SCH_1):LED_HFI0_CPU0_N
BR20 FM_MODPRST_HFI0_CPU0_LVT2_N CD_HFI0_MODPRST_N @BASEBOARD_FAB2_LIB.BASEBOARD_FAB2(SCH_1):FM_MODPRST_HFI0_CPU0_LVT2_N
BN24 RST_HFI0_CPU0_LVT2_N CD_HFI0_RESET_N @BASEBOARD_FAB2_LIB.BASEBOARD_FAB2(SCH_1):RST_HFI0_CPU0_LVT2_N
BJ22 SMB_HFI1_CPU0_LVC2_SCL CD_HFI1_I2CCLK @BASEBOARD_FAB2_LIB.BASEBOARD_FAB2(SCH_1):SMB_HFI1_CPU0_LVC2_SCL
BH23 SMB_HFI1_CPU0_LVC2_SDA CD_HFI1_I2CDAT @BASEBOARD_FAB2_LIB.BASEBOARD_FAB2(SCH_1):SMB_HFI1_CPU0_LVC2_SDA
BM21 IRQ_HFI1_CPU0_LVT2_N CD_HFI1_INT_N @BASEBOARD_FAB2_LIB.BASEBOARD_FAB2(SCH_1):IRQ_HFI1_CPU0_LVT2_N
BM23 LED_HFI1_CPU0_N CD_HFI1_LED_N @BASEBOARD_FAB2_LIB.BASEBOARD_FAB2(SCH_1):LED_HFI1_CPU0_N
BT19 FM_MODPRST_HFI1_CPU0_LVT2_N CD_HFI1_MODPRST_N @BASEBOARD_FAB2_LIB.BASEBOARD_FAB2(SCH_1):FM_MODPRST_HFI1_CPU0_LVT2_N
BK23 RST_HFI1_CPU0_LVT2_N CD_HFI1_RESET_N @BASEBOARD_FAB2_LIB.BASEBOARD_FAB2(SCH_1):RST_HFI1_CPU0_LVT2_N
BE16 CLK_156M_OSC_CPU0_HFI_DN CD_HFI_REFCLK_DN @BASEBOARD_FAB2_LIB.BASEBOARD_FAB2(SCH_1):CLK_156M_OSC_CPU0_HFI_DN
BG16 CLK_156M_OSC_CPU0_HFI_DP CD_HFI_REFCLK_DP @BASEBOARD_FAB2_LIB.BASEBOARD_FAB2(SCH_1):CLK_156M_OSC_CPU0_HFI_DP
BU24 CLK_100M_CPU0_PE_REFCLK_DN CD_PE_REFCLK_DN @BASEBOARD_FAB2_LIB.BASEBOARD_FAB2(SCH_1):CLK_100M_CPU0_PE_REFCLK_DN
BW24 CLK_100M_CPU0_PE_REFCLK_DP CD_PE_REFCLK_DP @BASEBOARD_FAB2_LIB.BASEBOARD_FAB2(SCH_1):CLK_100M_CPU0_PE_REFCLK_DP
CF25 RST_CD_CPU0_POR_N CD_POR_N @BASEBOARD_FAB2_LIB.BASEBOARD_FAB2(SCH_1):RST_CD_CPU0_POR_N
CB23 JTAG_MCP_TCK CD_TCLK @BASEBOARD_FAB2_LIB.BASEBOARD_FAB2(SCH_1):JTAG_MCP_TCK
BY21 JTAG_MCP_CPU0_TDI CD_TDI @BASEBOARD_FAB2_LIB.BASEBOARD_FAB2(SCH_1):JTAG_MCP_CPU0_TDI
CC22 JTAG_MCP_CPU0_TDO CD_TDO @BASEBOARD_FAB2_LIB.BASEBOARD_FAB2(SCH_1):JTAG_MCP_CPU0_TDO
CE24 JTAG_MCP_TMS CD_TMS @BASEBOARD_FAB2_LIB.BASEBOARD_FAB2(SCH_1):JTAG_MCP_TMS
CD23 JTAG_MCP_TRST_N CD_TRST_N @BASEBOARD_FAB2_LIB.BASEBOARD_FAB2(SCH_1):JTAG_MCP_TRST_N
CT11 DMI_CPU0_PCH_RX_C_DN<3> DMI_RX_DN<3> @BASEBOARD_FAB2_LIB.BASEBOARD_FAB2(SCH_1):DMI_CPU0_PCH_RX_C_DN(3)
CR12 DMI_CPU0_PCH_RX_C_DN<2> DMI_RX_DN<2> @BASEBOARD_FAB2_LIB.BASEBOARD_FAB2(SCH_1):DMI_CPU0_PCH_RX_C_DN(2)
CM11 DMI_CPU0_PCH_RX_C_DN<1> DMI_RX_DN<1> @BASEBOARD_FAB2_LIB.BASEBOARD_FAB2(SCH_1):DMI_CPU0_PCH_RX_C_DN(1)
 CK9 DMI_CPU0_PCH_RX_C_DN<0> DMI_RX_DN<0> @BASEBOARD_FAB2_LIB.BASEBOARD_FAB2(SCH_1):DMI_CPU0_PCH_RX_C_DN(0)
CV11 DMI_CPU0_PCH_RX_C_DP<3> DMI_RX_DP<3> @BASEBOARD_FAB2_LIB.BASEBOARD_FAB2(SCH_1):DMI_CPU0_PCH_RX_C_DP(3)
CP11 DMI_CPU0_PCH_RX_C_DP<2> DMI_RX_DP<2> @BASEBOARD_FAB2_LIB.BASEBOARD_FAB2(SCH_1):DMI_CPU0_PCH_RX_C_DP(2)
CN10 DMI_CPU0_PCH_RX_C_DP<1> DMI_RX_DP<1> @BASEBOARD_FAB2_LIB.BASEBOARD_FAB2(SCH_1):DMI_CPU0_PCH_RX_C_DP(1)
CL10 DMI_CPU0_PCH_RX_C_DP<0> DMI_RX_DP<0> @BASEBOARD_FAB2_LIB.BASEBOARD_FAB2(SCH_1):DMI_CPU0_PCH_RX_C_DP(0)
 CP5 DMI_CPU0_PCH_TX_DN<3> DMI_TX_DN<3> @BASEBOARD_FAB2_LIB.BASEBOARD_FAB2(SCH_1):DMI_CPU0_PCH_TX_DN(3)
 CN4 DMI_CPU0_PCH_TX_DN<2> DMI_TX_DN<2> @BASEBOARD_FAB2_LIB.BASEBOARD_FAB2(SCH_1):DMI_CPU0_PCH_TX_DN(2)
 CJ4 DMI_CPU0_PCH_TX_DN<1> DMI_TX_DN<1> @BASEBOARD_FAB2_LIB.BASEBOARD_FAB2(SCH_1):DMI_CPU0_PCH_TX_DN(1)
 CG4 DMI_CPU0_PCH_TX_DN<0> DMI_TX_DN<0> @BASEBOARD_FAB2_LIB.BASEBOARD_FAB2(SCH_1):DMI_CPU0_PCH_TX_DN(0)
 CR4 DMI_CPU0_PCH_TX_DP<3> DMI_TX_DP<3> @BASEBOARD_FAB2_LIB.BASEBOARD_FAB2(SCH_1):DMI_CPU0_PCH_TX_DP(3)
 CM3 DMI_CPU0_PCH_TX_DP<2> DMI_TX_DP<2> @BASEBOARD_FAB2_LIB.BASEBOARD_FAB2(SCH_1):DMI_CPU0_PCH_TX_DP(2)
 CL4 DMI_CPU0_PCH_TX_DP<1> DMI_TX_DP<1> @BASEBOARD_FAB2_LIB.BASEBOARD_FAB2(SCH_1):DMI_CPU0_PCH_TX_DP(1)
 CH5 DMI_CPU0_PCH_TX_DP<0> DMI_TX_DP<0> @BASEBOARD_FAB2_LIB.BASEBOARD_FAB2(SCH_1):DMI_CPU0_PCH_TX_DP(0)
AR20 PVCCMCP_CPU0 RSVD<193> @BASEBOARD_FAB2_LIB.BASEBOARD_FAB2(SCH_1):PVCCMCP_CPU0
AR22 PVCCMCP_CPU0 RSVD<192> @BASEBOARD_FAB2_LIB.BASEBOARD_FAB2(SCH_1):PVCCMCP_CPU0
AR26 PVCCMCP_CPU0 RSVD<191> @BASEBOARD_FAB2_LIB.BASEBOARD_FAB2(SCH_1):PVCCMCP_CPU0
AR62 TP_CPU0_RSVD_190 RSVD<190> @BASEBOARD_FAB2_LIB.BASEBOARD_FAB2(SCH_1):TP_CPU0_RSVD_190
AT13 TP_CPU0_RSVD_189 RSVD<189> @BASEBOARD_FAB2_LIB.BASEBOARD_FAB2(SCH_1):TP_CPU0_RSVD_189
AT23 PVCCMCP_CPU0 RSVD<188> @BASEBOARD_FAB2_LIB.BASEBOARD_FAB2(SCH_1):PVCCMCP_CPU0
AT25 PVCCMCP_CPU0 RSVD<187> @BASEBOARD_FAB2_LIB.BASEBOARD_FAB2(SCH_1):PVCCMCP_CPU0
AV77 TP_CPU0_RSVD_186 RSVD<186> @BASEBOARD_FAB2_LIB.BASEBOARD_FAB2(SCH_1):TP_CPU0_RSVD_186
AW64 TP_CPU0_RSVD_184 RSVD<184> @BASEBOARD_FAB2_LIB.BASEBOARD_FAB2(SCH_1):TP_CPU0_RSVD_184
AW76 TP_CPU0_RSVD_183 RSVD<183> @BASEBOARD_FAB2_LIB.BASEBOARD_FAB2(SCH_1):TP_CPU0_RSVD_183
AY65 TP_CPU0_RSVD_182 RSVD<182> @BASEBOARD_FAB2_LIB.BASEBOARD_FAB2(SCH_1):TP_CPU0_RSVD_182
AY67 TP_CPU0_RSVD_181 RSVD<181> @BASEBOARD_FAB2_LIB.BASEBOARD_FAB2(SCH_1):TP_CPU0_RSVD_181
AY75 TP_CPU0_RSVD_180 RSVD<180> @BASEBOARD_FAB2_LIB.BASEBOARD_FAB2(SCH_1):TP_CPU0_RSVD_180
AY77 TP_CPU0_RSVD_179 RSVD<179> @BASEBOARD_FAB2_LIB.BASEBOARD_FAB2(SCH_1):TP_CPU0_RSVD_179
BA14 TP_CPU0_RSVD_178 RSVD<178> @BASEBOARD_FAB2_LIB.BASEBOARD_FAB2(SCH_1):TP_CPU0_RSVD_178
BA16 TP_CPU0_RSVD_177 RSVD<177> @BASEBOARD_FAB2_LIB.BASEBOARD_FAB2(SCH_1):TP_CPU0_RSVD_177
BA18 TP_CPU0_RSVD_176 RSVD<176> @BASEBOARD_FAB2_LIB.BASEBOARD_FAB2(SCH_1):TP_CPU0_RSVD_176
BA22 TP_CPU0_RSVD_175 RSVD<175> @BASEBOARD_FAB2_LIB.BASEBOARD_FAB2(SCH_1):TP_CPU0_RSVD_175
BA64 TP_CPU0_RSVD_174 RSVD<174> @BASEBOARD_FAB2_LIB.BASEBOARD_FAB2(SCH_1):TP_CPU0_RSVD_174
BA66 TP_CPU0_RSVD_173 RSVD<173> @BASEBOARD_FAB2_LIB.BASEBOARD_FAB2(SCH_1):TP_CPU0_RSVD_173
BA76 TP_CPU0_RSVD_172 RSVD<172> @BASEBOARD_FAB2_LIB.BASEBOARD_FAB2(SCH_1):TP_CPU0_RSVD_172


DRAWING: @BASEBOARD_FAB2_LIB.BASEBOARD_FAB2(SCH_1):PAGE30 

SKX_EXT_B_BGA1-IC,TBD  I84  U5D1
DU16 P3E_CPU0_PE1_PCH_RXN<15> PE1_RX_DN<15> @BASEBOARD_FAB2_LIB.BASEBOARD_FAB2(SCH_1):P3E_CPU0_PE1_PCH_RXN(15)
DY15 P3E_CPU0_PE1_PCH_RXN<14> PE1_RX_DN<14> @BASEBOARD_FAB2_LIB.BASEBOARD_FAB2(SCH_1):P3E_CPU0_PE1_PCH_RXN(14)
DW14 P3E_CPU0_PE1_PCH_RXN<13> PE1_RX_DN<13> @BASEBOARD_FAB2_LIB.BASEBOARD_FAB2(SCH_1):P3E_CPU0_PE1_PCH_RXN(13)
DV13 P3E_CPU0_PE1_PCH_RXN<12> PE1_RX_DN<12> @BASEBOARD_FAB2_LIB.BASEBOARD_FAB2(SCH_1):P3E_CPU0_PE1_PCH_RXN(12)
DT13 P3E_CPU0_PE1_PCH_RXN<11> PE1_RX_DN<11> @BASEBOARD_FAB2_LIB.BASEBOARD_FAB2(SCH_1):P3E_CPU0_PE1_PCH_RXN(11)
DT11 P3E_CPU0_PE1_PCH_RXN<10> PE1_RX_DN<10> @BASEBOARD_FAB2_LIB.BASEBOARD_FAB2(SCH_1):P3E_CPU0_PE1_PCH_RXN(10)
DP11 P3E_CPU0_PE1_PCH_RXN<9> PE1_RX_DN<9> @BASEBOARD_FAB2_LIB.BASEBOARD_FAB2(SCH_1):P3E_CPU0_PE1_PCH_RXN(9)
DM11 P3E_CPU0_PE1_PCH_RXN<8> PE1_RX_DN<8> @BASEBOARD_FAB2_LIB.BASEBOARD_FAB2(SCH_1):P3E_CPU0_PE1_PCH_RXN(8)
 DM9 P3E_CPU0_PE1_SS_RXN<7> PE1_RX_DN<7> @BASEBOARD_FAB2_LIB.BASEBOARD_FAB2(SCH_1):P3E_CPU0_PE1_SS_RXN(7)
 DK9 P3E_CPU0_PE1_SS_RXN<6> PE1_RX_DN<6> @BASEBOARD_FAB2_LIB.BASEBOARD_FAB2(SCH_1):P3E_CPU0_PE1_SS_RXN(6)
 DH9 P3E_CPU0_PE1_SS_RXN<5> PE1_RX_DN<5> @BASEBOARD_FAB2_LIB.BASEBOARD_FAB2(SCH_1):P3E_CPU0_PE1_SS_RXN(5)
DE10 P3E_CPU0_PE1_SS_RXN<4> PE1_RX_DN<4> @BASEBOARD_FAB2_LIB.BASEBOARD_FAB2(SCH_1):P3E_CPU0_PE1_SS_RXN(4)
DC10 P3E_CPU0_PE1_SS_RXN<3> PE1_RX_DN<3> @BASEBOARD_FAB2_LIB.BASEBOARD_FAB2(SCH_1):P3E_CPU0_PE1_SS_RXN(3)
 DC8 P3E_CPU0_PE1_SS_RXN<2> PE1_RX_DN<2> @BASEBOARD_FAB2_LIB.BASEBOARD_FAB2(SCH_1):P3E_CPU0_PE1_SS_RXN(2)
 DA8 P3E_CPU0_PE1_SS_RXN<1> PE1_RX_DN<1> @BASEBOARD_FAB2_LIB.BASEBOARD_FAB2(SCH_1):P3E_CPU0_PE1_SS_RXN(1)
 CW8 P3E_CPU0_PE1_SS_RXN<0> PE1_RX_DN<0> @BASEBOARD_FAB2_LIB.BASEBOARD_FAB2(SCH_1):P3E_CPU0_PE1_SS_RXN(0)
DT15 P3E_CPU0_PE1_PCH_RXP<15> PE1_RX_DP<15> @BASEBOARD_FAB2_LIB.BASEBOARD_FAB2(SCH_1):P3E_CPU0_PE1_PCH_RXP(15)
DV15 P3E_CPU0_PE1_PCH_RXP<14> PE1_RX_DP<14> @BASEBOARD_FAB2_LIB.BASEBOARD_FAB2(SCH_1):P3E_CPU0_PE1_PCH_RXP(14)
DY13 P3E_CPU0_PE1_PCH_RXP<13> PE1_RX_DP<13> @BASEBOARD_FAB2_LIB.BASEBOARD_FAB2(SCH_1):P3E_CPU0_PE1_PCH_RXP(13)
DU12 P3E_CPU0_PE1_PCH_RXP<12> PE1_RX_DP<12> @BASEBOARD_FAB2_LIB.BASEBOARD_FAB2(SCH_1):P3E_CPU0_PE1_PCH_RXP(12)
DP13 P3E_CPU0_PE1_PCH_RXP<11> PE1_RX_DP<11> @BASEBOARD_FAB2_LIB.BASEBOARD_FAB2(SCH_1):P3E_CPU0_PE1_PCH_RXP(11)
DR12 P3E_CPU0_PE1_PCH_RXP<10> PE1_RX_DP<10> @BASEBOARD_FAB2_LIB.BASEBOARD_FAB2(SCH_1):P3E_CPU0_PE1_PCH_RXP(10)
DN10 P3E_CPU0_PE1_PCH_RXP<9> PE1_RX_DP<9> @BASEBOARD_FAB2_LIB.BASEBOARD_FAB2(SCH_1):P3E_CPU0_PE1_PCH_RXP(9)
DK11 P3E_CPU0_PE1_PCH_RXP<8> PE1_RX_DP<8> @BASEBOARD_FAB2_LIB.BASEBOARD_FAB2(SCH_1):P3E_CPU0_PE1_PCH_RXP(8)
DL10 P3E_CPU0_PE1_SS_RXP<7> PE1_RX_DP<7> @BASEBOARD_FAB2_LIB.BASEBOARD_FAB2(SCH_1):P3E_CPU0_PE1_SS_RXP(7)
 DJ8 P3E_CPU0_PE1_SS_RXP<6> PE1_RX_DP<6> @BASEBOARD_FAB2_LIB.BASEBOARD_FAB2(SCH_1):P3E_CPU0_PE1_SS_RXP(6)
 DF9 P3E_CPU0_PE1_SS_RXP<5> PE1_RX_DP<5> @BASEBOARD_FAB2_LIB.BASEBOARD_FAB2(SCH_1):P3E_CPU0_PE1_SS_RXP(5)
 DD9 P3E_CPU0_PE1_SS_RXP<4> PE1_RX_DP<4> @BASEBOARD_FAB2_LIB.BASEBOARD_FAB2(SCH_1):P3E_CPU0_PE1_SS_RXP(4)
DA10 P3E_CPU0_PE1_SS_RXP<3> PE1_RX_DP<3> @BASEBOARD_FAB2_LIB.BASEBOARD_FAB2(SCH_1):P3E_CPU0_PE1_SS_RXP(3)
 DB9 P3E_CPU0_PE1_SS_RXP<2> PE1_RX_DP<2> @BASEBOARD_FAB2_LIB.BASEBOARD_FAB2(SCH_1):P3E_CPU0_PE1_SS_RXP(2)
 CY7 P3E_CPU0_PE1_SS_RXP<1> PE1_RX_DP<1> @BASEBOARD_FAB2_LIB.BASEBOARD_FAB2(SCH_1):P3E_CPU0_PE1_SS_RXP(1)
 CU8 P3E_CPU0_PE1_SS_RXP<0> PE1_RX_DP<0> @BASEBOARD_FAB2_LIB.BASEBOARD_FAB2(SCH_1):P3E_CPU0_PE1_SS_RXP(0)
 ED9 P3E_CPU0_PE1_PCH_TXN<15> PE1_TX_DN<15> @BASEBOARD_FAB2_LIB.BASEBOARD_FAB2(SCH_1):P3E_CPU0_PE1_PCH_TXN(15)
 EA8 P3E_CPU0_PE1_PCH_TXN<14> PE1_TX_DN<14> @BASEBOARD_FAB2_LIB.BASEBOARD_FAB2(SCH_1):P3E_CPU0_PE1_PCH_TXN(14)
 DY7 P3E_CPU0_PE1_PCH_TXN<13> PE1_TX_DN<13> @BASEBOARD_FAB2_LIB.BASEBOARD_FAB2(SCH_1):P3E_CPU0_PE1_PCH_TXN(13)
 DV7 P3E_CPU0_PE1_PCH_TXN<12> PE1_TX_DN<12> @BASEBOARD_FAB2_LIB.BASEBOARD_FAB2(SCH_1):P3E_CPU0_PE1_PCH_TXN(12)
 DU6 P3E_CPU0_PE1_PCH_TXN<11> PE1_TX_DN<11> @BASEBOARD_FAB2_LIB.BASEBOARD_FAB2(SCH_1):P3E_CPU0_PE1_PCH_TXN(11)
 DW4 P3E_CPU0_PE1_PCH_TXN<10> PE1_TX_DN<10> @BASEBOARD_FAB2_LIB.BASEBOARD_FAB2(SCH_1):P3E_CPU0_PE1_PCH_TXN(10)
 DV3 P3E_CPU0_PE1_PCH_TXN<9> PE1_TX_DN<9> @BASEBOARD_FAB2_LIB.BASEBOARD_FAB2(SCH_1):P3E_CPU0_PE1_PCH_TXN(9)
 DT5 P3E_CPU0_PE1_PCH_TXN<8> PE1_TX_DN<8> @BASEBOARD_FAB2_LIB.BASEBOARD_FAB2(SCH_1):P3E_CPU0_PE1_PCH_TXN(8)
 DN4 P3E_CPU0_PE1_SS_TXN<7> PE1_TX_DN<7> @BASEBOARD_FAB2_LIB.BASEBOARD_FAB2(SCH_1):P3E_CPU0_PE1_SS_TXN(7)
 DM3 P3E_CPU0_PE1_SS_TXN<6> PE1_TX_DN<6> @BASEBOARD_FAB2_LIB.BASEBOARD_FAB2(SCH_1):P3E_CPU0_PE1_SS_TXN(6)
 DK3 P3E_CPU0_PE1_SS_TXN<5> PE1_TX_DN<5> @BASEBOARD_FAB2_LIB.BASEBOARD_FAB2(SCH_1):P3E_CPU0_PE1_SS_TXN(5)
 DG4 P3E_CPU0_PE1_SS_TXN<4> PE1_TX_DN<4> @BASEBOARD_FAB2_LIB.BASEBOARD_FAB2(SCH_1):P3E_CPU0_PE1_SS_TXN(4)
 DE4 P3E_CPU0_PE1_SS_TXN<3> PE1_TX_DN<3> @BASEBOARD_FAB2_LIB.BASEBOARD_FAB2(SCH_1):P3E_CPU0_PE1_SS_TXN(3)
 DE2 P3E_CPU0_PE1_SS_TXN<2> PE1_TX_DN<2> @BASEBOARD_FAB2_LIB.BASEBOARD_FAB2(SCH_1):P3E_CPU0_PE1_SS_TXN(2)
 DC2 P3E_CPU0_PE1_SS_TXN<1> PE1_TX_DN<1> @BASEBOARD_FAB2_LIB.BASEBOARD_FAB2(SCH_1):P3E_CPU0_PE1_SS_TXN(1)
 DA2 P3E_CPU0_PE1_SS_TXN<0> PE1_TX_DN<0> @BASEBOARD_FAB2_LIB.BASEBOARD_FAB2(SCH_1):P3E_CPU0_PE1_SS_TXN(0)
 EC8 P3E_CPU0_PE1_PCH_TXP<15> PE1_TX_DP<15> @BASEBOARD_FAB2_LIB.BASEBOARD_FAB2(SCH_1):P3E_CPU0_PE1_PCH_TXP(15)
 EB7 P3E_CPU0_PE1_PCH_TXP<14> PE1_TX_DP<14> @BASEBOARD_FAB2_LIB.BASEBOARD_FAB2(SCH_1):P3E_CPU0_PE1_PCH_TXP(14)
 DW6 P3E_CPU0_PE1_PCH_TXP<13> PE1_TX_DP<13> @BASEBOARD_FAB2_LIB.BASEBOARD_FAB2(SCH_1):P3E_CPU0_PE1_PCH_TXP(13)
 DT7 P3E_CPU0_PE1_PCH_TXP<12> PE1_TX_DP<12> @BASEBOARD_FAB2_LIB.BASEBOARD_FAB2(SCH_1):P3E_CPU0_PE1_PCH_TXP(12)
 DV5 P3E_CPU0_PE1_PCH_TXP<11> PE1_TX_DP<11> @BASEBOARD_FAB2_LIB.BASEBOARD_FAB2(SCH_1):P3E_CPU0_PE1_PCH_TXP(11)
 DU4 P3E_CPU0_PE1_PCH_TXP<10> PE1_TX_DP<10> @BASEBOARD_FAB2_LIB.BASEBOARD_FAB2(SCH_1):P3E_CPU0_PE1_PCH_TXP(10)
 DU2 P3E_CPU0_PE1_PCH_TXP<9> PE1_TX_DP<9> @BASEBOARD_FAB2_LIB.BASEBOARD_FAB2(SCH_1):P3E_CPU0_PE1_PCH_TXP(9)
 DR4 P3E_CPU0_PE1_PCH_TXP<8> PE1_TX_DP<8> @BASEBOARD_FAB2_LIB.BASEBOARD_FAB2(SCH_1):P3E_CPU0_PE1_PCH_TXP(8)
 DP3 P3E_CPU0_PE1_SS_TXP<7> PE1_TX_DP<7> @BASEBOARD_FAB2_LIB.BASEBOARD_FAB2(SCH_1):P3E_CPU0_PE1_SS_TXP(7)
 DL2 P3E_CPU0_PE1_SS_TXP<6> PE1_TX_DP<6> @BASEBOARD_FAB2_LIB.BASEBOARD_FAB2(SCH_1):P3E_CPU0_PE1_SS_TXP(6)
 DH3 P3E_CPU0_PE1_SS_TXP<5> PE1_TX_DP<5> @BASEBOARD_FAB2_LIB.BASEBOARD_FAB2(SCH_1):P3E_CPU0_PE1_SS_TXP(5)
 DF3 P3E_CPU0_PE1_SS_TXP<4> PE1_TX_DP<4> @BASEBOARD_FAB2_LIB.BASEBOARD_FAB2(SCH_1):P3E_CPU0_PE1_SS_TXP(4)
 DC4 P3E_CPU0_PE1_SS_TXP<3> PE1_TX_DP<3> @BASEBOARD_FAB2_LIB.BASEBOARD_FAB2(SCH_1):P3E_CPU0_PE1_SS_TXP(3)
 DD3 P3E_CPU0_PE1_SS_TXP<2> PE1_TX_DP<2> @BASEBOARD_FAB2_LIB.BASEBOARD_FAB2(SCH_1):P3E_CPU0_PE1_SS_TXP(2)
 DB1 P3E_CPU0_PE1_SS_TXP<1> PE1_TX_DP<1> @BASEBOARD_FAB2_LIB.BASEBOARD_FAB2(SCH_1):P3E_CPU0_PE1_SS_TXP(1)
 CW2 P3E_CPU0_PE1_SS_TXP<0> PE1_TX_DP<0> @BASEBOARD_FAB2_LIB.BASEBOARD_FAB2(SCH_1):P3E_CPU0_PE1_SS_TXP(0)


DRAWING: @BASEBOARD_FAB2_LIB.BASEBOARD_FAB2(SCH_1):PAGE31 

SKX_EXT_B_BGA1-IC,TBD  I106  U5D1
 BK9 P3E_CPU0_PE2_SS_RXN<15> PE2_RX_DN<15> @BASEBOARD_FAB2_LIB.BASEBOARD_FAB2(SCH_1):P3E_CPU0_PE2_SS_RXN(15)
 BL8 P3E_CPU0_PE2_SS_RXN<14> PE2_RX_DN<14> @BASEBOARD_FAB2_LIB.BASEBOARD_FAB2(SCH_1):P3E_CPU0_PE2_SS_RXN(14)
 BN8 P3E_CPU0_PE2_SS_RXN<13> PE2_RX_DN<13> @BASEBOARD_FAB2_LIB.BASEBOARD_FAB2(SCH_1):P3E_CPU0_PE2_SS_RXN(13)
 BR8 P3E_CPU0_PE2_SS_RXN<12> PE2_RX_DN<12> @BASEBOARD_FAB2_LIB.BASEBOARD_FAB2(SCH_1):P3E_CPU0_PE2_SS_RXN(12)
 BT7 P3E_CPU0_PE2_SS_RXN<11> PE2_RX_DN<11> @BASEBOARD_FAB2_LIB.BASEBOARD_FAB2(SCH_1):P3E_CPU0_PE2_SS_RXN(11)
 BV7 P3E_CPU0_PE2_SS_RXN<10> PE2_RX_DN<10> @BASEBOARD_FAB2_LIB.BASEBOARD_FAB2(SCH_1):P3E_CPU0_PE2_SS_RXN(10)
 BY7 P3E_CPU0_PE2_SS_RXN<9> PE2_RX_DN<9> @BASEBOARD_FAB2_LIB.BASEBOARD_FAB2(SCH_1):P3E_CPU0_PE2_SS_RXN(9)
 BY9 P3E_CPU0_PE2_SS_RXN<8> PE2_RX_DN<8> @BASEBOARD_FAB2_LIB.BASEBOARD_FAB2(SCH_1):P3E_CPU0_PE2_SS_RXN(8)
 CE8 P3E_CPU0_PE2_SS_RXN<7> PE2_RX_DN<7> @BASEBOARD_FAB2_LIB.BASEBOARD_FAB2(SCH_1):P3E_CPU0_PE2_SS_RXN(7)
 CE6 P3E_CPU0_PE2_SS_RXN<6> PE2_RX_DN<6> @BASEBOARD_FAB2_LIB.BASEBOARD_FAB2(SCH_1):P3E_CPU0_PE2_SS_RXN(6)
 CG8 P3E_CPU0_PE2_SS_RXN<5> PE2_RX_DN<5> @BASEBOARD_FAB2_LIB.BASEBOARD_FAB2(SCH_1):P3E_CPU0_PE2_SS_RXN(5)
 CK7 P3E_CPU0_PE2_SS_RXN<4> PE2_RX_DN<4> @BASEBOARD_FAB2_LIB.BASEBOARD_FAB2(SCH_1):P3E_CPU0_PE2_SS_RXN(4)
 CM7 P3E_CPU0_PE2_SS_RXN<3> PE2_RX_DN<3> @BASEBOARD_FAB2_LIB.BASEBOARD_FAB2(SCH_1):P3E_CPU0_PE2_SS_RXN(3)
 CP7 P3E_CPU0_PE2_SS_RXN<2> PE2_RX_DN<2> @BASEBOARD_FAB2_LIB.BASEBOARD_FAB2(SCH_1):P3E_CPU0_PE2_SS_RXN(2)
 CP9 P3E_CPU0_PE2_SS_RXN<1> PE2_RX_DN<1> @BASEBOARD_FAB2_LIB.BASEBOARD_FAB2(SCH_1):P3E_CPU0_PE2_SS_RXN(1)
 CT9 P3E_CPU0_PE2_SS_RXN<0> PE2_RX_DN<0> @BASEBOARD_FAB2_LIB.BASEBOARD_FAB2(SCH_1):P3E_CPU0_PE2_SS_RXN(0)
BJ10 P3E_CPU0_PE2_SS_RXP<15> PE2_RX_DP<15> @BASEBOARD_FAB2_LIB.BASEBOARD_FAB2(SCH_1):P3E_CPU0_PE2_SS_RXP(15)
 BJ8 P3E_CPU0_PE2_SS_RXP<14> PE2_RX_DP<14> @BASEBOARD_FAB2_LIB.BASEBOARD_FAB2(SCH_1):P3E_CPU0_PE2_SS_RXP(14)
 BM7 P3E_CPU0_PE2_SS_RXP<13> PE2_RX_DP<13> @BASEBOARD_FAB2_LIB.BASEBOARD_FAB2(SCH_1):P3E_CPU0_PE2_SS_RXP(13)
 BP9 P3E_CPU0_PE2_SS_RXP<12> PE2_RX_DP<12> @BASEBOARD_FAB2_LIB.BASEBOARD_FAB2(SCH_1):P3E_CPU0_PE2_SS_RXP(12)
 BP7 P3E_CPU0_PE2_SS_RXP<11> PE2_RX_DP<11> @BASEBOARD_FAB2_LIB.BASEBOARD_FAB2(SCH_1):P3E_CPU0_PE2_SS_RXP(11)
 BU6 P3E_CPU0_PE2_SS_RXP<10> PE2_RX_DP<10> @BASEBOARD_FAB2_LIB.BASEBOARD_FAB2(SCH_1):P3E_CPU0_PE2_SS_RXP(10)
 BW8 P3E_CPU0_PE2_SS_RXP<9> PE2_RX_DP<9> @BASEBOARD_FAB2_LIB.BASEBOARD_FAB2(SCH_1):P3E_CPU0_PE2_SS_RXP(9)
 BV9 P3E_CPU0_PE2_SS_RXP<8> PE2_RX_DP<8> @BASEBOARD_FAB2_LIB.BASEBOARD_FAB2(SCH_1):P3E_CPU0_PE2_SS_RXP(8)
 CC8 P3E_CPU0_PE2_SS_RXP<7> PE2_RX_DP<7> @BASEBOARD_FAB2_LIB.BASEBOARD_FAB2(SCH_1):P3E_CPU0_PE2_SS_RXP(7)
 CD7 P3E_CPU0_PE2_SS_RXP<6> PE2_RX_DP<6> @BASEBOARD_FAB2_LIB.BASEBOARD_FAB2(SCH_1):P3E_CPU0_PE2_SS_RXP(6)
 CF7 P3E_CPU0_PE2_SS_RXP<5> PE2_RX_DP<5> @BASEBOARD_FAB2_LIB.BASEBOARD_FAB2(SCH_1):P3E_CPU0_PE2_SS_RXP(5)
 CH7 P3E_CPU0_PE2_SS_RXP<4> PE2_RX_DP<4> @BASEBOARD_FAB2_LIB.BASEBOARD_FAB2(SCH_1):P3E_CPU0_PE2_SS_RXP(4)
 CL6 P3E_CPU0_PE2_SS_RXP<3> PE2_RX_DP<3> @BASEBOARD_FAB2_LIB.BASEBOARD_FAB2(SCH_1):P3E_CPU0_PE2_SS_RXP(3)
 CN8 P3E_CPU0_PE2_SS_RXP<2> PE2_RX_DP<2> @BASEBOARD_FAB2_LIB.BASEBOARD_FAB2(SCH_1):P3E_CPU0_PE2_SS_RXP(2)
 CM9 P3E_CPU0_PE2_SS_RXP<1> PE2_RX_DP<1> @BASEBOARD_FAB2_LIB.BASEBOARD_FAB2(SCH_1):P3E_CPU0_PE2_SS_RXP(1)
 CR8 P3E_CPU0_PE2_SS_RXP<0> PE2_RX_DP<0> @BASEBOARD_FAB2_LIB.BASEBOARD_FAB2(SCH_1):P3E_CPU0_PE2_SS_RXP(0)
 BM5 P3E_CPU0_PE2_SS_TXN<15> PE2_TX_DN<15> @BASEBOARD_FAB2_LIB.BASEBOARD_FAB2(SCH_1):P3E_CPU0_PE2_SS_TXN(15)
 BL4 P3E_CPU0_PE2_SS_TXN<14> PE2_TX_DN<14> @BASEBOARD_FAB2_LIB.BASEBOARD_FAB2(SCH_1):P3E_CPU0_PE2_SS_TXN(14)
 BP5 P3E_CPU0_PE2_SS_TXN<13> PE2_TX_DN<13> @BASEBOARD_FAB2_LIB.BASEBOARD_FAB2(SCH_1):P3E_CPU0_PE2_SS_TXN(13)
 BU4 P3E_CPU0_PE2_SS_TXN<12> PE2_TX_DN<12> @BASEBOARD_FAB2_LIB.BASEBOARD_FAB2(SCH_1):P3E_CPU0_PE2_SS_TXN(12)
 BW4 P3E_CPU0_PE2_SS_TXN<11> PE2_TX_DN<11> @BASEBOARD_FAB2_LIB.BASEBOARD_FAB2(SCH_1):P3E_CPU0_PE2_SS_TXN(11)
 CA4 P3E_CPU0_PE2_SS_TXN<10> PE2_TX_DN<10> @BASEBOARD_FAB2_LIB.BASEBOARD_FAB2(SCH_1):P3E_CPU0_PE2_SS_TXN(10)
 CB3 P3E_CPU0_PE2_SS_TXN<9> PE2_TX_DN<9> @BASEBOARD_FAB2_LIB.BASEBOARD_FAB2(SCH_1):P3E_CPU0_PE2_SS_TXN(9)
 CC2 P3E_CPU0_PE2_SS_TXN<8> PE2_TX_DN<8> @BASEBOARD_FAB2_LIB.BASEBOARD_FAB2(SCH_1):P3E_CPU0_PE2_SS_TXN(8)
 CF3 P3E_CPU0_PE2_SS_TXN<7> PE2_TX_DN<7> @BASEBOARD_FAB2_LIB.BASEBOARD_FAB2(SCH_1):P3E_CPU0_PE2_SS_TXN(7)
 CG2 P3E_CPU0_PE2_SS_TXN<6> PE2_TX_DN<6> @BASEBOARD_FAB2_LIB.BASEBOARD_FAB2(SCH_1):P3E_CPU0_PE2_SS_TXN(6)
 CL2 P3E_CPU0_PE2_SS_TXN<5> PE2_TX_DN<5> @BASEBOARD_FAB2_LIB.BASEBOARD_FAB2(SCH_1):P3E_CPU0_PE2_SS_TXN(5)
 CM1 P3E_CPU0_PE2_SS_TXN<4> PE2_TX_DN<4> @BASEBOARD_FAB2_LIB.BASEBOARD_FAB2(SCH_1):P3E_CPU0_PE2_SS_TXN(4)
 CT3 P3E_CPU0_PE2_SS_TXN<3> PE2_TX_DN<3> @BASEBOARD_FAB2_LIB.BASEBOARD_FAB2(SCH_1):P3E_CPU0_PE2_SS_TXN(3)
 CT1 P3E_CPU0_PE2_SS_TXN<2> PE2_TX_DN<2> @BASEBOARD_FAB2_LIB.BASEBOARD_FAB2(SCH_1):P3E_CPU0_PE2_SS_TXN(2)
 CV3 P3E_CPU0_PE2_SS_TXN<1> PE2_TX_DN<1> @BASEBOARD_FAB2_LIB.BASEBOARD_FAB2(SCH_1):P3E_CPU0_PE2_SS_TXN(1)
 CY3 P3E_CPU0_PE2_SS_TXN<0> PE2_TX_DN<0> @BASEBOARD_FAB2_LIB.BASEBOARD_FAB2(SCH_1):P3E_CPU0_PE2_SS_TXN(0)
 BK5 P3E_CPU0_PE2_SS_TXP<15> PE2_TX_DP<15> @BASEBOARD_FAB2_LIB.BASEBOARD_FAB2(SCH_1):P3E_CPU0_PE2_SS_TXP(15)
 BM3 P3E_CPU0_PE2_SS_TXP<14> PE2_TX_DP<14> @BASEBOARD_FAB2_LIB.BASEBOARD_FAB2(SCH_1):P3E_CPU0_PE2_SS_TXP(14)
 BN4 P3E_CPU0_PE2_SS_TXP<13> PE2_TX_DP<13> @BASEBOARD_FAB2_LIB.BASEBOARD_FAB2(SCH_1):P3E_CPU0_PE2_SS_TXP(13)
 BR4 P3E_CPU0_PE2_SS_TXP<12> PE2_TX_DP<12> @BASEBOARD_FAB2_LIB.BASEBOARD_FAB2(SCH_1):P3E_CPU0_PE2_SS_TXP(12)
 BV3 P3E_CPU0_PE2_SS_TXP<11> PE2_TX_DP<11> @BASEBOARD_FAB2_LIB.BASEBOARD_FAB2(SCH_1):P3E_CPU0_PE2_SS_TXP(11)
 BY5 P3E_CPU0_PE2_SS_TXP<10> PE2_TX_DP<10> @BASEBOARD_FAB2_LIB.BASEBOARD_FAB2(SCH_1):P3E_CPU0_PE2_SS_TXP(10)
 BY3 P3E_CPU0_PE2_SS_TXP<9> PE2_TX_DP<9> @BASEBOARD_FAB2_LIB.BASEBOARD_FAB2(SCH_1):P3E_CPU0_PE2_SS_TXP(9)
 CD3 P3E_CPU0_PE2_SS_TXP<8> PE2_TX_DP<8> @BASEBOARD_FAB2_LIB.BASEBOARD_FAB2(SCH_1):P3E_CPU0_PE2_SS_TXP(8)
 CE4 P3E_CPU0_PE2_SS_TXP<7> PE2_TX_DP<7> @BASEBOARD_FAB2_LIB.BASEBOARD_FAB2(SCH_1):P3E_CPU0_PE2_SS_TXP(7)
 CE2 P3E_CPU0_PE2_SS_TXP<6> PE2_TX_DP<6> @BASEBOARD_FAB2_LIB.BASEBOARD_FAB2(SCH_1):P3E_CPU0_PE2_SS_TXP(6)
 CK3 P3E_CPU0_PE2_SS_TXP<5> PE2_TX_DP<5> @BASEBOARD_FAB2_LIB.BASEBOARD_FAB2(SCH_1):P3E_CPU0_PE2_SS_TXP(5)
 CK1 P3E_CPU0_PE2_SS_TXP<4> PE2_TX_DP<4> @BASEBOARD_FAB2_LIB.BASEBOARD_FAB2(SCH_1):P3E_CPU0_PE2_SS_TXP(4)
 CP3 P3E_CPU0_PE2_SS_TXP<3> PE2_TX_DP<3> @BASEBOARD_FAB2_LIB.BASEBOARD_FAB2(SCH_1):P3E_CPU0_PE2_SS_TXP(3)
 CR2 P3E_CPU0_PE2_SS_TXP<2> PE2_TX_DP<2> @BASEBOARD_FAB2_LIB.BASEBOARD_FAB2(SCH_1):P3E_CPU0_PE2_SS_TXP(2)
 CU2 P3E_CPU0_PE2_SS_TXP<1> PE2_TX_DP<1> @BASEBOARD_FAB2_LIB.BASEBOARD_FAB2(SCH_1):P3E_CPU0_PE2_SS_TXP(1)
 CW4 P3E_CPU0_PE2_SS_TXP<0> PE2_TX_DP<0> @BASEBOARD_FAB2_LIB.BASEBOARD_FAB2(SCH_1):P3E_CPU0_PE2_SS_TXP(0)


DRAWING: @BASEBOARD_FAB2_LIB.BASEBOARD_FAB2(SCH_1):PAGE32 

SKX_EXT_B_BGA1-IC,TBD  I89  U5D1
 CV9 P3E_CPU0_PE3_OCP_RXN<15> PE3_RX_DN<15> @BASEBOARD_FAB2_LIB.BASEBOARD_FAB2(SCH_1):P3E_CPU0_PE3_OCP_RXN(15)
CY11 P3E_CPU0_PE3_OCP_RXN<14> PE3_RX_DN<14> @BASEBOARD_FAB2_LIB.BASEBOARD_FAB2(SCH_1):P3E_CPU0_PE3_OCP_RXN(14)
DB11 P3E_CPU0_PE3_OCP_RXN<13> PE3_RX_DN<13> @BASEBOARD_FAB2_LIB.BASEBOARD_FAB2(SCH_1):P3E_CPU0_PE3_OCP_RXN(13)
DD13 P3E_CPU0_PE3_OCP_RXN<12> PE3_RX_DN<12> @BASEBOARD_FAB2_LIB.BASEBOARD_FAB2(SCH_1):P3E_CPU0_PE3_OCP_RXN(12)
DG10 P3E_CPU0_PE3_OCP_RXN<11> PE3_RX_DN<11> @BASEBOARD_FAB2_LIB.BASEBOARD_FAB2(SCH_1):P3E_CPU0_PE3_OCP_RXN(11)
DG12 P3E_CPU0_PE3_OCP_RXN<10> PE3_RX_DN<10> @BASEBOARD_FAB2_LIB.BASEBOARD_FAB2(SCH_1):P3E_CPU0_PE3_OCP_RXN(10)
DJ12 P3E_CPU0_PE3_OCP_RXN<9> PE3_RX_DN<9> @BASEBOARD_FAB2_LIB.BASEBOARD_FAB2(SCH_1):P3E_CPU0_PE3_OCP_RXN(9)
DL12 P3E_CPU0_PE3_OCP_RXN<8> PE3_RX_DN<8> @BASEBOARD_FAB2_LIB.BASEBOARD_FAB2(SCH_1):P3E_CPU0_PE3_OCP_RXN(8)
DL14 P3E_CPU0_PE3_OCP_RXN<7> PE3_RX_DN<7> @BASEBOARD_FAB2_LIB.BASEBOARD_FAB2(SCH_1):P3E_CPU0_PE3_OCP_RXN(7)
DN14 P3E_CPU0_PE3_OCP_RXN<6> PE3_RX_DN<6> @BASEBOARD_FAB2_LIB.BASEBOARD_FAB2(SCH_1):P3E_CPU0_PE3_OCP_RXN(6)
DR14 P3E_CPU0_PE3_OCP_RXN<5> PE3_RX_DN<5> @BASEBOARD_FAB2_LIB.BASEBOARD_FAB2(SCH_1):P3E_CPU0_PE3_OCP_RXN(5)
DR16 P3E_CPU0_PE3_OCP_RXN<4> PE3_RX_DN<4> @BASEBOARD_FAB2_LIB.BASEBOARD_FAB2(SCH_1):P3E_CPU0_PE3_OCP_RXN(4)
DT19 P3E_CPU0_PE3_OCP_RXN<3> PE3_RX_DN<3> @BASEBOARD_FAB2_LIB.BASEBOARD_FAB2(SCH_1):P3E_CPU0_PE3_OCP_RXN(3)
DW16 P3E_CPU0_PE3_OCP_RXN<2> PE3_RX_DN<2> @BASEBOARD_FAB2_LIB.BASEBOARD_FAB2(SCH_1):P3E_CPU0_PE3_OCP_RXN(2)
DW18 P3E_CPU0_PE3_OCP_RXN<1> PE3_RX_DN<1> @BASEBOARD_FAB2_LIB.BASEBOARD_FAB2(SCH_1):P3E_CPU0_PE3_OCP_RXN(1)
EA18 P3E_CPU0_PE3_OCP_RXN<0> PE3_RX_DN<0> @BASEBOARD_FAB2_LIB.BASEBOARD_FAB2(SCH_1):P3E_CPU0_PE3_OCP_RXN(0)
CU10 P3E_CPU0_PE3_OCP_RXP<15> PE3_RX_DP<15> @BASEBOARD_FAB2_LIB.BASEBOARD_FAB2(SCH_1):P3E_CPU0_PE3_OCP_RXP(15)
CW10 P3E_CPU0_PE3_OCP_RXP<14> PE3_RX_DP<14> @BASEBOARD_FAB2_LIB.BASEBOARD_FAB2(SCH_1):P3E_CPU0_PE3_OCP_RXP(14)
DA12 P3E_CPU0_PE3_OCP_RXP<13> PE3_RX_DP<13> @BASEBOARD_FAB2_LIB.BASEBOARD_FAB2(SCH_1):P3E_CPU0_PE3_OCP_RXP(13)
DC12 P3E_CPU0_PE3_OCP_RXP<12> PE3_RX_DP<12> @BASEBOARD_FAB2_LIB.BASEBOARD_FAB2(SCH_1):P3E_CPU0_PE3_OCP_RXP(12)
DF11 P3E_CPU0_PE3_OCP_RXP<11> PE3_RX_DP<11> @BASEBOARD_FAB2_LIB.BASEBOARD_FAB2(SCH_1):P3E_CPU0_PE3_OCP_RXP(11)
DE12 P3E_CPU0_PE3_OCP_RXP<10> PE3_RX_DP<10> @BASEBOARD_FAB2_LIB.BASEBOARD_FAB2(SCH_1):P3E_CPU0_PE3_OCP_RXP(10)
DH11 P3E_CPU0_PE3_OCP_RXP<9> PE3_RX_DP<9> @BASEBOARD_FAB2_LIB.BASEBOARD_FAB2(SCH_1):P3E_CPU0_PE3_OCP_RXP(9)
DK13 P3E_CPU0_PE3_OCP_RXP<8> PE3_RX_DP<8> @BASEBOARD_FAB2_LIB.BASEBOARD_FAB2(SCH_1):P3E_CPU0_PE3_OCP_RXP(8)
DJ14 P3E_CPU0_PE3_OCP_RXP<7> PE3_RX_DP<7> @BASEBOARD_FAB2_LIB.BASEBOARD_FAB2(SCH_1):P3E_CPU0_PE3_OCP_RXP(7)
DM13 P3E_CPU0_PE3_OCP_RXP<6> PE3_RX_DP<6> @BASEBOARD_FAB2_LIB.BASEBOARD_FAB2(SCH_1):P3E_CPU0_PE3_OCP_RXP(6)
DP15 P3E_CPU0_PE3_OCP_RXP<5> PE3_RX_DP<5> @BASEBOARD_FAB2_LIB.BASEBOARD_FAB2(SCH_1):P3E_CPU0_PE3_OCP_RXP(5)
DN16 P3E_CPU0_PE3_OCP_RXP<4> PE3_RX_DP<4> @BASEBOARD_FAB2_LIB.BASEBOARD_FAB2(SCH_1):P3E_CPU0_PE3_OCP_RXP(4)
DR18 P3E_CPU0_PE3_OCP_RXP<3> PE3_RX_DP<3> @BASEBOARD_FAB2_LIB.BASEBOARD_FAB2(SCH_1):P3E_CPU0_PE3_OCP_RXP(3)
DV17 P3E_CPU0_PE3_OCP_RXP<2> PE3_RX_DP<2> @BASEBOARD_FAB2_LIB.BASEBOARD_FAB2(SCH_1):P3E_CPU0_PE3_OCP_RXP(2)
DU18 P3E_CPU0_PE3_OCP_RXP<1> PE3_RX_DP<1> @BASEBOARD_FAB2_LIB.BASEBOARD_FAB2(SCH_1):P3E_CPU0_PE3_OCP_RXP(1)
DY17 P3E_CPU0_PE3_OCP_RXP<0> PE3_RX_DP<0> @BASEBOARD_FAB2_LIB.BASEBOARD_FAB2(SCH_1):P3E_CPU0_PE3_OCP_RXP(0)
 CY5 P3E_CPU0_PE3_OCP_TXN<15> PE3_TX_DN<15> @BASEBOARD_FAB2_LIB.BASEBOARD_FAB2(SCH_1):P3E_CPU0_PE3_OCP_TXN(15)
 DB5 P3E_CPU0_PE3_OCP_TXN<14> PE3_TX_DN<14> @BASEBOARD_FAB2_LIB.BASEBOARD_FAB2(SCH_1):P3E_CPU0_PE3_OCP_TXN(14)
 DD5 P3E_CPU0_PE3_OCP_TXN<13> PE3_TX_DN<13> @BASEBOARD_FAB2_LIB.BASEBOARD_FAB2(SCH_1):P3E_CPU0_PE3_OCP_TXN(13)
 DJ6 P3E_CPU0_PE3_OCP_TXN<12> PE3_TX_DN<12> @BASEBOARD_FAB2_LIB.BASEBOARD_FAB2(SCH_1):P3E_CPU0_PE3_OCP_TXN(12)
 DJ4 P3E_CPU0_PE3_OCP_TXN<11> PE3_TX_DN<11> @BASEBOARD_FAB2_LIB.BASEBOARD_FAB2(SCH_1):P3E_CPU0_PE3_OCP_TXN(11)
 DL6 P3E_CPU0_PE3_OCP_TXN<10> PE3_TX_DN<10> @BASEBOARD_FAB2_LIB.BASEBOARD_FAB2(SCH_1):P3E_CPU0_PE3_OCP_TXN(10)
 DP5 P3E_CPU0_PE3_OCP_TXN<9> PE3_TX_DN<9> @BASEBOARD_FAB2_LIB.BASEBOARD_FAB2(SCH_1):P3E_CPU0_PE3_OCP_TXN(9)
 DM7 P3E_CPU0_PE3_OCP_TXN<8> PE3_TX_DN<8> @BASEBOARD_FAB2_LIB.BASEBOARD_FAB2(SCH_1):P3E_CPU0_PE3_OCP_TXN(8)
 DR8 P3E_CPU0_PE3_OCP_TXN<7> PE3_TX_DN<7> @BASEBOARD_FAB2_LIB.BASEBOARD_FAB2(SCH_1):P3E_CPU0_PE3_OCP_TXN(7)
 DU8 P3E_CPU0_PE3_OCP_TXN<6> PE3_TX_DN<6> @BASEBOARD_FAB2_LIB.BASEBOARD_FAB2(SCH_1):P3E_CPU0_PE3_OCP_TXN(6)
DW10 P3E_CPU0_PE3_OCP_TXN<5> PE3_TX_DN<5> @BASEBOARD_FAB2_LIB.BASEBOARD_FAB2(SCH_1):P3E_CPU0_PE3_OCP_TXN(5)
 EB9 P3E_CPU0_PE3_OCP_TXN<4> PE3_TX_DN<4> @BASEBOARD_FAB2_LIB.BASEBOARD_FAB2(SCH_1):P3E_CPU0_PE3_OCP_TXN(4)
DY11 P3E_CPU0_PE3_OCP_TXN<3> PE3_TX_DN<3> @BASEBOARD_FAB2_LIB.BASEBOARD_FAB2(SCH_1):P3E_CPU0_PE3_OCP_TXN(3)
EC12 P3E_CPU0_PE3_OCP_TXN<2> PE3_TX_DN<2> @BASEBOARD_FAB2_LIB.BASEBOARD_FAB2(SCH_1):P3E_CPU0_PE3_OCP_TXN(2)
EE12 P3E_CPU0_PE3_OCP_TXN<1> PE3_TX_DN<1> @BASEBOARD_FAB2_LIB.BASEBOARD_FAB2(SCH_1):P3E_CPU0_PE3_OCP_TXN(1)
EE14 P3E_CPU0_PE3_OCP_TXN<0> PE3_TX_DN<0> @BASEBOARD_FAB2_LIB.BASEBOARD_FAB2(SCH_1):P3E_CPU0_PE3_OCP_TXN(0)
 CV5 P3E_CPU0_PE3_OCP_TXP<15> PE3_TX_DP<15> @BASEBOARD_FAB2_LIB.BASEBOARD_FAB2(SCH_1):P3E_CPU0_PE3_OCP_TXP(15)
 DA4 P3E_CPU0_PE3_OCP_TXP<14> PE3_TX_DP<14> @BASEBOARD_FAB2_LIB.BASEBOARD_FAB2(SCH_1):P3E_CPU0_PE3_OCP_TXP(14)
 DC6 P3E_CPU0_PE3_OCP_TXP<13> PE3_TX_DP<13> @BASEBOARD_FAB2_LIB.BASEBOARD_FAB2(SCH_1):P3E_CPU0_PE3_OCP_TXP(13)
 DG6 P3E_CPU0_PE3_OCP_TXP<12> PE3_TX_DP<12> @BASEBOARD_FAB2_LIB.BASEBOARD_FAB2(SCH_1):P3E_CPU0_PE3_OCP_TXP(12)
 DH5 P3E_CPU0_PE3_OCP_TXP<11> PE3_TX_DP<11> @BASEBOARD_FAB2_LIB.BASEBOARD_FAB2(SCH_1):P3E_CPU0_PE3_OCP_TXP(11)
 DK5 P3E_CPU0_PE3_OCP_TXP<10> PE3_TX_DP<10> @BASEBOARD_FAB2_LIB.BASEBOARD_FAB2(SCH_1):P3E_CPU0_PE3_OCP_TXP(10)
 DM5 P3E_CPU0_PE3_OCP_TXP<9> PE3_TX_DP<9> @BASEBOARD_FAB2_LIB.BASEBOARD_FAB2(SCH_1):P3E_CPU0_PE3_OCP_TXP(9)
 DN6 P3E_CPU0_PE3_OCP_TXP<8> PE3_TX_DP<8> @BASEBOARD_FAB2_LIB.BASEBOARD_FAB2(SCH_1):P3E_CPU0_PE3_OCP_TXP(8)
 DP7 P3E_CPU0_PE3_OCP_TXP<7> PE3_TX_DP<7> @BASEBOARD_FAB2_LIB.BASEBOARD_FAB2(SCH_1):P3E_CPU0_PE3_OCP_TXP(7)
 DT9 P3E_CPU0_PE3_OCP_TXP<6> PE3_TX_DP<6> @BASEBOARD_FAB2_LIB.BASEBOARD_FAB2(SCH_1):P3E_CPU0_PE3_OCP_TXP(6)
 DV9 P3E_CPU0_PE3_OCP_TXP<5> PE3_TX_DP<5> @BASEBOARD_FAB2_LIB.BASEBOARD_FAB2(SCH_1):P3E_CPU0_PE3_OCP_TXP(5)
 DY9 P3E_CPU0_PE3_OCP_TXP<4> PE3_TX_DP<4> @BASEBOARD_FAB2_LIB.BASEBOARD_FAB2(SCH_1):P3E_CPU0_PE3_OCP_TXP(4)
EA10 P3E_CPU0_PE3_OCP_TXP<3> PE3_TX_DP<3> @BASEBOARD_FAB2_LIB.BASEBOARD_FAB2(SCH_1):P3E_CPU0_PE3_OCP_TXP(3)
EB11 P3E_CPU0_PE3_OCP_TXP<2> PE3_TX_DP<2> @BASEBOARD_FAB2_LIB.BASEBOARD_FAB2(SCH_1):P3E_CPU0_PE3_OCP_TXP(2)
ED13 P3E_CPU0_PE3_OCP_TXP<1> PE3_TX_DP<1> @BASEBOARD_FAB2_LIB.BASEBOARD_FAB2(SCH_1):P3E_CPU0_PE3_OCP_TXP(1)
EC14 P3E_CPU0_PE3_OCP_TXP<0> PE3_TX_DP<0> @BASEBOARD_FAB2_LIB.BASEBOARD_FAB2(SCH_1):P3E_CPU0_PE3_OCP_TXP(0)


DRAWING: @BASEBOARD_FAB2_LIB.BASEBOARD_FAB2(SCH_1):PAGE33 

SKX_EXT_B_BGA1-IC,TBD  I86  U5D1
BB11 UPI_CPU1_CPU0_P0P0_DN<0> UPI0_RX_DN<19> @BASEBOARD_FAB2_LIB.BASEBOARD_FAB2(SCH_1):UPI_CPU1_CPU0_P0P0_DN(0)
 BD9 UPI_CPU1_CPU0_P0P0_DN<1> UPI0_RX_DN<18> @BASEBOARD_FAB2_LIB.BASEBOARD_FAB2(SCH_1):UPI_CPU1_CPU0_P0P0_DN(1)
 AY9 UPI_CPU1_CPU0_P0P0_DN<2> UPI0_RX_DN<17> @BASEBOARD_FAB2_LIB.BASEBOARD_FAB2(SCH_1):UPI_CPU1_CPU0_P0P0_DN(2)
 AW8 UPI_CPU1_CPU0_P0P0_DN<3> UPI0_RX_DN<16> @BASEBOARD_FAB2_LIB.BASEBOARD_FAB2(SCH_1):UPI_CPU1_CPU0_P0P0_DN(3)
 BD7 UPI_CPU1_CPU0_P0P0_DN<4> UPI0_RX_DN<15> @BASEBOARD_FAB2_LIB.BASEBOARD_FAB2(SCH_1):UPI_CPU1_CPU0_P0P0_DN(4)
 BC6 UPI_CPU1_CPU0_P0P0_DN<5> UPI0_RX_DN<14> @BASEBOARD_FAB2_LIB.BASEBOARD_FAB2(SCH_1):UPI_CPU1_CPU0_P0P0_DN(5)
 BA8 UPI_CPU1_CPU0_P0P0_DN<6> UPI0_RX_DN<13> @BASEBOARD_FAB2_LIB.BASEBOARD_FAB2(SCH_1):UPI_CPU1_CPU0_P0P0_DN(6)
AU10 UPI_CPU1_CPU0_P0P0_DN<7> UPI0_RX_DN<12> @BASEBOARD_FAB2_LIB.BASEBOARD_FAB2(SCH_1):UPI_CPU1_CPU0_P0P0_DN(7)
 AR8 UPI_CPU1_CPU0_P0P0_DN<8> UPI0_RX_DN<11> @BASEBOARD_FAB2_LIB.BASEBOARD_FAB2(SCH_1):UPI_CPU1_CPU0_P0P0_DN(8)
 AP7 UPI_CPU1_CPU0_P0P0_DN<9> UPI0_RX_DN<10> @BASEBOARD_FAB2_LIB.BASEBOARD_FAB2(SCH_1):UPI_CPU1_CPU0_P0P0_DN(9)
 AM9 UPI_CPU1_CPU0_P0P0_DN<10> UPI0_RX_DN<9> @BASEBOARD_FAB2_LIB.BASEBOARD_FAB2(SCH_1):UPI_CPU1_CPU0_P0P0_DN(10)
 AK7 UPI_CPU1_CPU0_P0P0_DN<11> UPI0_RX_DN<8> @BASEBOARD_FAB2_LIB.BASEBOARD_FAB2(SCH_1):UPI_CPU1_CPU0_P0P0_DN(11)
 AL6 UPI_CPU1_CPU0_P0P0_DN<12> UPI0_RX_DN<7> @BASEBOARD_FAB2_LIB.BASEBOARD_FAB2(SCH_1):UPI_CPU1_CPU0_P0P0_DN(12)
 AJ6 UPI_CPU1_CPU0_P0P0_DN<13> UPI0_RX_DN<6> @BASEBOARD_FAB2_LIB.BASEBOARD_FAB2(SCH_1):UPI_CPU1_CPU0_P0P0_DN(13)
 AG8 UPI_CPU1_CPU0_P0P0_DN<14> UPI0_RX_DN<5> @BASEBOARD_FAB2_LIB.BASEBOARD_FAB2(SCH_1):UPI_CPU1_CPU0_P0P0_DN(14)
 AE6 UPI_CPU1_CPU0_P0P0_DN<15> UPI0_RX_DN<4> @BASEBOARD_FAB2_LIB.BASEBOARD_FAB2(SCH_1):UPI_CPU1_CPU0_P0P0_DN(15)
 AD5 UPI_CPU1_CPU0_P0P0_DN<16> UPI0_RX_DN<3> @BASEBOARD_FAB2_LIB.BASEBOARD_FAB2(SCH_1):UPI_CPU1_CPU0_P0P0_DN(16)
 AB7 UPI_CPU1_CPU0_P0P0_DN<17> UPI0_RX_DN<2> @BASEBOARD_FAB2_LIB.BASEBOARD_FAB2(SCH_1):UPI_CPU1_CPU0_P0P0_DN(17)
 AA8 UPI_CPU1_CPU0_P0P0_DN<18> UPI0_RX_DN<1> @BASEBOARD_FAB2_LIB.BASEBOARD_FAB2(SCH_1):UPI_CPU1_CPU0_P0P0_DN(18)
AC10 UPI_CPU1_CPU0_P0P0_DN<19> UPI0_RX_DN<0> @BASEBOARD_FAB2_LIB.BASEBOARD_FAB2(SCH_1):UPI_CPU1_CPU0_P0P0_DN(19)
BA10 UPI_CPU1_CPU0_P0P0_DP<0> UPI0_RX_DP<19> @BASEBOARD_FAB2_LIB.BASEBOARD_FAB2(SCH_1):UPI_CPU1_CPU0_P0P0_DP(0)
BC10 UPI_CPU1_CPU0_P0P0_DP<1> UPI0_RX_DP<18> @BASEBOARD_FAB2_LIB.BASEBOARD_FAB2(SCH_1):UPI_CPU1_CPU0_P0P0_DP(1)
 BB9 UPI_CPU1_CPU0_P0P0_DP<2> UPI0_RX_DP<17> @BASEBOARD_FAB2_LIB.BASEBOARD_FAB2(SCH_1):UPI_CPU1_CPU0_P0P0_DP(2)
 AV9 UPI_CPU1_CPU0_P0P0_DP<3> UPI0_RX_DP<16> @BASEBOARD_FAB2_LIB.BASEBOARD_FAB2(SCH_1):UPI_CPU1_CPU0_P0P0_DP(3)
 BF7 UPI_CPU1_CPU0_P0P0_DP<4> UPI0_RX_DP<15> @BASEBOARD_FAB2_LIB.BASEBOARD_FAB2(SCH_1):UPI_CPU1_CPU0_P0P0_DP(4)
 BB7 UPI_CPU1_CPU0_P0P0_DP<5> UPI0_RX_DP<14> @BASEBOARD_FAB2_LIB.BASEBOARD_FAB2(SCH_1):UPI_CPU1_CPU0_P0P0_DP(5)
 AY7 UPI_CPU1_CPU0_P0P0_DP<6> UPI0_RX_DP<13> @BASEBOARD_FAB2_LIB.BASEBOARD_FAB2(SCH_1):UPI_CPU1_CPU0_P0P0_DP(6)
 AT9 UPI_CPU1_CPU0_P0P0_DP<7> UPI0_RX_DP<12> @BASEBOARD_FAB2_LIB.BASEBOARD_FAB2(SCH_1):UPI_CPU1_CPU0_P0P0_DP(7)
 AU8 UPI_CPU1_CPU0_P0P0_DP<8> UPI0_RX_DP<11> @BASEBOARD_FAB2_LIB.BASEBOARD_FAB2(SCH_1):UPI_CPU1_CPU0_P0P0_DP(8)
 AN8 UPI_CPU1_CPU0_P0P0_DP<9> UPI0_RX_DP<10> @BASEBOARD_FAB2_LIB.BASEBOARD_FAB2(SCH_1):UPI_CPU1_CPU0_P0P0_DP(9)
 AL8 UPI_CPU1_CPU0_P0P0_DP<10> UPI0_RX_DP<9> @BASEBOARD_FAB2_LIB.BASEBOARD_FAB2(SCH_1):UPI_CPU1_CPU0_P0P0_DP(10)
 AM7 UPI_CPU1_CPU0_P0P0_DP<11> UPI0_RX_DP<8> @BASEBOARD_FAB2_LIB.BASEBOARD_FAB2(SCH_1):UPI_CPU1_CPU0_P0P0_DP(11)
 AK5 UPI_CPU1_CPU0_P0P0_DP<12> UPI0_RX_DP<7> @BASEBOARD_FAB2_LIB.BASEBOARD_FAB2(SCH_1):UPI_CPU1_CPU0_P0P0_DP(12)
 AH7 UPI_CPU1_CPU0_P0P0_DP<13> UPI0_RX_DP<6> @BASEBOARD_FAB2_LIB.BASEBOARD_FAB2(SCH_1):UPI_CPU1_CPU0_P0P0_DP(13)
 AF7 UPI_CPU1_CPU0_P0P0_DP<14> UPI0_RX_DP<5> @BASEBOARD_FAB2_LIB.BASEBOARD_FAB2(SCH_1):UPI_CPU1_CPU0_P0P0_DP(14)
 AG6 UPI_CPU1_CPU0_P0P0_DP<15> UPI0_RX_DP<4> @BASEBOARD_FAB2_LIB.BASEBOARD_FAB2(SCH_1):UPI_CPU1_CPU0_P0P0_DP(15)
 AC6 UPI_CPU1_CPU0_P0P0_DP<16> UPI0_RX_DP<3> @BASEBOARD_FAB2_LIB.BASEBOARD_FAB2(SCH_1):UPI_CPU1_CPU0_P0P0_DP(16)
 AA6 UPI_CPU1_CPU0_P0P0_DP<17> UPI0_RX_DP<2> @BASEBOARD_FAB2_LIB.BASEBOARD_FAB2(SCH_1):UPI_CPU1_CPU0_P0P0_DP(17)
 AC8 UPI_CPU1_CPU0_P0P0_DP<18> UPI0_RX_DP<1> @BASEBOARD_FAB2_LIB.BASEBOARD_FAB2(SCH_1):UPI_CPU1_CPU0_P0P0_DP(18)
 AB9 UPI_CPU1_CPU0_P0P0_DP<19> UPI0_RX_DP<0> @BASEBOARD_FAB2_LIB.BASEBOARD_FAB2(SCH_1):UPI_CPU1_CPU0_P0P0_DP(19)
 BG4 UPI_CPU0_CPU1_P0P0_DN<0> UPI0_TX_DN<19> @BASEBOARD_FAB2_LIB.BASEBOARD_FAB2(SCH_1):UPI_CPU0_CPU1_P0P0_DN(0)
 BF3 UPI_CPU0_CPU1_P0P0_DN<1> UPI0_TX_DN<18> @BASEBOARD_FAB2_LIB.BASEBOARD_FAB2(SCH_1):UPI_CPU0_CPU1_P0P0_DN(1)
 BB3 UPI_CPU0_CPU1_P0P0_DN<2> UPI0_TX_DN<17> @BASEBOARD_FAB2_LIB.BASEBOARD_FAB2(SCH_1):UPI_CPU0_CPU1_P0P0_DN(2)
 BA4 UPI_CPU0_CPU1_P0P0_DN<3> UPI0_TX_DN<16> @BASEBOARD_FAB2_LIB.BASEBOARD_FAB2(SCH_1):UPI_CPU0_CPU1_P0P0_DN(3)
 AV5 UPI_CPU0_CPU1_P0P0_DN<4> UPI0_TX_DN<15> @BASEBOARD_FAB2_LIB.BASEBOARD_FAB2(SCH_1):UPI_CPU0_CPU1_P0P0_DN(4)
 AU4 UPI_CPU0_CPU1_P0P0_DN<5> UPI0_TX_DN<14> @BASEBOARD_FAB2_LIB.BASEBOARD_FAB2(SCH_1):UPI_CPU0_CPU1_P0P0_DN(5)
 AT3 UPI_CPU0_CPU1_P0P0_DN<6> UPI0_TX_DN<13> @BASEBOARD_FAB2_LIB.BASEBOARD_FAB2(SCH_1):UPI_CPU0_CPU1_P0P0_DN(6)
 AT1 UPI_CPU0_CPU1_P0P0_DN<7> UPI0_TX_DN<12> @BASEBOARD_FAB2_LIB.BASEBOARD_FAB2(SCH_1):UPI_CPU0_CPU1_P0P0_DN(7)
 AN4 UPI_CPU0_CPU1_P0P0_DN<8> UPI0_TX_DN<11> @BASEBOARD_FAB2_LIB.BASEBOARD_FAB2(SCH_1):UPI_CPU0_CPU1_P0P0_DN(8)
 AM3 UPI_CPU0_CPU1_P0P0_DN<9> UPI0_TX_DN<10> @BASEBOARD_FAB2_LIB.BASEBOARD_FAB2(SCH_1):UPI_CPU0_CPU1_P0P0_DN(9)
 AL2 UPI_CPU0_CPU1_P0P0_DN<10> UPI0_TX_DN<9> @BASEBOARD_FAB2_LIB.BASEBOARD_FAB2(SCH_1):UPI_CPU0_CPU1_P0P0_DN(10)
 AH3 UPI_CPU0_CPU1_P0P0_DN<11> UPI0_TX_DN<8> @BASEBOARD_FAB2_LIB.BASEBOARD_FAB2(SCH_1):UPI_CPU0_CPU1_P0P0_DN(11)
 AE2 UPI_CPU0_CPU1_P0P0_DN<12> UPI0_TX_DN<7> @BASEBOARD_FAB2_LIB.BASEBOARD_FAB2(SCH_1):UPI_CPU0_CPU1_P0P0_DN(12)
 AG4 UPI_CPU0_CPU1_P0P0_DN<13> UPI0_TX_DN<6> @BASEBOARD_FAB2_LIB.BASEBOARD_FAB2(SCH_1):UPI_CPU0_CPU1_P0P0_DN(13)
 AC2 UPI_CPU0_CPU1_P0P0_DN<14> UPI0_TX_DN<5> @BASEBOARD_FAB2_LIB.BASEBOARD_FAB2(SCH_1):UPI_CPU0_CPU1_P0P0_DN(14)
 AB3 UPI_CPU0_CPU1_P0P0_DN<15> UPI0_TX_DN<4> @BASEBOARD_FAB2_LIB.BASEBOARD_FAB2(SCH_1):UPI_CPU0_CPU1_P0P0_DN(15)
  Y1 UPI_CPU0_CPU1_P0P0_DN<16> UPI0_TX_DN<3> @BASEBOARD_FAB2_LIB.BASEBOARD_FAB2(SCH_1):UPI_CPU0_CPU1_P0P0_DN(16)
  V3 UPI_CPU0_CPU1_P0P0_DN<17> UPI0_TX_DN<2> @BASEBOARD_FAB2_LIB.BASEBOARD_FAB2(SCH_1):UPI_CPU0_CPU1_P0P0_DN(17)
  P1 UPI_CPU0_CPU1_P0P0_DN<18> UPI0_TX_DN<1> @BASEBOARD_FAB2_LIB.BASEBOARD_FAB2(SCH_1):UPI_CPU0_CPU1_P0P0_DN(18)
  N2 UPI_CPU0_CPU1_P0P0_DN<19> UPI0_TX_DN<0> @BASEBOARD_FAB2_LIB.BASEBOARD_FAB2(SCH_1):UPI_CPU0_CPU1_P0P0_DN(19)
 BH3 UPI_CPU0_CPU1_P0P0_DP<0> UPI0_TX_DP<19> @BASEBOARD_FAB2_LIB.BASEBOARD_FAB2(SCH_1):UPI_CPU0_CPU1_P0P0_DP(0)
 BD3 UPI_CPU0_CPU1_P0P0_DP<1> UPI0_TX_DP<18> @BASEBOARD_FAB2_LIB.BASEBOARD_FAB2(SCH_1):UPI_CPU0_CPU1_P0P0_DP(1)
 BC2 UPI_CPU0_CPU1_P0P0_DP<2> UPI0_TX_DP<17> @BASEBOARD_FAB2_LIB.BASEBOARD_FAB2(SCH_1):UPI_CPU0_CPU1_P0P0_DP(2)
 AY3 UPI_CPU0_CPU1_P0P0_DP<3> UPI0_TX_DP<16> @BASEBOARD_FAB2_LIB.BASEBOARD_FAB2(SCH_1):UPI_CPU0_CPU1_P0P0_DP(3)
 AW4 UPI_CPU0_CPU1_P0P0_DP<4> UPI0_TX_DP<15> @BASEBOARD_FAB2_LIB.BASEBOARD_FAB2(SCH_1):UPI_CPU0_CPU1_P0P0_DP(4)
 AR4 UPI_CPU0_CPU1_P0P0_DP<5> UPI0_TX_DP<14> @BASEBOARD_FAB2_LIB.BASEBOARD_FAB2(SCH_1):UPI_CPU0_CPU1_P0P0_DP(5)
 AR2 UPI_CPU0_CPU1_P0P0_DP<6> UPI0_TX_DP<13> @BASEBOARD_FAB2_LIB.BASEBOARD_FAB2(SCH_1):UPI_CPU0_CPU1_P0P0_DP(6)
 AP1 UPI_CPU0_CPU1_P0P0_DP<7> UPI0_TX_DP<12> @BASEBOARD_FAB2_LIB.BASEBOARD_FAB2(SCH_1):UPI_CPU0_CPU1_P0P0_DP(7)
 AP3 UPI_CPU0_CPU1_P0P0_DP<8> UPI0_TX_DP<11> @BASEBOARD_FAB2_LIB.BASEBOARD_FAB2(SCH_1):UPI_CPU0_CPU1_P0P0_DP(8)
 AK3 UPI_CPU0_CPU1_P0P0_DP<9> UPI0_TX_DP<10> @BASEBOARD_FAB2_LIB.BASEBOARD_FAB2(SCH_1):UPI_CPU0_CPU1_P0P0_DP(9)
 AK1 UPI_CPU0_CPU1_P0P0_DP<10> UPI0_TX_DP<9> @BASEBOARD_FAB2_LIB.BASEBOARD_FAB2(SCH_1):UPI_CPU0_CPU1_P0P0_DP(10)
 AJ2 UPI_CPU0_CPU1_P0P0_DP<11> UPI0_TX_DP<8> @BASEBOARD_FAB2_LIB.BASEBOARD_FAB2(SCH_1):UPI_CPU0_CPU1_P0P0_DP(11)
 AG2 UPI_CPU0_CPU1_P0P0_DP<12> UPI0_TX_DP<7> @BASEBOARD_FAB2_LIB.BASEBOARD_FAB2(SCH_1):UPI_CPU0_CPU1_P0P0_DP(12)
 AF3 UPI_CPU0_CPU1_P0P0_DP<13> UPI0_TX_DP<6> @BASEBOARD_FAB2_LIB.BASEBOARD_FAB2(SCH_1):UPI_CPU0_CPU1_P0P0_DP(13)
 AD1 UPI_CPU0_CPU1_P0P0_DP<14> UPI0_TX_DP<5> @BASEBOARD_FAB2_LIB.BASEBOARD_FAB2(SCH_1):UPI_CPU0_CPU1_P0P0_DP(14)
 AA2 UPI_CPU0_CPU1_P0P0_DP<15> UPI0_TX_DP<4> @BASEBOARD_FAB2_LIB.BASEBOARD_FAB2(SCH_1):UPI_CPU0_CPU1_P0P0_DP(15)
  W2 UPI_CPU0_CPU1_P0P0_DP<16> UPI0_TX_DP<3> @BASEBOARD_FAB2_LIB.BASEBOARD_FAB2(SCH_1):UPI_CPU0_CPU1_P0P0_DP(16)
  Y3 UPI_CPU0_CPU1_P0P0_DP<17> UPI0_TX_DP<2> @BASEBOARD_FAB2_LIB.BASEBOARD_FAB2(SCH_1):UPI_CPU0_CPU1_P0P0_DP(17)
  T1 UPI_CPU0_CPU1_P0P0_DP<18> UPI0_TX_DP<1> @BASEBOARD_FAB2_LIB.BASEBOARD_FAB2(SCH_1):UPI_CPU0_CPU1_P0P0_DP(18)
  M1 UPI_CPU0_CPU1_P0P0_DP<19> UPI0_TX_DP<0> @BASEBOARD_FAB2_LIB.BASEBOARD_FAB2(SCH_1):UPI_CPU0_CPU1_P0P0_DP(19)


DRAWING: @BASEBOARD_FAB2_LIB.BASEBOARD_FAB2(SCH_1):PAGE34 

SKX_EXT_B_BGA1-IC,TBD  I86  U5D1
AB19 UPI_CPU1_CPU0_P1P1_DN<0> UPI1_RX_DN<19> @BASEBOARD_FAB2_LIB.BASEBOARD_FAB2(SCH_1):UPI_CPU1_CPU0_P1P1_DN(0)
 Y21 UPI_CPU1_CPU0_P1P1_DN<1> UPI1_RX_DN<18> @BASEBOARD_FAB2_LIB.BASEBOARD_FAB2(SCH_1):UPI_CPU1_CPU0_P1P1_DN(1)
 V19 UPI_CPU1_CPU0_P1P1_DN<2> UPI1_RX_DN<17> @BASEBOARD_FAB2_LIB.BASEBOARD_FAB2(SCH_1):UPI_CPU1_CPU0_P1P1_DN(2)
 P21 UPI_CPU1_CPU0_P1P1_DN<3> UPI1_RX_DN<16> @BASEBOARD_FAB2_LIB.BASEBOARD_FAB2(SCH_1):UPI_CPU1_CPU0_P1P1_DN(3)
 U18 UPI_CPU1_CPU0_P1P1_DN<4> UPI1_RX_DN<15> @BASEBOARD_FAB2_LIB.BASEBOARD_FAB2(SCH_1):UPI_CPU1_CPU0_P1P1_DN(4)
 R20 UPI_CPU1_CPU0_P1P1_DN<5> UPI1_RX_DN<14> @BASEBOARD_FAB2_LIB.BASEBOARD_FAB2(SCH_1):UPI_CPU1_CPU0_P1P1_DN(5)
 W18 UPI_CPU1_CPU0_P1P1_DN<6> UPI1_RX_DN<13> @BASEBOARD_FAB2_LIB.BASEBOARD_FAB2(SCH_1):UPI_CPU1_CPU0_P1P1_DN(6)
 U16 UPI_CPU1_CPU0_P1P1_DN<7> UPI1_RX_DN<12> @BASEBOARD_FAB2_LIB.BASEBOARD_FAB2(SCH_1):UPI_CPU1_CPU0_P1P1_DN(7)
 P17 UPI_CPU1_CPU0_P1P1_DN<8> UPI1_RX_DN<11> @BASEBOARD_FAB2_LIB.BASEBOARD_FAB2(SCH_1):UPI_CPU1_CPU0_P1P1_DN(8)
 R16 UPI_CPU1_CPU0_P1P1_DN<9> UPI1_RX_DN<10> @BASEBOARD_FAB2_LIB.BASEBOARD_FAB2(SCH_1):UPI_CPU1_CPU0_P1P1_DN(9)
 R12 UPI_CPU1_CPU0_P1P1_DN<10> UPI1_RX_DN<9> @BASEBOARD_FAB2_LIB.BASEBOARD_FAB2(SCH_1):UPI_CPU1_CPU0_P1P1_DN(10)
 N14 UPI_CPU1_CPU0_P1P1_DN<11> UPI1_RX_DN<8> @BASEBOARD_FAB2_LIB.BASEBOARD_FAB2(SCH_1):UPI_CPU1_CPU0_P1P1_DN(11)
 L12 UPI_CPU1_CPU0_P1P1_DN<12> UPI1_RX_DN<7> @BASEBOARD_FAB2_LIB.BASEBOARD_FAB2(SCH_1):UPI_CPU1_CPU0_P1P1_DN(12)
 U12 UPI_CPU1_CPU0_P1P1_DN<13> UPI1_RX_DN<6> @BASEBOARD_FAB2_LIB.BASEBOARD_FAB2(SCH_1):UPI_CPU1_CPU0_P1P1_DN(13)
 R10 UPI_CPU1_CPU0_P1P1_DN<14> UPI1_RX_DN<5> @BASEBOARD_FAB2_LIB.BASEBOARD_FAB2(SCH_1):UPI_CPU1_CPU0_P1P1_DN(14)
  P9 UPI_CPU1_CPU0_P1P1_DN<15> UPI1_RX_DN<4> @BASEBOARD_FAB2_LIB.BASEBOARD_FAB2(SCH_1):UPI_CPU1_CPU0_P1P1_DN(15)
  T9 UPI_CPU1_CPU0_P1P1_DN<16> UPI1_RX_DN<3> @BASEBOARD_FAB2_LIB.BASEBOARD_FAB2(SCH_1):UPI_CPU1_CPU0_P1P1_DN(16)
  V7 UPI_CPU1_CPU0_P1P1_DN<17> UPI1_RX_DN<2> @BASEBOARD_FAB2_LIB.BASEBOARD_FAB2(SCH_1):UPI_CPU1_CPU0_P1P1_DN(17)
  P7 UPI_CPU1_CPU0_P1P1_DN<18> UPI1_RX_DN<1> @BASEBOARD_FAB2_LIB.BASEBOARD_FAB2(SCH_1):UPI_CPU1_CPU0_P1P1_DN(18)
  T5 UPI_CPU1_CPU0_P1P1_DN<19> UPI1_RX_DN<0> @BASEBOARD_FAB2_LIB.BASEBOARD_FAB2(SCH_1):UPI_CPU1_CPU0_P1P1_DN(19)
AA20 UPI_CPU1_CPU0_P1P1_DP<0> UPI1_RX_DP<19> @BASEBOARD_FAB2_LIB.BASEBOARD_FAB2(SCH_1):UPI_CPU1_CPU0_P1P1_DP(0)
 W20 UPI_CPU1_CPU0_P1P1_DP<1> UPI1_RX_DP<18> @BASEBOARD_FAB2_LIB.BASEBOARD_FAB2(SCH_1):UPI_CPU1_CPU0_P1P1_DP(1)
 Y19 UPI_CPU1_CPU0_P1P1_DP<2> UPI1_RX_DP<17> @BASEBOARD_FAB2_LIB.BASEBOARD_FAB2(SCH_1):UPI_CPU1_CPU0_P1P1_DP(2)
 T21 UPI_CPU1_CPU0_P1P1_DP<3> UPI1_RX_DP<16> @BASEBOARD_FAB2_LIB.BASEBOARD_FAB2(SCH_1):UPI_CPU1_CPU0_P1P1_DP(3)
 T19 UPI_CPU1_CPU0_P1P1_DP<4> UPI1_RX_DP<15> @BASEBOARD_FAB2_LIB.BASEBOARD_FAB2(SCH_1):UPI_CPU1_CPU0_P1P1_DP(4)
 P19 UPI_CPU1_CPU0_P1P1_DP<5> UPI1_RX_DP<14> @BASEBOARD_FAB2_LIB.BASEBOARD_FAB2(SCH_1):UPI_CPU1_CPU0_P1P1_DP(5)
 V17 UPI_CPU1_CPU0_P1P1_DP<6> UPI1_RX_DP<13> @BASEBOARD_FAB2_LIB.BASEBOARD_FAB2(SCH_1):UPI_CPU1_CPU0_P1P1_DP(6)
 W16 UPI_CPU1_CPU0_P1P1_DP<7> UPI1_RX_DP<12> @BASEBOARD_FAB2_LIB.BASEBOARD_FAB2(SCH_1):UPI_CPU1_CPU0_P1P1_DP(7)
 N16 UPI_CPU1_CPU0_P1P1_DP<8> UPI1_RX_DP<11> @BASEBOARD_FAB2_LIB.BASEBOARD_FAB2(SCH_1):UPI_CPU1_CPU0_P1P1_DP(8)
 T15 UPI_CPU1_CPU0_P1P1_DP<9> UPI1_RX_DP<10> @BASEBOARD_FAB2_LIB.BASEBOARD_FAB2(SCH_1):UPI_CPU1_CPU0_P1P1_DP(9)
 P13 UPI_CPU1_CPU0_P1P1_DP<10> UPI1_RX_DP<9> @BASEBOARD_FAB2_LIB.BASEBOARD_FAB2(SCH_1):UPI_CPU1_CPU0_P1P1_DP(10)
 M13 UPI_CPU1_CPU0_P1P1_DP<11> UPI1_RX_DP<8> @BASEBOARD_FAB2_LIB.BASEBOARD_FAB2(SCH_1):UPI_CPU1_CPU0_P1P1_DP(11)
 N12 UPI_CPU1_CPU0_P1P1_DP<12> UPI1_RX_DP<7> @BASEBOARD_FAB2_LIB.BASEBOARD_FAB2(SCH_1):UPI_CPU1_CPU0_P1P1_DP(12)
 T11 UPI_CPU1_CPU0_P1P1_DP<13> UPI1_RX_DP<6> @BASEBOARD_FAB2_LIB.BASEBOARD_FAB2(SCH_1):UPI_CPU1_CPU0_P1P1_DP(13)
 U10 UPI_CPU1_CPU0_P1P1_DP<14> UPI1_RX_DP<5> @BASEBOARD_FAB2_LIB.BASEBOARD_FAB2(SCH_1):UPI_CPU1_CPU0_P1P1_DP(14)
 N10 UPI_CPU1_CPU0_P1P1_DP<15> UPI1_RX_DP<4> @BASEBOARD_FAB2_LIB.BASEBOARD_FAB2(SCH_1):UPI_CPU1_CPU0_P1P1_DP(15)
  R8 UPI_CPU1_CPU0_P1P1_DP<16> UPI1_RX_DP<3> @BASEBOARD_FAB2_LIB.BASEBOARD_FAB2(SCH_1):UPI_CPU1_CPU0_P1P1_DP(16)
  U8 UPI_CPU1_CPU0_P1P1_DP<17> UPI1_RX_DP<2> @BASEBOARD_FAB2_LIB.BASEBOARD_FAB2(SCH_1):UPI_CPU1_CPU0_P1P1_DP(17)
  T7 UPI_CPU1_CPU0_P1P1_DP<18> UPI1_RX_DP<1> @BASEBOARD_FAB2_LIB.BASEBOARD_FAB2(SCH_1):UPI_CPU1_CPU0_P1P1_DP(18)
  R6 UPI_CPU1_CPU0_P1P1_DP<19> UPI1_RX_DP<0> @BASEBOARD_FAB2_LIB.BASEBOARD_FAB2(SCH_1):UPI_CPU1_CPU0_P1P1_DP(19)
 H21 UPI_CPU0_CPU1_P1P1_DN<0> UPI1_TX_DN<19> @BASEBOARD_FAB2_LIB.BASEBOARD_FAB2(SCH_1):UPI_CPU0_CPU1_P1P1_DN(0)
 F21 UPI_CPU0_CPU1_P1P1_DN<1> UPI1_TX_DN<18> @BASEBOARD_FAB2_LIB.BASEBOARD_FAB2(SCH_1):UPI_CPU0_CPU1_P1P1_DN(1)
 J20 UPI_CPU0_CPU1_P1P1_DN<2> UPI1_TX_DN<17> @BASEBOARD_FAB2_LIB.BASEBOARD_FAB2(SCH_1):UPI_CPU0_CPU1_P1P1_DN(2)
 G18 UPI_CPU0_CPU1_P1P1_DN<3> UPI1_TX_DN<16> @BASEBOARD_FAB2_LIB.BASEBOARD_FAB2(SCH_1):UPI_CPU0_CPU1_P1P1_DN(3)
 K19 UPI_CPU0_CPU1_P1P1_DN<4> UPI1_TX_DN<15> @BASEBOARD_FAB2_LIB.BASEBOARD_FAB2(SCH_1):UPI_CPU0_CPU1_P1P1_DN(4)
 H17 UPI_CPU0_CPU1_P1P1_DN<5> UPI1_TX_DN<14> @BASEBOARD_FAB2_LIB.BASEBOARD_FAB2(SCH_1):UPI_CPU0_CPU1_P1P1_DN(5)
 F15 UPI_CPU0_CPU1_P1P1_DN<6> UPI1_TX_DN<13> @BASEBOARD_FAB2_LIB.BASEBOARD_FAB2(SCH_1):UPI_CPU0_CPU1_P1P1_DN(6)
 D15 UPI_CPU0_CPU1_P1P1_DN<7> UPI1_TX_DN<12> @BASEBOARD_FAB2_LIB.BASEBOARD_FAB2(SCH_1):UPI_CPU0_CPU1_P1P1_DN(7)
 G14 UPI_CPU0_CPU1_P1P1_DN<8> UPI1_TX_DN<11> @BASEBOARD_FAB2_LIB.BASEBOARD_FAB2(SCH_1):UPI_CPU0_CPU1_P1P1_DN(8)
 E12 UPI_CPU0_CPU1_P1P1_DN<9> UPI1_TX_DN<10> @BASEBOARD_FAB2_LIB.BASEBOARD_FAB2(SCH_1):UPI_CPU0_CPU1_P1P1_DN(9)
 G10 UPI_CPU0_CPU1_P1P1_DN<10> UPI1_TX_DN<9> @BASEBOARD_FAB2_LIB.BASEBOARD_FAB2(SCH_1):UPI_CPU0_CPU1_P1P1_DN(10)
 F11 UPI_CPU0_CPU1_P1P1_DN<11> UPI1_TX_DN<8> @BASEBOARD_FAB2_LIB.BASEBOARD_FAB2(SCH_1):UPI_CPU0_CPU1_P1P1_DN(11)
  D9 UPI_CPU0_CPU1_P1P1_DN<12> UPI1_TX_DN<7> @BASEBOARD_FAB2_LIB.BASEBOARD_FAB2(SCH_1):UPI_CPU0_CPU1_P1P1_DN(12)
  K9 UPI_CPU0_CPU1_P1P1_DN<13> UPI1_TX_DN<6> @BASEBOARD_FAB2_LIB.BASEBOARD_FAB2(SCH_1):UPI_CPU0_CPU1_P1P1_DN(13)
  H7 UPI_CPU0_CPU1_P1P1_DN<14> UPI1_TX_DN<5> @BASEBOARD_FAB2_LIB.BASEBOARD_FAB2(SCH_1):UPI_CPU0_CPU1_P1P1_DN(14)
  G6 UPI_CPU0_CPU1_P1P1_DN<15> UPI1_TX_DN<4> @BASEBOARD_FAB2_LIB.BASEBOARD_FAB2(SCH_1):UPI_CPU0_CPU1_P1P1_DN(15)
  J6 UPI_CPU0_CPU1_P1P1_DN<16> UPI1_TX_DN<3> @BASEBOARD_FAB2_LIB.BASEBOARD_FAB2(SCH_1):UPI_CPU0_CPU1_P1P1_DN(16)
  K5 UPI_CPU0_CPU1_P1P1_DN<17> UPI1_TX_DN<2> @BASEBOARD_FAB2_LIB.BASEBOARD_FAB2(SCH_1):UPI_CPU0_CPU1_P1P1_DN(17)
  L4 UPI_CPU0_CPU1_P1P1_DN<18> UPI1_TX_DN<1> @BASEBOARD_FAB2_LIB.BASEBOARD_FAB2(SCH_1):UPI_CPU0_CPU1_P1P1_DN(18)
  M3 UPI_CPU0_CPU1_P1P1_DN<19> UPI1_TX_DN<0> @BASEBOARD_FAB2_LIB.BASEBOARD_FAB2(SCH_1):UPI_CPU0_CPU1_P1P1_DN(19)
 K21 UPI_CPU0_CPU1_P1P1_DP<0> UPI1_TX_DP<19> @BASEBOARD_FAB2_LIB.BASEBOARD_FAB2(SCH_1):UPI_CPU0_CPU1_P1P1_DP(0)
 G20 UPI_CPU0_CPU1_P1P1_DP<1> UPI1_TX_DP<18> @BASEBOARD_FAB2_LIB.BASEBOARD_FAB2(SCH_1):UPI_CPU0_CPU1_P1P1_DP(1)
 H19 UPI_CPU0_CPU1_P1P1_DP<2> UPI1_TX_DP<17> @BASEBOARD_FAB2_LIB.BASEBOARD_FAB2(SCH_1):UPI_CPU0_CPU1_P1P1_DP(2)
 J18 UPI_CPU0_CPU1_P1P1_DP<3> UPI1_TX_DP<16> @BASEBOARD_FAB2_LIB.BASEBOARD_FAB2(SCH_1):UPI_CPU0_CPU1_P1P1_DP(3)
 L18 UPI_CPU0_CPU1_P1P1_DP<4> UPI1_TX_DP<15> @BASEBOARD_FAB2_LIB.BASEBOARD_FAB2(SCH_1):UPI_CPU0_CPU1_P1P1_DP(4)
 G16 UPI_CPU0_CPU1_P1P1_DP<5> UPI1_TX_DP<14> @BASEBOARD_FAB2_LIB.BASEBOARD_FAB2(SCH_1):UPI_CPU0_CPU1_P1P1_DP(5)
 H15 UPI_CPU0_CPU1_P1P1_DP<6> UPI1_TX_DP<13> @BASEBOARD_FAB2_LIB.BASEBOARD_FAB2(SCH_1):UPI_CPU0_CPU1_P1P1_DP(6)
 E14 UPI_CPU0_CPU1_P1P1_DP<7> UPI1_TX_DP<12> @BASEBOARD_FAB2_LIB.BASEBOARD_FAB2(SCH_1):UPI_CPU0_CPU1_P1P1_DP(7)
 F13 UPI_CPU0_CPU1_P1P1_DP<8> UPI1_TX_DP<11> @BASEBOARD_FAB2_LIB.BASEBOARD_FAB2(SCH_1):UPI_CPU0_CPU1_P1P1_DP(8)
 G12 UPI_CPU0_CPU1_P1P1_DP<9> UPI1_TX_DP<10> @BASEBOARD_FAB2_LIB.BASEBOARD_FAB2(SCH_1):UPI_CPU0_CPU1_P1P1_DP(9)
  H9 UPI_CPU0_CPU1_P1P1_DP<10> UPI1_TX_DP<9> @BASEBOARD_FAB2_LIB.BASEBOARD_FAB2(SCH_1):UPI_CPU0_CPU1_P1P1_DP(10)
 E10 UPI_CPU0_CPU1_P1P1_DP<11> UPI1_TX_DP<8> @BASEBOARD_FAB2_LIB.BASEBOARD_FAB2(SCH_1):UPI_CPU0_CPU1_P1P1_DP(11)
  F9 UPI_CPU0_CPU1_P1P1_DP<12> UPI1_TX_DP<7> @BASEBOARD_FAB2_LIB.BASEBOARD_FAB2(SCH_1):UPI_CPU0_CPU1_P1P1_DP(12)
  J8 UPI_CPU0_CPU1_P1P1_DP<13> UPI1_TX_DP<6> @BASEBOARD_FAB2_LIB.BASEBOARD_FAB2(SCH_1):UPI_CPU0_CPU1_P1P1_DP(13)
  K7 UPI_CPU0_CPU1_P1P1_DP<14> UPI1_TX_DP<5> @BASEBOARD_FAB2_LIB.BASEBOARD_FAB2(SCH_1):UPI_CPU0_CPU1_P1P1_DP(14)
  F7 UPI_CPU0_CPU1_P1P1_DP<15> UPI1_TX_DP<4> @BASEBOARD_FAB2_LIB.BASEBOARD_FAB2(SCH_1):UPI_CPU0_CPU1_P1P1_DP(15)
  H5 UPI_CPU0_CPU1_P1P1_DP<16> UPI1_TX_DP<3> @BASEBOARD_FAB2_LIB.BASEBOARD_FAB2(SCH_1):UPI_CPU0_CPU1_P1P1_DP(16)
  M5 UPI_CPU0_CPU1_P1P1_DP<17> UPI1_TX_DP<2> @BASEBOARD_FAB2_LIB.BASEBOARD_FAB2(SCH_1):UPI_CPU0_CPU1_P1P1_DP(17)
  K3 UPI_CPU0_CPU1_P1P1_DP<18> UPI1_TX_DP<1> @BASEBOARD_FAB2_LIB.BASEBOARD_FAB2(SCH_1):UPI_CPU0_CPU1_P1P1_DP(18)
  P3 UPI_CPU0_CPU1_P1P1_DP<19> UPI1_TX_DP<0> @BASEBOARD_FAB2_LIB.BASEBOARD_FAB2(SCH_1):UPI_CPU0_CPU1_P1P1_DP(19)


DRAWING: @BASEBOARD_FAB2_LIB.BASEBOARD_FAB2(SCH_1):PAGE35 

SKX_EXT_B_BGA1-IC,TBD  I3  U5D1
BY17    GND UPI2_RX_DN<19> @BASEBOARD_FAB2_LIB.BASEBOARD_FAB2(SCH_1):GND
CB15    GND UPI2_RX_DN<18> @BASEBOARD_FAB2_LIB.BASEBOARD_FAB2(SCH_1):GND
CF17    GND UPI2_RX_DN<17> @BASEBOARD_FAB2_LIB.BASEBOARD_FAB2(SCH_1):GND
CD15    GND UPI2_RX_DN<16> @BASEBOARD_FAB2_LIB.BASEBOARD_FAB2(SCH_1):GND
CE16    GND UPI2_RX_DN<15> @BASEBOARD_FAB2_LIB.BASEBOARD_FAB2(SCH_1):GND
CH17    GND UPI2_RX_DN<14> @BASEBOARD_FAB2_LIB.BASEBOARD_FAB2(SCH_1):GND
CJ18    GND UPI2_RX_DN<13> @BASEBOARD_FAB2_LIB.BASEBOARD_FAB2(SCH_1):GND
CL16    GND UPI2_RX_DN<12> @BASEBOARD_FAB2_LIB.BASEBOARD_FAB2(SCH_1):GND
CP21    GND UPI2_RX_DN<11> @BASEBOARD_FAB2_LIB.BASEBOARD_FAB2(SCH_1):GND
CN20    GND UPI2_RX_DN<10> @BASEBOARD_FAB2_LIB.BASEBOARD_FAB2(SCH_1):GND
CR18    GND UPI2_RX_DN<9> @BASEBOARD_FAB2_LIB.BASEBOARD_FAB2(SCH_1):GND
CT21    GND UPI2_RX_DN<8> @BASEBOARD_FAB2_LIB.BASEBOARD_FAB2(SCH_1):GND
CV19    GND UPI2_RX_DN<7> @BASEBOARD_FAB2_LIB.BASEBOARD_FAB2(SCH_1):GND
CW20    GND UPI2_RX_DN<6> @BASEBOARD_FAB2_LIB.BASEBOARD_FAB2(SCH_1):GND
DA20    GND UPI2_RX_DN<5> @BASEBOARD_FAB2_LIB.BASEBOARD_FAB2(SCH_1):GND
DD19    GND UPI2_RX_DN<4> @BASEBOARD_FAB2_LIB.BASEBOARD_FAB2(SCH_1):GND
DB21    GND UPI2_RX_DN<3> @BASEBOARD_FAB2_LIB.BASEBOARD_FAB2(SCH_1):GND
DC22    GND UPI2_RX_DN<2> @BASEBOARD_FAB2_LIB.BASEBOARD_FAB2(SCH_1):GND
DE22    GND UPI2_RX_DN<1> @BASEBOARD_FAB2_LIB.BASEBOARD_FAB2(SCH_1):GND
DF23    GND UPI2_RX_DN<0> @BASEBOARD_FAB2_LIB.BASEBOARD_FAB2(SCH_1):GND
CA16    GND UPI2_RX_DP<19> @BASEBOARD_FAB2_LIB.BASEBOARD_FAB2(SCH_1):GND
BY15    GND UPI2_RX_DP<18> @BASEBOARD_FAB2_LIB.BASEBOARD_FAB2(SCH_1):GND
CD17    GND UPI2_RX_DP<17> @BASEBOARD_FAB2_LIB.BASEBOARD_FAB2(SCH_1):GND
CC14    GND UPI2_RX_DP<16> @BASEBOARD_FAB2_LIB.BASEBOARD_FAB2(SCH_1):GND
CF15    GND UPI2_RX_DP<15> @BASEBOARD_FAB2_LIB.BASEBOARD_FAB2(SCH_1):GND
CG16    GND UPI2_RX_DP<14> @BASEBOARD_FAB2_LIB.BASEBOARD_FAB2(SCH_1):GND
CK17    GND UPI2_RX_DP<13> @BASEBOARD_FAB2_LIB.BASEBOARD_FAB2(SCH_1):GND
CJ16    GND UPI2_RX_DP<12> @BASEBOARD_FAB2_LIB.BASEBOARD_FAB2(SCH_1):GND
CM21    GND UPI2_RX_DP<11> @BASEBOARD_FAB2_LIB.BASEBOARD_FAB2(SCH_1):GND
CP19    GND UPI2_RX_DP<10> @BASEBOARD_FAB2_LIB.BASEBOARD_FAB2(SCH_1):GND
CN18    GND UPI2_RX_DP<9> @BASEBOARD_FAB2_LIB.BASEBOARD_FAB2(SCH_1):GND
CR20    GND UPI2_RX_DP<8> @BASEBOARD_FAB2_LIB.BASEBOARD_FAB2(SCH_1):GND
CW18    GND UPI2_RX_DP<7> @BASEBOARD_FAB2_LIB.BASEBOARD_FAB2(SCH_1):GND
CU20    GND UPI2_RX_DP<6> @BASEBOARD_FAB2_LIB.BASEBOARD_FAB2(SCH_1):GND
CY19    GND UPI2_RX_DP<5> @BASEBOARD_FAB2_LIB.BASEBOARD_FAB2(SCH_1):GND
DB19    GND UPI2_RX_DP<4> @BASEBOARD_FAB2_LIB.BASEBOARD_FAB2(SCH_1):GND
DC20    GND UPI2_RX_DP<3> @BASEBOARD_FAB2_LIB.BASEBOARD_FAB2(SCH_1):GND
DA22    GND UPI2_RX_DP<2> @BASEBOARD_FAB2_LIB.BASEBOARD_FAB2(SCH_1):GND
DD21    GND UPI2_RX_DP<1> @BASEBOARD_FAB2_LIB.BASEBOARD_FAB2(SCH_1):GND
DG22    GND UPI2_RX_DP<0> @BASEBOARD_FAB2_LIB.BASEBOARD_FAB2(SCH_1):GND
CC12 TP_CPU0_UPI2_RSVD_DT21 UPI2_TX_DN<19> @BASEBOARD_FAB2_LIB.BASEBOARD_FAB2(SCH_1):TP_CPU0_UPI2_RSVD_DT21
CC10 TP_CPU0_UPI2_RSVD_DM21 UPI2_TX_DN<18> @BASEBOARD_FAB2_LIB.BASEBOARD_FAB2(SCH_1):TP_CPU0_UPI2_RSVD_DM21
CE12 TP_CPU0_UPI2_RSVD_DL20 UPI2_TX_DN<17> @BASEBOARD_FAB2_LIB.BASEBOARD_FAB2(SCH_1):TP_CPU0_UPI2_RSVD_DL20
CH11 TP_CPU0_UPI2_RSVD_DG20 UPI2_TX_DN<16> @BASEBOARD_FAB2_LIB.BASEBOARD_FAB2(SCH_1):TP_CPU0_UPI2_RSVD_DG20
CF13 TP_CPU0_UPI2_RSVD_DH19 UPI2_TX_DN<15> @BASEBOARD_FAB2_LIB.BASEBOARD_FAB2(SCH_1):TP_CPU0_UPI2_RSVD_DH19
CJ14 TP_CPU0_UPI2_RSVD_DK17 UPI2_TX_DN<14> @BASEBOARD_FAB2_LIB.BASEBOARD_FAB2(SCH_1):TP_CPU0_UPI2_RSVD_DK17
CM13 TP_CPU0_UPI2_RSVD_DG18 UPI2_TX_DN<13> @BASEBOARD_FAB2_LIB.BASEBOARD_FAB2(SCH_1):TP_CPU0_UPI2_RSVD_DG18
CU14 TP_CPU0_UPI2_RSVD_DD17 UPI2_TX_DN<12> @BASEBOARD_FAB2_LIB.BASEBOARD_FAB2(SCH_1):TP_CPU0_UPI2_RSVD_DD17
CW14 TP_CPU0_UPI2_RSVD_DF15 UPI2_TX_DN<11> @BASEBOARD_FAB2_LIB.BASEBOARD_FAB2(SCH_1):TP_CPU0_UPI2_RSVD_DF15
DA16 TP_CPU0_UPI2_RSVD_DC16 UPI2_TX_DN<10> @BASEBOARD_FAB2_LIB.BASEBOARD_FAB2(SCH_1):TP_CPU0_UPI2_RSVD_DC16
DC16 TP_CPU0_UPI2_RSVD_DA16 UPI2_TX_DN<9> @BASEBOARD_FAB2_LIB.BASEBOARD_FAB2(SCH_1):TP_CPU0_UPI2_RSVD_DA16
DF15 TP_CPU0_UPI2_RSVD_CW14 UPI2_TX_DN<8> @BASEBOARD_FAB2_LIB.BASEBOARD_FAB2(SCH_1):TP_CPU0_UPI2_RSVD_CW14
DD17 TP_CPU0_UPI2_RSVD_CU14 UPI2_TX_DN<7> @BASEBOARD_FAB2_LIB.BASEBOARD_FAB2(SCH_1):TP_CPU0_UPI2_RSVD_CU14
DG18 TP_CPU0_UPI2_RSVD_CM13 UPI2_TX_DN<6> @BASEBOARD_FAB2_LIB.BASEBOARD_FAB2(SCH_1):TP_CPU0_UPI2_RSVD_CM13
DK17 TP_CPU0_UPI2_RSVD_CJ14 UPI2_TX_DN<5> @BASEBOARD_FAB2_LIB.BASEBOARD_FAB2(SCH_1):TP_CPU0_UPI2_RSVD_CJ14
DH19 TP_CPU0_UPI2_RSVD_CF13 UPI2_TX_DN<4> @BASEBOARD_FAB2_LIB.BASEBOARD_FAB2(SCH_1):TP_CPU0_UPI2_RSVD_CF13
DG20 TP_CPU0_UPI2_RSVD_CH11 UPI2_TX_DN<3> @BASEBOARD_FAB2_LIB.BASEBOARD_FAB2(SCH_1):TP_CPU0_UPI2_RSVD_CH11
DL20 TP_CPU0_UPI2_RSVD_CE12 UPI2_TX_DN<2> @BASEBOARD_FAB2_LIB.BASEBOARD_FAB2(SCH_1):TP_CPU0_UPI2_RSVD_CE12
DM21 TP_CPU0_UPI2_RSVD_CC10 UPI2_TX_DN<1> @BASEBOARD_FAB2_LIB.BASEBOARD_FAB2(SCH_1):TP_CPU0_UPI2_RSVD_CC10
DT21 TP_CPU0_UPI2_RSVD_CC12 UPI2_TX_DN<0> @BASEBOARD_FAB2_LIB.BASEBOARD_FAB2(SCH_1):TP_CPU0_UPI2_RSVD_CC12
CA12 TP_CPU0_UPI2_RSVD_DP21 UPI2_TX_DP<19> @BASEBOARD_FAB2_LIB.BASEBOARD_FAB2(SCH_1):TP_CPU0_UPI2_RSVD_DP21
CB11 TP_CPU0_UPI2_RSVD_DN20 UPI2_TX_DP<18> @BASEBOARD_FAB2_LIB.BASEBOARD_FAB2(SCH_1):TP_CPU0_UPI2_RSVD_DN20
CD11 TP_CPU0_UPI2_RSVD_DK19 UPI2_TX_DP<17> @BASEBOARD_FAB2_LIB.BASEBOARD_FAB2(SCH_1):TP_CPU0_UPI2_RSVD_DK19
CF11 TP_CPU0_UPI2_RSVD_DJ20 UPI2_TX_DP<16> @BASEBOARD_FAB2_LIB.BASEBOARD_FAB2(SCH_1):TP_CPU0_UPI2_RSVD_DJ20
CG12 TP_CPU0_UPI2_RSVD_DJ18 UPI2_TX_DP<15> @BASEBOARD_FAB2_LIB.BASEBOARD_FAB2(SCH_1):TP_CPU0_UPI2_RSVD_DJ18
CH13 TP_CPU0_UPI2_RSVD_DH17 UPI2_TX_DP<14> @BASEBOARD_FAB2_LIB.BASEBOARD_FAB2(SCH_1):TP_CPU0_UPI2_RSVD_DH17
CK13 TP_CPU0_UPI2_RSVD_DF17 UPI2_TX_DP<13> @BASEBOARD_FAB2_LIB.BASEBOARD_FAB2(SCH_1):TP_CPU0_UPI2_RSVD_DF17
CR14 TP_CPU0_UPI2_RSVD_DE16 UPI2_TX_DP<12> @BASEBOARD_FAB2_LIB.BASEBOARD_FAB2(SCH_1):TP_CPU0_UPI2_RSVD_DE16
CV13 TP_CPU0_UPI2_RSVD_DD15 UPI2_TX_DP<11> @BASEBOARD_FAB2_LIB.BASEBOARD_FAB2(SCH_1):TP_CPU0_UPI2_RSVD_DD15
CW16 TP_CPU0_UPI2_RSVD_DB15 UPI2_TX_DP<10> @BASEBOARD_FAB2_LIB.BASEBOARD_FAB2(SCH_1):TP_CPU0_UPI2_RSVD_DB15
DB15 TP_CPU0_UPI2_RSVD_CW16 UPI2_TX_DP<9> @BASEBOARD_FAB2_LIB.BASEBOARD_FAB2(SCH_1):TP_CPU0_UPI2_RSVD_CW16
DD15 TP_CPU0_UPI2_RSVD_CV13 UPI2_TX_DP<8> @BASEBOARD_FAB2_LIB.BASEBOARD_FAB2(SCH_1):TP_CPU0_UPI2_RSVD_CV13
DE16 TP_CPU0_UPI2_RSVD_CR14 UPI2_TX_DP<7> @BASEBOARD_FAB2_LIB.BASEBOARD_FAB2(SCH_1):TP_CPU0_UPI2_RSVD_CR14
DF17 TP_CPU0_UPI2_RSVD_CK13 UPI2_TX_DP<6> @BASEBOARD_FAB2_LIB.BASEBOARD_FAB2(SCH_1):TP_CPU0_UPI2_RSVD_CK13
DH17 TP_CPU0_UPI2_RSVD_CH13 UPI2_TX_DP<5> @BASEBOARD_FAB2_LIB.BASEBOARD_FAB2(SCH_1):TP_CPU0_UPI2_RSVD_CH13
DJ18 TP_CPU0_UPI2_RSVD_CG12 UPI2_TX_DP<4> @BASEBOARD_FAB2_LIB.BASEBOARD_FAB2(SCH_1):TP_CPU0_UPI2_RSVD_CG12
DJ20 TP_CPU0_UPI2_RSVD_CF11 UPI2_TX_DP<3> @BASEBOARD_FAB2_LIB.BASEBOARD_FAB2(SCH_1):TP_CPU0_UPI2_RSVD_CF11
DK19 TP_CPU0_UPI2_RSVD_CD11 UPI2_TX_DP<2> @BASEBOARD_FAB2_LIB.BASEBOARD_FAB2(SCH_1):TP_CPU0_UPI2_RSVD_CD11
DN20 TP_CPU0_UPI2_RSVD_CB11 UPI2_TX_DP<1> @BASEBOARD_FAB2_LIB.BASEBOARD_FAB2(SCH_1):TP_CPU0_UPI2_RSVD_CB11
DP21 TP_CPU0_UPI2_RSVD_CA12 UPI2_TX_DP<0> @BASEBOARD_FAB2_LIB.BASEBOARD_FAB2(SCH_1):TP_CPU0_UPI2_RSVD_CA12


DRAWING: @BASEBOARD_FAB2_LIB.BASEBOARD_FAB2(SCH_1):PAGE36 

SKX_EXT_B_BGA1-IC,TBD  I15  U5D1
AY83 TP_CPU0_RSVD_255 RSVD<255> @BASEBOARD_FAB2_LIB.BASEBOARD_FAB2(SCH_1):TP_CPU0_RSVD_255
BA78 TP_CPU0_RSVD_171 RSVD<171> @BASEBOARD_FAB2_LIB.BASEBOARD_FAB2(SCH_1):TP_CPU0_RSVD_171
BA82 TP_CPU0_RSVD_170 RSVD<170> @BASEBOARD_FAB2_LIB.BASEBOARD_FAB2(SCH_1):TP_CPU0_RSVD_170
BB13 TP_CPU0_RSVD_169 RSVD<169> @BASEBOARD_FAB2_LIB.BASEBOARD_FAB2(SCH_1):TP_CPU0_RSVD_169
BB15 TP_CPU0_RSVD_168 RSVD<168> @BASEBOARD_FAB2_LIB.BASEBOARD_FAB2(SCH_1):TP_CPU0_RSVD_168
BB17 TP_CPU0_RSVD_167 RSVD<167> @BASEBOARD_FAB2_LIB.BASEBOARD_FAB2(SCH_1):TP_CPU0_RSVD_167
BB21 TP_CPU0_RSVD_166 RSVD<166> @BASEBOARD_FAB2_LIB.BASEBOARD_FAB2(SCH_1):TP_CPU0_RSVD_166
BB25 CLK_100M_CPU0_RC_REFCLK1_DN RSVD<165> @BASEBOARD_FAB2_LIB.BASEBOARD_FAB2(SCH_1):CLK_100M_CPU0_RC_REFCLK1_DN
BB65 TP_CPU0_RSVD_164 RSVD<164> @BASEBOARD_FAB2_LIB.BASEBOARD_FAB2(SCH_1):TP_CPU0_RSVD_164
BB67 TP_CPU0_RSVD_163 RSVD<163> @BASEBOARD_FAB2_LIB.BASEBOARD_FAB2(SCH_1):TP_CPU0_RSVD_163
BC14 TP_CPU0_RSVD_162 RSVD<162> @BASEBOARD_FAB2_LIB.BASEBOARD_FAB2(SCH_1):TP_CPU0_RSVD_162
BC18 TP_CPU0_RSVD_161 RSVD<161> @BASEBOARD_FAB2_LIB.BASEBOARD_FAB2(SCH_1):TP_CPU0_RSVD_161
BC20 TP_CPU0_RSVD_160 RSVD<160> @BASEBOARD_FAB2_LIB.BASEBOARD_FAB2(SCH_1):TP_CPU0_RSVD_160
BC22 TP_CPU0_RSVD_159 RSVD<159> @BASEBOARD_FAB2_LIB.BASEBOARD_FAB2(SCH_1):TP_CPU0_RSVD_159
BC64 TP_CPU0_RSVD_158 RSVD<158> @BASEBOARD_FAB2_LIB.BASEBOARD_FAB2(SCH_1):TP_CPU0_RSVD_158
BC66 TP_CPU0_RSVD_157 RSVD<157> @BASEBOARD_FAB2_LIB.BASEBOARD_FAB2(SCH_1):TP_CPU0_RSVD_157
BC68 TP_CPU0_RSVD_156 RSVD<156> @BASEBOARD_FAB2_LIB.BASEBOARD_FAB2(SCH_1):TP_CPU0_RSVD_156
BD17 TP_CPU0_RSVD_155 RSVD<155> @BASEBOARD_FAB2_LIB.BASEBOARD_FAB2(SCH_1):TP_CPU0_RSVD_155
BD19 TP_CPU0_RSVD_154 RSVD<154> @BASEBOARD_FAB2_LIB.BASEBOARD_FAB2(SCH_1):TP_CPU0_RSVD_154
BD25 CLK_100M_CPU0_RC_REFCLK1_DP RSVD<153> @BASEBOARD_FAB2_LIB.BASEBOARD_FAB2(SCH_1):CLK_100M_CPU0_RC_REFCLK1_DP
BD65 TP_CPU0_RSVD_152 RSVD<152> @BASEBOARD_FAB2_LIB.BASEBOARD_FAB2(SCH_1):TP_CPU0_RSVD_152
BD67 TP_CPU0_RSVD_151 RSVD<151> @BASEBOARD_FAB2_LIB.BASEBOARD_FAB2(SCH_1):TP_CPU0_RSVD_151
BD69 TP_CPU0_RSVD_150 RSVD<150> @BASEBOARD_FAB2_LIB.BASEBOARD_FAB2(SCH_1):TP_CPU0_RSVD_150
BE18 TP_CPU0_RSVD_149 RSVD<149> @BASEBOARD_FAB2_LIB.BASEBOARD_FAB2(SCH_1):TP_CPU0_RSVD_149
BE20 TP_CPU0_RSVD_148 RSVD<148> @BASEBOARD_FAB2_LIB.BASEBOARD_FAB2(SCH_1):TP_CPU0_RSVD_148
BE22 TP_CPU0_RSVD_147 RSVD<147> @BASEBOARD_FAB2_LIB.BASEBOARD_FAB2(SCH_1):TP_CPU0_RSVD_147
BF21 TP_CPU0_RSVD_146 RSVD<146> @BASEBOARD_FAB2_LIB.BASEBOARD_FAB2(SCH_1):TP_CPU0_RSVD_146
BG18 TP_CPU0_RSVD_145 RSVD<145> @BASEBOARD_FAB2_LIB.BASEBOARD_FAB2(SCH_1):TP_CPU0_RSVD_145
BG20 TP_CPU0_RSVD_144 RSVD<144> @BASEBOARD_FAB2_LIB.BASEBOARD_FAB2(SCH_1):TP_CPU0_RSVD_144
BH19 PVCCMCP_CPU0 RSVD<143> @BASEBOARD_FAB2_LIB.BASEBOARD_FAB2(SCH_1):PVCCMCP_CPU0
BJ16 PVCCMCP_CPU0 RSVD<142> @BASEBOARD_FAB2_LIB.BASEBOARD_FAB2(SCH_1):PVCCMCP_CPU0
BJ18 PVCCMCP_CPU0 RSVD<141> @BASEBOARD_FAB2_LIB.BASEBOARD_FAB2(SCH_1):PVCCMCP_CPU0
BJ20 PVCCMCP_CPU0 RSVD<140> @BASEBOARD_FAB2_LIB.BASEBOARD_FAB2(SCH_1):PVCCMCP_CPU0
BK17 PVCCMCP_CPU0 RSVD<139> @BASEBOARD_FAB2_LIB.BASEBOARD_FAB2(SCH_1):PVCCMCP_CPU0
BL18 PVCCMCP_CPU0 RSVD<138> @BASEBOARD_FAB2_LIB.BASEBOARD_FAB2(SCH_1):PVCCMCP_CPU0
BL20 PVCCMCP_CPU0 RSVD<137> @BASEBOARD_FAB2_LIB.BASEBOARD_FAB2(SCH_1):PVCCMCP_CPU0
BM17 PVCCMCP_CPU0 RSVD<136> @BASEBOARD_FAB2_LIB.BASEBOARD_FAB2(SCH_1):PVCCMCP_CPU0
BM19 PVCCMCP_CPU0 RSVD<135> @BASEBOARD_FAB2_LIB.BASEBOARD_FAB2(SCH_1):PVCCMCP_CPU0
BN18 PVCCMCP_CPU0 RSVD<134> @BASEBOARD_FAB2_LIB.BASEBOARD_FAB2(SCH_1):PVCCMCP_CPU0
BP17 PVCCMCP_CPU0 RSVD<133> @BASEBOARD_FAB2_LIB.BASEBOARD_FAB2(SCH_1):PVCCMCP_CPU0
BP21 PVCCMCP_CPU0 RSVD<132> @BASEBOARD_FAB2_LIB.BASEBOARD_FAB2(SCH_1):PVCCMCP_CPU0
BR22 PVCCMCP_CPU0 RSVD<131> @BASEBOARD_FAB2_LIB.BASEBOARD_FAB2(SCH_1):PVCCMCP_CPU0
BR24 PVCCMCP_CPU0 RSVD<130> @BASEBOARD_FAB2_LIB.BASEBOARD_FAB2(SCH_1):PVCCMCP_CPU0
BU18 PVCCMCP_CPU0 RSVD<129> @BASEBOARD_FAB2_LIB.BASEBOARD_FAB2(SCH_1):PVCCMCP_CPU0
BU20 PVCCMCP_CPU0 RSVD<128> @BASEBOARD_FAB2_LIB.BASEBOARD_FAB2(SCH_1):PVCCMCP_CPU0
BU22 PVCCMCP_CPU0 RSVD<127> @BASEBOARD_FAB2_LIB.BASEBOARD_FAB2(SCH_1):PVCCMCP_CPU0
BV19 PVCCMCP_CPU0 RSVD<126> @BASEBOARD_FAB2_LIB.BASEBOARD_FAB2(SCH_1):PVCCMCP_CPU0
BV21 PVCCMCP_CPU0 RSVD<125> @BASEBOARD_FAB2_LIB.BASEBOARD_FAB2(SCH_1):PVCCMCP_CPU0
BV23 TP_CPU0_RSVD_124 RSVD<124> @BASEBOARD_FAB2_LIB.BASEBOARD_FAB2(SCH_1):TP_CPU0_RSVD_124
BW10 TP_CPU0_RSVD_123 RSVD<123> @BASEBOARD_FAB2_LIB.BASEBOARD_FAB2(SCH_1):TP_CPU0_RSVD_123
BW20 PVCCMCP_CPU0 RSVD<122> @BASEBOARD_FAB2_LIB.BASEBOARD_FAB2(SCH_1):PVCCMCP_CPU0
BW22 TP_CPU0_RSVD_121 RSVD<121> @BASEBOARD_FAB2_LIB.BASEBOARD_FAB2(SCH_1):TP_CPU0_RSVD_121
BY19 PVCCMCP_CPU0 RSVD<120> @BASEBOARD_FAB2_LIB.BASEBOARD_FAB2(SCH_1):PVCCMCP_CPU0
BY25 TP_CPU0_RSVD_119 RSVD<119> @BASEBOARD_FAB2_LIB.BASEBOARD_FAB2(SCH_1):TP_CPU0_RSVD_119
CA22 PVCCMCP_CPU0 RSVD<118> @BASEBOARD_FAB2_LIB.BASEBOARD_FAB2(SCH_1):PVCCMCP_CPU0
CA24 TP_CPU0_RSVD_117 RSVD<117> @BASEBOARD_FAB2_LIB.BASEBOARD_FAB2(SCH_1):TP_CPU0_RSVD_117
CB19 PVCCMCP_CPU0 RSVD<116> @BASEBOARD_FAB2_LIB.BASEBOARD_FAB2(SCH_1):PVCCMCP_CPU0
CB21 PVCCMCP_CPU0 RSVD<115> @BASEBOARD_FAB2_LIB.BASEBOARD_FAB2(SCH_1):PVCCMCP_CPU0
CB25 TP_CPU0_RSVD_114 RSVD<114> @BASEBOARD_FAB2_LIB.BASEBOARD_FAB2(SCH_1):TP_CPU0_RSVD_114
 CB5 TP_CPU0_RSVD_113 RSVD<113> @BASEBOARD_FAB2_LIB.BASEBOARD_FAB2(SCH_1):TP_CPU0_RSVD_113
CC20 PVCCMCP_CPU0 RSVD<112> @BASEBOARD_FAB2_LIB.BASEBOARD_FAB2(SCH_1):PVCCMCP_CPU0
 CC6 TP_CPU0_RSVD_111 RSVD<111> @BASEBOARD_FAB2_LIB.BASEBOARD_FAB2(SCH_1):TP_CPU0_RSVD_111
CD19 PVCCMCP_CPU0 RSVD<110> @BASEBOARD_FAB2_LIB.BASEBOARD_FAB2(SCH_1):PVCCMCP_CPU0
CD21 PVCCMCP_CPU0 RSVD<109> @BASEBOARD_FAB2_LIB.BASEBOARD_FAB2(SCH_1):PVCCMCP_CPU0
CD25 TP_CPU0_RSVD_108 RSVD<108> @BASEBOARD_FAB2_LIB.BASEBOARD_FAB2(SCH_1):TP_CPU0_RSVD_108
CE22 PVCCMCP_CPU0 RSVD<107> @BASEBOARD_FAB2_LIB.BASEBOARD_FAB2(SCH_1):PVCCMCP_CPU0
CE78 TP_CPU0_RSVD_106 RSVD<106> @BASEBOARD_FAB2_LIB.BASEBOARD_FAB2(SCH_1):TP_CPU0_RSVD_106
CE80 TP_CPU0_RSVD_105 RSVD<105> @BASEBOARD_FAB2_LIB.BASEBOARD_FAB2(SCH_1):TP_CPU0_RSVD_105
CF19 PVCCMCP_CPU0 RSVD<104> @BASEBOARD_FAB2_LIB.BASEBOARD_FAB2(SCH_1):PVCCMCP_CPU0
CF21 PVCCMCP_CPU0 RSVD<103> @BASEBOARD_FAB2_LIB.BASEBOARD_FAB2(SCH_1):PVCCMCP_CPU0
CF23 PVCCMCP_CPU0 RSVD<102> @BASEBOARD_FAB2_LIB.BASEBOARD_FAB2(SCH_1):PVCCMCP_CPU0
CF79 TP_CPU0_RSVD_101 RSVD<101> @BASEBOARD_FAB2_LIB.BASEBOARD_FAB2(SCH_1):TP_CPU0_RSVD_101
CF81 TP_CPU0_RSVD_100 RSVD<100> @BASEBOARD_FAB2_LIB.BASEBOARD_FAB2(SCH_1):TP_CPU0_RSVD_100
CG10 TP_CPU0_RSVD_99 RSVD<99> @BASEBOARD_FAB2_LIB.BASEBOARD_FAB2(SCH_1):TP_CPU0_RSVD_99
CG20 PVCCMCP_CPU0 RSVD<98> @BASEBOARD_FAB2_LIB.BASEBOARD_FAB2(SCH_1):PVCCMCP_CPU0
CG24 TP_CPU0_RSVD_97 RSVD<97> @BASEBOARD_FAB2_LIB.BASEBOARD_FAB2(SCH_1):TP_CPU0_RSVD_97
CG26 PVCCMCP_CPU0 RSVD<96> @BASEBOARD_FAB2_LIB.BASEBOARD_FAB2(SCH_1):PVCCMCP_CPU0
CG78 TP_CPU0_RSVD_95 RSVD<95> @BASEBOARD_FAB2_LIB.BASEBOARD_FAB2(SCH_1):TP_CPU0_RSVD_95
CG82 TP_CPU0_RSVD_94 RSVD<94> @BASEBOARD_FAB2_LIB.BASEBOARD_FAB2(SCH_1):TP_CPU0_RSVD_94
CH21 PVCCMCP_CPU0 RSVD<93> @BASEBOARD_FAB2_LIB.BASEBOARD_FAB2(SCH_1):PVCCMCP_CPU0
CH23 PVCCMCP_CPU0 RSVD<92> @BASEBOARD_FAB2_LIB.BASEBOARD_FAB2(SCH_1):PVCCMCP_CPU0

SKX_EXT_B_BGA1-IC,TBD  I16  U5D1
CH25 TP_CPU0_RSVD_91 RSVD<91> @BASEBOARD_FAB2_LIB.BASEBOARD_FAB2(SCH_1):TP_CPU0_RSVD_91
CH77 TP_CPU0_RSVD_90 RSVD<90> @BASEBOARD_FAB2_LIB.BASEBOARD_FAB2(SCH_1):TP_CPU0_RSVD_90
CJ20 PVCCMCP_CPU0 RSVD<89> @BASEBOARD_FAB2_LIB.BASEBOARD_FAB2(SCH_1):PVCCMCP_CPU0
CJ22 PVCCMCP_CPU0 RSVD<88> @BASEBOARD_FAB2_LIB.BASEBOARD_FAB2(SCH_1):PVCCMCP_CPU0
CJ24 PVCCMCP_CPU0 RSVD<87> @BASEBOARD_FAB2_LIB.BASEBOARD_FAB2(SCH_1):PVCCMCP_CPU0
CJ26 PVCCMCP_CPU0 RSVD<86> @BASEBOARD_FAB2_LIB.BASEBOARD_FAB2(SCH_1):PVCCMCP_CPU0
CK19 TP_CPU0_RSVD_85 RSVD<85> @BASEBOARD_FAB2_LIB.BASEBOARD_FAB2(SCH_1):TP_CPU0_RSVD_85
CK23 PVCCMCP_CPU0 RSVD<84> @BASEBOARD_FAB2_LIB.BASEBOARD_FAB2(SCH_1):PVCCMCP_CPU0
CK25 PVCCMCP_CPU0 RSVD<83> @BASEBOARD_FAB2_LIB.BASEBOARD_FAB2(SCH_1):PVCCMCP_CPU0
CK77 TP_CPU0_RSVD_82 RSVD<82> @BASEBOARD_FAB2_LIB.BASEBOARD_FAB2(SCH_1):TP_CPU0_RSVD_82
CL24 PVCCMCP_CPU0 RSVD<81> @BASEBOARD_FAB2_LIB.BASEBOARD_FAB2(SCH_1):PVCCMCP_CPU0
AW22 TP_CPU0_TEST_10 TEST_10 @BASEBOARD_FAB2_LIB.BASEBOARD_FAB2(SCH_1):TP_CPU0_TEST_10
AR16 TP_CPU0_TEST_6 TEST_6 @BASEBOARD_FAB2_LIB.BASEBOARD_FAB2(SCH_1):TP_CPU0_TEST_6
AU18 TP_CPU0_TEST_7 TEST_7 @BASEBOARD_FAB2_LIB.BASEBOARD_FAB2(SCH_1):TP_CPU0_TEST_7
AW16 TP_CPU0_TEST_8 TEST_8 @BASEBOARD_FAB2_LIB.BASEBOARD_FAB2(SCH_1):TP_CPU0_TEST_8
AW20 TP_CPU0_TEST_9 TEST_9 @BASEBOARD_FAB2_LIB.BASEBOARD_FAB2(SCH_1):TP_CPU0_TEST_9


DRAWING: @BASEBOARD_FAB2_LIB.BASEBOARD_FAB2(SCH_1):PAGE37 

RES_0402-249,0.1%,1/16W,CHIP,GA  I303  R5D5
   1 VSENSE_PMAX_CPU0      A @BASEBOARD_FAB2_LIB.BASEBOARD_FAB2(SCH_1):VSENSE_PMAX_CPU0
   2    GND      B @BASEBOARD_FAB2_LIB.BASEBOARD_FAB2(SCH_1):GND

RES_0603-100.0K,1%,1/10W,CHIP,A  I309  R5P1
   1 PVCCIN_CPU0      A @BASEBOARD_FAB2_LIB.BASEBOARD_FAB2(SCH_1):PVCCIN_CPU0
   2 VSENSE_VCCINR2PMAX_CPU0      B @BASEBOARD_FAB2_LIB.BASEBOARD_FAB2(SCH_1):VSENSE_VCCINR2PMAX_CPU0

SKX_EXT_B_BGA1-IC,TBD  I310  U5D1
AF43 PVCCIN_CPU0 VCCIN<267> @BASEBOARD_FAB2_LIB.BASEBOARD_FAB2(SCH_1):PVCCIN_CPU0
AG38 PVCCIN_CPU0 VCCIN<266> @BASEBOARD_FAB2_LIB.BASEBOARD_FAB2(SCH_1):PVCCIN_CPU0
AG40 PVCCIN_CPU0 VCCIN<265> @BASEBOARD_FAB2_LIB.BASEBOARD_FAB2(SCH_1):PVCCIN_CPU0
AG42 PVCCIN_CPU0 VCCIN<264> @BASEBOARD_FAB2_LIB.BASEBOARD_FAB2(SCH_1):PVCCIN_CPU0
AH37 PVCCIN_CPU0 VCCIN<263> @BASEBOARD_FAB2_LIB.BASEBOARD_FAB2(SCH_1):PVCCIN_CPU0
AH39 PVCCIN_CPU0 VCCIN<262> @BASEBOARD_FAB2_LIB.BASEBOARD_FAB2(SCH_1):PVCCIN_CPU0
AH41 PVCCIN_CPU0 VCCIN<261> @BASEBOARD_FAB2_LIB.BASEBOARD_FAB2(SCH_1):PVCCIN_CPU0
AJ36 PVCCIN_CPU0 VCCIN<260> @BASEBOARD_FAB2_LIB.BASEBOARD_FAB2(SCH_1):PVCCIN_CPU0
AK35 PVCCIN_CPU0 VCCIN<259> @BASEBOARD_FAB2_LIB.BASEBOARD_FAB2(SCH_1):PVCCIN_CPU0
AK45 PVCCIN_CPU0 VCCIN<258> @BASEBOARD_FAB2_LIB.BASEBOARD_FAB2(SCH_1):PVCCIN_CPU0
AK47 PVCCIN_CPU0 VCCIN<257> @BASEBOARD_FAB2_LIB.BASEBOARD_FAB2(SCH_1):PVCCIN_CPU0
AK49 PVCCIN_CPU0 VCCIN<256> @BASEBOARD_FAB2_LIB.BASEBOARD_FAB2(SCH_1):PVCCIN_CPU0
AK51 PVCCIN_CPU0 VCCIN<255> @BASEBOARD_FAB2_LIB.BASEBOARD_FAB2(SCH_1):PVCCIN_CPU0
AK53 PVCCIN_CPU0 VCCIN<254> @BASEBOARD_FAB2_LIB.BASEBOARD_FAB2(SCH_1):PVCCIN_CPU0
AL34 PVCCIN_CPU0 VCCIN<253> @BASEBOARD_FAB2_LIB.BASEBOARD_FAB2(SCH_1):PVCCIN_CPU0
AL46 PVCCIN_CPU0 VCCIN<252> @BASEBOARD_FAB2_LIB.BASEBOARD_FAB2(SCH_1):PVCCIN_CPU0
AL48 PVCCIN_CPU0 VCCIN<251> @BASEBOARD_FAB2_LIB.BASEBOARD_FAB2(SCH_1):PVCCIN_CPU0
AL50 PVCCIN_CPU0 VCCIN<250> @BASEBOARD_FAB2_LIB.BASEBOARD_FAB2(SCH_1):PVCCIN_CPU0
AL52 PVCCIN_CPU0 VCCIN<249> @BASEBOARD_FAB2_LIB.BASEBOARD_FAB2(SCH_1):PVCCIN_CPU0
AL54 PVCCIN_CPU0 VCCIN<248> @BASEBOARD_FAB2_LIB.BASEBOARD_FAB2(SCH_1):PVCCIN_CPU0
AM33 PVCCIN_CPU0 VCCIN<247> @BASEBOARD_FAB2_LIB.BASEBOARD_FAB2(SCH_1):PVCCIN_CPU0
AM53 PVCCIN_CPU0 VCCIN<246> @BASEBOARD_FAB2_LIB.BASEBOARD_FAB2(SCH_1):PVCCIN_CPU0
AM55 PVCCIN_CPU0 VCCIN<245> @BASEBOARD_FAB2_LIB.BASEBOARD_FAB2(SCH_1):PVCCIN_CPU0
AN32 PVCCIN_CPU0 VCCIN<244> @BASEBOARD_FAB2_LIB.BASEBOARD_FAB2(SCH_1):PVCCIN_CPU0
AN54 PVCCIN_CPU0 VCCIN<243> @BASEBOARD_FAB2_LIB.BASEBOARD_FAB2(SCH_1):PVCCIN_CPU0
AN56 PVCCIN_CPU0 VCCIN<242> @BASEBOARD_FAB2_LIB.BASEBOARD_FAB2(SCH_1):PVCCIN_CPU0
AP55 PVCCIN_CPU0 VCCIN<241> @BASEBOARD_FAB2_LIB.BASEBOARD_FAB2(SCH_1):PVCCIN_CPU0
AP57 PVCCIN_CPU0 VCCIN<240> @BASEBOARD_FAB2_LIB.BASEBOARD_FAB2(SCH_1):PVCCIN_CPU0
AR56 PVCCIN_CPU0 VCCIN<239> @BASEBOARD_FAB2_LIB.BASEBOARD_FAB2(SCH_1):PVCCIN_CPU0
AR58 PVCCIN_CPU0 VCCIN<238> @BASEBOARD_FAB2_LIB.BASEBOARD_FAB2(SCH_1):PVCCIN_CPU0
AT57 PVCCIN_CPU0 VCCIN<237> @BASEBOARD_FAB2_LIB.BASEBOARD_FAB2(SCH_1):PVCCIN_CPU0
AT59 PVCCIN_CPU0 VCCIN<236> @BASEBOARD_FAB2_LIB.BASEBOARD_FAB2(SCH_1):PVCCIN_CPU0
AU58 PVCCIN_CPU0 VCCIN<235> @BASEBOARD_FAB2_LIB.BASEBOARD_FAB2(SCH_1):PVCCIN_CPU0
AU60 PVCCIN_CPU0 VCCIN<234> @BASEBOARD_FAB2_LIB.BASEBOARD_FAB2(SCH_1):PVCCIN_CPU0
AV59 PVCCIN_CPU0 VCCIN<233> @BASEBOARD_FAB2_LIB.BASEBOARD_FAB2(SCH_1):PVCCIN_CPU0
AV61 PVCCIN_CPU0 VCCIN<232> @BASEBOARD_FAB2_LIB.BASEBOARD_FAB2(SCH_1):PVCCIN_CPU0
AW60 PVCCIN_CPU0 VCCIN<231> @BASEBOARD_FAB2_LIB.BASEBOARD_FAB2(SCH_1):PVCCIN_CPU0
AY61 PVCCIN_CPU0 VCCIN<230> @BASEBOARD_FAB2_LIB.BASEBOARD_FAB2(SCH_1):PVCCIN_CPU0
BA60 PVCCIN_CPU0 VCCIN<229> @BASEBOARD_FAB2_LIB.BASEBOARD_FAB2(SCH_1):PVCCIN_CPU0
BB61 PVCCIN_CPU0 VCCIN<228> @BASEBOARD_FAB2_LIB.BASEBOARD_FAB2(SCH_1):PVCCIN_CPU0
BB85 PVCCIN_CPU0 VCCIN<227> @BASEBOARD_FAB2_LIB.BASEBOARD_FAB2(SCH_1):PVCCIN_CPU0
BC60 PVCCIN_CPU0 VCCIN<226> @BASEBOARD_FAB2_LIB.BASEBOARD_FAB2(SCH_1):PVCCIN_CPU0
BC62 PVCCIN_CPU0 VCCIN<225> @BASEBOARD_FAB2_LIB.BASEBOARD_FAB2(SCH_1):PVCCIN_CPU0
BC84 PVCCIN_CPU0 VCCIN<224> @BASEBOARD_FAB2_LIB.BASEBOARD_FAB2(SCH_1):PVCCIN_CPU0
BD61 PVCCIN_CPU0 VCCIN<223> @BASEBOARD_FAB2_LIB.BASEBOARD_FAB2(SCH_1):PVCCIN_CPU0
BD73 PVCCIN_CPU0 VCCIN<222> @BASEBOARD_FAB2_LIB.BASEBOARD_FAB2(SCH_1):PVCCIN_CPU0
BD75 PVCCIN_CPU0 VCCIN<221> @BASEBOARD_FAB2_LIB.BASEBOARD_FAB2(SCH_1):PVCCIN_CPU0
BD77 PVCCIN_CPU0 VCCIN<220> @BASEBOARD_FAB2_LIB.BASEBOARD_FAB2(SCH_1):PVCCIN_CPU0
BD79 PVCCIN_CPU0 VCCIN<219> @BASEBOARD_FAB2_LIB.BASEBOARD_FAB2(SCH_1):PVCCIN_CPU0
BD81 PVCCIN_CPU0 VCCIN<218> @BASEBOARD_FAB2_LIB.BASEBOARD_FAB2(SCH_1):PVCCIN_CPU0
BD83 PVCCIN_CPU0 VCCIN<217> @BASEBOARD_FAB2_LIB.BASEBOARD_FAB2(SCH_1):PVCCIN_CPU0
BD85 PVCCIN_CPU0 VCCIN<216> @BASEBOARD_FAB2_LIB.BASEBOARD_FAB2(SCH_1):PVCCIN_CPU0
BE60 PVCCIN_CPU0 VCCIN<215> @BASEBOARD_FAB2_LIB.BASEBOARD_FAB2(SCH_1):PVCCIN_CPU0
BE62 PVCCIN_CPU0 VCCIN<214> @BASEBOARD_FAB2_LIB.BASEBOARD_FAB2(SCH_1):PVCCIN_CPU0
BE72 PVCCIN_CPU0 VCCIN<213> @BASEBOARD_FAB2_LIB.BASEBOARD_FAB2(SCH_1):PVCCIN_CPU0
BE74 PVCCIN_CPU0 VCCIN<212> @BASEBOARD_FAB2_LIB.BASEBOARD_FAB2(SCH_1):PVCCIN_CPU0
BE76 PVCCIN_CPU0 VCCIN<211> @BASEBOARD_FAB2_LIB.BASEBOARD_FAB2(SCH_1):PVCCIN_CPU0
BE78 PVCCIN_CPU0 VCCIN<210> @BASEBOARD_FAB2_LIB.BASEBOARD_FAB2(SCH_1):PVCCIN_CPU0
BE80 PVCCIN_CPU0 VCCIN<209> @BASEBOARD_FAB2_LIB.BASEBOARD_FAB2(SCH_1):PVCCIN_CPU0
BE82 PVCCIN_CPU0 VCCIN<208> @BASEBOARD_FAB2_LIB.BASEBOARD_FAB2(SCH_1):PVCCIN_CPU0
BE84 PVCCIN_CPU0 VCCIN<207> @BASEBOARD_FAB2_LIB.BASEBOARD_FAB2(SCH_1):PVCCIN_CPU0
BF61 PVCCIN_CPU0 VCCIN<206> @BASEBOARD_FAB2_LIB.BASEBOARD_FAB2(SCH_1):PVCCIN_CPU0
BF73 PVCCIN_CPU0 VCCIN<205> @BASEBOARD_FAB2_LIB.BASEBOARD_FAB2(SCH_1):PVCCIN_CPU0
BF75 PVCCIN_CPU0 VCCIN<204> @BASEBOARD_FAB2_LIB.BASEBOARD_FAB2(SCH_1):PVCCIN_CPU0
BF77 PVCCIN_CPU0 VCCIN<203> @BASEBOARD_FAB2_LIB.BASEBOARD_FAB2(SCH_1):PVCCIN_CPU0
BF79 PVCCIN_CPU0 VCCIN<202> @BASEBOARD_FAB2_LIB.BASEBOARD_FAB2(SCH_1):PVCCIN_CPU0
BF81 PVCCIN_CPU0 VCCIN<201> @BASEBOARD_FAB2_LIB.BASEBOARD_FAB2(SCH_1):PVCCIN_CPU0
BF83 PVCCIN_CPU0 VCCIN<200> @BASEBOARD_FAB2_LIB.BASEBOARD_FAB2(SCH_1):PVCCIN_CPU0
BF85 PVCCIN_CPU0 VCCIN<199> @BASEBOARD_FAB2_LIB.BASEBOARD_FAB2(SCH_1):PVCCIN_CPU0
BG60 PVCCIN_CPU0 VCCIN<198> @BASEBOARD_FAB2_LIB.BASEBOARD_FAB2(SCH_1):PVCCIN_CPU0
BG62 PVCCIN_CPU0 VCCIN<197> @BASEBOARD_FAB2_LIB.BASEBOARD_FAB2(SCH_1):PVCCIN_CPU0
BG64 PVCCIN_CPU0 VCCIN<196> @BASEBOARD_FAB2_LIB.BASEBOARD_FAB2(SCH_1):PVCCIN_CPU0
BG66 PVCCIN_CPU0 VCCIN<195> @BASEBOARD_FAB2_LIB.BASEBOARD_FAB2(SCH_1):PVCCIN_CPU0
BG68 PVCCIN_CPU0 VCCIN<194> @BASEBOARD_FAB2_LIB.BASEBOARD_FAB2(SCH_1):PVCCIN_CPU0
BG70 PVCCIN_CPU0 VCCIN<193> @BASEBOARD_FAB2_LIB.BASEBOARD_FAB2(SCH_1):PVCCIN_CPU0
BG84 PVCCIN_CPU0 VCCIN<192> @BASEBOARD_FAB2_LIB.BASEBOARD_FAB2(SCH_1):PVCCIN_CPU0
BH61 PVCCIN_CPU0 VCCIN<191> @BASEBOARD_FAB2_LIB.BASEBOARD_FAB2(SCH_1):PVCCIN_CPU0
BH63 PVCCIN_CPU0 VCCIN<190> @BASEBOARD_FAB2_LIB.BASEBOARD_FAB2(SCH_1):PVCCIN_CPU0
BH65 PVCCIN_CPU0 VCCIN<189> @BASEBOARD_FAB2_LIB.BASEBOARD_FAB2(SCH_1):PVCCIN_CPU0
BH67 PVCCIN_CPU0 VCCIN<188> @BASEBOARD_FAB2_LIB.BASEBOARD_FAB2(SCH_1):PVCCIN_CPU0
BH69 PVCCIN_CPU0 VCCIN<187> @BASEBOARD_FAB2_LIB.BASEBOARD_FAB2(SCH_1):PVCCIN_CPU0
BH71 PVCCIN_CPU0 VCCIN<186> @BASEBOARD_FAB2_LIB.BASEBOARD_FAB2(SCH_1):PVCCIN_CPU0
BH73 PVCCIN_CPU0 VCCIN<185> @BASEBOARD_FAB2_LIB.BASEBOARD_FAB2(SCH_1):PVCCIN_CPU0
BH75 PVCCIN_CPU0 VCCIN<184> @BASEBOARD_FAB2_LIB.BASEBOARD_FAB2(SCH_1):PVCCIN_CPU0
BH77 PVCCIN_CPU0 VCCIN<183> @BASEBOARD_FAB2_LIB.BASEBOARD_FAB2(SCH_1):PVCCIN_CPU0
BH79 PVCCIN_CPU0 VCCIN<182> @BASEBOARD_FAB2_LIB.BASEBOARD_FAB2(SCH_1):PVCCIN_CPU0
BH81 PVCCIN_CPU0 VCCIN<181> @BASEBOARD_FAB2_LIB.BASEBOARD_FAB2(SCH_1):PVCCIN_CPU0
BH83 PVCCIN_CPU0 VCCIN<180> @BASEBOARD_FAB2_LIB.BASEBOARD_FAB2(SCH_1):PVCCIN_CPU0
BJ60 PVCCIN_CPU0 VCCIN<179> @BASEBOARD_FAB2_LIB.BASEBOARD_FAB2(SCH_1):PVCCIN_CPU0
BJ62 PVCCIN_CPU0 VCCIN<178> @BASEBOARD_FAB2_LIB.BASEBOARD_FAB2(SCH_1):PVCCIN_CPU0
BJ64 PVCCIN_CPU0 VCCIN<177> @BASEBOARD_FAB2_LIB.BASEBOARD_FAB2(SCH_1):PVCCIN_CPU0
BJ66 PVCCIN_CPU0 VCCIN<176> @BASEBOARD_FAB2_LIB.BASEBOARD_FAB2(SCH_1):PVCCIN_CPU0
BJ68 PVCCIN_CPU0 VCCIN<175> @BASEBOARD_FAB2_LIB.BASEBOARD_FAB2(SCH_1):PVCCIN_CPU0
BJ70 PVCCIN_CPU0 VCCIN<174> @BASEBOARD_FAB2_LIB.BASEBOARD_FAB2(SCH_1):PVCCIN_CPU0
BJ72 PVCCIN_CPU0 VCCIN<173> @BASEBOARD_FAB2_LIB.BASEBOARD_FAB2(SCH_1):PVCCIN_CPU0
BJ74 PVCCIN_CPU0 VCCIN<172> @BASEBOARD_FAB2_LIB.BASEBOARD_FAB2(SCH_1):PVCCIN_CPU0
BJ76 PVCCIN_CPU0 VCCIN<171> @BASEBOARD_FAB2_LIB.BASEBOARD_FAB2(SCH_1):PVCCIN_CPU0
BJ78 PVCCIN_CPU0 VCCIN<170> @BASEBOARD_FAB2_LIB.BASEBOARD_FAB2(SCH_1):PVCCIN_CPU0
BJ80 PVCCIN_CPU0 VCCIN<169> @BASEBOARD_FAB2_LIB.BASEBOARD_FAB2(SCH_1):PVCCIN_CPU0
BJ82 PVCCIN_CPU0 VCCIN<168> @BASEBOARD_FAB2_LIB.BASEBOARD_FAB2(SCH_1):PVCCIN_CPU0
BJ84 PVCCIN_CPU0 VCCIN<167> @BASEBOARD_FAB2_LIB.BASEBOARD_FAB2(SCH_1):PVCCIN_CPU0
BK61 PVCCIN_CPU0 VCCIN<166> @BASEBOARD_FAB2_LIB.BASEBOARD_FAB2(SCH_1):PVCCIN_CPU0
BK63 PVCCIN_CPU0 VCCIN<165> @BASEBOARD_FAB2_LIB.BASEBOARD_FAB2(SCH_1):PVCCIN_CPU0
BK65 PVCCIN_CPU0 VCCIN<164> @BASEBOARD_FAB2_LIB.BASEBOARD_FAB2(SCH_1):PVCCIN_CPU0
BK67 PVCCIN_CPU0 VCCIN<163> @BASEBOARD_FAB2_LIB.BASEBOARD_FAB2(SCH_1):PVCCIN_CPU0
BK69 PVCCIN_CPU0 VCCIN<162> @BASEBOARD_FAB2_LIB.BASEBOARD_FAB2(SCH_1):PVCCIN_CPU0
BK71 PVCCIN_CPU0 VCCIN<161> @BASEBOARD_FAB2_LIB.BASEBOARD_FAB2(SCH_1):PVCCIN_CPU0
BK73 PVCCIN_CPU0 VCCIN<160> @BASEBOARD_FAB2_LIB.BASEBOARD_FAB2(SCH_1):PVCCIN_CPU0
BK75 PVCCIN_CPU0 VCCIN<159> @BASEBOARD_FAB2_LIB.BASEBOARD_FAB2(SCH_1):PVCCIN_CPU0
BK77 PVCCIN_CPU0 VCCIN<158> @BASEBOARD_FAB2_LIB.BASEBOARD_FAB2(SCH_1):PVCCIN_CPU0
BK79 PVCCIN_CPU0 VCCIN<157> @BASEBOARD_FAB2_LIB.BASEBOARD_FAB2(SCH_1):PVCCIN_CPU0
BK81 PVCCIN_CPU0 VCCIN<156> @BASEBOARD_FAB2_LIB.BASEBOARD_FAB2(SCH_1):PVCCIN_CPU0
BK83 PVCCIN_CPU0 VCCIN<155> @BASEBOARD_FAB2_LIB.BASEBOARD_FAB2(SCH_1):PVCCIN_CPU0
BL60 PVCCIN_CPU0 VCCIN<154> @BASEBOARD_FAB2_LIB.BASEBOARD_FAB2(SCH_1):PVCCIN_CPU0
BL62 PVCCIN_CPU0 VCCIN<153> @BASEBOARD_FAB2_LIB.BASEBOARD_FAB2(SCH_1):PVCCIN_CPU0
BL84 PVCCIN_CPU0 VCCIN<152> @BASEBOARD_FAB2_LIB.BASEBOARD_FAB2(SCH_1):PVCCIN_CPU0
BM61 PVCCIN_CPU0 VCCIN<151> @BASEBOARD_FAB2_LIB.BASEBOARD_FAB2(SCH_1):PVCCIN_CPU0
BM63 PVCCIN_CPU0 VCCIN<150> @BASEBOARD_FAB2_LIB.BASEBOARD_FAB2(SCH_1):PVCCIN_CPU0
BM65 PVCCIN_CPU0 VCCIN<149> @BASEBOARD_FAB2_LIB.BASEBOARD_FAB2(SCH_1):PVCCIN_CPU0
BM67 PVCCIN_CPU0 VCCIN<148> @BASEBOARD_FAB2_LIB.BASEBOARD_FAB2(SCH_1):PVCCIN_CPU0
BM69 PVCCIN_CPU0 VCCIN<147> @BASEBOARD_FAB2_LIB.BASEBOARD_FAB2(SCH_1):PVCCIN_CPU0
BM71 PVCCIN_CPU0 VCCIN<146> @BASEBOARD_FAB2_LIB.BASEBOARD_FAB2(SCH_1):PVCCIN_CPU0
BM73 PVCCIN_CPU0 VCCIN<145> @BASEBOARD_FAB2_LIB.BASEBOARD_FAB2(SCH_1):PVCCIN_CPU0
BM75 PVCCIN_CPU0 VCCIN<144> @BASEBOARD_FAB2_LIB.BASEBOARD_FAB2(SCH_1):PVCCIN_CPU0
BM77 PVCCIN_CPU0 VCCIN<143> @BASEBOARD_FAB2_LIB.BASEBOARD_FAB2(SCH_1):PVCCIN_CPU0
BM79 PVCCIN_CPU0 VCCIN<142> @BASEBOARD_FAB2_LIB.BASEBOARD_FAB2(SCH_1):PVCCIN_CPU0
BM81 PVCCIN_CPU0 VCCIN<141> @BASEBOARD_FAB2_LIB.BASEBOARD_FAB2(SCH_1):PVCCIN_CPU0
BM83 PVCCIN_CPU0 VCCIN<140> @BASEBOARD_FAB2_LIB.BASEBOARD_FAB2(SCH_1):PVCCIN_CPU0
BN60 PVCCIN_CPU0 VCCIN<139> @BASEBOARD_FAB2_LIB.BASEBOARD_FAB2(SCH_1):PVCCIN_CPU0
BN62 PVCCIN_CPU0 VCCIN<138> @BASEBOARD_FAB2_LIB.BASEBOARD_FAB2(SCH_1):PVCCIN_CPU0
BN64 PVCCIN_CPU0 VCCIN<137> @BASEBOARD_FAB2_LIB.BASEBOARD_FAB2(SCH_1):PVCCIN_CPU0
BN66 PVCCIN_CPU0 VCCIN<136> @BASEBOARD_FAB2_LIB.BASEBOARD_FAB2(SCH_1):PVCCIN_CPU0
BN68 PVCCIN_CPU0 VCCIN<135> @BASEBOARD_FAB2_LIB.BASEBOARD_FAB2(SCH_1):PVCCIN_CPU0
BN70 PVCCIN_CPU0 VCCIN<134> @BASEBOARD_FAB2_LIB.BASEBOARD_FAB2(SCH_1):PVCCIN_CPU0
BN72 PVCCIN_CPU0 VCCIN<133> @BASEBOARD_FAB2_LIB.BASEBOARD_FAB2(SCH_1):PVCCIN_CPU0
BN74 PVCCIN_CPU0 VCCIN<132> @BASEBOARD_FAB2_LIB.BASEBOARD_FAB2(SCH_1):PVCCIN_CPU0
BN76 PVCCIN_CPU0 VCCIN<131> @BASEBOARD_FAB2_LIB.BASEBOARD_FAB2(SCH_1):PVCCIN_CPU0
BN78 PVCCIN_CPU0 VCCIN<130> @BASEBOARD_FAB2_LIB.BASEBOARD_FAB2(SCH_1):PVCCIN_CPU0

SKX_EXT_B_BGA1-IC,TBD  I311  U5D1
BN80 PVCCIN_CPU0 VCCIN<129> @BASEBOARD_FAB2_LIB.BASEBOARD_FAB2(SCH_1):PVCCIN_CPU0
BN82 PVCCIN_CPU0 VCCIN<128> @BASEBOARD_FAB2_LIB.BASEBOARD_FAB2(SCH_1):PVCCIN_CPU0
BN84 PVCCIN_CPU0 VCCIN<127> @BASEBOARD_FAB2_LIB.BASEBOARD_FAB2(SCH_1):PVCCIN_CPU0
BP61 PVCCIN_CPU0 VCCIN<126> @BASEBOARD_FAB2_LIB.BASEBOARD_FAB2(SCH_1):PVCCIN_CPU0
BP63 PVCCIN_CPU0 VCCIN<125> @BASEBOARD_FAB2_LIB.BASEBOARD_FAB2(SCH_1):PVCCIN_CPU0
BP65 PVCCIN_CPU0 VCCIN<124> @BASEBOARD_FAB2_LIB.BASEBOARD_FAB2(SCH_1):PVCCIN_CPU0
BP67 PVCCIN_CPU0 VCCIN<123> @BASEBOARD_FAB2_LIB.BASEBOARD_FAB2(SCH_1):PVCCIN_CPU0
BP69 PVCCIN_CPU0 VCCIN<122> @BASEBOARD_FAB2_LIB.BASEBOARD_FAB2(SCH_1):PVCCIN_CPU0
BP71 PVCCIN_CPU0 VCCIN<121> @BASEBOARD_FAB2_LIB.BASEBOARD_FAB2(SCH_1):PVCCIN_CPU0
BP73 PVCCIN_CPU0 VCCIN<120> @BASEBOARD_FAB2_LIB.BASEBOARD_FAB2(SCH_1):PVCCIN_CPU0
BP75 PVCCIN_CPU0 VCCIN<119> @BASEBOARD_FAB2_LIB.BASEBOARD_FAB2(SCH_1):PVCCIN_CPU0
BP77 PVCCIN_CPU0 VCCIN<118> @BASEBOARD_FAB2_LIB.BASEBOARD_FAB2(SCH_1):PVCCIN_CPU0
BP79 PVCCIN_CPU0 VCCIN<117> @BASEBOARD_FAB2_LIB.BASEBOARD_FAB2(SCH_1):PVCCIN_CPU0
BP81 PVCCIN_CPU0 VCCIN<116> @BASEBOARD_FAB2_LIB.BASEBOARD_FAB2(SCH_1):PVCCIN_CPU0
BP83 PVCCIN_CPU0 VCCIN<115> @BASEBOARD_FAB2_LIB.BASEBOARD_FAB2(SCH_1):PVCCIN_CPU0
BR60 PVCCIN_CPU0 VCCIN<114> @BASEBOARD_FAB2_LIB.BASEBOARD_FAB2(SCH_1):PVCCIN_CPU0
BR62 PVCCIN_CPU0 VCCIN<113> @BASEBOARD_FAB2_LIB.BASEBOARD_FAB2(SCH_1):PVCCIN_CPU0
BR84 PVCCIN_CPU0 VCCIN<112> @BASEBOARD_FAB2_LIB.BASEBOARD_FAB2(SCH_1):PVCCIN_CPU0
BT61 PVCCIN_CPU0 VCCIN<111> @BASEBOARD_FAB2_LIB.BASEBOARD_FAB2(SCH_1):PVCCIN_CPU0
BT63 PVCCIN_CPU0 VCCIN<110> @BASEBOARD_FAB2_LIB.BASEBOARD_FAB2(SCH_1):PVCCIN_CPU0
BT65 PVCCIN_CPU0 VCCIN<109> @BASEBOARD_FAB2_LIB.BASEBOARD_FAB2(SCH_1):PVCCIN_CPU0
BT67 PVCCIN_CPU0 VCCIN<108> @BASEBOARD_FAB2_LIB.BASEBOARD_FAB2(SCH_1):PVCCIN_CPU0
BT69 PVCCIN_CPU0 VCCIN<107> @BASEBOARD_FAB2_LIB.BASEBOARD_FAB2(SCH_1):PVCCIN_CPU0
BT71 PVCCIN_CPU0 VCCIN<106> @BASEBOARD_FAB2_LIB.BASEBOARD_FAB2(SCH_1):PVCCIN_CPU0
BT73 PVCCIN_CPU0 VCCIN<105> @BASEBOARD_FAB2_LIB.BASEBOARD_FAB2(SCH_1):PVCCIN_CPU0
BT75 PVCCIN_CPU0 VCCIN<104> @BASEBOARD_FAB2_LIB.BASEBOARD_FAB2(SCH_1):PVCCIN_CPU0
BT77 PVCCIN_CPU0 VCCIN<103> @BASEBOARD_FAB2_LIB.BASEBOARD_FAB2(SCH_1):PVCCIN_CPU0
BT79 PVCCIN_CPU0 VCCIN<102> @BASEBOARD_FAB2_LIB.BASEBOARD_FAB2(SCH_1):PVCCIN_CPU0
BT81 PVCCIN_CPU0 VCCIN<101> @BASEBOARD_FAB2_LIB.BASEBOARD_FAB2(SCH_1):PVCCIN_CPU0
BT83 PVCCIN_CPU0 VCCIN<100> @BASEBOARD_FAB2_LIB.BASEBOARD_FAB2(SCH_1):PVCCIN_CPU0
BU60 PVCCIN_CPU0 VCCIN<99> @BASEBOARD_FAB2_LIB.BASEBOARD_FAB2(SCH_1):PVCCIN_CPU0
BU62 PVCCIN_CPU0 VCCIN<98> @BASEBOARD_FAB2_LIB.BASEBOARD_FAB2(SCH_1):PVCCIN_CPU0
BU64 PVCCIN_CPU0 VCCIN<97> @BASEBOARD_FAB2_LIB.BASEBOARD_FAB2(SCH_1):PVCCIN_CPU0
BU66 PVCCIN_CPU0 VCCIN<96> @BASEBOARD_FAB2_LIB.BASEBOARD_FAB2(SCH_1):PVCCIN_CPU0
BU68 PVCCIN_CPU0 VCCIN<95> @BASEBOARD_FAB2_LIB.BASEBOARD_FAB2(SCH_1):PVCCIN_CPU0
BU70 PVCCIN_CPU0 VCCIN<94> @BASEBOARD_FAB2_LIB.BASEBOARD_FAB2(SCH_1):PVCCIN_CPU0
BU72 PVCCIN_CPU0 VCCIN<93> @BASEBOARD_FAB2_LIB.BASEBOARD_FAB2(SCH_1):PVCCIN_CPU0
BU74 PVCCIN_CPU0 VCCIN<92> @BASEBOARD_FAB2_LIB.BASEBOARD_FAB2(SCH_1):PVCCIN_CPU0
BU76 PVCCIN_CPU0 VCCIN<91> @BASEBOARD_FAB2_LIB.BASEBOARD_FAB2(SCH_1):PVCCIN_CPU0
BU78 PVCCIN_CPU0 VCCIN<90> @BASEBOARD_FAB2_LIB.BASEBOARD_FAB2(SCH_1):PVCCIN_CPU0
BU80 PVCCIN_CPU0 VCCIN<89> @BASEBOARD_FAB2_LIB.BASEBOARD_FAB2(SCH_1):PVCCIN_CPU0
BU82 PVCCIN_CPU0 VCCIN<88> @BASEBOARD_FAB2_LIB.BASEBOARD_FAB2(SCH_1):PVCCIN_CPU0
BU84 PVCCIN_CPU0 VCCIN<87> @BASEBOARD_FAB2_LIB.BASEBOARD_FAB2(SCH_1):PVCCIN_CPU0
BV61 PVCCIN_CPU0 VCCIN<86> @BASEBOARD_FAB2_LIB.BASEBOARD_FAB2(SCH_1):PVCCIN_CPU0
BV63 PVCCIN_CPU0 VCCIN<85> @BASEBOARD_FAB2_LIB.BASEBOARD_FAB2(SCH_1):PVCCIN_CPU0
BV65 PVCCIN_CPU0 VCCIN<84> @BASEBOARD_FAB2_LIB.BASEBOARD_FAB2(SCH_1):PVCCIN_CPU0
BV67 PVCCIN_CPU0 VCCIN<83> @BASEBOARD_FAB2_LIB.BASEBOARD_FAB2(SCH_1):PVCCIN_CPU0
BV69 PVCCIN_CPU0 VCCIN<82> @BASEBOARD_FAB2_LIB.BASEBOARD_FAB2(SCH_1):PVCCIN_CPU0
BV71 PVCCIN_CPU0 VCCIN<81> @BASEBOARD_FAB2_LIB.BASEBOARD_FAB2(SCH_1):PVCCIN_CPU0
BV73 PVCCIN_CPU0 VCCIN<80> @BASEBOARD_FAB2_LIB.BASEBOARD_FAB2(SCH_1):PVCCIN_CPU0
BV75 PVCCIN_CPU0 VCCIN<79> @BASEBOARD_FAB2_LIB.BASEBOARD_FAB2(SCH_1):PVCCIN_CPU0
BV77 PVCCIN_CPU0 VCCIN<78> @BASEBOARD_FAB2_LIB.BASEBOARD_FAB2(SCH_1):PVCCIN_CPU0
BV79 PVCCIN_CPU0 VCCIN<77> @BASEBOARD_FAB2_LIB.BASEBOARD_FAB2(SCH_1):PVCCIN_CPU0
BV81 PVCCIN_CPU0 VCCIN<76> @BASEBOARD_FAB2_LIB.BASEBOARD_FAB2(SCH_1):PVCCIN_CPU0
BV83 PVCCIN_CPU0 VCCIN<75> @BASEBOARD_FAB2_LIB.BASEBOARD_FAB2(SCH_1):PVCCIN_CPU0
BW60 PVCCIN_CPU0 VCCIN<74> @BASEBOARD_FAB2_LIB.BASEBOARD_FAB2(SCH_1):PVCCIN_CPU0
BW62 PVCCIN_CPU0 VCCIN<73> @BASEBOARD_FAB2_LIB.BASEBOARD_FAB2(SCH_1):PVCCIN_CPU0
BW64 PVCCIN_CPU0 VCCIN<72> @BASEBOARD_FAB2_LIB.BASEBOARD_FAB2(SCH_1):PVCCIN_CPU0
BW66 PVCCIN_CPU0 VCCIN<71> @BASEBOARD_FAB2_LIB.BASEBOARD_FAB2(SCH_1):PVCCIN_CPU0
BW68 PVCCIN_CPU0 VCCIN<70> @BASEBOARD_FAB2_LIB.BASEBOARD_FAB2(SCH_1):PVCCIN_CPU0
BW70 PVCCIN_CPU0 VCCIN<69> @BASEBOARD_FAB2_LIB.BASEBOARD_FAB2(SCH_1):PVCCIN_CPU0
BW84 PVCCIN_CPU0 VCCIN<68> @BASEBOARD_FAB2_LIB.BASEBOARD_FAB2(SCH_1):PVCCIN_CPU0
BY61 PVCCIN_CPU0 VCCIN<67> @BASEBOARD_FAB2_LIB.BASEBOARD_FAB2(SCH_1):PVCCIN_CPU0
BY73 PVCCIN_CPU0 VCCIN<66> @BASEBOARD_FAB2_LIB.BASEBOARD_FAB2(SCH_1):PVCCIN_CPU0
BY75 PVCCIN_CPU0 VCCIN<65> @BASEBOARD_FAB2_LIB.BASEBOARD_FAB2(SCH_1):PVCCIN_CPU0
BY77 PVCCIN_CPU0 VCCIN<64> @BASEBOARD_FAB2_LIB.BASEBOARD_FAB2(SCH_1):PVCCIN_CPU0
BY79 PVCCIN_CPU0 VCCIN<63> @BASEBOARD_FAB2_LIB.BASEBOARD_FAB2(SCH_1):PVCCIN_CPU0
BY81 PVCCIN_CPU0 VCCIN<62> @BASEBOARD_FAB2_LIB.BASEBOARD_FAB2(SCH_1):PVCCIN_CPU0
BY83 PVCCIN_CPU0 VCCIN<61> @BASEBOARD_FAB2_LIB.BASEBOARD_FAB2(SCH_1):PVCCIN_CPU0
CA60 PVCCIN_CPU0 VCCIN<60> @BASEBOARD_FAB2_LIB.BASEBOARD_FAB2(SCH_1):PVCCIN_CPU0
CA62 PVCCIN_CPU0 VCCIN<59> @BASEBOARD_FAB2_LIB.BASEBOARD_FAB2(SCH_1):PVCCIN_CPU0
CA72 PVCCIN_CPU0 VCCIN<58> @BASEBOARD_FAB2_LIB.BASEBOARD_FAB2(SCH_1):PVCCIN_CPU0
CA74 PVCCIN_CPU0 VCCIN<57> @BASEBOARD_FAB2_LIB.BASEBOARD_FAB2(SCH_1):PVCCIN_CPU0
CA76 PVCCIN_CPU0 VCCIN<56> @BASEBOARD_FAB2_LIB.BASEBOARD_FAB2(SCH_1):PVCCIN_CPU0
CA78 PVCCIN_CPU0 VCCIN<55> @BASEBOARD_FAB2_LIB.BASEBOARD_FAB2(SCH_1):PVCCIN_CPU0
CA80 PVCCIN_CPU0 VCCIN<54> @BASEBOARD_FAB2_LIB.BASEBOARD_FAB2(SCH_1):PVCCIN_CPU0
CA82 PVCCIN_CPU0 VCCIN<53> @BASEBOARD_FAB2_LIB.BASEBOARD_FAB2(SCH_1):PVCCIN_CPU0
CA84 PVCCIN_CPU0 VCCIN<52> @BASEBOARD_FAB2_LIB.BASEBOARD_FAB2(SCH_1):PVCCIN_CPU0
CB61 PVCCIN_CPU0 VCCIN<51> @BASEBOARD_FAB2_LIB.BASEBOARD_FAB2(SCH_1):PVCCIN_CPU0
CB73 PVCCIN_CPU0 VCCIN<50> @BASEBOARD_FAB2_LIB.BASEBOARD_FAB2(SCH_1):PVCCIN_CPU0
CB75 PVCCIN_CPU0 VCCIN<49> @BASEBOARD_FAB2_LIB.BASEBOARD_FAB2(SCH_1):PVCCIN_CPU0
CB77 PVCCIN_CPU0 VCCIN<48> @BASEBOARD_FAB2_LIB.BASEBOARD_FAB2(SCH_1):PVCCIN_CPU0
CB79 PVCCIN_CPU0 VCCIN<47> @BASEBOARD_FAB2_LIB.BASEBOARD_FAB2(SCH_1):PVCCIN_CPU0
CB81 PVCCIN_CPU0 VCCIN<46> @BASEBOARD_FAB2_LIB.BASEBOARD_FAB2(SCH_1):PVCCIN_CPU0
CB83 PVCCIN_CPU0 VCCIN<45> @BASEBOARD_FAB2_LIB.BASEBOARD_FAB2(SCH_1):PVCCIN_CPU0
CC60 PVCCIN_CPU0 VCCIN<44> @BASEBOARD_FAB2_LIB.BASEBOARD_FAB2(SCH_1):PVCCIN_CPU0
CC62 PVCCIN_CPU0 VCCIN<43> @BASEBOARD_FAB2_LIB.BASEBOARD_FAB2(SCH_1):PVCCIN_CPU0
CC84 PVCCIN_CPU0 VCCIN<42> @BASEBOARD_FAB2_LIB.BASEBOARD_FAB2(SCH_1):PVCCIN_CPU0
CD61 PVCCIN_CPU0 VCCIN<41> @BASEBOARD_FAB2_LIB.BASEBOARD_FAB2(SCH_1):PVCCIN_CPU0
CD83 PVCCIN_CPU0 VCCIN<40> @BASEBOARD_FAB2_LIB.BASEBOARD_FAB2(SCH_1):PVCCIN_CPU0
CD85 PVCCIN_CPU0 VCCIN<39> @BASEBOARD_FAB2_LIB.BASEBOARD_FAB2(SCH_1):PVCCIN_CPU0
CE60 PVCCIN_CPU0 VCCIN<38> @BASEBOARD_FAB2_LIB.BASEBOARD_FAB2(SCH_1):PVCCIN_CPU0
CE84 PVCCIN_CPU0 VCCIN<37> @BASEBOARD_FAB2_LIB.BASEBOARD_FAB2(SCH_1):PVCCIN_CPU0
CF61 PVCCIN_CPU0 VCCIN<36> @BASEBOARD_FAB2_LIB.BASEBOARD_FAB2(SCH_1):PVCCIN_CPU0
CF85 PVCCIN_CPU0 VCCIN<35> @BASEBOARD_FAB2_LIB.BASEBOARD_FAB2(SCH_1):PVCCIN_CPU0
CG60 PVCCIN_CPU0 VCCIN<34> @BASEBOARD_FAB2_LIB.BASEBOARD_FAB2(SCH_1):PVCCIN_CPU0
CG84 PVCCIN_CPU0 VCCIN<33> @BASEBOARD_FAB2_LIB.BASEBOARD_FAB2(SCH_1):PVCCIN_CPU0
CH61 PVCCIN_CPU0 VCCIN<32> @BASEBOARD_FAB2_LIB.BASEBOARD_FAB2(SCH_1):PVCCIN_CPU0
CH85 PVCCIN_CPU0 VCCIN<31> @BASEBOARD_FAB2_LIB.BASEBOARD_FAB2(SCH_1):PVCCIN_CPU0
CJ60 PVCCIN_CPU0 VCCIN<30> @BASEBOARD_FAB2_LIB.BASEBOARD_FAB2(SCH_1):PVCCIN_CPU0
CK59 PVCCIN_CPU0 VCCIN<29> @BASEBOARD_FAB2_LIB.BASEBOARD_FAB2(SCH_1):PVCCIN_CPU0
CK61 PVCCIN_CPU0 VCCIN<28> @BASEBOARD_FAB2_LIB.BASEBOARD_FAB2(SCH_1):PVCCIN_CPU0
CL58 PVCCIN_CPU0 VCCIN<27> @BASEBOARD_FAB2_LIB.BASEBOARD_FAB2(SCH_1):PVCCIN_CPU0
CL60 PVCCIN_CPU0 VCCIN<26> @BASEBOARD_FAB2_LIB.BASEBOARD_FAB2(SCH_1):PVCCIN_CPU0
CM57 PVCCIN_CPU0 VCCIN<25> @BASEBOARD_FAB2_LIB.BASEBOARD_FAB2(SCH_1):PVCCIN_CPU0
CM59 PVCCIN_CPU0 VCCIN<24> @BASEBOARD_FAB2_LIB.BASEBOARD_FAB2(SCH_1):PVCCIN_CPU0
CN56 PVCCIN_CPU0 VCCIN<23> @BASEBOARD_FAB2_LIB.BASEBOARD_FAB2(SCH_1):PVCCIN_CPU0
CN58 PVCCIN_CPU0 VCCIN<22> @BASEBOARD_FAB2_LIB.BASEBOARD_FAB2(SCH_1):PVCCIN_CPU0
CP33 PVCCIN_CPU0 VCCIN<21> @BASEBOARD_FAB2_LIB.BASEBOARD_FAB2(SCH_1):PVCCIN_CPU0
CP55 PVCCIN_CPU0 VCCIN<20> @BASEBOARD_FAB2_LIB.BASEBOARD_FAB2(SCH_1):PVCCIN_CPU0
CP57 PVCCIN_CPU0 VCCIN<19> @BASEBOARD_FAB2_LIB.BASEBOARD_FAB2(SCH_1):PVCCIN_CPU0
CR34 PVCCIN_CPU0 VCCIN<18> @BASEBOARD_FAB2_LIB.BASEBOARD_FAB2(SCH_1):PVCCIN_CPU0
CR54 PVCCIN_CPU0 VCCIN<17> @BASEBOARD_FAB2_LIB.BASEBOARD_FAB2(SCH_1):PVCCIN_CPU0
CR56 PVCCIN_CPU0 VCCIN<16> @BASEBOARD_FAB2_LIB.BASEBOARD_FAB2(SCH_1):PVCCIN_CPU0
CT37 PVCCIN_CPU0 VCCIN<15> @BASEBOARD_FAB2_LIB.BASEBOARD_FAB2(SCH_1):PVCCIN_CPU0
CT39 PVCCIN_CPU0 VCCIN<14> @BASEBOARD_FAB2_LIB.BASEBOARD_FAB2(SCH_1):PVCCIN_CPU0
CT41 PVCCIN_CPU0 VCCIN<13> @BASEBOARD_FAB2_LIB.BASEBOARD_FAB2(SCH_1):PVCCIN_CPU0
CT53 PVCCIN_CPU0 VCCIN<12> @BASEBOARD_FAB2_LIB.BASEBOARD_FAB2(SCH_1):PVCCIN_CPU0
CT55 PVCCIN_CPU0 VCCIN<11> @BASEBOARD_FAB2_LIB.BASEBOARD_FAB2(SCH_1):PVCCIN_CPU0
CU38 PVCCIN_CPU0 VCCIN<10> @BASEBOARD_FAB2_LIB.BASEBOARD_FAB2(SCH_1):PVCCIN_CPU0
CU40 PVCCIN_CPU0 VCCIN<9> @BASEBOARD_FAB2_LIB.BASEBOARD_FAB2(SCH_1):PVCCIN_CPU0
CU42 PVCCIN_CPU0 VCCIN<8> @BASEBOARD_FAB2_LIB.BASEBOARD_FAB2(SCH_1):PVCCIN_CPU0
CU52 PVCCIN_CPU0 VCCIN<7> @BASEBOARD_FAB2_LIB.BASEBOARD_FAB2(SCH_1):PVCCIN_CPU0
CU54 PVCCIN_CPU0 VCCIN<6> @BASEBOARD_FAB2_LIB.BASEBOARD_FAB2(SCH_1):PVCCIN_CPU0
CV51 PVCCIN_CPU0 VCCIN<5> @BASEBOARD_FAB2_LIB.BASEBOARD_FAB2(SCH_1):PVCCIN_CPU0
CW46 PVCCIN_CPU0 VCCIN<4> @BASEBOARD_FAB2_LIB.BASEBOARD_FAB2(SCH_1):PVCCIN_CPU0
CW48 PVCCIN_CPU0 VCCIN<3> @BASEBOARD_FAB2_LIB.BASEBOARD_FAB2(SCH_1):PVCCIN_CPU0
CW50 PVCCIN_CPU0 VCCIN<2> @BASEBOARD_FAB2_LIB.BASEBOARD_FAB2(SCH_1):PVCCIN_CPU0
CY47 PVCCIN_CPU0 VCCIN<1> @BASEBOARD_FAB2_LIB.BASEBOARD_FAB2(SCH_1):PVCCIN_CPU0
CY49 PVCCIN_CPU0 VCCIN<0> @BASEBOARD_FAB2_LIB.BASEBOARD_FAB2(SCH_1):PVCCIN_CPU0
AV85 VSENSE_VCCINR2PMAX_CPU0 VCCINPMAX<1> @BASEBOARD_FAB2_LIB.BASEBOARD_FAB2(SCH_1):VSENSE_VCCINR2PMAX_CPU0
AW86 VSENSE_VCCINR2PMAX_CPU0 VCCINPMAX<0> @BASEBOARD_FAB2_LIB.BASEBOARD_FAB2(SCH_1):VSENSE_VCCINR2PMAX_CPU0
BA86 VSENSE_PVCCIN_CPU0_SKT_VSEN VCCIN_SENSE @BASEBOARD_FAB2_LIB.BASEBOARD_FAB2(SCH_1):VSENSE_PVCCIN_CPU0_SKT_VSEN
AD41 VSENSE_PMAX_CPU0 VSENSEPMAX @BASEBOARD_FAB2_LIB.BASEBOARD_FAB2(SCH_1):VSENSE_PMAX_CPU0
AY85 VSENSE_PVCCIN_CPU0_SKT_VRTN VSS_VCCIN_SENSE @BASEBOARD_FAB2_LIB.BASEBOARD_FAB2(SCH_1):VSENSE_PVCCIN_CPU0_SKT_VRTN

RES_0402-10.0,1%,1/16W,EMPTY,GA  I312  R5D6
   1 PVCCIO_CPU0      A @BASEBOARD_FAB2_LIB.BASEBOARD_FAB2(SCH_1):PVCCIO_CPU0
   2 VSENSE_PMAX_CPU0      B @BASEBOARD_FAB2_LIB.BASEBOARD_FAB2(SCH_1):VSENSE_PMAX_CPU0


DRAWING: @BASEBOARD_FAB2_LIB.BASEBOARD_FAB2(SCH_1):PAGE38 

CAP_0603LF-10UF,4V,20%,X6S,E15A  I19  C6D1
   1 P1V8_MCP_CPU0      A @BASEBOARD_FAB2_LIB.BASEBOARD_FAB2(SCH_1):P1V8_MCP_CPU0
   2    GND      B @BASEBOARD_FAB2_LIB.BASEBOARD_FAB2(SCH_1):GND

SKX_EXT_B_BGA1-IC,TBD  I33  U5D1
 B47 PVDDQ_ABC VCCD012<51> @BASEBOARD_FAB2_LIB.BASEBOARD_FAB2(SCH_1):PVDDQ_ABC
 C46 PVDDQ_ABC VCCD012<50> @BASEBOARD_FAB2_LIB.BASEBOARD_FAB2(SCH_1):PVDDQ_ABC
 D45 PVDDQ_ABC VCCD012<49> @BASEBOARD_FAB2_LIB.BASEBOARD_FAB2(SCH_1):PVDDQ_ABC
AF63 PVDDQ_ABC VCCD012<48> @BASEBOARD_FAB2_LIB.BASEBOARD_FAB2(SCH_1):PVDDQ_ABC
AF61 PVDDQ_ABC VCCD012<47> @BASEBOARD_FAB2_LIB.BASEBOARD_FAB2(SCH_1):PVDDQ_ABC
AF59 PVDDQ_ABC VCCD012<46> @BASEBOARD_FAB2_LIB.BASEBOARD_FAB2(SCH_1):PVDDQ_ABC
AF57 PVDDQ_ABC VCCD012<45> @BASEBOARD_FAB2_LIB.BASEBOARD_FAB2(SCH_1):PVDDQ_ABC
AF55 PVDDQ_ABC VCCD012<44> @BASEBOARD_FAB2_LIB.BASEBOARD_FAB2(SCH_1):PVDDQ_ABC
AD45 PVDDQ_ABC VCCD012<43> @BASEBOARD_FAB2_LIB.BASEBOARD_FAB2(SCH_1):PVDDQ_ABC
 Y63 PVDDQ_ABC VCCD012<42> @BASEBOARD_FAB2_LIB.BASEBOARD_FAB2(SCH_1):PVDDQ_ABC
 Y61 PVDDQ_ABC VCCD012<41> @BASEBOARD_FAB2_LIB.BASEBOARD_FAB2(SCH_1):PVDDQ_ABC
 Y59 PVDDQ_ABC VCCD012<40> @BASEBOARD_FAB2_LIB.BASEBOARD_FAB2(SCH_1):PVDDQ_ABC
 Y57 PVDDQ_ABC VCCD012<39> @BASEBOARD_FAB2_LIB.BASEBOARD_FAB2(SCH_1):PVDDQ_ABC
 Y55 PVDDQ_ABC VCCD012<38> @BASEBOARD_FAB2_LIB.BASEBOARD_FAB2(SCH_1):PVDDQ_ABC
 Y53 PVDDQ_ABC VCCD012<37> @BASEBOARD_FAB2_LIB.BASEBOARD_FAB2(SCH_1):PVDDQ_ABC
 Y51 PVDDQ_ABC VCCD012<36> @BASEBOARD_FAB2_LIB.BASEBOARD_FAB2(SCH_1):PVDDQ_ABC
 Y49 PVDDQ_ABC VCCD012<35> @BASEBOARD_FAB2_LIB.BASEBOARD_FAB2(SCH_1):PVDDQ_ABC
 Y47 PVDDQ_ABC VCCD012<34> @BASEBOARD_FAB2_LIB.BASEBOARD_FAB2(SCH_1):PVDDQ_ABC
 Y45 PVDDQ_ABC VCCD012<33> @BASEBOARD_FAB2_LIB.BASEBOARD_FAB2(SCH_1):PVDDQ_ABC
 W64 PVDDQ_ABC VCCD012<32> @BASEBOARD_FAB2_LIB.BASEBOARD_FAB2(SCH_1):PVDDQ_ABC
 U62 PVDDQ_ABC VCCD012<31> @BASEBOARD_FAB2_LIB.BASEBOARD_FAB2(SCH_1):PVDDQ_ABC
 U60 PVDDQ_ABC VCCD012<30> @BASEBOARD_FAB2_LIB.BASEBOARD_FAB2(SCH_1):PVDDQ_ABC
 U58 PVDDQ_ABC VCCD012<29> @BASEBOARD_FAB2_LIB.BASEBOARD_FAB2(SCH_1):PVDDQ_ABC
 U56 PVDDQ_ABC VCCD012<28> @BASEBOARD_FAB2_LIB.BASEBOARD_FAB2(SCH_1):PVDDQ_ABC
 U54 PVDDQ_ABC VCCD012<27> @BASEBOARD_FAB2_LIB.BASEBOARD_FAB2(SCH_1):PVDDQ_ABC
 U52 PVDDQ_ABC VCCD012<26> @BASEBOARD_FAB2_LIB.BASEBOARD_FAB2(SCH_1):PVDDQ_ABC
 U50 PVDDQ_ABC VCCD012<25> @BASEBOARD_FAB2_LIB.BASEBOARD_FAB2(SCH_1):PVDDQ_ABC
 U48 PVDDQ_ABC VCCD012<24> @BASEBOARD_FAB2_LIB.BASEBOARD_FAB2(SCH_1):PVDDQ_ABC
 U46 PVDDQ_ABC VCCD012<23> @BASEBOARD_FAB2_LIB.BASEBOARD_FAB2(SCH_1):PVDDQ_ABC
 N64 PVDDQ_ABC VCCD012<22> @BASEBOARD_FAB2_LIB.BASEBOARD_FAB2(SCH_1):PVDDQ_ABC
 L62 PVDDQ_ABC VCCD012<21> @BASEBOARD_FAB2_LIB.BASEBOARD_FAB2(SCH_1):PVDDQ_ABC
 L60 PVDDQ_ABC VCCD012<20> @BASEBOARD_FAB2_LIB.BASEBOARD_FAB2(SCH_1):PVDDQ_ABC
 L58 PVDDQ_ABC VCCD012<19> @BASEBOARD_FAB2_LIB.BASEBOARD_FAB2(SCH_1):PVDDQ_ABC
 L56 PVDDQ_ABC VCCD012<18> @BASEBOARD_FAB2_LIB.BASEBOARD_FAB2(SCH_1):PVDDQ_ABC
 L54 PVDDQ_ABC VCCD012<17> @BASEBOARD_FAB2_LIB.BASEBOARD_FAB2(SCH_1):PVDDQ_ABC
 L52 PVDDQ_ABC VCCD012<16> @BASEBOARD_FAB2_LIB.BASEBOARD_FAB2(SCH_1):PVDDQ_ABC
 L50 PVDDQ_ABC VCCD012<15> @BASEBOARD_FAB2_LIB.BASEBOARD_FAB2(SCH_1):PVDDQ_ABC
 L48 PVDDQ_ABC VCCD012<14> @BASEBOARD_FAB2_LIB.BASEBOARD_FAB2(SCH_1):PVDDQ_ABC
 L46 PVDDQ_ABC VCCD012<13> @BASEBOARD_FAB2_LIB.BASEBOARD_FAB2(SCH_1):PVDDQ_ABC
 E64 PVDDQ_ABC VCCD012<12> @BASEBOARD_FAB2_LIB.BASEBOARD_FAB2(SCH_1):PVDDQ_ABC
 E62 PVDDQ_ABC VCCD012<11> @BASEBOARD_FAB2_LIB.BASEBOARD_FAB2(SCH_1):PVDDQ_ABC
 E60 PVDDQ_ABC VCCD012<10> @BASEBOARD_FAB2_LIB.BASEBOARD_FAB2(SCH_1):PVDDQ_ABC
 E58 PVDDQ_ABC VCCD012<9> @BASEBOARD_FAB2_LIB.BASEBOARD_FAB2(SCH_1):PVDDQ_ABC
 E56 PVDDQ_ABC VCCD012<8> @BASEBOARD_FAB2_LIB.BASEBOARD_FAB2(SCH_1):PVDDQ_ABC
 E54 PVDDQ_ABC VCCD012<7> @BASEBOARD_FAB2_LIB.BASEBOARD_FAB2(SCH_1):PVDDQ_ABC
 E52 PVDDQ_ABC VCCD012<6> @BASEBOARD_FAB2_LIB.BASEBOARD_FAB2(SCH_1):PVDDQ_ABC
 E50 PVDDQ_ABC VCCD012<5> @BASEBOARD_FAB2_LIB.BASEBOARD_FAB2(SCH_1):PVDDQ_ABC
 E48 PVDDQ_ABC VCCD012<4> @BASEBOARD_FAB2_LIB.BASEBOARD_FAB2(SCH_1):PVDDQ_ABC
 E46 PVDDQ_ABC VCCD012<3> @BASEBOARD_FAB2_LIB.BASEBOARD_FAB2(SCH_1):PVDDQ_ABC
 B59 PVDDQ_ABC VCCD012<2> @BASEBOARD_FAB2_LIB.BASEBOARD_FAB2(SCH_1):PVDDQ_ABC
 B53 PVDDQ_ABC VCCD012<1> @BASEBOARD_FAB2_LIB.BASEBOARD_FAB2(SCH_1):PVDDQ_ABC
 B49 PVDDQ_ABC VCCD012<0> @BASEBOARD_FAB2_LIB.BASEBOARD_FAB2(SCH_1):PVDDQ_ABC
EE44 PVDDQ_DEF VCCD345<50> @BASEBOARD_FAB2_LIB.BASEBOARD_FAB2(SCH_1):PVDDQ_DEF
EF45 PVDDQ_DEF VCCD345<49> @BASEBOARD_FAB2_LIB.BASEBOARD_FAB2(SCH_1):PVDDQ_DEF
DB53 PVDDQ_DEF VCCD345<48> @BASEBOARD_FAB2_LIB.BASEBOARD_FAB2(SCH_1):PVDDQ_DEF
DB55 PVDDQ_DEF VCCD345<47> @BASEBOARD_FAB2_LIB.BASEBOARD_FAB2(SCH_1):PVDDQ_DEF
DB57 PVDDQ_DEF VCCD345<46> @BASEBOARD_FAB2_LIB.BASEBOARD_FAB2(SCH_1):PVDDQ_DEF
DB59 PVDDQ_DEF VCCD345<45> @BASEBOARD_FAB2_LIB.BASEBOARD_FAB2(SCH_1):PVDDQ_DEF
DB61 PVDDQ_DEF VCCD345<44> @BASEBOARD_FAB2_LIB.BASEBOARD_FAB2(SCH_1):PVDDQ_DEF
DB63 PVDDQ_DEF VCCD345<43> @BASEBOARD_FAB2_LIB.BASEBOARD_FAB2(SCH_1):PVDDQ_DEF
DD45 PVDDQ_DEF VCCD345<42> @BASEBOARD_FAB2_LIB.BASEBOARD_FAB2(SCH_1):PVDDQ_DEF
DH45 PVDDQ_DEF VCCD345<41> @BASEBOARD_FAB2_LIB.BASEBOARD_FAB2(SCH_1):PVDDQ_DEF
DH47 PVDDQ_DEF VCCD345<40> @BASEBOARD_FAB2_LIB.BASEBOARD_FAB2(SCH_1):PVDDQ_DEF
DH49 PVDDQ_DEF VCCD345<39> @BASEBOARD_FAB2_LIB.BASEBOARD_FAB2(SCH_1):PVDDQ_DEF
DH51 PVDDQ_DEF VCCD345<38> @BASEBOARD_FAB2_LIB.BASEBOARD_FAB2(SCH_1):PVDDQ_DEF
DH53 PVDDQ_DEF VCCD345<37> @BASEBOARD_FAB2_LIB.BASEBOARD_FAB2(SCH_1):PVDDQ_DEF
DH55 PVDDQ_DEF VCCD345<36> @BASEBOARD_FAB2_LIB.BASEBOARD_FAB2(SCH_1):PVDDQ_DEF
DH57 PVDDQ_DEF VCCD345<35> @BASEBOARD_FAB2_LIB.BASEBOARD_FAB2(SCH_1):PVDDQ_DEF
DH59 PVDDQ_DEF VCCD345<34> @BASEBOARD_FAB2_LIB.BASEBOARD_FAB2(SCH_1):PVDDQ_DEF
DH61 PVDDQ_DEF VCCD345<33> @BASEBOARD_FAB2_LIB.BASEBOARD_FAB2(SCH_1):PVDDQ_DEF
DH63 PVDDQ_DEF VCCD345<32> @BASEBOARD_FAB2_LIB.BASEBOARD_FAB2(SCH_1):PVDDQ_DEF
DJ64 PVDDQ_DEF VCCD345<31> @BASEBOARD_FAB2_LIB.BASEBOARD_FAB2(SCH_1):PVDDQ_DEF
DL46 PVDDQ_DEF VCCD345<30> @BASEBOARD_FAB2_LIB.BASEBOARD_FAB2(SCH_1):PVDDQ_DEF
DL48 PVDDQ_DEF VCCD345<29> @BASEBOARD_FAB2_LIB.BASEBOARD_FAB2(SCH_1):PVDDQ_DEF
DL50 PVDDQ_DEF VCCD345<28> @BASEBOARD_FAB2_LIB.BASEBOARD_FAB2(SCH_1):PVDDQ_DEF
DL52 PVDDQ_DEF VCCD345<27> @BASEBOARD_FAB2_LIB.BASEBOARD_FAB2(SCH_1):PVDDQ_DEF
DL54 PVDDQ_DEF VCCD345<26> @BASEBOARD_FAB2_LIB.BASEBOARD_FAB2(SCH_1):PVDDQ_DEF
DL56 PVDDQ_DEF VCCD345<25> @BASEBOARD_FAB2_LIB.BASEBOARD_FAB2(SCH_1):PVDDQ_DEF
DL58 PVDDQ_DEF VCCD345<24> @BASEBOARD_FAB2_LIB.BASEBOARD_FAB2(SCH_1):PVDDQ_DEF
DL60 PVDDQ_DEF VCCD345<23> @BASEBOARD_FAB2_LIB.BASEBOARD_FAB2(SCH_1):PVDDQ_DEF
DL62 PVDDQ_DEF VCCD345<22> @BASEBOARD_FAB2_LIB.BASEBOARD_FAB2(SCH_1):PVDDQ_DEF
DU46 PVDDQ_DEF VCCD345<21> @BASEBOARD_FAB2_LIB.BASEBOARD_FAB2(SCH_1):PVDDQ_DEF
DU48 PVDDQ_DEF VCCD345<20> @BASEBOARD_FAB2_LIB.BASEBOARD_FAB2(SCH_1):PVDDQ_DEF
DU50 PVDDQ_DEF VCCD345<19> @BASEBOARD_FAB2_LIB.BASEBOARD_FAB2(SCH_1):PVDDQ_DEF
DU52 PVDDQ_DEF VCCD345<18> @BASEBOARD_FAB2_LIB.BASEBOARD_FAB2(SCH_1):PVDDQ_DEF
DU54 PVDDQ_DEF VCCD345<17> @BASEBOARD_FAB2_LIB.BASEBOARD_FAB2(SCH_1):PVDDQ_DEF
DU56 PVDDQ_DEF VCCD345<16> @BASEBOARD_FAB2_LIB.BASEBOARD_FAB2(SCH_1):PVDDQ_DEF
DU58 PVDDQ_DEF VCCD345<15> @BASEBOARD_FAB2_LIB.BASEBOARD_FAB2(SCH_1):PVDDQ_DEF
DU60 PVDDQ_DEF VCCD345<14> @BASEBOARD_FAB2_LIB.BASEBOARD_FAB2(SCH_1):PVDDQ_DEF
DU62 PVDDQ_DEF VCCD345<13> @BASEBOARD_FAB2_LIB.BASEBOARD_FAB2(SCH_1):PVDDQ_DEF
DU64 PVDDQ_DEF VCCD345<12> @BASEBOARD_FAB2_LIB.BASEBOARD_FAB2(SCH_1):PVDDQ_DEF
EC46 PVDDQ_DEF VCCD345<11> @BASEBOARD_FAB2_LIB.BASEBOARD_FAB2(SCH_1):PVDDQ_DEF
EC48 PVDDQ_DEF VCCD345<10> @BASEBOARD_FAB2_LIB.BASEBOARD_FAB2(SCH_1):PVDDQ_DEF
EC50 PVDDQ_DEF VCCD345<9> @BASEBOARD_FAB2_LIB.BASEBOARD_FAB2(SCH_1):PVDDQ_DEF
EC52 PVDDQ_DEF VCCD345<8> @BASEBOARD_FAB2_LIB.BASEBOARD_FAB2(SCH_1):PVDDQ_DEF
EC54 PVDDQ_DEF VCCD345<7> @BASEBOARD_FAB2_LIB.BASEBOARD_FAB2(SCH_1):PVDDQ_DEF
EC56 PVDDQ_DEF VCCD345<6> @BASEBOARD_FAB2_LIB.BASEBOARD_FAB2(SCH_1):PVDDQ_DEF
EC58 PVDDQ_DEF VCCD345<5> @BASEBOARD_FAB2_LIB.BASEBOARD_FAB2(SCH_1):PVDDQ_DEF
EC60 PVDDQ_DEF VCCD345<4> @BASEBOARD_FAB2_LIB.BASEBOARD_FAB2(SCH_1):PVDDQ_DEF
EC62 PVDDQ_DEF VCCD345<3> @BASEBOARD_FAB2_LIB.BASEBOARD_FAB2(SCH_1):PVDDQ_DEF
EF49 PVDDQ_DEF VCCD345<2> @BASEBOARD_FAB2_LIB.BASEBOARD_FAB2(SCH_1):PVDDQ_DEF
EF53 PVDDQ_DEF VCCD345<1> @BASEBOARD_FAB2_LIB.BASEBOARD_FAB2(SCH_1):PVDDQ_DEF
EF59 PVDDQ_DEF VCCD345<0> @BASEBOARD_FAB2_LIB.BASEBOARD_FAB2(SCH_1):PVDDQ_DEF

SKX_EXT_B_BGA1-IC,TBD  I34  U5D1
BY27 P1V8_MCP_CPU0 CD_VCCIN<3> @BASEBOARD_FAB2_LIB.BASEBOARD_FAB2(SCH_1):P1V8_MCP_CPU0
BV27 P1V8_MCP_CPU0 CD_VCCIN<2> @BASEBOARD_FAB2_LIB.BASEBOARD_FAB2(SCH_1):P1V8_MCP_CPU0
BU26 P1V8_MCP_CPU0 CD_VCCIN<1> @BASEBOARD_FAB2_LIB.BASEBOARD_FAB2(SCH_1):P1V8_MCP_CPU0
BT27 P1V8_MCP_CPU0 CD_VCCIN<0> @BASEBOARD_FAB2_LIB.BASEBOARD_FAB2(SCH_1):P1V8_MCP_CPU0
BM11 PVCCIOMCP_CPU0 CD_VCCP<15> @BASEBOARD_FAB2_LIB.BASEBOARD_FAB2(SCH_1):PVCCIOMCP_CPU0
BN12 PVCCIOMCP_CPU0 CD_VCCP<14> @BASEBOARD_FAB2_LIB.BASEBOARD_FAB2(SCH_1):PVCCIOMCP_CPU0
BN14 PVCCIOMCP_CPU0 CD_VCCP<13> @BASEBOARD_FAB2_LIB.BASEBOARD_FAB2(SCH_1):PVCCIOMCP_CPU0
BP11 PVCCIOMCP_CPU0 CD_VCCP<12> @BASEBOARD_FAB2_LIB.BASEBOARD_FAB2(SCH_1):PVCCIOMCP_CPU0
BP13 PVCCIOMCP_CPU0 CD_VCCP<11> @BASEBOARD_FAB2_LIB.BASEBOARD_FAB2(SCH_1):PVCCIOMCP_CPU0
BP15 PVCCIOMCP_CPU0 CD_VCCP<10> @BASEBOARD_FAB2_LIB.BASEBOARD_FAB2(SCH_1):PVCCIOMCP_CPU0
BR12 PVCCIOMCP_CPU0 CD_VCCP<9> @BASEBOARD_FAB2_LIB.BASEBOARD_FAB2(SCH_1):PVCCIOMCP_CPU0
BR14 PVCCIOMCP_CPU0 CD_VCCP<8> @BASEBOARD_FAB2_LIB.BASEBOARD_FAB2(SCH_1):PVCCIOMCP_CPU0
BT11 PVCCIOMCP_CPU0 CD_VCCP<7> @BASEBOARD_FAB2_LIB.BASEBOARD_FAB2(SCH_1):PVCCIOMCP_CPU0
BT13 PVCCIOMCP_CPU0 CD_VCCP<6> @BASEBOARD_FAB2_LIB.BASEBOARD_FAB2(SCH_1):PVCCIOMCP_CPU0
BT15 PVCCIOMCP_CPU0 CD_VCCP<5> @BASEBOARD_FAB2_LIB.BASEBOARD_FAB2(SCH_1):PVCCIOMCP_CPU0
BU12 PVCCIOMCP_CPU0 CD_VCCP<4> @BASEBOARD_FAB2_LIB.BASEBOARD_FAB2(SCH_1):PVCCIOMCP_CPU0
BU14 PVCCIOMCP_CPU0 CD_VCCP<3> @BASEBOARD_FAB2_LIB.BASEBOARD_FAB2(SCH_1):PVCCIOMCP_CPU0
BV11 PVCCIOMCP_CPU0 CD_VCCP<2> @BASEBOARD_FAB2_LIB.BASEBOARD_FAB2(SCH_1):PVCCIOMCP_CPU0
BV13 PVCCIOMCP_CPU0 CD_VCCP<1> @BASEBOARD_FAB2_LIB.BASEBOARD_FAB2(SCH_1):PVCCIOMCP_CPU0
BV15 PVCCIOMCP_CPU0 CD_VCCP<0> @BASEBOARD_FAB2_LIB.BASEBOARD_FAB2(SCH_1):PVCCIOMCP_CPU0
BD13 PVCCMCP_CPU0 CD_VCC_CORE<12> @BASEBOARD_FAB2_LIB.BASEBOARD_FAB2(SCH_1):PVCCMCP_CPU0
BE12 PVCCMCP_CPU0 CD_VCC_CORE<11> @BASEBOARD_FAB2_LIB.BASEBOARD_FAB2(SCH_1):PVCCMCP_CPU0
BE14 PVCCMCP_CPU0 CD_VCC_CORE<10> @BASEBOARD_FAB2_LIB.BASEBOARD_FAB2(SCH_1):PVCCMCP_CPU0
BF11 PVCCMCP_CPU0 CD_VCC_CORE<9> @BASEBOARD_FAB2_LIB.BASEBOARD_FAB2(SCH_1):PVCCMCP_CPU0
BF13 PVCCMCP_CPU0 CD_VCC_CORE<8> @BASEBOARD_FAB2_LIB.BASEBOARD_FAB2(SCH_1):PVCCMCP_CPU0
BG12 PVCCMCP_CPU0 CD_VCC_CORE<7> @BASEBOARD_FAB2_LIB.BASEBOARD_FAB2(SCH_1):PVCCMCP_CPU0
BG14 PVCCMCP_CPU0 CD_VCC_CORE<6> @BASEBOARD_FAB2_LIB.BASEBOARD_FAB2(SCH_1):PVCCMCP_CPU0
BH13 PVCCMCP_CPU0 CD_VCC_CORE<5> @BASEBOARD_FAB2_LIB.BASEBOARD_FAB2(SCH_1):PVCCMCP_CPU0
BJ12 PVCCMCP_CPU0 CD_VCC_CORE<4> @BASEBOARD_FAB2_LIB.BASEBOARD_FAB2(SCH_1):PVCCMCP_CPU0
BJ14 PVCCMCP_CPU0 CD_VCC_CORE<3> @BASEBOARD_FAB2_LIB.BASEBOARD_FAB2(SCH_1):PVCCMCP_CPU0
BK13 PVCCMCP_CPU0 CD_VCC_CORE<2> @BASEBOARD_FAB2_LIB.BASEBOARD_FAB2(SCH_1):PVCCMCP_CPU0
BK15 PVCCMCP_CPU0 CD_VCC_CORE<1> @BASEBOARD_FAB2_LIB.BASEBOARD_FAB2(SCH_1):PVCCMCP_CPU0
BL14 PVCCMCP_CPU0 CD_VCC_CORE<0> @BASEBOARD_FAB2_LIB.BASEBOARD_FAB2(SCH_1):PVCCMCP_CPU0
  A8 PVPP_ABC CD_VPP<3> @BASEBOARD_FAB2_LIB.BASEBOARD_FAB2(SCH_1):PVPP_ABC
 A10 PVPP_ABC CD_VPP<2> @BASEBOARD_FAB2_LIB.BASEBOARD_FAB2(SCH_1):PVPP_ABC
 A12 PVPP_ABC CD_VPP<1> @BASEBOARD_FAB2_LIB.BASEBOARD_FAB2(SCH_1):PVPP_ABC
 B11 PVPP_ABC CD_VPP<0> @BASEBOARD_FAB2_LIB.BASEBOARD_FAB2(SCH_1):PVPP_ABC
CY55 P3V3_STBY  VCC33 @BASEBOARD_FAB2_LIB.BASEBOARD_FAB2(SCH_1):P3V3_STBY
AR28 PVCCIO_CPU0 VCCIO<104> @BASEBOARD_FAB2_LIB.BASEBOARD_FAB2(SCH_1):PVCCIO_CPU0
AL28 PVCCIO_CPU0 VCCIO<103> @BASEBOARD_FAB2_LIB.BASEBOARD_FAB2(SCH_1):PVCCIO_CPU0
AM29 PVCCIO_CPU0 VCCIO<102> @BASEBOARD_FAB2_LIB.BASEBOARD_FAB2(SCH_1):PVCCIO_CPU0
AG34 PVCCIO_CPU0 VCCIO<101> @BASEBOARD_FAB2_LIB.BASEBOARD_FAB2(SCH_1):PVCCIO_CPU0
AE34 PVCCIO_CPU0 VCCIO<100> @BASEBOARD_FAB2_LIB.BASEBOARD_FAB2(SCH_1):PVCCIO_CPU0
AD35 PVCCIO_CPU0 VCCIO<99> @BASEBOARD_FAB2_LIB.BASEBOARD_FAB2(SCH_1):PVCCIO_CPU0
AF35 PVCCIO_CPU0 VCCIO<98> @BASEBOARD_FAB2_LIB.BASEBOARD_FAB2(SCH_1):PVCCIO_CPU0
AC36 PVCCIO_CPU0 VCCIO<97> @BASEBOARD_FAB2_LIB.BASEBOARD_FAB2(SCH_1):PVCCIO_CPU0
AD37 PVCCIO_CPU0 VCCIO<96> @BASEBOARD_FAB2_LIB.BASEBOARD_FAB2(SCH_1):PVCCIO_CPU0
AE36 PVCCIO_CPU0 VCCIO<95> @BASEBOARD_FAB2_LIB.BASEBOARD_FAB2(SCH_1):PVCCIO_CPU0
BF27 PVCCIO_CPU0 VCCIO<94> @BASEBOARD_FAB2_LIB.BASEBOARD_FAB2(SCH_1):PVCCIO_CPU0
BG26 PVCCIO_CPU0 VCCIO<93> @BASEBOARD_FAB2_LIB.BASEBOARD_FAB2(SCH_1):PVCCIO_CPU0
BH25 PVCCIO_CPU0 VCCIO<92> @BASEBOARD_FAB2_LIB.BASEBOARD_FAB2(SCH_1):PVCCIO_CPU0
BH27 PVCCIO_CPU0 VCCIO<91> @BASEBOARD_FAB2_LIB.BASEBOARD_FAB2(SCH_1):PVCCIO_CPU0
BJ26 PVCCIO_CPU0 VCCIO<90> @BASEBOARD_FAB2_LIB.BASEBOARD_FAB2(SCH_1):PVCCIO_CPU0
BK25 PVCCIO_CPU0 VCCIO<89> @BASEBOARD_FAB2_LIB.BASEBOARD_FAB2(SCH_1):PVCCIO_CPU0
BK27 PVCCIO_CPU0 VCCIO<88> @BASEBOARD_FAB2_LIB.BASEBOARD_FAB2(SCH_1):PVCCIO_CPU0
BL26 PVCCIO_CPU0 VCCIO<87> @BASEBOARD_FAB2_LIB.BASEBOARD_FAB2(SCH_1):PVCCIO_CPU0
BM27 PVCCIO_CPU0 VCCIO<86> @BASEBOARD_FAB2_LIB.BASEBOARD_FAB2(SCH_1):PVCCIO_CPU0
CH27 PVCCIO_CPU0 VCCIO<85> @BASEBOARD_FAB2_LIB.BASEBOARD_FAB2(SCH_1):PVCCIO_CPU0
CJ28 PVCCIO_CPU0 VCCIO<84> @BASEBOARD_FAB2_LIB.BASEBOARD_FAB2(SCH_1):PVCCIO_CPU0
CC26 PVCCIO_CPU0 VCCIO<83> @BASEBOARD_FAB2_LIB.BASEBOARD_FAB2(SCH_1):PVCCIO_CPU0
CD27 PVCCIO_CPU0 VCCIO<82> @BASEBOARD_FAB2_LIB.BASEBOARD_FAB2(SCH_1):PVCCIO_CPU0
CF27 PVCCIO_CPU0 VCCIO<81> @BASEBOARD_FAB2_LIB.BASEBOARD_FAB2(SCH_1):PVCCIO_CPU0
AV27 PVCCIO_CPU0 VCCIO<80> @BASEBOARD_FAB2_LIB.BASEBOARD_FAB2(SCH_1):PVCCIO_CPU0
AW26 PVCCIO_CPU0 VCCIO<79> @BASEBOARD_FAB2_LIB.BASEBOARD_FAB2(SCH_1):PVCCIO_CPU0
AY27 PVCCIO_CPU0 VCCIO<78> @BASEBOARD_FAB2_LIB.BASEBOARD_FAB2(SCH_1):PVCCIO_CPU0
BA26 PVCCIO_CPU0 VCCIO<77> @BASEBOARD_FAB2_LIB.BASEBOARD_FAB2(SCH_1):PVCCIO_CPU0
BB27 PVCCIO_CPU0 VCCIO<76> @BASEBOARD_FAB2_LIB.BASEBOARD_FAB2(SCH_1):PVCCIO_CPU0
BC26 PVCCIO_CPU0 VCCIO<75> @BASEBOARD_FAB2_LIB.BASEBOARD_FAB2(SCH_1):PVCCIO_CPU0
 W10 PVCCIO_CPU0 VCCIO<74> @BASEBOARD_FAB2_LIB.BASEBOARD_FAB2(SCH_1):PVCCIO_CPU0
 N18 PVCCIO_CPU0 VCCIO<73> @BASEBOARD_FAB2_LIB.BASEBOARD_FAB2(SCH_1):PVCCIO_CPU0
  M9 PVCCIO_CPU0 VCCIO<72> @BASEBOARD_FAB2_LIB.BASEBOARD_FAB2(SCH_1):PVCCIO_CPU0
  M7 PVCCIO_CPU0 VCCIO<71> @BASEBOARD_FAB2_LIB.BASEBOARD_FAB2(SCH_1):PVCCIO_CPU0
 K15 PVCCIO_CPU0 VCCIO<70> @BASEBOARD_FAB2_LIB.BASEBOARD_FAB2(SCH_1):PVCCIO_CPU0
  J2 PVCCIO_CPU0 VCCIO<69> @BASEBOARD_FAB2_LIB.BASEBOARD_FAB2(SCH_1):PVCCIO_CPU0
EB15 PVCCIO_CPU0 VCCIO<68> @BASEBOARD_FAB2_LIB.BASEBOARD_FAB2(SCH_1):PVCCIO_CPU0
EA12 PVCCIO_CPU0 VCCIO<67> @BASEBOARD_FAB2_LIB.BASEBOARD_FAB2(SCH_1):PVCCIO_CPU0
DU20 PVCCIO_CPU0 VCCIO<66> @BASEBOARD_FAB2_LIB.BASEBOARD_FAB2(SCH_1):PVCCIO_CPU0
 DR2 PVCCIO_CPU0 VCCIO<65> @BASEBOARD_FAB2_LIB.BASEBOARD_FAB2(SCH_1):PVCCIO_CPU0
DR10 PVCCIO_CPU0 VCCIO<64> @BASEBOARD_FAB2_LIB.BASEBOARD_FAB2(SCH_1):PVCCIO_CPU0
DP19 PVCCIO_CPU0 VCCIO<63> @BASEBOARD_FAB2_LIB.BASEBOARD_FAB2(SCH_1):PVCCIO_CPU0
 DN8 PVCCIO_CPU0 VCCIO<62> @BASEBOARD_FAB2_LIB.BASEBOARD_FAB2(SCH_1):PVCCIO_CPU0
DM17 PVCCIO_CPU0 VCCIO<61> @BASEBOARD_FAB2_LIB.BASEBOARD_FAB2(SCH_1):PVCCIO_CPU0
DJ16 PVCCIO_CPU0 VCCIO<60> @BASEBOARD_FAB2_LIB.BASEBOARD_FAB2(SCH_1):PVCCIO_CPU0
 H13 PVCCIO_CPU0 VCCIO<59> @BASEBOARD_FAB2_LIB.BASEBOARD_FAB2(SCH_1):PVCCIO_CPU0
 J10 PVCCIO_CPU0 VCCIO<58> @BASEBOARD_FAB2_LIB.BASEBOARD_FAB2(SCH_1):PVCCIO_CPU0
 L14 PVCCIO_CPU0 VCCIO<57> @BASEBOARD_FAB2_LIB.BASEBOARD_FAB2(SCH_1):PVCCIO_CPU0
 L16 PVCCIO_CPU0 VCCIO<56> @BASEBOARD_FAB2_LIB.BASEBOARD_FAB2(SCH_1):PVCCIO_CPU0
 DH7 PVCCIO_CPU0 VCCIO<55> @BASEBOARD_FAB2_LIB.BASEBOARD_FAB2(SCH_1):PVCCIO_CPU0
 DG8 PVCCIO_CPU0 VCCIO<54> @BASEBOARD_FAB2_LIB.BASEBOARD_FAB2(SCH_1):PVCCIO_CPU0
 M11 PVCCIO_CPU0 VCCIO<53> @BASEBOARD_FAB2_LIB.BASEBOARD_FAB2(SCH_1):PVCCIO_CPU0
 M21 PVCCIO_CPU0 VCCIO<52> @BASEBOARD_FAB2_LIB.BASEBOARD_FAB2(SCH_1):PVCCIO_CPU0
  P5 PVCCIO_CPU0 VCCIO<51> @BASEBOARD_FAB2_LIB.BASEBOARD_FAB2(SCH_1):PVCCIO_CPU0
  T3 PVCCIO_CPU0 VCCIO<50> @BASEBOARD_FAB2_LIB.BASEBOARD_FAB2(SCH_1):PVCCIO_CPU0
 U14 PVCCIO_CPU0 VCCIO<49> @BASEBOARD_FAB2_LIB.BASEBOARD_FAB2(SCH_1):PVCCIO_CPU0
DF21 PVCCIO_CPU0 VCCIO<48> @BASEBOARD_FAB2_LIB.BASEBOARD_FAB2(SCH_1):PVCCIO_CPU0
  W4 PVCCIO_CPU0 VCCIO<47> @BASEBOARD_FAB2_LIB.BASEBOARD_FAB2(SCH_1):PVCCIO_CPU0
  W6 PVCCIO_CPU0 VCCIO<46> @BASEBOARD_FAB2_LIB.BASEBOARD_FAB2(SCH_1):PVCCIO_CPU0
AA10 PVCCIO_CPU0 VCCIO<45> @BASEBOARD_FAB2_LIB.BASEBOARD_FAB2(SCH_1):PVCCIO_CPU0
AC20 PVCCIO_CPU0 VCCIO<44> @BASEBOARD_FAB2_LIB.BASEBOARD_FAB2(SCH_1):PVCCIO_CPU0
 AC4 PVCCIO_CPU0 VCCIO<43> @BASEBOARD_FAB2_LIB.BASEBOARD_FAB2(SCH_1):PVCCIO_CPU0
 AH9 PVCCIO_CPU0 VCCIO<42> @BASEBOARD_FAB2_LIB.BASEBOARD_FAB2(SCH_1):PVCCIO_CPU0
DF13 PVCCIO_CPU0 VCCIO<41> @BASEBOARD_FAB2_LIB.BASEBOARD_FAB2(SCH_1):PVCCIO_CPU0
AN10 PVCCIO_CPU0 VCCIO<40> @BASEBOARD_FAB2_LIB.BASEBOARD_FAB2(SCH_1):PVCCIO_CPU0
 DD7 PVCCIO_CPU0 VCCIO<39> @BASEBOARD_FAB2_LIB.BASEBOARD_FAB2(SCH_1):PVCCIO_CPU0
AT11 PVCCIO_CPU0 VCCIO<38> @BASEBOARD_FAB2_LIB.BASEBOARD_FAB2(SCH_1):PVCCIO_CPU0
 AW6 PVCCIO_CPU0 VCCIO<37> @BASEBOARD_FAB2_LIB.BASEBOARD_FAB2(SCH_1):PVCCIO_CPU0
AY11 PVCCIO_CPU0 VCCIO<36> @BASEBOARD_FAB2_LIB.BASEBOARD_FAB2(SCH_1):PVCCIO_CPU0
BA24 PVCCIO_CPU0 VCCIO<35> @BASEBOARD_FAB2_LIB.BASEBOARD_FAB2(SCH_1):PVCCIO_CPU0
 BB5 PVCCIO_CPU0 VCCIO<34> @BASEBOARD_FAB2_LIB.BASEBOARD_FAB2(SCH_1):PVCCIO_CPU0
DA14 PVCCIO_CPU0 VCCIO<33> @BASEBOARD_FAB2_LIB.BASEBOARD_FAB2(SCH_1):PVCCIO_CPU0
BF23 PVCCIO_CPU0 VCCIO<32> @BASEBOARD_FAB2_LIB.BASEBOARD_FAB2(SCH_1):PVCCIO_CPU0
BJ24 PVCCIO_CPU0 VCCIO<31> @BASEBOARD_FAB2_LIB.BASEBOARD_FAB2(SCH_1):PVCCIO_CPU0
BP25 PVCCIO_CPU0 VCCIO<30> @BASEBOARD_FAB2_LIB.BASEBOARD_FAB2(SCH_1):PVCCIO_CPU0
CB13 PVCCIO_CPU0 VCCIO<29> @BASEBOARD_FAB2_LIB.BASEBOARD_FAB2(SCH_1):PVCCIO_CPU0
CB17 PVCCIO_CPU0 VCCIO<28> @BASEBOARD_FAB2_LIB.BASEBOARD_FAB2(SCH_1):PVCCIO_CPU0
 CD9 PVCCIO_CPU0 VCCIO<27> @BASEBOARD_FAB2_LIB.BASEBOARD_FAB2(SCH_1):PVCCIO_CPU0
CE18 PVCCIO_CPU0 VCCIO<26> @BASEBOARD_FAB2_LIB.BASEBOARD_FAB2(SCH_1):PVCCIO_CPU0
  D7 PVCCIO_CPU0 VCCIO<25> @BASEBOARD_FAB2_LIB.BASEBOARD_FAB2(SCH_1):PVCCIO_CPU0
 CH9 PVCCIO_CPU0 VCCIO<24> @BASEBOARD_FAB2_LIB.BASEBOARD_FAB2(SCH_1):PVCCIO_CPU0
 CV7 PVCCIO_CPU0 VCCIO<23> @BASEBOARD_FAB2_LIB.BASEBOARD_FAB2(SCH_1):PVCCIO_CPU0
 CK5 PVCCIO_CPU0 VCCIO<22> @BASEBOARD_FAB2_LIB.BASEBOARD_FAB2(SCH_1):PVCCIO_CPU0
CL12 PVCCIO_CPU0 VCCIO<21> @BASEBOARD_FAB2_LIB.BASEBOARD_FAB2(SCH_1):PVCCIO_CPU0
CM15 PVCCIO_CPU0 VCCIO<20> @BASEBOARD_FAB2_LIB.BASEBOARD_FAB2(SCH_1):PVCCIO_CPU0
CB65 PVSA_CPU0 VCCSA<25> @BASEBOARD_FAB2_LIB.BASEBOARD_FAB2(SCH_1):PVSA_CPU0
CB67 PVSA_CPU0 VCCSA<24> @BASEBOARD_FAB2_LIB.BASEBOARD_FAB2(SCH_1):PVSA_CPU0
CB69 PVSA_CPU0 VCCSA<23> @BASEBOARD_FAB2_LIB.BASEBOARD_FAB2(SCH_1):PVSA_CPU0
CC66 PVSA_CPU0 VCCSA<22> @BASEBOARD_FAB2_LIB.BASEBOARD_FAB2(SCH_1):PVSA_CPU0
CC68 PVSA_CPU0 VCCSA<21> @BASEBOARD_FAB2_LIB.BASEBOARD_FAB2(SCH_1):PVSA_CPU0
CC70 PVSA_CPU0 VCCSA<20> @BASEBOARD_FAB2_LIB.BASEBOARD_FAB2(SCH_1):PVSA_CPU0
CD65 PVSA_CPU0 VCCSA<19> @BASEBOARD_FAB2_LIB.BASEBOARD_FAB2(SCH_1):PVSA_CPU0
CD67 PVSA_CPU0 VCCSA<18> @BASEBOARD_FAB2_LIB.BASEBOARD_FAB2(SCH_1):PVSA_CPU0
CD69 PVSA_CPU0 VCCSA<17> @BASEBOARD_FAB2_LIB.BASEBOARD_FAB2(SCH_1):PVSA_CPU0
CD71 PVSA_CPU0 VCCSA<16> @BASEBOARD_FAB2_LIB.BASEBOARD_FAB2(SCH_1):PVSA_CPU0
CE64 PVSA_CPU0 VCCSA<15> @BASEBOARD_FAB2_LIB.BASEBOARD_FAB2(SCH_1):PVSA_CPU0
CE66 PVSA_CPU0 VCCSA<14> @BASEBOARD_FAB2_LIB.BASEBOARD_FAB2(SCH_1):PVSA_CPU0
CE68 PVSA_CPU0 VCCSA<13> @BASEBOARD_FAB2_LIB.BASEBOARD_FAB2(SCH_1):PVSA_CPU0
CE72 PVSA_CPU0 VCCSA<12> @BASEBOARD_FAB2_LIB.BASEBOARD_FAB2(SCH_1):PVSA_CPU0
CE74 PVSA_CPU0 VCCSA<11> @BASEBOARD_FAB2_LIB.BASEBOARD_FAB2(SCH_1):PVSA_CPU0
CF65 PVSA_CPU0 VCCSA<10> @BASEBOARD_FAB2_LIB.BASEBOARD_FAB2(SCH_1):PVSA_CPU0
CF67 PVSA_CPU0 VCCSA<9> @BASEBOARD_FAB2_LIB.BASEBOARD_FAB2(SCH_1):PVSA_CPU0
CF73 PVSA_CPU0 VCCSA<8> @BASEBOARD_FAB2_LIB.BASEBOARD_FAB2(SCH_1):PVSA_CPU0
CF75 PVSA_CPU0 VCCSA<7> @BASEBOARD_FAB2_LIB.BASEBOARD_FAB2(SCH_1):PVSA_CPU0
CG64 PVSA_CPU0 VCCSA<6> @BASEBOARD_FAB2_LIB.BASEBOARD_FAB2(SCH_1):PVSA_CPU0
CG66 PVSA_CPU0 VCCSA<5> @BASEBOARD_FAB2_LIB.BASEBOARD_FAB2(SCH_1):PVSA_CPU0
CG74 PVSA_CPU0 VCCSA<4> @BASEBOARD_FAB2_LIB.BASEBOARD_FAB2(SCH_1):PVSA_CPU0
CH65 PVSA_CPU0 VCCSA<3> @BASEBOARD_FAB2_LIB.BASEBOARD_FAB2(SCH_1):PVSA_CPU0
CH75 PVSA_CPU0 VCCSA<2> @BASEBOARD_FAB2_LIB.BASEBOARD_FAB2(SCH_1):PVSA_CPU0
CJ64 PVSA_CPU0 VCCSA<1> @BASEBOARD_FAB2_LIB.BASEBOARD_FAB2(SCH_1):PVSA_CPU0
CJ66 PVSA_CPU0 VCCSA<0> @BASEBOARD_FAB2_LIB.BASEBOARD_FAB2(SCH_1):PVSA_CPU0


DRAWING: @BASEBOARD_FAB2_LIB.BASEBOARD_FAB2(SCH_1):PAGE39 

SKX_EXT_B_BGA1-IC,TBD  I127  U5D1
BT17 VSENSE_PVCCIOMCP_CPU0_SKT_VSEN CD_VCCP_SENSE<1> @BASEBOARD_FAB2_LIB.BASEBOARD_FAB2(SCH_1):VSENSE_PVCCIOMCP_CPU0_SKT_VSEN
BU16 VSENSE_PVCCIOMCP_CPU0_SKT_VRTN CD_VCCP_SENSE<0> @BASEBOARD_FAB2_LIB.BASEBOARD_FAB2(SCH_1):VSENSE_PVCCIOMCP_CPU0_SKT_VRTN
BN16 VSENSE_PVCCMCP_CPU0_SKT_VSEN CD_VCC_CORE_SENSE @BASEBOARD_FAB2_LIB.BASEBOARD_FAB2(SCH_1):VSENSE_PVCCMCP_CPU0_SKT_VSEN
BL16 VSENSE_PVCCMCP_CPU0_SKT_VRTN CD_VSS_VCC_CORE_SENSE @BASEBOARD_FAB2_LIB.BASEBOARD_FAB2(SCH_1):VSENSE_PVCCMCP_CPU0_SKT_VRTN
CL26 PVCCMCP_CPU0 RSVD<80> @BASEBOARD_FAB2_LIB.BASEBOARD_FAB2(SCH_1):PVCCMCP_CPU0
CM23 PVCCMCP_CPU0 RSVD<79> @BASEBOARD_FAB2_LIB.BASEBOARD_FAB2(SCH_1):PVCCMCP_CPU0
CM25 PVCCMCP_CPU0 RSVD<78> @BASEBOARD_FAB2_LIB.BASEBOARD_FAB2(SCH_1):PVCCMCP_CPU0
CN22 TP_CPU0_KTI2_AMONV RSVD<77> @BASEBOARD_FAB2_LIB.BASEBOARD_FAB2(SCH_1):TP_CPU0_KTI2_AMONV
CN24 PVCCMCP_CPU0 RSVD<76> @BASEBOARD_FAB2_LIB.BASEBOARD_FAB2(SCH_1):PVCCMCP_CPU0
CN28 PD_CPU0_MCP01_DMON RSVD<75> @BASEBOARD_FAB2_LIB.BASEBOARD_FAB2(SCH_1):PD_CPU0_MCP01_DMON
CP23 PVCCMCP_CPU0 RSVD<74> @BASEBOARD_FAB2_LIB.BASEBOARD_FAB2(SCH_1):PVCCMCP_CPU0
CP31 TP_CPU0_RSVD_73 RSVD<73> @BASEBOARD_FAB2_LIB.BASEBOARD_FAB2(SCH_1):TP_CPU0_RSVD_73
CR60 TP_CPU0_RSVD_72 RSVD<72> @BASEBOARD_FAB2_LIB.BASEBOARD_FAB2(SCH_1):TP_CPU0_RSVD_72
CT23 PVCCMCP_CPU0 RSVD<71> @BASEBOARD_FAB2_LIB.BASEBOARD_FAB2(SCH_1):PVCCMCP_CPU0
 CT5 TP_CPU0_RSVD_70 RSVD<70> @BASEBOARD_FAB2_LIB.BASEBOARD_FAB2(SCH_1):TP_CPU0_RSVD_70
CT69 TP_CPU0_RSVD_69 RSVD<69> @BASEBOARD_FAB2_LIB.BASEBOARD_FAB2(SCH_1):TP_CPU0_RSVD_69
CU24 PVCCMCP_CPU0 RSVD<68> @BASEBOARD_FAB2_LIB.BASEBOARD_FAB2(SCH_1):PVCCMCP_CPU0
 CU6 TP_CPU0_RSVD_67 RSVD<67> @BASEBOARD_FAB2_LIB.BASEBOARD_FAB2(SCH_1):TP_CPU0_RSVD_67
CU60 TP_CPU0_RSVD_66 RSVD<66> @BASEBOARD_FAB2_LIB.BASEBOARD_FAB2(SCH_1):TP_CPU0_RSVD_66
CV23 PVCCMCP_CPU0 RSVD<65> @BASEBOARD_FAB2_LIB.BASEBOARD_FAB2(SCH_1):PVCCMCP_CPU0
CV69 TP_CPU0_RSVD_64 RSVD<64> @BASEBOARD_FAB2_LIB.BASEBOARD_FAB2(SCH_1):TP_CPU0_RSVD_64
CW22 TP_CPU0_KTI2_DFX_DN RSVD<63> @BASEBOARD_FAB2_LIB.BASEBOARD_FAB2(SCH_1):TP_CPU0_KTI2_DFX_DN
CW24 PVCCMCP_CPU0 RSVD<62> @BASEBOARD_FAB2_LIB.BASEBOARD_FAB2(SCH_1):PVCCMCP_CPU0
CW60 TP_CPU0_RSVD_61 RSVD<61> @BASEBOARD_FAB2_LIB.BASEBOARD_FAB2(SCH_1):TP_CPU0_RSVD_61
CW62 TP_CPU0_RSVD_60 RSVD<60> @BASEBOARD_FAB2_LIB.BASEBOARD_FAB2(SCH_1):TP_CPU0_RSVD_60
CY23 TP_CPU0_RSVD_59 RSVD<59> @BASEBOARD_FAB2_LIB.BASEBOARD_FAB2(SCH_1):TP_CPU0_RSVD_59
CY25 PVCCMCP_CPU0 RSVD<58> @BASEBOARD_FAB2_LIB.BASEBOARD_FAB2(SCH_1):PVCCMCP_CPU0
CY39 TP_CPU0_RSVD_57 RSVD<57> @BASEBOARD_FAB2_LIB.BASEBOARD_FAB2(SCH_1):TP_CPU0_RSVD_57
CY53 TP_CPU0_RSVD_56 RSVD<56> @BASEBOARD_FAB2_LIB.BASEBOARD_FAB2(SCH_1):TP_CPU0_RSVD_56
CY57 TP_CPU0_RSVD_55 RSVD<55> @BASEBOARD_FAB2_LIB.BASEBOARD_FAB2(SCH_1):TP_CPU0_RSVD_55
CY63 TP_CPU0_RSVD_54 RSVD<54> @BASEBOARD_FAB2_LIB.BASEBOARD_FAB2(SCH_1):TP_CPU0_RSVD_54
CY73 TP_CPU0_RSVD_53 RSVD<53> @BASEBOARD_FAB2_LIB.BASEBOARD_FAB2(SCH_1):TP_CPU0_RSVD_53
DA24 PVCCMCP_CPU0 RSVD<52> @BASEBOARD_FAB2_LIB.BASEBOARD_FAB2(SCH_1):PVCCMCP_CPU0
DA40 TP_CPU0_RSVD_51 RSVD<51> @BASEBOARD_FAB2_LIB.BASEBOARD_FAB2(SCH_1):TP_CPU0_RSVD_51
DA52 TP_CPU0_RSVD_50 RSVD<50> @BASEBOARD_FAB2_LIB.BASEBOARD_FAB2(SCH_1):TP_CPU0_RSVD_50
DA54 TP_CPU0_RSVD_49 RSVD<49> @BASEBOARD_FAB2_LIB.BASEBOARD_FAB2(SCH_1):TP_CPU0_RSVD_49
DA56 TP_CPU0_RSVD_48 RSVD<48> @BASEBOARD_FAB2_LIB.BASEBOARD_FAB2(SCH_1):TP_CPU0_RSVD_48
DC46 TP_CPU0_RSVD_47 RSVD<47> @BASEBOARD_FAB2_LIB.BASEBOARD_FAB2(SCH_1):TP_CPU0_RSVD_47
DC52 TP_CPU0_RSVD_46 RSVD<46> @BASEBOARD_FAB2_LIB.BASEBOARD_FAB2(SCH_1):TP_CPU0_RSVD_46
DD51 TP_CPU0_RSVD_45 RSVD<45> @BASEBOARD_FAB2_LIB.BASEBOARD_FAB2(SCH_1):TP_CPU0_RSVD_45
DG36 TP_CPU0_RSVD_44 RSVD<44> @BASEBOARD_FAB2_LIB.BASEBOARD_FAB2(SCH_1):TP_CPU0_RSVD_44
DG64 TP_CPU0_RSVD_43 RSVD<43> @BASEBOARD_FAB2_LIB.BASEBOARD_FAB2(SCH_1):TP_CPU0_RSVD_43
DH65 TP_CPU0_RSVD_42 RSVD<42> @BASEBOARD_FAB2_LIB.BASEBOARD_FAB2(SCH_1):TP_CPU0_RSVD_42
DJ36 TP_CPU0_RSVD_41 RSVD<41> @BASEBOARD_FAB2_LIB.BASEBOARD_FAB2(SCH_1):TP_CPU0_RSVD_41
DJ66 TP_CPU0_RSVD_40 RSVD<40> @BASEBOARD_FAB2_LIB.BASEBOARD_FAB2(SCH_1):TP_CPU0_RSVD_40
DK15 TP_CPU0_RSVD_39 RSVD<39> @BASEBOARD_FAB2_LIB.BASEBOARD_FAB2(SCH_1):TP_CPU0_RSVD_39
DK37 TP_CPU0_RSVD_38 RSVD<38> @BASEBOARD_FAB2_LIB.BASEBOARD_FAB2(SCH_1):TP_CPU0_RSVD_38
DK65 TP_CPU0_RSVD_37 RSVD<37> @BASEBOARD_FAB2_LIB.BASEBOARD_FAB2(SCH_1):TP_CPU0_RSVD_37
DK67 TP_CPU0_RSVD_36 RSVD<36> @BASEBOARD_FAB2_LIB.BASEBOARD_FAB2(SCH_1):TP_CPU0_RSVD_36
DL38 TP_CPU0_RSVD_35 RSVD<35> @BASEBOARD_FAB2_LIB.BASEBOARD_FAB2(SCH_1):TP_CPU0_RSVD_35
DL66 TP_CPU0_RSVD_34 RSVD<34> @BASEBOARD_FAB2_LIB.BASEBOARD_FAB2(SCH_1):TP_CPU0_RSVD_34
DM67 TP_CPU0_RSVD_33 RSVD<33> @BASEBOARD_FAB2_LIB.BASEBOARD_FAB2(SCH_1):TP_CPU0_RSVD_33
DN62 TP_CPU0_RSVD_32 RSVD<32> @BASEBOARD_FAB2_LIB.BASEBOARD_FAB2(SCH_1):TP_CPU0_RSVD_32
DN66 TP_CPU0_RSVD_31 RSVD<31> @BASEBOARD_FAB2_LIB.BASEBOARD_FAB2(SCH_1):TP_CPU0_RSVD_31
DP17 TP_CPU0_RSVD_30 RSVD<30> @BASEBOARD_FAB2_LIB.BASEBOARD_FAB2(SCH_1):TP_CPU0_RSVD_30
DP65 TP_CPU0_RSVD_29 RSVD<29> @BASEBOARD_FAB2_LIB.BASEBOARD_FAB2(SCH_1):TP_CPU0_RSVD_29
DR44 TP_CPU0_RSVD_28 RSVD<28> @BASEBOARD_FAB2_LIB.BASEBOARD_FAB2(SCH_1):TP_CPU0_RSVD_28
DT71 TP_CPU0_RSVD_27 RSVD<27> @BASEBOARD_FAB2_LIB.BASEBOARD_FAB2(SCH_1):TP_CPU0_RSVD_27
DU44 TP_CPU0_RSVD_26 RSVD<26> @BASEBOARD_FAB2_LIB.BASEBOARD_FAB2(SCH_1):TP_CPU0_RSVD_26
DV61 TP_CPU0_RSVD_25 RSVD<25> @BASEBOARD_FAB2_LIB.BASEBOARD_FAB2(SCH_1):TP_CPU0_RSVD_25
DV71 TP_CPU0_RSVD_24 RSVD<24> @BASEBOARD_FAB2_LIB.BASEBOARD_FAB2(SCH_1):TP_CPU0_RSVD_24
DW44 TP_CPU0_RSVD_23 RSVD<23> @BASEBOARD_FAB2_LIB.BASEBOARD_FAB2(SCH_1):TP_CPU0_RSVD_23
DW46 TP_CPU0_RSVD_22 RSVD<22> @BASEBOARD_FAB2_LIB.BASEBOARD_FAB2(SCH_1):TP_CPU0_RSVD_22
 DY3 TP_CPU0_RSVD_21 RSVD<21> @BASEBOARD_FAB2_LIB.BASEBOARD_FAB2(SCH_1):TP_CPU0_RSVD_21
 EA4 TP_CPU0_RSVD_20 RSVD<20> @BASEBOARD_FAB2_LIB.BASEBOARD_FAB2(SCH_1):TP_CPU0_RSVD_20
EA44 TP_CPU0_RSVD_19 RSVD<19> @BASEBOARD_FAB2_LIB.BASEBOARD_FAB2(SCH_1):TP_CPU0_RSVD_19
 EB3 TP_CPU0_RSVD_18 RSVD<18> @BASEBOARD_FAB2_LIB.BASEBOARD_FAB2(SCH_1):TP_CPU0_RSVD_18
 EB5 TP_CPU0_RSVD_17 RSVD<17> @BASEBOARD_FAB2_LIB.BASEBOARD_FAB2(SCH_1):TP_CPU0_RSVD_17
EB85 TP_CPU0_RSVD_16 RSVD<16> @BASEBOARD_FAB2_LIB.BASEBOARD_FAB2(SCH_1):TP_CPU0_RSVD_16
EC16 TP_CPU0_RSVD_15 RSVD<15> @BASEBOARD_FAB2_LIB.BASEBOARD_FAB2(SCH_1):TP_CPU0_RSVD_15
 EC4 TP_CPU0_RSVD_14 RSVD<14> @BASEBOARD_FAB2_LIB.BASEBOARD_FAB2(SCH_1):TP_CPU0_RSVD_14
EC44 TP_CPU0_RSVD_13 RSVD<13> @BASEBOARD_FAB2_LIB.BASEBOARD_FAB2(SCH_1):TP_CPU0_RSVD_13
EC84 TP_CPU0_RSVD_12 RSVD<12> @BASEBOARD_FAB2_LIB.BASEBOARD_FAB2(SCH_1):TP_CPU0_RSVD_12
ED45 TP_CPU0_RSVD_11 RSVD<11> @BASEBOARD_FAB2_LIB.BASEBOARD_FAB2(SCH_1):TP_CPU0_RSVD_11
 ED5 TP_CPU0_RSVD_10 RSVD<10> @BASEBOARD_FAB2_LIB.BASEBOARD_FAB2(SCH_1):TP_CPU0_RSVD_10
ED83 TP_CPU0_RSVD_9 RSVD<9> @BASEBOARD_FAB2_LIB.BASEBOARD_FAB2(SCH_1):TP_CPU0_RSVD_9
EE16 TP_CPU0_RSVD_8 RSVD<8> @BASEBOARD_FAB2_LIB.BASEBOARD_FAB2(SCH_1):TP_CPU0_RSVD_8
EE46 TP_CPU0_RSVD_7 RSVD<7> @BASEBOARD_FAB2_LIB.BASEBOARD_FAB2(SCH_1):TP_CPU0_RSVD_7
 EE6 TP_CPU0_RSVD_6 RSVD<6> @BASEBOARD_FAB2_LIB.BASEBOARD_FAB2(SCH_1):TP_CPU0_RSVD_6
EE82 TP_CPU0_RSVD_5 RSVD<5> @BASEBOARD_FAB2_LIB.BASEBOARD_FAB2(SCH_1):TP_CPU0_RSVD_5
EE84 TP_CPU0_RSVD_4 RSVD<4> @BASEBOARD_FAB2_LIB.BASEBOARD_FAB2(SCH_1):TP_CPU0_RSVD_4
EF47 TP_CPU0_RSVD_3 RSVD<3> @BASEBOARD_FAB2_LIB.BASEBOARD_FAB2(SCH_1):TP_CPU0_RSVD_3
EF77 TP_CPU0_RSVD_2 RSVD<2> @BASEBOARD_FAB2_LIB.BASEBOARD_FAB2(SCH_1):TP_CPU0_RSVD_2
EF81 TP_CPU0_RSVD_1 RSVD<1> @BASEBOARD_FAB2_LIB.BASEBOARD_FAB2(SCH_1):TP_CPU0_RSVD_1
EF83 TP_CPU0_RSVD_0 RSVD<0> @BASEBOARD_FAB2_LIB.BASEBOARD_FAB2(SCH_1):TP_CPU0_RSVD_0
 CN6 PVCCIO_CPU0 VCCIO<19> @BASEBOARD_FAB2_LIB.BASEBOARD_FAB2(SCH_1):PVCCIO_CPU0
CU12 PVCCIO_CPU0 VCCIO<18> @BASEBOARD_FAB2_LIB.BASEBOARD_FAB2(SCH_1):PVCCIO_CPU0
CV21 PVCCIO_CPU0 VCCIO<17> @BASEBOARD_FAB2_LIB.BASEBOARD_FAB2(SCH_1):PVCCIO_CPU0
CU18 PVCCIO_CPU0 VCCIO<16> @BASEBOARD_FAB2_LIB.BASEBOARD_FAB2(SCH_1):PVCCIO_CPU0
CY17 PVCCIO_CPU0 VCCIO<15> @BASEBOARD_FAB2_LIB.BASEBOARD_FAB2(SCH_1):PVCCIO_CPU0
DC18 PVCCIO_CPU0 VCCIO<14> @BASEBOARD_FAB2_LIB.BASEBOARD_FAB2(SCH_1):PVCCIO_CPU0
DE14 PVCCIO_CPU0 VCCIO<13> @BASEBOARD_FAB2_LIB.BASEBOARD_FAB2(SCH_1):PVCCIO_CPU0
CP13 PVCCIO_CPU0 VCCIO<12> @BASEBOARD_FAB2_LIB.BASEBOARD_FAB2(SCH_1):PVCCIO_CPU0
CL20 PVCCIO_CPU0 VCCIO<11> @BASEBOARD_FAB2_LIB.BASEBOARD_FAB2(SCH_1):PVCCIO_CPU0
CG14 PVCCIO_CPU0 VCCIO<10> @BASEBOARD_FAB2_LIB.BASEBOARD_FAB2(SCH_1):PVCCIO_CPU0
 CF5 PVCCIO_CPU0 VCCIO<9> @BASEBOARD_FAB2_LIB.BASEBOARD_FAB2(SCH_1):PVCCIO_CPU0
DK21 PVCCIO_CPU0 VCCIO<8> @BASEBOARD_FAB2_LIB.BASEBOARD_FAB2(SCH_1):PVCCIO_CPU0
BE24 PVCCIO_CPU0 VCCIO<7> @BASEBOARD_FAB2_LIB.BASEBOARD_FAB2(SCH_1):PVCCIO_CPU0
 AT7 PVCCIO_CPU0 VCCIO<6> @BASEBOARD_FAB2_LIB.BASEBOARD_FAB2(SCH_1):PVCCIO_CPU0
 AT5 PVCCIO_CPU0 VCCIO<5> @BASEBOARD_FAB2_LIB.BASEBOARD_FAB2(SCH_1):PVCCIO_CPU0
 AM5 PVCCIO_CPU0 VCCIO<4> @BASEBOARD_FAB2_LIB.BASEBOARD_FAB2(SCH_1):PVCCIO_CPU0
DV11 PVCCIO_CPU0 VCCIO<3> @BASEBOARD_FAB2_LIB.BASEBOARD_FAB2(SCH_1):PVCCIO_CPU0
 AF5 PVCCIO_CPU0 VCCIO<2> @BASEBOARD_FAB2_LIB.BASEBOARD_FAB2(SCH_1):PVCCIO_CPU0
AE10 PVCCIO_CPU0 VCCIO<1> @BASEBOARD_FAB2_LIB.BASEBOARD_FAB2(SCH_1):PVCCIO_CPU0
EE10 PVCCIO_CPU0 VCCIO<0> @BASEBOARD_FAB2_LIB.BASEBOARD_FAB2(SCH_1):PVCCIO_CPU0
 BH5 VSENSE_PVCCIO_CPU0_SKT_VSEN VCCIO_SENSE @BASEBOARD_FAB2_LIB.BASEBOARD_FAB2(SCH_1):VSENSE_PVCCIO_CPU0_SKT_VSEN
CE76 VSENSE_PVSA_CPU0_SKT_VSEN VCCSA_SENSE @BASEBOARD_FAB2_LIB.BASEBOARD_FAB2(SCH_1):VSENSE_PVSA_CPU0_SKT_VSEN
 BF5 VSENSE_PVCCIO_CPU0_SKT_VRTN VSS_VCCIO_SENSE @BASEBOARD_FAB2_LIB.BASEBOARD_FAB2(SCH_1):VSENSE_PVCCIO_CPU0_SKT_VRTN
CG76 VSENSE_PVSA_CPU0_SKT_VRTN VSS_VCCSA_SENSE @BASEBOARD_FAB2_LIB.BASEBOARD_FAB2(SCH_1):VSENSE_PVSA_CPU0_SKT_VRTN


DRAWING: @BASEBOARD_FAB2_LIB.BASEBOARD_FAB2(SCH_1):PAGE40 

SKX_EXT_B_BGA1-IC,TBD  I20  U5D1
  B9    GND VSS<1253> @BASEBOARD_FAB2_LIB.BASEBOARD_FAB2(SCH_1):GND
 A42    GND VSS<1252> @BASEBOARD_FAB2_LIB.BASEBOARD_FAB2(SCH_1):GND
 B43    GND VSS<1251> @BASEBOARD_FAB2_LIB.BASEBOARD_FAB2(SCH_1):GND
  B5    GND VSS<1250> @BASEBOARD_FAB2_LIB.BASEBOARD_FAB2(SCH_1):GND
 B79    GND VSS<1249> @BASEBOARD_FAB2_LIB.BASEBOARD_FAB2(SCH_1):GND
  C4    GND VSS<1248> @BASEBOARD_FAB2_LIB.BASEBOARD_FAB2(SCH_1):GND
 C80    GND VSS<1247> @BASEBOARD_FAB2_LIB.BASEBOARD_FAB2(SCH_1):GND
  D3    GND VSS<1246> @BASEBOARD_FAB2_LIB.BASEBOARD_FAB2(SCH_1):GND
 D81    GND VSS<1245> @BASEBOARD_FAB2_LIB.BASEBOARD_FAB2(SCH_1):GND
 E82    GND VSS<1244> @BASEBOARD_FAB2_LIB.BASEBOARD_FAB2(SCH_1):GND
 J86    GND VSS<1243> @BASEBOARD_FAB2_LIB.BASEBOARD_FAB2(SCH_1):GND
DY85    GND VSS<1242> @BASEBOARD_FAB2_LIB.BASEBOARD_FAB2(SCH_1):GND
EA84    GND VSS<1241> @BASEBOARD_FAB2_LIB.BASEBOARD_FAB2(SCH_1):GND
EB83    GND VSS<1240> @BASEBOARD_FAB2_LIB.BASEBOARD_FAB2(SCH_1):GND
 DW2    GND VSS<1239> @BASEBOARD_FAB2_LIB.BASEBOARD_FAB2(SCH_1):GND
EC42    GND VSS<1238> @BASEBOARD_FAB2_LIB.BASEBOARD_FAB2(SCH_1):GND
 EC6    GND VSS<1237> @BASEBOARD_FAB2_LIB.BASEBOARD_FAB2(SCH_1):GND
EC82    GND VSS<1236> @BASEBOARD_FAB2_LIB.BASEBOARD_FAB2(SCH_1):GND
ED41    GND VSS<1235> @BASEBOARD_FAB2_LIB.BASEBOARD_FAB2(SCH_1):GND
 ED7    GND VSS<1234> @BASEBOARD_FAB2_LIB.BASEBOARD_FAB2(SCH_1):GND
ED81    GND VSS<1233> @BASEBOARD_FAB2_LIB.BASEBOARD_FAB2(SCH_1):GND
EE40    GND VSS<1232> @BASEBOARD_FAB2_LIB.BASEBOARD_FAB2(SCH_1):GND
 EE8    GND VSS<1231> @BASEBOARD_FAB2_LIB.BASEBOARD_FAB2(SCH_1):GND
EE80    GND VSS<1230> @BASEBOARD_FAB2_LIB.BASEBOARD_FAB2(SCH_1):GND
ED69    GND VSS<1229> @BASEBOARD_FAB2_LIB.BASEBOARD_FAB2(SCH_1):GND
 E66    GND VSS<1228> @BASEBOARD_FAB2_LIB.BASEBOARD_FAB2(SCH_1):GND
 V11    GND VSS<1227> @BASEBOARD_FAB2_LIB.BASEBOARD_FAB2(SCH_1):GND
  L8    GND VSS<1226> @BASEBOARD_FAB2_LIB.BASEBOARD_FAB2(SCH_1):GND
EA14    GND VSS<1225> @BASEBOARD_FAB2_LIB.BASEBOARD_FAB2(SCH_1):GND
DY63    GND VSS<1224> @BASEBOARD_FAB2_LIB.BASEBOARD_FAB2(SCH_1):GND
DY61    GND VSS<1223> @BASEBOARD_FAB2_LIB.BASEBOARD_FAB2(SCH_1):GND
DY59    GND VSS<1222> @BASEBOARD_FAB2_LIB.BASEBOARD_FAB2(SCH_1):GND
DY57    GND VSS<1221> @BASEBOARD_FAB2_LIB.BASEBOARD_FAB2(SCH_1):GND
DY55    GND VSS<1220> @BASEBOARD_FAB2_LIB.BASEBOARD_FAB2(SCH_1):GND
DY53    GND VSS<1219> @BASEBOARD_FAB2_LIB.BASEBOARD_FAB2(SCH_1):GND
DY51    GND VSS<1218> @BASEBOARD_FAB2_LIB.BASEBOARD_FAB2(SCH_1):GND
DY49    GND VSS<1217> @BASEBOARD_FAB2_LIB.BASEBOARD_FAB2(SCH_1):GND
DY47    GND VSS<1216> @BASEBOARD_FAB2_LIB.BASEBOARD_FAB2(SCH_1):GND
DY45    GND VSS<1215> @BASEBOARD_FAB2_LIB.BASEBOARD_FAB2(SCH_1):GND
DV19    GND VSS<1214> @BASEBOARD_FAB2_LIB.BASEBOARD_FAB2(SCH_1):GND
 DP9    GND VSS<1213> @BASEBOARD_FAB2_LIB.BASEBOARD_FAB2(SCH_1):GND
DP63    GND VSS<1212> @BASEBOARD_FAB2_LIB.BASEBOARD_FAB2(SCH_1):GND
DP61    GND VSS<1211> @BASEBOARD_FAB2_LIB.BASEBOARD_FAB2(SCH_1):GND
DP59    GND VSS<1210> @BASEBOARD_FAB2_LIB.BASEBOARD_FAB2(SCH_1):GND
DP57    GND VSS<1209> @BASEBOARD_FAB2_LIB.BASEBOARD_FAB2(SCH_1):GND
DP55    GND VSS<1208> @BASEBOARD_FAB2_LIB.BASEBOARD_FAB2(SCH_1):GND
DP53    GND VSS<1207> @BASEBOARD_FAB2_LIB.BASEBOARD_FAB2(SCH_1):GND
DP51    GND VSS<1206> @BASEBOARD_FAB2_LIB.BASEBOARD_FAB2(SCH_1):GND
DP49    GND VSS<1205> @BASEBOARD_FAB2_LIB.BASEBOARD_FAB2(SCH_1):GND
DP47    GND VSS<1204> @BASEBOARD_FAB2_LIB.BASEBOARD_FAB2(SCH_1):GND
DP45    GND VSS<1203> @BASEBOARD_FAB2_LIB.BASEBOARD_FAB2(SCH_1):GND
DN18    GND VSS<1202> @BASEBOARD_FAB2_LIB.BASEBOARD_FAB2(SCH_1):GND
 DL8    GND VSS<1201> @BASEBOARD_FAB2_LIB.BASEBOARD_FAB2(SCH_1):GND
DE62    GND VSS<1200> @BASEBOARD_FAB2_LIB.BASEBOARD_FAB2(SCH_1):GND
DE60    GND VSS<1199> @BASEBOARD_FAB2_LIB.BASEBOARD_FAB2(SCH_1):GND
DE58    GND VSS<1198> @BASEBOARD_FAB2_LIB.BASEBOARD_FAB2(SCH_1):GND
DE56    GND VSS<1197> @BASEBOARD_FAB2_LIB.BASEBOARD_FAB2(SCH_1):GND
DE54    GND VSS<1196> @BASEBOARD_FAB2_LIB.BASEBOARD_FAB2(SCH_1):GND
DE52    GND VSS<1195> @BASEBOARD_FAB2_LIB.BASEBOARD_FAB2(SCH_1):GND
DE50    GND VSS<1194> @BASEBOARD_FAB2_LIB.BASEBOARD_FAB2(SCH_1):GND
DE48    GND VSS<1193> @BASEBOARD_FAB2_LIB.BASEBOARD_FAB2(SCH_1):GND
 CW6    GND VSS<1192> @BASEBOARD_FAB2_LIB.BASEBOARD_FAB2(SCH_1):GND
 CG6    GND VSS<1191> @BASEBOARD_FAB2_LIB.BASEBOARD_FAB2(SCH_1):GND
 AR6    GND VSS<1190> @BASEBOARD_FAB2_LIB.BASEBOARD_FAB2(SCH_1):GND
 AJ4    GND VSS<1189> @BASEBOARD_FAB2_LIB.BASEBOARD_FAB2(SCH_1):GND
AC62    GND VSS<1188> @BASEBOARD_FAB2_LIB.BASEBOARD_FAB2(SCH_1):GND
AC60    GND VSS<1187> @BASEBOARD_FAB2_LIB.BASEBOARD_FAB2(SCH_1):GND
AC58    GND VSS<1186> @BASEBOARD_FAB2_LIB.BASEBOARD_FAB2(SCH_1):GND
 A26    GND VSS<1185> @BASEBOARD_FAB2_LIB.BASEBOARD_FAB2(SCH_1):GND
 A30    GND VSS<1184> @BASEBOARD_FAB2_LIB.BASEBOARD_FAB2(SCH_1):GND
 A32    GND VSS<1183> @BASEBOARD_FAB2_LIB.BASEBOARD_FAB2(SCH_1):GND
 A36    GND VSS<1182> @BASEBOARD_FAB2_LIB.BASEBOARD_FAB2(SCH_1):GND
 A38    GND VSS<1181> @BASEBOARD_FAB2_LIB.BASEBOARD_FAB2(SCH_1):GND
 B25    GND VSS<1180> @BASEBOARD_FAB2_LIB.BASEBOARD_FAB2(SCH_1):GND
 B31    GND VSS<1179> @BASEBOARD_FAB2_LIB.BASEBOARD_FAB2(SCH_1):GND
 B37    GND VSS<1178> @BASEBOARD_FAB2_LIB.BASEBOARD_FAB2(SCH_1):GND
 B71    GND VSS<1177> @BASEBOARD_FAB2_LIB.BASEBOARD_FAB2(SCH_1):GND
 B75    GND VSS<1176> @BASEBOARD_FAB2_LIB.BASEBOARD_FAB2(SCH_1):GND
  C8    GND VSS<1175> @BASEBOARD_FAB2_LIB.BASEBOARD_FAB2(SCH_1):GND
 C10    GND VSS<1174> @BASEBOARD_FAB2_LIB.BASEBOARD_FAB2(SCH_1):GND
 C12    GND VSS<1173> @BASEBOARD_FAB2_LIB.BASEBOARD_FAB2(SCH_1):GND
 C14    GND VSS<1172> @BASEBOARD_FAB2_LIB.BASEBOARD_FAB2(SCH_1):GND
 C16    GND VSS<1171> @BASEBOARD_FAB2_LIB.BASEBOARD_FAB2(SCH_1):GND
 C76    GND VSS<1170> @BASEBOARD_FAB2_LIB.BASEBOARD_FAB2(SCH_1):GND
 C78    GND VSS<1169> @BASEBOARD_FAB2_LIB.BASEBOARD_FAB2(SCH_1):GND
CM27    GND VSS<1168> @BASEBOARD_FAB2_LIB.BASEBOARD_FAB2(SCH_1):GND
 D11    GND VSS<1167> @BASEBOARD_FAB2_LIB.BASEBOARD_FAB2(SCH_1):GND
 D13    GND VSS<1166> @BASEBOARD_FAB2_LIB.BASEBOARD_FAB2(SCH_1):GND
 D25    GND VSS<1165> @BASEBOARD_FAB2_LIB.BASEBOARD_FAB2(SCH_1):GND
 D27    GND VSS<1164> @BASEBOARD_FAB2_LIB.BASEBOARD_FAB2(SCH_1):GND
 D29    GND VSS<1163> @BASEBOARD_FAB2_LIB.BASEBOARD_FAB2(SCH_1):GND
 D31    GND VSS<1162> @BASEBOARD_FAB2_LIB.BASEBOARD_FAB2(SCH_1):GND
 D33    GND VSS<1161> @BASEBOARD_FAB2_LIB.BASEBOARD_FAB2(SCH_1):GND
 D35    GND VSS<1160> @BASEBOARD_FAB2_LIB.BASEBOARD_FAB2(SCH_1):GND
 D37    GND VSS<1159> @BASEBOARD_FAB2_LIB.BASEBOARD_FAB2(SCH_1):GND
 D39    GND VSS<1158> @BASEBOARD_FAB2_LIB.BASEBOARD_FAB2(SCH_1):GND
 D41    GND VSS<1157> @BASEBOARD_FAB2_LIB.BASEBOARD_FAB2(SCH_1):GND
 D43    GND VSS<1156> @BASEBOARD_FAB2_LIB.BASEBOARD_FAB2(SCH_1):GND
 D77    GND VSS<1155> @BASEBOARD_FAB2_LIB.BASEBOARD_FAB2(SCH_1):GND
  E6    GND VSS<1154> @BASEBOARD_FAB2_LIB.BASEBOARD_FAB2(SCH_1):GND
  E8    GND VSS<1153> @BASEBOARD_FAB2_LIB.BASEBOARD_FAB2(SCH_1):GND
 E16    GND VSS<1152> @BASEBOARD_FAB2_LIB.BASEBOARD_FAB2(SCH_1):GND
 E18    GND VSS<1151> @BASEBOARD_FAB2_LIB.BASEBOARD_FAB2(SCH_1):GND
 E20    GND VSS<1150> @BASEBOARD_FAB2_LIB.BASEBOARD_FAB2(SCH_1):GND
 E22    GND VSS<1149> @BASEBOARD_FAB2_LIB.BASEBOARD_FAB2(SCH_1):GND
 E72    GND VSS<1148> @BASEBOARD_FAB2_LIB.BASEBOARD_FAB2(SCH_1):GND
 E74    GND VSS<1147> @BASEBOARD_FAB2_LIB.BASEBOARD_FAB2(SCH_1):GND
 E76    GND VSS<1146> @BASEBOARD_FAB2_LIB.BASEBOARD_FAB2(SCH_1):GND
  F5    GND VSS<1145> @BASEBOARD_FAB2_LIB.BASEBOARD_FAB2(SCH_1):GND
 F17    GND VSS<1144> @BASEBOARD_FAB2_LIB.BASEBOARD_FAB2(SCH_1):GND
 F19    GND VSS<1143> @BASEBOARD_FAB2_LIB.BASEBOARD_FAB2(SCH_1):GND
 F25    GND VSS<1142> @BASEBOARD_FAB2_LIB.BASEBOARD_FAB2(SCH_1):GND
 F31    GND VSS<1141> @BASEBOARD_FAB2_LIB.BASEBOARD_FAB2(SCH_1):GND
 F37    GND VSS<1140> @BASEBOARD_FAB2_LIB.BASEBOARD_FAB2(SCH_1):GND
 F43    GND VSS<1139> @BASEBOARD_FAB2_LIB.BASEBOARD_FAB2(SCH_1):GND
 F67    GND VSS<1138> @BASEBOARD_FAB2_LIB.BASEBOARD_FAB2(SCH_1):GND
 F69    GND VSS<1137> @BASEBOARD_FAB2_LIB.BASEBOARD_FAB2(SCH_1):GND
  G4    GND VSS<1136> @BASEBOARD_FAB2_LIB.BASEBOARD_FAB2(SCH_1):GND
  G8    GND VSS<1135> @BASEBOARD_FAB2_LIB.BASEBOARD_FAB2(SCH_1):GND
 G22    GND VSS<1134> @BASEBOARD_FAB2_LIB.BASEBOARD_FAB2(SCH_1):GND
 G24    GND VSS<1133> @BASEBOARD_FAB2_LIB.BASEBOARD_FAB2(SCH_1):GND
 G26    GND VSS<1132> @BASEBOARD_FAB2_LIB.BASEBOARD_FAB2(SCH_1):GND
 G30    GND VSS<1131> @BASEBOARD_FAB2_LIB.BASEBOARD_FAB2(SCH_1):GND
 G32    GND VSS<1130> @BASEBOARD_FAB2_LIB.BASEBOARD_FAB2(SCH_1):GND
 G36    GND VSS<1129> @BASEBOARD_FAB2_LIB.BASEBOARD_FAB2(SCH_1):GND
 G38    GND VSS<1128> @BASEBOARD_FAB2_LIB.BASEBOARD_FAB2(SCH_1):GND
 G42    GND VSS<1127> @BASEBOARD_FAB2_LIB.BASEBOARD_FAB2(SCH_1):GND
 G66    GND VSS<1126> @BASEBOARD_FAB2_LIB.BASEBOARD_FAB2(SCH_1):GND
 G70    GND VSS<1125> @BASEBOARD_FAB2_LIB.BASEBOARD_FAB2(SCH_1):GND
 G76    GND VSS<1124> @BASEBOARD_FAB2_LIB.BASEBOARD_FAB2(SCH_1):GND
 G78    GND VSS<1123> @BASEBOARD_FAB2_LIB.BASEBOARD_FAB2(SCH_1):GND
 G80    GND VSS<1122> @BASEBOARD_FAB2_LIB.BASEBOARD_FAB2(SCH_1):GND
 G82    GND VSS<1121> @BASEBOARD_FAB2_LIB.BASEBOARD_FAB2(SCH_1):GND
  H3    GND VSS<1120> @BASEBOARD_FAB2_LIB.BASEBOARD_FAB2(SCH_1):GND
 H11    GND VSS<1119> @BASEBOARD_FAB2_LIB.BASEBOARD_FAB2(SCH_1):GND
 H25    GND VSS<1118> @BASEBOARD_FAB2_LIB.BASEBOARD_FAB2(SCH_1):GND
 H27    GND VSS<1117> @BASEBOARD_FAB2_LIB.BASEBOARD_FAB2(SCH_1):GND
 H29    GND VSS<1116> @BASEBOARD_FAB2_LIB.BASEBOARD_FAB2(SCH_1):GND
 H31    GND VSS<1115> @BASEBOARD_FAB2_LIB.BASEBOARD_FAB2(SCH_1):GND
 H33    GND VSS<1114> @BASEBOARD_FAB2_LIB.BASEBOARD_FAB2(SCH_1):GND
 H35    GND VSS<1113> @BASEBOARD_FAB2_LIB.BASEBOARD_FAB2(SCH_1):GND
 H37    GND VSS<1112> @BASEBOARD_FAB2_LIB.BASEBOARD_FAB2(SCH_1):GND
 H39    GND VSS<1111> @BASEBOARD_FAB2_LIB.BASEBOARD_FAB2(SCH_1):GND
 H41    GND VSS<1110> @BASEBOARD_FAB2_LIB.BASEBOARD_FAB2(SCH_1):GND
 H65    GND VSS<1109> @BASEBOARD_FAB2_LIB.BASEBOARD_FAB2(SCH_1):GND
 H71    GND VSS<1108> @BASEBOARD_FAB2_LIB.BASEBOARD_FAB2(SCH_1):GND
 H75    GND VSS<1107> @BASEBOARD_FAB2_LIB.BASEBOARD_FAB2(SCH_1):GND
DN44    GND VSS<1106> @BASEBOARD_FAB2_LIB.BASEBOARD_FAB2(SCH_1):GND
  J4    GND VSS<1105> @BASEBOARD_FAB2_LIB.BASEBOARD_FAB2(SCH_1):GND
 J12    GND VSS<1104> @BASEBOARD_FAB2_LIB.BASEBOARD_FAB2(SCH_1):GND
 J14    GND VSS<1103> @BASEBOARD_FAB2_LIB.BASEBOARD_FAB2(SCH_1):GND
 J22    GND VSS<1102> @BASEBOARD_FAB2_LIB.BASEBOARD_FAB2(SCH_1):GND
 J26    GND VSS<1101> @BASEBOARD_FAB2_LIB.BASEBOARD_FAB2(SCH_1):GND
 J28    GND VSS<1100> @BASEBOARD_FAB2_LIB.BASEBOARD_FAB2(SCH_1):GND
 J32    GND VSS<1099> @BASEBOARD_FAB2_LIB.BASEBOARD_FAB2(SCH_1):GND
 J34    GND VSS<1098> @BASEBOARD_FAB2_LIB.BASEBOARD_FAB2(SCH_1):GND
 J38    GND VSS<1097> @BASEBOARD_FAB2_LIB.BASEBOARD_FAB2(SCH_1):GND
 J40    GND VSS<1096> @BASEBOARD_FAB2_LIB.BASEBOARD_FAB2(SCH_1):GND
 J72    GND VSS<1095> @BASEBOARD_FAB2_LIB.BASEBOARD_FAB2(SCH_1):GND
 J74    GND VSS<1094> @BASEBOARD_FAB2_LIB.BASEBOARD_FAB2(SCH_1):GND

SKX_EXT_B_BGA1-IC,TBD  I21  U5D1
 J76    GND VSS<1093> @BASEBOARD_FAB2_LIB.BASEBOARD_FAB2(SCH_1):GND
 J82    GND VSS<1092> @BASEBOARD_FAB2_LIB.BASEBOARD_FAB2(SCH_1):GND
 J84    GND VSS<1091> @BASEBOARD_FAB2_LIB.BASEBOARD_FAB2(SCH_1):GND
  K1    GND VSS<1090> @BASEBOARD_FAB2_LIB.BASEBOARD_FAB2(SCH_1):GND
 K11    GND VSS<1089> @BASEBOARD_FAB2_LIB.BASEBOARD_FAB2(SCH_1):GND
 K13    GND VSS<1088> @BASEBOARD_FAB2_LIB.BASEBOARD_FAB2(SCH_1):GND
 K17    GND VSS<1087> @BASEBOARD_FAB2_LIB.BASEBOARD_FAB2(SCH_1):GND
 DB7    GND VSS<1086> @BASEBOARD_FAB2_LIB.BASEBOARD_FAB2(SCH_1):GND
 K27    GND VSS<1085> @BASEBOARD_FAB2_LIB.BASEBOARD_FAB2(SCH_1):GND
 K33    GND VSS<1084> @BASEBOARD_FAB2_LIB.BASEBOARD_FAB2(SCH_1):GND
 K39    GND VSS<1083> @BASEBOARD_FAB2_LIB.BASEBOARD_FAB2(SCH_1):GND
 K65    GND VSS<1082> @BASEBOARD_FAB2_LIB.BASEBOARD_FAB2(SCH_1):GND
 K67    GND VSS<1081> @BASEBOARD_FAB2_LIB.BASEBOARD_FAB2(SCH_1):GND
 K69    GND VSS<1080> @BASEBOARD_FAB2_LIB.BASEBOARD_FAB2(SCH_1):GND
 K71    GND VSS<1079> @BASEBOARD_FAB2_LIB.BASEBOARD_FAB2(SCH_1):GND
 K73    GND VSS<1078> @BASEBOARD_FAB2_LIB.BASEBOARD_FAB2(SCH_1):GND
 K77    GND VSS<1077> @BASEBOARD_FAB2_LIB.BASEBOARD_FAB2(SCH_1):GND
 K81    GND VSS<1076> @BASEBOARD_FAB2_LIB.BASEBOARD_FAB2(SCH_1):GND
 K83    GND VSS<1075> @BASEBOARD_FAB2_LIB.BASEBOARD_FAB2(SCH_1):GND
 K85    GND VSS<1074> @BASEBOARD_FAB2_LIB.BASEBOARD_FAB2(SCH_1):GND
 L10    GND VSS<1073> @BASEBOARD_FAB2_LIB.BASEBOARD_FAB2(SCH_1):GND
  L2    GND VSS<1072> @BASEBOARD_FAB2_LIB.BASEBOARD_FAB2(SCH_1):GND
  L6    GND VSS<1071> @BASEBOARD_FAB2_LIB.BASEBOARD_FAB2(SCH_1):GND
 L20    GND VSS<1070> @BASEBOARD_FAB2_LIB.BASEBOARD_FAB2(SCH_1):GND
 L22    GND VSS<1069> @BASEBOARD_FAB2_LIB.BASEBOARD_FAB2(SCH_1):GND
 L72    GND VSS<1068> @BASEBOARD_FAB2_LIB.BASEBOARD_FAB2(SCH_1):GND
 L78    GND VSS<1067> @BASEBOARD_FAB2_LIB.BASEBOARD_FAB2(SCH_1):GND
 L80    GND VSS<1066> @BASEBOARD_FAB2_LIB.BASEBOARD_FAB2(SCH_1):GND
 L82    GND VSS<1065> @BASEBOARD_FAB2_LIB.BASEBOARD_FAB2(SCH_1):GND
 BT9    GND VSS<1064> @BASEBOARD_FAB2_LIB.BASEBOARD_FAB2(SCH_1):GND
 CT7    GND VSS<1063> @BASEBOARD_FAB2_LIB.BASEBOARD_FAB2(SCH_1):GND
 M15    GND VSS<1062> @BASEBOARD_FAB2_LIB.BASEBOARD_FAB2(SCH_1):GND
 M17    GND VSS<1061> @BASEBOARD_FAB2_LIB.BASEBOARD_FAB2(SCH_1):GND
 M19    GND VSS<1060> @BASEBOARD_FAB2_LIB.BASEBOARD_FAB2(SCH_1):GND
 M23    GND VSS<1059> @BASEBOARD_FAB2_LIB.BASEBOARD_FAB2(SCH_1):GND
 M25    GND VSS<1058> @BASEBOARD_FAB2_LIB.BASEBOARD_FAB2(SCH_1):GND
 M27    GND VSS<1057> @BASEBOARD_FAB2_LIB.BASEBOARD_FAB2(SCH_1):GND
 M29    GND VSS<1056> @BASEBOARD_FAB2_LIB.BASEBOARD_FAB2(SCH_1):GND
 M31    GND VSS<1055> @BASEBOARD_FAB2_LIB.BASEBOARD_FAB2(SCH_1):GND
 M33    GND VSS<1054> @BASEBOARD_FAB2_LIB.BASEBOARD_FAB2(SCH_1):GND
 M35    GND VSS<1053> @BASEBOARD_FAB2_LIB.BASEBOARD_FAB2(SCH_1):GND
 M37    GND VSS<1052> @BASEBOARD_FAB2_LIB.BASEBOARD_FAB2(SCH_1):GND
 M39    GND VSS<1051> @BASEBOARD_FAB2_LIB.BASEBOARD_FAB2(SCH_1):GND
 M41    GND VSS<1050> @BASEBOARD_FAB2_LIB.BASEBOARD_FAB2(SCH_1):GND
 M43    GND VSS<1049> @BASEBOARD_FAB2_LIB.BASEBOARD_FAB2(SCH_1):GND
 M65    GND VSS<1048> @BASEBOARD_FAB2_LIB.BASEBOARD_FAB2(SCH_1):GND
 M71    GND VSS<1047> @BASEBOARD_FAB2_LIB.BASEBOARD_FAB2(SCH_1):GND
 M79    GND VSS<1046> @BASEBOARD_FAB2_LIB.BASEBOARD_FAB2(SCH_1):GND
 M83    GND VSS<1045> @BASEBOARD_FAB2_LIB.BASEBOARD_FAB2(SCH_1):GND
 M85    GND VSS<1044> @BASEBOARD_FAB2_LIB.BASEBOARD_FAB2(SCH_1):GND
DM19    GND VSS<1043> @BASEBOARD_FAB2_LIB.BASEBOARD_FAB2(SCH_1):GND
 N20    GND VSS<1042> @BASEBOARD_FAB2_LIB.BASEBOARD_FAB2(SCH_1):GND
 N22    GND VSS<1041> @BASEBOARD_FAB2_LIB.BASEBOARD_FAB2(SCH_1):GND
  N6    GND VSS<1040> @BASEBOARD_FAB2_LIB.BASEBOARD_FAB2(SCH_1):GND
 N66    GND VSS<1039> @BASEBOARD_FAB2_LIB.BASEBOARD_FAB2(SCH_1):GND
 N70    GND VSS<1038> @BASEBOARD_FAB2_LIB.BASEBOARD_FAB2(SCH_1):GND
 N72    GND VSS<1037> @BASEBOARD_FAB2_LIB.BASEBOARD_FAB2(SCH_1):GND
 N74    GND VSS<1036> @BASEBOARD_FAB2_LIB.BASEBOARD_FAB2(SCH_1):GND
 N76    GND VSS<1035> @BASEBOARD_FAB2_LIB.BASEBOARD_FAB2(SCH_1):GND
 N78    GND VSS<1034> @BASEBOARD_FAB2_LIB.BASEBOARD_FAB2(SCH_1):GND
  N4    GND VSS<1033> @BASEBOARD_FAB2_LIB.BASEBOARD_FAB2(SCH_1):GND
  N8    GND VSS<1032> @BASEBOARD_FAB2_LIB.BASEBOARD_FAB2(SCH_1):GND
 P11    GND VSS<1031> @BASEBOARD_FAB2_LIB.BASEBOARD_FAB2(SCH_1):GND
 P15    GND VSS<1030> @BASEBOARD_FAB2_LIB.BASEBOARD_FAB2(SCH_1):GND
 P27    GND VSS<1029> @BASEBOARD_FAB2_LIB.BASEBOARD_FAB2(SCH_1):GND
 P33    GND VSS<1028> @BASEBOARD_FAB2_LIB.BASEBOARD_FAB2(SCH_1):GND
 P39    GND VSS<1027> @BASEBOARD_FAB2_LIB.BASEBOARD_FAB2(SCH_1):GND
 P67    GND VSS<1026> @BASEBOARD_FAB2_LIB.BASEBOARD_FAB2(SCH_1):GND
 P69    GND VSS<1025> @BASEBOARD_FAB2_LIB.BASEBOARD_FAB2(SCH_1):GND
 P71    GND VSS<1024> @BASEBOARD_FAB2_LIB.BASEBOARD_FAB2(SCH_1):GND
 P81    GND VSS<1023> @BASEBOARD_FAB2_LIB.BASEBOARD_FAB2(SCH_1):GND
 P83    GND VSS<1022> @BASEBOARD_FAB2_LIB.BASEBOARD_FAB2(SCH_1):GND
 R14    GND VSS<1021> @BASEBOARD_FAB2_LIB.BASEBOARD_FAB2(SCH_1):GND
 R18    GND VSS<1020> @BASEBOARD_FAB2_LIB.BASEBOARD_FAB2(SCH_1):GND
  R2    GND VSS<1019> @BASEBOARD_FAB2_LIB.BASEBOARD_FAB2(SCH_1):GND
  R4    GND VSS<1018> @BASEBOARD_FAB2_LIB.BASEBOARD_FAB2(SCH_1):GND
 R22    GND VSS<1017> @BASEBOARD_FAB2_LIB.BASEBOARD_FAB2(SCH_1):GND
 R26    GND VSS<1016> @BASEBOARD_FAB2_LIB.BASEBOARD_FAB2(SCH_1):GND
 R28    GND VSS<1015> @BASEBOARD_FAB2_LIB.BASEBOARD_FAB2(SCH_1):GND
 R32    GND VSS<1014> @BASEBOARD_FAB2_LIB.BASEBOARD_FAB2(SCH_1):GND
 R34    GND VSS<1013> @BASEBOARD_FAB2_LIB.BASEBOARD_FAB2(SCH_1):GND
 R38    GND VSS<1012> @BASEBOARD_FAB2_LIB.BASEBOARD_FAB2(SCH_1):GND
 R40    GND VSS<1011> @BASEBOARD_FAB2_LIB.BASEBOARD_FAB2(SCH_1):GND
 R68    GND VSS<1010> @BASEBOARD_FAB2_LIB.BASEBOARD_FAB2(SCH_1):GND
 R72    GND VSS<1009> @BASEBOARD_FAB2_LIB.BASEBOARD_FAB2(SCH_1):GND
 R78    GND VSS<1008> @BASEBOARD_FAB2_LIB.BASEBOARD_FAB2(SCH_1):GND
 R86    GND VSS<1007> @BASEBOARD_FAB2_LIB.BASEBOARD_FAB2(SCH_1):GND
 T13    GND VSS<1006> @BASEBOARD_FAB2_LIB.BASEBOARD_FAB2(SCH_1):GND
 T17    GND VSS<1005> @BASEBOARD_FAB2_LIB.BASEBOARD_FAB2(SCH_1):GND
 T25    GND VSS<1004> @BASEBOARD_FAB2_LIB.BASEBOARD_FAB2(SCH_1):GND
 T29    GND VSS<1003> @BASEBOARD_FAB2_LIB.BASEBOARD_FAB2(SCH_1):GND
 T31    GND VSS<1002> @BASEBOARD_FAB2_LIB.BASEBOARD_FAB2(SCH_1):GND
 T35    GND VSS<1001> @BASEBOARD_FAB2_LIB.BASEBOARD_FAB2(SCH_1):GND
 T37    GND VSS<1000> @BASEBOARD_FAB2_LIB.BASEBOARD_FAB2(SCH_1):GND
 T41    GND VSS<999> @BASEBOARD_FAB2_LIB.BASEBOARD_FAB2(SCH_1):GND
 T65    GND VSS<998> @BASEBOARD_FAB2_LIB.BASEBOARD_FAB2(SCH_1):GND
 T73    GND VSS<997> @BASEBOARD_FAB2_LIB.BASEBOARD_FAB2(SCH_1):GND
 T77    GND VSS<996> @BASEBOARD_FAB2_LIB.BASEBOARD_FAB2(SCH_1):GND
 T83    GND VSS<995> @BASEBOARD_FAB2_LIB.BASEBOARD_FAB2(SCH_1):GND
 T85    GND VSS<994> @BASEBOARD_FAB2_LIB.BASEBOARD_FAB2(SCH_1):GND
  U2    GND VSS<993> @BASEBOARD_FAB2_LIB.BASEBOARD_FAB2(SCH_1):GND
  U4    GND VSS<992> @BASEBOARD_FAB2_LIB.BASEBOARD_FAB2(SCH_1):GND
  U6    GND VSS<991> @BASEBOARD_FAB2_LIB.BASEBOARD_FAB2(SCH_1):GND
 U20    GND VSS<990> @BASEBOARD_FAB2_LIB.BASEBOARD_FAB2(SCH_1):GND
 U22    GND VSS<989> @BASEBOARD_FAB2_LIB.BASEBOARD_FAB2(SCH_1):GND
 U24    GND VSS<988> @BASEBOARD_FAB2_LIB.BASEBOARD_FAB2(SCH_1):GND
 U30    GND VSS<987> @BASEBOARD_FAB2_LIB.BASEBOARD_FAB2(SCH_1):GND
 U36    GND VSS<986> @BASEBOARD_FAB2_LIB.BASEBOARD_FAB2(SCH_1):GND
 U42    GND VSS<985> @BASEBOARD_FAB2_LIB.BASEBOARD_FAB2(SCH_1):GND
 U68    GND VSS<984> @BASEBOARD_FAB2_LIB.BASEBOARD_FAB2(SCH_1):GND
 U70    GND VSS<983> @BASEBOARD_FAB2_LIB.BASEBOARD_FAB2(SCH_1):GND
 U74    GND VSS<982> @BASEBOARD_FAB2_LIB.BASEBOARD_FAB2(SCH_1):GND
 U76    GND VSS<981> @BASEBOARD_FAB2_LIB.BASEBOARD_FAB2(SCH_1):GND
 U78    GND VSS<980> @BASEBOARD_FAB2_LIB.BASEBOARD_FAB2(SCH_1):GND
 U80    GND VSS<979> @BASEBOARD_FAB2_LIB.BASEBOARD_FAB2(SCH_1):GND
 U86    GND VSS<978> @BASEBOARD_FAB2_LIB.BASEBOARD_FAB2(SCH_1):GND
  V1    GND VSS<977> @BASEBOARD_FAB2_LIB.BASEBOARD_FAB2(SCH_1):GND
  V5    GND VSS<976> @BASEBOARD_FAB2_LIB.BASEBOARD_FAB2(SCH_1):GND
  V9    GND VSS<975> @BASEBOARD_FAB2_LIB.BASEBOARD_FAB2(SCH_1):GND
 V13    GND VSS<974> @BASEBOARD_FAB2_LIB.BASEBOARD_FAB2(SCH_1):GND
 V15    GND VSS<973> @BASEBOARD_FAB2_LIB.BASEBOARD_FAB2(SCH_1):GND
 V21    GND VSS<972> @BASEBOARD_FAB2_LIB.BASEBOARD_FAB2(SCH_1):GND
 V23    GND VSS<971> @BASEBOARD_FAB2_LIB.BASEBOARD_FAB2(SCH_1):GND
 V43    GND VSS<970> @BASEBOARD_FAB2_LIB.BASEBOARD_FAB2(SCH_1):GND
 V73    GND VSS<969> @BASEBOARD_FAB2_LIB.BASEBOARD_FAB2(SCH_1):GND
 V75    GND VSS<968> @BASEBOARD_FAB2_LIB.BASEBOARD_FAB2(SCH_1):GND
 V77    GND VSS<967> @BASEBOARD_FAB2_LIB.BASEBOARD_FAB2(SCH_1):GND
 V83    GND VSS<966> @BASEBOARD_FAB2_LIB.BASEBOARD_FAB2(SCH_1):GND
  W8    GND VSS<965> @BASEBOARD_FAB2_LIB.BASEBOARD_FAB2(SCH_1):GND
AC56    GND VSS<964> @BASEBOARD_FAB2_LIB.BASEBOARD_FAB2(SCH_1):GND
 W12    GND VSS<963> @BASEBOARD_FAB2_LIB.BASEBOARD_FAB2(SCH_1):GND
 W22    GND VSS<962> @BASEBOARD_FAB2_LIB.BASEBOARD_FAB2(SCH_1):GND
 W24    GND VSS<961> @BASEBOARD_FAB2_LIB.BASEBOARD_FAB2(SCH_1):GND
 W26    GND VSS<960> @BASEBOARD_FAB2_LIB.BASEBOARD_FAB2(SCH_1):GND
 W28    GND VSS<959> @BASEBOARD_FAB2_LIB.BASEBOARD_FAB2(SCH_1):GND
 W30    GND VSS<958> @BASEBOARD_FAB2_LIB.BASEBOARD_FAB2(SCH_1):GND
 W32    GND VSS<957> @BASEBOARD_FAB2_LIB.BASEBOARD_FAB2(SCH_1):GND
 W34    GND VSS<956> @BASEBOARD_FAB2_LIB.BASEBOARD_FAB2(SCH_1):GND
 W36    GND VSS<955> @BASEBOARD_FAB2_LIB.BASEBOARD_FAB2(SCH_1):GND
 W38    GND VSS<954> @BASEBOARD_FAB2_LIB.BASEBOARD_FAB2(SCH_1):GND
 W40    GND VSS<953> @BASEBOARD_FAB2_LIB.BASEBOARD_FAB2(SCH_1):GND
 W42    GND VSS<952> @BASEBOARD_FAB2_LIB.BASEBOARD_FAB2(SCH_1):GND
 W68    GND VSS<951> @BASEBOARD_FAB2_LIB.BASEBOARD_FAB2(SCH_1):GND
 W74    GND VSS<950> @BASEBOARD_FAB2_LIB.BASEBOARD_FAB2(SCH_1):GND
 W78    GND VSS<949> @BASEBOARD_FAB2_LIB.BASEBOARD_FAB2(SCH_1):GND
 W82    GND VSS<948> @BASEBOARD_FAB2_LIB.BASEBOARD_FAB2(SCH_1):GND
 Y15    GND VSS<947> @BASEBOARD_FAB2_LIB.BASEBOARD_FAB2(SCH_1):GND
 Y17    GND VSS<946> @BASEBOARD_FAB2_LIB.BASEBOARD_FAB2(SCH_1):GND
  Y5    GND VSS<945> @BASEBOARD_FAB2_LIB.BASEBOARD_FAB2(SCH_1):GND
 Y67    GND VSS<944> @BASEBOARD_FAB2_LIB.BASEBOARD_FAB2(SCH_1):GND
  Y7    GND VSS<943> @BASEBOARD_FAB2_LIB.BASEBOARD_FAB2(SCH_1):GND
  Y9    GND VSS<942> @BASEBOARD_FAB2_LIB.BASEBOARD_FAB2(SCH_1):GND
 Y71    GND VSS<941> @BASEBOARD_FAB2_LIB.BASEBOARD_FAB2(SCH_1):GND
 Y73    GND VSS<940> @BASEBOARD_FAB2_LIB.BASEBOARD_FAB2(SCH_1):GND
 Y79    GND VSS<939> @BASEBOARD_FAB2_LIB.BASEBOARD_FAB2(SCH_1):GND
 Y81    GND VSS<938> @BASEBOARD_FAB2_LIB.BASEBOARD_FAB2(SCH_1):GND
 Y83    GND VSS<937> @BASEBOARD_FAB2_LIB.BASEBOARD_FAB2(SCH_1):GND
 Y85    GND VSS<936> @BASEBOARD_FAB2_LIB.BASEBOARD_FAB2(SCH_1):GND
 AA4    GND VSS<935> @BASEBOARD_FAB2_LIB.BASEBOARD_FAB2(SCH_1):GND
AA16    GND VSS<934> @BASEBOARD_FAB2_LIB.BASEBOARD_FAB2(SCH_1):GND

SKX_EXT_B_BGA1-IC,TBD  I22  U5D1
AA18    GND VSS<933> @BASEBOARD_FAB2_LIB.BASEBOARD_FAB2(SCH_1):GND
AA22    GND VSS<932> @BASEBOARD_FAB2_LIB.BASEBOARD_FAB2(SCH_1):GND
AA24    GND VSS<931> @BASEBOARD_FAB2_LIB.BASEBOARD_FAB2(SCH_1):GND
AA30    GND VSS<930> @BASEBOARD_FAB2_LIB.BASEBOARD_FAB2(SCH_1):GND
AA36    GND VSS<929> @BASEBOARD_FAB2_LIB.BASEBOARD_FAB2(SCH_1):GND
AA42    GND VSS<928> @BASEBOARD_FAB2_LIB.BASEBOARD_FAB2(SCH_1):GND
AA64    GND VSS<927> @BASEBOARD_FAB2_LIB.BASEBOARD_FAB2(SCH_1):GND
AA66    GND VSS<926> @BASEBOARD_FAB2_LIB.BASEBOARD_FAB2(SCH_1):GND
AA68    GND VSS<925> @BASEBOARD_FAB2_LIB.BASEBOARD_FAB2(SCH_1):GND
AA76    GND VSS<924> @BASEBOARD_FAB2_LIB.BASEBOARD_FAB2(SCH_1):GND
AA78    GND VSS<923> @BASEBOARD_FAB2_LIB.BASEBOARD_FAB2(SCH_1):GND
AA80    GND VSS<922> @BASEBOARD_FAB2_LIB.BASEBOARD_FAB2(SCH_1):GND
AA82    GND VSS<921> @BASEBOARD_FAB2_LIB.BASEBOARD_FAB2(SCH_1):GND
 AB1    GND VSS<920> @BASEBOARD_FAB2_LIB.BASEBOARD_FAB2(SCH_1):GND
 AB5    GND VSS<919> @BASEBOARD_FAB2_LIB.BASEBOARD_FAB2(SCH_1):GND
AB11    GND VSS<918> @BASEBOARD_FAB2_LIB.BASEBOARD_FAB2(SCH_1):GND
AB21    GND VSS<917> @BASEBOARD_FAB2_LIB.BASEBOARD_FAB2(SCH_1):GND
AB23    GND VSS<916> @BASEBOARD_FAB2_LIB.BASEBOARD_FAB2(SCH_1):GND
AB25    GND VSS<915> @BASEBOARD_FAB2_LIB.BASEBOARD_FAB2(SCH_1):GND
AB29    GND VSS<914> @BASEBOARD_FAB2_LIB.BASEBOARD_FAB2(SCH_1):GND
AB31    GND VSS<913> @BASEBOARD_FAB2_LIB.BASEBOARD_FAB2(SCH_1):GND
AB35    GND VSS<912> @BASEBOARD_FAB2_LIB.BASEBOARD_FAB2(SCH_1):GND
AB37    GND VSS<911> @BASEBOARD_FAB2_LIB.BASEBOARD_FAB2(SCH_1):GND
AB41    GND VSS<910> @BASEBOARD_FAB2_LIB.BASEBOARD_FAB2(SCH_1):GND
AB65    GND VSS<909> @BASEBOARD_FAB2_LIB.BASEBOARD_FAB2(SCH_1):GND
AB69    GND VSS<908> @BASEBOARD_FAB2_LIB.BASEBOARD_FAB2(SCH_1):GND
AB73    GND VSS<907> @BASEBOARD_FAB2_LIB.BASEBOARD_FAB2(SCH_1):GND
AB79    GND VSS<906> @BASEBOARD_FAB2_LIB.BASEBOARD_FAB2(SCH_1):GND
AB83    GND VSS<905> @BASEBOARD_FAB2_LIB.BASEBOARD_FAB2(SCH_1):GND
AB85    GND VSS<904> @BASEBOARD_FAB2_LIB.BASEBOARD_FAB2(SCH_1):GND
AC18    GND VSS<903> @BASEBOARD_FAB2_LIB.BASEBOARD_FAB2(SCH_1):GND
AC22    GND VSS<902> @BASEBOARD_FAB2_LIB.BASEBOARD_FAB2(SCH_1):GND
AC26    GND VSS<901> @BASEBOARD_FAB2_LIB.BASEBOARD_FAB2(SCH_1):GND
AC28    GND VSS<900> @BASEBOARD_FAB2_LIB.BASEBOARD_FAB2(SCH_1):GND
AC32    GND VSS<899> @BASEBOARD_FAB2_LIB.BASEBOARD_FAB2(SCH_1):GND
AC34    GND VSS<898> @BASEBOARD_FAB2_LIB.BASEBOARD_FAB2(SCH_1):GND
AC38    GND VSS<897> @BASEBOARD_FAB2_LIB.BASEBOARD_FAB2(SCH_1):GND
AC40    GND VSS<896> @BASEBOARD_FAB2_LIB.BASEBOARD_FAB2(SCH_1):GND
AC64    GND VSS<895> @BASEBOARD_FAB2_LIB.BASEBOARD_FAB2(SCH_1):GND
AC70    GND VSS<894> @BASEBOARD_FAB2_LIB.BASEBOARD_FAB2(SCH_1):GND
AC72    GND VSS<893> @BASEBOARD_FAB2_LIB.BASEBOARD_FAB2(SCH_1):GND
AC78    GND VSS<892> @BASEBOARD_FAB2_LIB.BASEBOARD_FAB2(SCH_1):GND
AC84    GND VSS<891> @BASEBOARD_FAB2_LIB.BASEBOARD_FAB2(SCH_1):GND
AC86    GND VSS<890> @BASEBOARD_FAB2_LIB.BASEBOARD_FAB2(SCH_1):GND
 AD3    GND VSS<889> @BASEBOARD_FAB2_LIB.BASEBOARD_FAB2(SCH_1):GND
 AD7    GND VSS<888> @BASEBOARD_FAB2_LIB.BASEBOARD_FAB2(SCH_1):GND
 AD9    GND VSS<887> @BASEBOARD_FAB2_LIB.BASEBOARD_FAB2(SCH_1):GND
AD11    GND VSS<886> @BASEBOARD_FAB2_LIB.BASEBOARD_FAB2(SCH_1):GND
AD13    GND VSS<885> @BASEBOARD_FAB2_LIB.BASEBOARD_FAB2(SCH_1):GND
AD15    GND VSS<884> @BASEBOARD_FAB2_LIB.BASEBOARD_FAB2(SCH_1):GND
AD19    GND VSS<883> @BASEBOARD_FAB2_LIB.BASEBOARD_FAB2(SCH_1):GND
AD21    GND VSS<882> @BASEBOARD_FAB2_LIB.BASEBOARD_FAB2(SCH_1):GND
AD27    GND VSS<881> @BASEBOARD_FAB2_LIB.BASEBOARD_FAB2(SCH_1):GND
AD33    GND VSS<880> @BASEBOARD_FAB2_LIB.BASEBOARD_FAB2(SCH_1):GND
AD39    GND VSS<879> @BASEBOARD_FAB2_LIB.BASEBOARD_FAB2(SCH_1):GND
AD43    GND VSS<878> @BASEBOARD_FAB2_LIB.BASEBOARD_FAB2(SCH_1):GND
AD71    GND VSS<877> @BASEBOARD_FAB2_LIB.BASEBOARD_FAB2(SCH_1):GND
AD73    GND VSS<876> @BASEBOARD_FAB2_LIB.BASEBOARD_FAB2(SCH_1):GND
AD75    GND VSS<875> @BASEBOARD_FAB2_LIB.BASEBOARD_FAB2(SCH_1):GND
AD81    GND VSS<874> @BASEBOARD_FAB2_LIB.BASEBOARD_FAB2(SCH_1):GND
AD83    GND VSS<873> @BASEBOARD_FAB2_LIB.BASEBOARD_FAB2(SCH_1):GND
AD85    GND VSS<872> @BASEBOARD_FAB2_LIB.BASEBOARD_FAB2(SCH_1):GND
 AE4    GND VSS<871> @BASEBOARD_FAB2_LIB.BASEBOARD_FAB2(SCH_1):GND
 AE8    GND VSS<870> @BASEBOARD_FAB2_LIB.BASEBOARD_FAB2(SCH_1):GND
AC54    GND VSS<869> @BASEBOARD_FAB2_LIB.BASEBOARD_FAB2(SCH_1):GND
AE16    GND VSS<868> @BASEBOARD_FAB2_LIB.BASEBOARD_FAB2(SCH_1):GND
AE38    GND VSS<867> @BASEBOARD_FAB2_LIB.BASEBOARD_FAB2(SCH_1):GND
AE40    GND VSS<866> @BASEBOARD_FAB2_LIB.BASEBOARD_FAB2(SCH_1):GND
AE42    GND VSS<865> @BASEBOARD_FAB2_LIB.BASEBOARD_FAB2(SCH_1):GND
AE64    GND VSS<864> @BASEBOARD_FAB2_LIB.BASEBOARD_FAB2(SCH_1):GND
AE66    GND VSS<863> @BASEBOARD_FAB2_LIB.BASEBOARD_FAB2(SCH_1):GND
AE68    GND VSS<862> @BASEBOARD_FAB2_LIB.BASEBOARD_FAB2(SCH_1):GND
AE70    GND VSS<861> @BASEBOARD_FAB2_LIB.BASEBOARD_FAB2(SCH_1):GND
AE78    GND VSS<860> @BASEBOARD_FAB2_LIB.BASEBOARD_FAB2(SCH_1):GND
 AF1    GND VSS<859> @BASEBOARD_FAB2_LIB.BASEBOARD_FAB2(SCH_1):GND
AC52    GND VSS<858> @BASEBOARD_FAB2_LIB.BASEBOARD_FAB2(SCH_1):GND
 AF9    GND VSS<857> @BASEBOARD_FAB2_LIB.BASEBOARD_FAB2(SCH_1):GND
AF21    GND VSS<856> @BASEBOARD_FAB2_LIB.BASEBOARD_FAB2(SCH_1):GND
AF23    GND VSS<855> @BASEBOARD_FAB2_LIB.BASEBOARD_FAB2(SCH_1):GND
AF25    GND VSS<854> @BASEBOARD_FAB2_LIB.BASEBOARD_FAB2(SCH_1):GND
AF27    GND VSS<853> @BASEBOARD_FAB2_LIB.BASEBOARD_FAB2(SCH_1):GND
AF29    GND VSS<852> @BASEBOARD_FAB2_LIB.BASEBOARD_FAB2(SCH_1):GND
AF31    GND VSS<851> @BASEBOARD_FAB2_LIB.BASEBOARD_FAB2(SCH_1):GND
AF33    GND VSS<850> @BASEBOARD_FAB2_LIB.BASEBOARD_FAB2(SCH_1):GND
AF37    GND VSS<849> @BASEBOARD_FAB2_LIB.BASEBOARD_FAB2(SCH_1):GND
AF39    GND VSS<848> @BASEBOARD_FAB2_LIB.BASEBOARD_FAB2(SCH_1):GND
AF41    GND VSS<847> @BASEBOARD_FAB2_LIB.BASEBOARD_FAB2(SCH_1):GND
AF73    GND VSS<846> @BASEBOARD_FAB2_LIB.BASEBOARD_FAB2(SCH_1):GND
AF77    GND VSS<845> @BASEBOARD_FAB2_LIB.BASEBOARD_FAB2(SCH_1):GND
AF83    GND VSS<844> @BASEBOARD_FAB2_LIB.BASEBOARD_FAB2(SCH_1):GND
AF85    GND VSS<843> @BASEBOARD_FAB2_LIB.BASEBOARD_FAB2(SCH_1):GND
AG12    GND VSS<842> @BASEBOARD_FAB2_LIB.BASEBOARD_FAB2(SCH_1):GND
AG14    GND VSS<841> @BASEBOARD_FAB2_LIB.BASEBOARD_FAB2(SCH_1):GND
AG18    GND VSS<840> @BASEBOARD_FAB2_LIB.BASEBOARD_FAB2(SCH_1):GND
AG36    GND VSS<839> @BASEBOARD_FAB2_LIB.BASEBOARD_FAB2(SCH_1):GND
AG64    GND VSS<838> @BASEBOARD_FAB2_LIB.BASEBOARD_FAB2(SCH_1):GND
AG70    GND VSS<837> @BASEBOARD_FAB2_LIB.BASEBOARD_FAB2(SCH_1):GND
AG74    GND VSS<836> @BASEBOARD_FAB2_LIB.BASEBOARD_FAB2(SCH_1):GND
AG76    GND VSS<835> @BASEBOARD_FAB2_LIB.BASEBOARD_FAB2(SCH_1):GND
AG78    GND VSS<834> @BASEBOARD_FAB2_LIB.BASEBOARD_FAB2(SCH_1):GND
AG80    GND VSS<833> @BASEBOARD_FAB2_LIB.BASEBOARD_FAB2(SCH_1):GND
 AH1    GND VSS<832> @BASEBOARD_FAB2_LIB.BASEBOARD_FAB2(SCH_1):GND
 AH5    GND VSS<831> @BASEBOARD_FAB2_LIB.BASEBOARD_FAB2(SCH_1):GND
AH21    GND VSS<830> @BASEBOARD_FAB2_LIB.BASEBOARD_FAB2(SCH_1):GND
AH27    GND VSS<829> @BASEBOARD_FAB2_LIB.BASEBOARD_FAB2(SCH_1):GND
AH33    GND VSS<828> @BASEBOARD_FAB2_LIB.BASEBOARD_FAB2(SCH_1):GND
AH35    GND VSS<827> @BASEBOARD_FAB2_LIB.BASEBOARD_FAB2(SCH_1):GND
AH45    GND VSS<826> @BASEBOARD_FAB2_LIB.BASEBOARD_FAB2(SCH_1):GND
AH47    GND VSS<825> @BASEBOARD_FAB2_LIB.BASEBOARD_FAB2(SCH_1):GND
AH49    GND VSS<824> @BASEBOARD_FAB2_LIB.BASEBOARD_FAB2(SCH_1):GND
AH51    GND VSS<823> @BASEBOARD_FAB2_LIB.BASEBOARD_FAB2(SCH_1):GND
AH53    GND VSS<822> @BASEBOARD_FAB2_LIB.BASEBOARD_FAB2(SCH_1):GND
AH59    GND VSS<821> @BASEBOARD_FAB2_LIB.BASEBOARD_FAB2(SCH_1):GND
AH61    GND VSS<820> @BASEBOARD_FAB2_LIB.BASEBOARD_FAB2(SCH_1):GND
AH65    GND VSS<819> @BASEBOARD_FAB2_LIB.BASEBOARD_FAB2(SCH_1):GND
AH69    GND VSS<818> @BASEBOARD_FAB2_LIB.BASEBOARD_FAB2(SCH_1):GND
AH75    GND VSS<817> @BASEBOARD_FAB2_LIB.BASEBOARD_FAB2(SCH_1):GND
AH77    GND VSS<816> @BASEBOARD_FAB2_LIB.BASEBOARD_FAB2(SCH_1):GND
AH83    GND VSS<815> @BASEBOARD_FAB2_LIB.BASEBOARD_FAB2(SCH_1):GND
 AJ8    GND VSS<814> @BASEBOARD_FAB2_LIB.BASEBOARD_FAB2(SCH_1):GND
AJ22    GND VSS<813> @BASEBOARD_FAB2_LIB.BASEBOARD_FAB2(SCH_1):GND
AJ26    GND VSS<812> @BASEBOARD_FAB2_LIB.BASEBOARD_FAB2(SCH_1):GND
AJ28    GND VSS<811> @BASEBOARD_FAB2_LIB.BASEBOARD_FAB2(SCH_1):GND
AJ32    GND VSS<810> @BASEBOARD_FAB2_LIB.BASEBOARD_FAB2(SCH_1):GND
AJ34    GND VSS<809> @BASEBOARD_FAB2_LIB.BASEBOARD_FAB2(SCH_1):GND
AJ46    GND VSS<808> @BASEBOARD_FAB2_LIB.BASEBOARD_FAB2(SCH_1):GND
AJ48    GND VSS<807> @BASEBOARD_FAB2_LIB.BASEBOARD_FAB2(SCH_1):GND
AJ50    GND VSS<806> @BASEBOARD_FAB2_LIB.BASEBOARD_FAB2(SCH_1):GND
AJ52    GND VSS<805> @BASEBOARD_FAB2_LIB.BASEBOARD_FAB2(SCH_1):GND
AJ54    GND VSS<804> @BASEBOARD_FAB2_LIB.BASEBOARD_FAB2(SCH_1):GND
AJ66    GND VSS<803> @BASEBOARD_FAB2_LIB.BASEBOARD_FAB2(SCH_1):GND
AJ68    GND VSS<802> @BASEBOARD_FAB2_LIB.BASEBOARD_FAB2(SCH_1):GND
AJ74    GND VSS<801> @BASEBOARD_FAB2_LIB.BASEBOARD_FAB2(SCH_1):GND
AJ78    GND VSS<800> @BASEBOARD_FAB2_LIB.BASEBOARD_FAB2(SCH_1):GND
AJ82    GND VSS<799> @BASEBOARD_FAB2_LIB.BASEBOARD_FAB2(SCH_1):GND
AJ86    GND VSS<798> @BASEBOARD_FAB2_LIB.BASEBOARD_FAB2(SCH_1):GND
 AK9    GND VSS<797> @BASEBOARD_FAB2_LIB.BASEBOARD_FAB2(SCH_1):GND
AK13    GND VSS<796> @BASEBOARD_FAB2_LIB.BASEBOARD_FAB2(SCH_1):GND
AK19    GND VSS<795> @BASEBOARD_FAB2_LIB.BASEBOARD_FAB2(SCH_1):GND
AK23    GND VSS<794> @BASEBOARD_FAB2_LIB.BASEBOARD_FAB2(SCH_1):GND
AK25    GND VSS<793> @BASEBOARD_FAB2_LIB.BASEBOARD_FAB2(SCH_1):GND
AK29    GND VSS<792> @BASEBOARD_FAB2_LIB.BASEBOARD_FAB2(SCH_1):GND
AK31    GND VSS<791> @BASEBOARD_FAB2_LIB.BASEBOARD_FAB2(SCH_1):GND
AK33    GND VSS<790> @BASEBOARD_FAB2_LIB.BASEBOARD_FAB2(SCH_1):GND
AK55    GND VSS<789> @BASEBOARD_FAB2_LIB.BASEBOARD_FAB2(SCH_1):GND
AK65    GND VSS<788> @BASEBOARD_FAB2_LIB.BASEBOARD_FAB2(SCH_1):GND
AK67    GND VSS<787> @BASEBOARD_FAB2_LIB.BASEBOARD_FAB2(SCH_1):GND
AK73    GND VSS<786> @BASEBOARD_FAB2_LIB.BASEBOARD_FAB2(SCH_1):GND
AK79    GND VSS<785> @BASEBOARD_FAB2_LIB.BASEBOARD_FAB2(SCH_1):GND
AK81    GND VSS<784> @BASEBOARD_FAB2_LIB.BASEBOARD_FAB2(SCH_1):GND
AK83    GND VSS<783> @BASEBOARD_FAB2_LIB.BASEBOARD_FAB2(SCH_1):GND
AK85    GND VSS<782> @BASEBOARD_FAB2_LIB.BASEBOARD_FAB2(SCH_1):GND
 AL4    GND VSS<781> @BASEBOARD_FAB2_LIB.BASEBOARD_FAB2(SCH_1):GND
AL10    GND VSS<780> @BASEBOARD_FAB2_LIB.BASEBOARD_FAB2(SCH_1):GND
AL24    GND VSS<779> @BASEBOARD_FAB2_LIB.BASEBOARD_FAB2(SCH_1):GND
AL30    GND VSS<778> @BASEBOARD_FAB2_LIB.BASEBOARD_FAB2(SCH_1):GND
AL32    GND VSS<777> @BASEBOARD_FAB2_LIB.BASEBOARD_FAB2(SCH_1):GND
AL56    GND VSS<776> @BASEBOARD_FAB2_LIB.BASEBOARD_FAB2(SCH_1):GND
AL64    GND VSS<775> @BASEBOARD_FAB2_LIB.BASEBOARD_FAB2(SCH_1):GND
AL68    GND VSS<774> @BASEBOARD_FAB2_LIB.BASEBOARD_FAB2(SCH_1):GND

SKX_EXT_B_BGA1-IC,TBD  I23  U5D1
AL76    GND VSS<773> @BASEBOARD_FAB2_LIB.BASEBOARD_FAB2(SCH_1):GND
AL78    GND VSS<772> @BASEBOARD_FAB2_LIB.BASEBOARD_FAB2(SCH_1):GND
AL80    GND VSS<771> @BASEBOARD_FAB2_LIB.BASEBOARD_FAB2(SCH_1):GND
AL82    GND VSS<770> @BASEBOARD_FAB2_LIB.BASEBOARD_FAB2(SCH_1):GND
AL86    GND VSS<769> @BASEBOARD_FAB2_LIB.BASEBOARD_FAB2(SCH_1):GND
 AM1    GND VSS<768> @BASEBOARD_FAB2_LIB.BASEBOARD_FAB2(SCH_1):GND
AC50    GND VSS<767> @BASEBOARD_FAB2_LIB.BASEBOARD_FAB2(SCH_1):GND
AM31    GND VSS<766> @BASEBOARD_FAB2_LIB.BASEBOARD_FAB2(SCH_1):GND
AM57    GND VSS<765> @BASEBOARD_FAB2_LIB.BASEBOARD_FAB2(SCH_1):GND
AM63    GND VSS<764> @BASEBOARD_FAB2_LIB.BASEBOARD_FAB2(SCH_1):GND
AM69    GND VSS<763> @BASEBOARD_FAB2_LIB.BASEBOARD_FAB2(SCH_1):GND
AM73    GND VSS<762> @BASEBOARD_FAB2_LIB.BASEBOARD_FAB2(SCH_1):GND
AM79    GND VSS<761> @BASEBOARD_FAB2_LIB.BASEBOARD_FAB2(SCH_1):GND
AM83    GND VSS<760> @BASEBOARD_FAB2_LIB.BASEBOARD_FAB2(SCH_1):GND
 AN2    GND VSS<759> @BASEBOARD_FAB2_LIB.BASEBOARD_FAB2(SCH_1):GND
 AN6    GND VSS<758> @BASEBOARD_FAB2_LIB.BASEBOARD_FAB2(SCH_1):GND
AN28    GND VSS<757> @BASEBOARD_FAB2_LIB.BASEBOARD_FAB2(SCH_1):GND
AN58    GND VSS<756> @BASEBOARD_FAB2_LIB.BASEBOARD_FAB2(SCH_1):GND
AN78    GND VSS<755> @BASEBOARD_FAB2_LIB.BASEBOARD_FAB2(SCH_1):GND
 AP5    GND VSS<754> @BASEBOARD_FAB2_LIB.BASEBOARD_FAB2(SCH_1):GND
 AP9    GND VSS<753> @BASEBOARD_FAB2_LIB.BASEBOARD_FAB2(SCH_1):GND
AP13    GND VSS<752> @BASEBOARD_FAB2_LIB.BASEBOARD_FAB2(SCH_1):GND
AP19    GND VSS<751> @BASEBOARD_FAB2_LIB.BASEBOARD_FAB2(SCH_1):GND
AP31    GND VSS<750> @BASEBOARD_FAB2_LIB.BASEBOARD_FAB2(SCH_1):GND
AP59    GND VSS<749> @BASEBOARD_FAB2_LIB.BASEBOARD_FAB2(SCH_1):GND
AP63    GND VSS<748> @BASEBOARD_FAB2_LIB.BASEBOARD_FAB2(SCH_1):GND
AP65    GND VSS<747> @BASEBOARD_FAB2_LIB.BASEBOARD_FAB2(SCH_1):GND
AP67    GND VSS<746> @BASEBOARD_FAB2_LIB.BASEBOARD_FAB2(SCH_1):GND
AP69    GND VSS<745> @BASEBOARD_FAB2_LIB.BASEBOARD_FAB2(SCH_1):GND
AP73    GND VSS<744> @BASEBOARD_FAB2_LIB.BASEBOARD_FAB2(SCH_1):GND
AP75    GND VSS<743> @BASEBOARD_FAB2_LIB.BASEBOARD_FAB2(SCH_1):GND
AP81    GND VSS<742> @BASEBOARD_FAB2_LIB.BASEBOARD_FAB2(SCH_1):GND
AP83    GND VSS<741> @BASEBOARD_FAB2_LIB.BASEBOARD_FAB2(SCH_1):GND
AP85    GND VSS<740> @BASEBOARD_FAB2_LIB.BASEBOARD_FAB2(SCH_1):GND
AR10    GND VSS<739> @BASEBOARD_FAB2_LIB.BASEBOARD_FAB2(SCH_1):GND
AR24    GND VSS<738> @BASEBOARD_FAB2_LIB.BASEBOARD_FAB2(SCH_1):GND
AR30    GND VSS<737> @BASEBOARD_FAB2_LIB.BASEBOARD_FAB2(SCH_1):GND
AR60    GND VSS<736> @BASEBOARD_FAB2_LIB.BASEBOARD_FAB2(SCH_1):GND
AR72    GND VSS<735> @BASEBOARD_FAB2_LIB.BASEBOARD_FAB2(SCH_1):GND
AR78    GND VSS<734> @BASEBOARD_FAB2_LIB.BASEBOARD_FAB2(SCH_1):GND
AC48    GND VSS<733> @BASEBOARD_FAB2_LIB.BASEBOARD_FAB2(SCH_1):GND
 P63    GND VSS<732> @BASEBOARD_FAB2_LIB.BASEBOARD_FAB2(SCH_1):GND
AT15    GND VSS<731> @BASEBOARD_FAB2_LIB.BASEBOARD_FAB2(SCH_1):GND
AT17    GND VSS<730> @BASEBOARD_FAB2_LIB.BASEBOARD_FAB2(SCH_1):GND
AT21    GND VSS<729> @BASEBOARD_FAB2_LIB.BASEBOARD_FAB2(SCH_1):GND
AT27    GND VSS<728> @BASEBOARD_FAB2_LIB.BASEBOARD_FAB2(SCH_1):GND
AT61    GND VSS<727> @BASEBOARD_FAB2_LIB.BASEBOARD_FAB2(SCH_1):GND
AT63    GND VSS<726> @BASEBOARD_FAB2_LIB.BASEBOARD_FAB2(SCH_1):GND
AT69    GND VSS<725> @BASEBOARD_FAB2_LIB.BASEBOARD_FAB2(SCH_1):GND
AT73    GND VSS<724> @BASEBOARD_FAB2_LIB.BASEBOARD_FAB2(SCH_1):GND
AT77    GND VSS<723> @BASEBOARD_FAB2_LIB.BASEBOARD_FAB2(SCH_1):GND
AT83    GND VSS<722> @BASEBOARD_FAB2_LIB.BASEBOARD_FAB2(SCH_1):GND
AT85    GND VSS<721> @BASEBOARD_FAB2_LIB.BASEBOARD_FAB2(SCH_1):GND
 AU2    GND VSS<720> @BASEBOARD_FAB2_LIB.BASEBOARD_FAB2(SCH_1):GND
 AU6    GND VSS<719> @BASEBOARD_FAB2_LIB.BASEBOARD_FAB2(SCH_1):GND
AU26    GND VSS<718> @BASEBOARD_FAB2_LIB.BASEBOARD_FAB2(SCH_1):GND
AU28    GND VSS<717> @BASEBOARD_FAB2_LIB.BASEBOARD_FAB2(SCH_1):GND
AU62    GND VSS<716> @BASEBOARD_FAB2_LIB.BASEBOARD_FAB2(SCH_1):GND
AU64    GND VSS<715> @BASEBOARD_FAB2_LIB.BASEBOARD_FAB2(SCH_1):GND
AU68    GND VSS<714> @BASEBOARD_FAB2_LIB.BASEBOARD_FAB2(SCH_1):GND
AU74    GND VSS<713> @BASEBOARD_FAB2_LIB.BASEBOARD_FAB2(SCH_1):GND
AU76    GND VSS<712> @BASEBOARD_FAB2_LIB.BASEBOARD_FAB2(SCH_1):GND
AU78    GND VSS<711> @BASEBOARD_FAB2_LIB.BASEBOARD_FAB2(SCH_1):GND
AU80    GND VSS<710> @BASEBOARD_FAB2_LIB.BASEBOARD_FAB2(SCH_1):GND
AU84    GND VSS<709> @BASEBOARD_FAB2_LIB.BASEBOARD_FAB2(SCH_1):GND
AU86    GND VSS<708> @BASEBOARD_FAB2_LIB.BASEBOARD_FAB2(SCH_1):GND
 AV1    GND VSS<707> @BASEBOARD_FAB2_LIB.BASEBOARD_FAB2(SCH_1):GND
 AV3    GND VSS<706> @BASEBOARD_FAB2_LIB.BASEBOARD_FAB2(SCH_1):GND
 AV7    GND VSS<705> @BASEBOARD_FAB2_LIB.BASEBOARD_FAB2(SCH_1):GND
AV11    GND VSS<704> @BASEBOARD_FAB2_LIB.BASEBOARD_FAB2(SCH_1):GND
AV13    GND VSS<703> @BASEBOARD_FAB2_LIB.BASEBOARD_FAB2(SCH_1):GND
AV19    GND VSS<702> @BASEBOARD_FAB2_LIB.BASEBOARD_FAB2(SCH_1):GND
AV23    GND VSS<701> @BASEBOARD_FAB2_LIB.BASEBOARD_FAB2(SCH_1):GND
AV25    GND VSS<700> @BASEBOARD_FAB2_LIB.BASEBOARD_FAB2(SCH_1):GND
AV63    GND VSS<699> @BASEBOARD_FAB2_LIB.BASEBOARD_FAB2(SCH_1):GND
AV65    GND VSS<698> @BASEBOARD_FAB2_LIB.BASEBOARD_FAB2(SCH_1):GND
AV67    GND VSS<697> @BASEBOARD_FAB2_LIB.BASEBOARD_FAB2(SCH_1):GND
AV75    GND VSS<696> @BASEBOARD_FAB2_LIB.BASEBOARD_FAB2(SCH_1):GND
AV83    GND VSS<695> @BASEBOARD_FAB2_LIB.BASEBOARD_FAB2(SCH_1):GND
 AW2    GND VSS<694> @BASEBOARD_FAB2_LIB.BASEBOARD_FAB2(SCH_1):GND
AW10    GND VSS<693> @BASEBOARD_FAB2_LIB.BASEBOARD_FAB2(SCH_1):GND
AW62    GND VSS<692> @BASEBOARD_FAB2_LIB.BASEBOARD_FAB2(SCH_1):GND
AW66    GND VSS<691> @BASEBOARD_FAB2_LIB.BASEBOARD_FAB2(SCH_1):GND
AW68    GND VSS<690> @BASEBOARD_FAB2_LIB.BASEBOARD_FAB2(SCH_1):GND
AW70    GND VSS<689> @BASEBOARD_FAB2_LIB.BASEBOARD_FAB2(SCH_1):GND
AW72    GND VSS<688> @BASEBOARD_FAB2_LIB.BASEBOARD_FAB2(SCH_1):GND
AW74    GND VSS<687> @BASEBOARD_FAB2_LIB.BASEBOARD_FAB2(SCH_1):GND
AW78    GND VSS<686> @BASEBOARD_FAB2_LIB.BASEBOARD_FAB2(SCH_1):GND
AW82    GND VSS<685> @BASEBOARD_FAB2_LIB.BASEBOARD_FAB2(SCH_1):GND
AW84    GND VSS<684> @BASEBOARD_FAB2_LIB.BASEBOARD_FAB2(SCH_1):GND
 AY5    GND VSS<683> @BASEBOARD_FAB2_LIB.BASEBOARD_FAB2(SCH_1):GND
AY15    GND VSS<682> @BASEBOARD_FAB2_LIB.BASEBOARD_FAB2(SCH_1):GND
AY17    GND VSS<681> @BASEBOARD_FAB2_LIB.BASEBOARD_FAB2(SCH_1):GND
AY21    GND VSS<680> @BASEBOARD_FAB2_LIB.BASEBOARD_FAB2(SCH_1):GND
AY23    GND VSS<679> @BASEBOARD_FAB2_LIB.BASEBOARD_FAB2(SCH_1):GND
AY25    GND VSS<678> @BASEBOARD_FAB2_LIB.BASEBOARD_FAB2(SCH_1):GND
AY63    GND VSS<677> @BASEBOARD_FAB2_LIB.BASEBOARD_FAB2(SCH_1):GND
AY79    GND VSS<676> @BASEBOARD_FAB2_LIB.BASEBOARD_FAB2(SCH_1):GND
AY81    GND VSS<675> @BASEBOARD_FAB2_LIB.BASEBOARD_FAB2(SCH_1):GND
 BA2    GND VSS<674> @BASEBOARD_FAB2_LIB.BASEBOARD_FAB2(SCH_1):GND
 BA6    GND VSS<673> @BASEBOARD_FAB2_LIB.BASEBOARD_FAB2(SCH_1):GND
BA12    GND VSS<672> @BASEBOARD_FAB2_LIB.BASEBOARD_FAB2(SCH_1):GND
BA62    GND VSS<671> @BASEBOARD_FAB2_LIB.BASEBOARD_FAB2(SCH_1):GND
BA68    GND VSS<670> @BASEBOARD_FAB2_LIB.BASEBOARD_FAB2(SCH_1):GND
BA74    GND VSS<669> @BASEBOARD_FAB2_LIB.BASEBOARD_FAB2(SCH_1):GND
BA80    GND VSS<668> @BASEBOARD_FAB2_LIB.BASEBOARD_FAB2(SCH_1):GND
BA84    GND VSS<667> @BASEBOARD_FAB2_LIB.BASEBOARD_FAB2(SCH_1):GND
BB19    GND VSS<666> @BASEBOARD_FAB2_LIB.BASEBOARD_FAB2(SCH_1):GND
BB23    GND VSS<665> @BASEBOARD_FAB2_LIB.BASEBOARD_FAB2(SCH_1):GND
BB63    GND VSS<664> @BASEBOARD_FAB2_LIB.BASEBOARD_FAB2(SCH_1):GND
BB69    GND VSS<663> @BASEBOARD_FAB2_LIB.BASEBOARD_FAB2(SCH_1):GND
BB73    GND VSS<662> @BASEBOARD_FAB2_LIB.BASEBOARD_FAB2(SCH_1):GND
BB75    GND VSS<661> @BASEBOARD_FAB2_LIB.BASEBOARD_FAB2(SCH_1):GND
BB77    GND VSS<660> @BASEBOARD_FAB2_LIB.BASEBOARD_FAB2(SCH_1):GND
BB79    GND VSS<659> @BASEBOARD_FAB2_LIB.BASEBOARD_FAB2(SCH_1):GND
BB81    GND VSS<658> @BASEBOARD_FAB2_LIB.BASEBOARD_FAB2(SCH_1):GND
BB83    GND VSS<657> @BASEBOARD_FAB2_LIB.BASEBOARD_FAB2(SCH_1):GND
 BC4    GND VSS<656> @BASEBOARD_FAB2_LIB.BASEBOARD_FAB2(SCH_1):GND
 BC8    GND VSS<655> @BASEBOARD_FAB2_LIB.BASEBOARD_FAB2(SCH_1):GND
BC12    GND VSS<654> @BASEBOARD_FAB2_LIB.BASEBOARD_FAB2(SCH_1):GND
BC16    GND VSS<653> @BASEBOARD_FAB2_LIB.BASEBOARD_FAB2(SCH_1):GND
BC70    GND VSS<652> @BASEBOARD_FAB2_LIB.BASEBOARD_FAB2(SCH_1):GND
BC72    GND VSS<651> @BASEBOARD_FAB2_LIB.BASEBOARD_FAB2(SCH_1):GND
BC74    GND VSS<650> @BASEBOARD_FAB2_LIB.BASEBOARD_FAB2(SCH_1):GND
BC76    GND VSS<649> @BASEBOARD_FAB2_LIB.BASEBOARD_FAB2(SCH_1):GND
BC78    GND VSS<648> @BASEBOARD_FAB2_LIB.BASEBOARD_FAB2(SCH_1):GND
BC80    GND VSS<647> @BASEBOARD_FAB2_LIB.BASEBOARD_FAB2(SCH_1):GND
BC82    GND VSS<646> @BASEBOARD_FAB2_LIB.BASEBOARD_FAB2(SCH_1):GND
 BD5    GND VSS<645> @BASEBOARD_FAB2_LIB.BASEBOARD_FAB2(SCH_1):GND
BD11    GND VSS<644> @BASEBOARD_FAB2_LIB.BASEBOARD_FAB2(SCH_1):GND
BD15    GND VSS<643> @BASEBOARD_FAB2_LIB.BASEBOARD_FAB2(SCH_1):GND
BD21    GND VSS<642> @BASEBOARD_FAB2_LIB.BASEBOARD_FAB2(SCH_1):GND
BD27    GND VSS<641> @BASEBOARD_FAB2_LIB.BASEBOARD_FAB2(SCH_1):GND
BD63    GND VSS<640> @BASEBOARD_FAB2_LIB.BASEBOARD_FAB2(SCH_1):GND
BD71    GND VSS<639> @BASEBOARD_FAB2_LIB.BASEBOARD_FAB2(SCH_1):GND
 BE4    GND VSS<638> @BASEBOARD_FAB2_LIB.BASEBOARD_FAB2(SCH_1):GND
 BE6    GND VSS<637> @BASEBOARD_FAB2_LIB.BASEBOARD_FAB2(SCH_1):GND
 BE8    GND VSS<636> @BASEBOARD_FAB2_LIB.BASEBOARD_FAB2(SCH_1):GND
BE10    GND VSS<635> @BASEBOARD_FAB2_LIB.BASEBOARD_FAB2(SCH_1):GND
BE26    GND VSS<634> @BASEBOARD_FAB2_LIB.BASEBOARD_FAB2(SCH_1):GND
BE64    GND VSS<633> @BASEBOARD_FAB2_LIB.BASEBOARD_FAB2(SCH_1):GND
BE66    GND VSS<632> @BASEBOARD_FAB2_LIB.BASEBOARD_FAB2(SCH_1):GND
BE68    GND VSS<631> @BASEBOARD_FAB2_LIB.BASEBOARD_FAB2(SCH_1):GND
BE70    GND VSS<630> @BASEBOARD_FAB2_LIB.BASEBOARD_FAB2(SCH_1):GND
 BF9    GND VSS<629> @BASEBOARD_FAB2_LIB.BASEBOARD_FAB2(SCH_1):GND
BF15    GND VSS<628> @BASEBOARD_FAB2_LIB.BASEBOARD_FAB2(SCH_1):GND
BF17    GND VSS<627> @BASEBOARD_FAB2_LIB.BASEBOARD_FAB2(SCH_1):GND
BF19    GND VSS<626> @BASEBOARD_FAB2_LIB.BASEBOARD_FAB2(SCH_1):GND
BF25    GND VSS<625> @BASEBOARD_FAB2_LIB.BASEBOARD_FAB2(SCH_1):GND
BF63    GND VSS<624> @BASEBOARD_FAB2_LIB.BASEBOARD_FAB2(SCH_1):GND
BF65    GND VSS<623> @BASEBOARD_FAB2_LIB.BASEBOARD_FAB2(SCH_1):GND
BF67    GND VSS<622> @BASEBOARD_FAB2_LIB.BASEBOARD_FAB2(SCH_1):GND
BF69    GND VSS<621> @BASEBOARD_FAB2_LIB.BASEBOARD_FAB2(SCH_1):GND
BF71    GND VSS<620> @BASEBOARD_FAB2_LIB.BASEBOARD_FAB2(SCH_1):GND
 BG6    GND VSS<619> @BASEBOARD_FAB2_LIB.BASEBOARD_FAB2(SCH_1):GND
 BG8    GND VSS<618> @BASEBOARD_FAB2_LIB.BASEBOARD_FAB2(SCH_1):GND
BG10    GND VSS<617> @BASEBOARD_FAB2_LIB.BASEBOARD_FAB2(SCH_1):GND
BG22    GND VSS<616> @BASEBOARD_FAB2_LIB.BASEBOARD_FAB2(SCH_1):GND
BG24    GND VSS<615> @BASEBOARD_FAB2_LIB.BASEBOARD_FAB2(SCH_1):GND
BG72    GND VSS<614> @BASEBOARD_FAB2_LIB.BASEBOARD_FAB2(SCH_1):GND


DRAWING: @BASEBOARD_FAB2_LIB.BASEBOARD_FAB2(SCH_1):PAGE41 

SKX_EXT_B_BGA1-IC,TBD  I283  U5D1
BG74    GND VSS<613> @BASEBOARD_FAB2_LIB.BASEBOARD_FAB2(SCH_1):GND
BG76    GND VSS<612> @BASEBOARD_FAB2_LIB.BASEBOARD_FAB2(SCH_1):GND
BG78    GND VSS<611> @BASEBOARD_FAB2_LIB.BASEBOARD_FAB2(SCH_1):GND
BG80    GND VSS<610> @BASEBOARD_FAB2_LIB.BASEBOARD_FAB2(SCH_1):GND
BG82    GND VSS<609> @BASEBOARD_FAB2_LIB.BASEBOARD_FAB2(SCH_1):GND
 BH7    GND VSS<608> @BASEBOARD_FAB2_LIB.BASEBOARD_FAB2(SCH_1):GND
 BH9    GND VSS<607> @BASEBOARD_FAB2_LIB.BASEBOARD_FAB2(SCH_1):GND
BH11    GND VSS<606> @BASEBOARD_FAB2_LIB.BASEBOARD_FAB2(SCH_1):GND
BH15    GND VSS<605> @BASEBOARD_FAB2_LIB.BASEBOARD_FAB2(SCH_1):GND
BH21    GND VSS<604> @BASEBOARD_FAB2_LIB.BASEBOARD_FAB2(SCH_1):GND
 BJ4    GND VSS<603> @BASEBOARD_FAB2_LIB.BASEBOARD_FAB2(SCH_1):GND
 BJ6    GND VSS<602> @BASEBOARD_FAB2_LIB.BASEBOARD_FAB2(SCH_1):GND
 BK3    GND VSS<601> @BASEBOARD_FAB2_LIB.BASEBOARD_FAB2(SCH_1):GND
 BK7    GND VSS<600> @BASEBOARD_FAB2_LIB.BASEBOARD_FAB2(SCH_1):GND
BK11    GND VSS<599> @BASEBOARD_FAB2_LIB.BASEBOARD_FAB2(SCH_1):GND
BK19    GND VSS<598> @BASEBOARD_FAB2_LIB.BASEBOARD_FAB2(SCH_1):GND
 BL6    GND VSS<597> @BASEBOARD_FAB2_LIB.BASEBOARD_FAB2(SCH_1):GND
BL10    GND VSS<596> @BASEBOARD_FAB2_LIB.BASEBOARD_FAB2(SCH_1):GND
BL12    GND VSS<595> @BASEBOARD_FAB2_LIB.BASEBOARD_FAB2(SCH_1):GND
 P61    GND VSS<594> @BASEBOARD_FAB2_LIB.BASEBOARD_FAB2(SCH_1):GND
BL22    GND VSS<593> @BASEBOARD_FAB2_LIB.BASEBOARD_FAB2(SCH_1):GND
BL24    GND VSS<592> @BASEBOARD_FAB2_LIB.BASEBOARD_FAB2(SCH_1):GND
BL64    GND VSS<591> @BASEBOARD_FAB2_LIB.BASEBOARD_FAB2(SCH_1):GND
BL66    GND VSS<590> @BASEBOARD_FAB2_LIB.BASEBOARD_FAB2(SCH_1):GND
BL68    GND VSS<589> @BASEBOARD_FAB2_LIB.BASEBOARD_FAB2(SCH_1):GND
BL70    GND VSS<588> @BASEBOARD_FAB2_LIB.BASEBOARD_FAB2(SCH_1):GND
BL72    GND VSS<587> @BASEBOARD_FAB2_LIB.BASEBOARD_FAB2(SCH_1):GND
BL74    GND VSS<586> @BASEBOARD_FAB2_LIB.BASEBOARD_FAB2(SCH_1):GND
BL76    GND VSS<585> @BASEBOARD_FAB2_LIB.BASEBOARD_FAB2(SCH_1):GND
BL78    GND VSS<584> @BASEBOARD_FAB2_LIB.BASEBOARD_FAB2(SCH_1):GND
BL80    GND VSS<583> @BASEBOARD_FAB2_LIB.BASEBOARD_FAB2(SCH_1):GND
BL82    GND VSS<582> @BASEBOARD_FAB2_LIB.BASEBOARD_FAB2(SCH_1):GND
 BM9    GND VSS<581> @BASEBOARD_FAB2_LIB.BASEBOARD_FAB2(SCH_1):GND
BM13    GND VSS<580> @BASEBOARD_FAB2_LIB.BASEBOARD_FAB2(SCH_1):GND
BM15    GND VSS<579> @BASEBOARD_FAB2_LIB.BASEBOARD_FAB2(SCH_1):GND
 P59    GND VSS<578> @BASEBOARD_FAB2_LIB.BASEBOARD_FAB2(SCH_1):GND
BM25    GND VSS<577> @BASEBOARD_FAB2_LIB.BASEBOARD_FAB2(SCH_1):GND
 BN6    GND VSS<576> @BASEBOARD_FAB2_LIB.BASEBOARD_FAB2(SCH_1):GND
BN10    GND VSS<575> @BASEBOARD_FAB2_LIB.BASEBOARD_FAB2(SCH_1):GND
BN20    GND VSS<574> @BASEBOARD_FAB2_LIB.BASEBOARD_FAB2(SCH_1):GND
BN26    GND VSS<573> @BASEBOARD_FAB2_LIB.BASEBOARD_FAB2(SCH_1):GND
 BP3    GND VSS<572> @BASEBOARD_FAB2_LIB.BASEBOARD_FAB2(SCH_1):GND
BP27    GND VSS<571> @BASEBOARD_FAB2_LIB.BASEBOARD_FAB2(SCH_1):GND
 BR6    GND VSS<570> @BASEBOARD_FAB2_LIB.BASEBOARD_FAB2(SCH_1):GND
BR10    GND VSS<569> @BASEBOARD_FAB2_LIB.BASEBOARD_FAB2(SCH_1):GND
BR16    GND VSS<568> @BASEBOARD_FAB2_LIB.BASEBOARD_FAB2(SCH_1):GND
 P57    GND VSS<567> @BASEBOARD_FAB2_LIB.BASEBOARD_FAB2(SCH_1):GND
BR64    GND VSS<566> @BASEBOARD_FAB2_LIB.BASEBOARD_FAB2(SCH_1):GND
BR66    GND VSS<565> @BASEBOARD_FAB2_LIB.BASEBOARD_FAB2(SCH_1):GND
BR68    GND VSS<564> @BASEBOARD_FAB2_LIB.BASEBOARD_FAB2(SCH_1):GND
BR70    GND VSS<563> @BASEBOARD_FAB2_LIB.BASEBOARD_FAB2(SCH_1):GND
BR72    GND VSS<562> @BASEBOARD_FAB2_LIB.BASEBOARD_FAB2(SCH_1):GND
BR74    GND VSS<561> @BASEBOARD_FAB2_LIB.BASEBOARD_FAB2(SCH_1):GND
BR76    GND VSS<560> @BASEBOARD_FAB2_LIB.BASEBOARD_FAB2(SCH_1):GND
BR78    GND VSS<559> @BASEBOARD_FAB2_LIB.BASEBOARD_FAB2(SCH_1):GND
BR80    GND VSS<558> @BASEBOARD_FAB2_LIB.BASEBOARD_FAB2(SCH_1):GND
BR82    GND VSS<557> @BASEBOARD_FAB2_LIB.BASEBOARD_FAB2(SCH_1):GND
 BT3    GND VSS<556> @BASEBOARD_FAB2_LIB.BASEBOARD_FAB2(SCH_1):GND
 BT5    GND VSS<555> @BASEBOARD_FAB2_LIB.BASEBOARD_FAB2(SCH_1):GND
BT21    GND VSS<554> @BASEBOARD_FAB2_LIB.BASEBOARD_FAB2(SCH_1):GND
BT23    GND VSS<553> @BASEBOARD_FAB2_LIB.BASEBOARD_FAB2(SCH_1):GND
BT25    GND VSS<552> @BASEBOARD_FAB2_LIB.BASEBOARD_FAB2(SCH_1):GND
 BU8    GND VSS<551> @BASEBOARD_FAB2_LIB.BASEBOARD_FAB2(SCH_1):GND
 BV5    GND VSS<550> @BASEBOARD_FAB2_LIB.BASEBOARD_FAB2(SCH_1):GND
BU10    GND VSS<549> @BASEBOARD_FAB2_LIB.BASEBOARD_FAB2(SCH_1):GND
BV17    GND VSS<548> @BASEBOARD_FAB2_LIB.BASEBOARD_FAB2(SCH_1):GND
BV25    GND VSS<547> @BASEBOARD_FAB2_LIB.BASEBOARD_FAB2(SCH_1):GND
 BW6    GND VSS<546> @BASEBOARD_FAB2_LIB.BASEBOARD_FAB2(SCH_1):GND
 P55    GND VSS<545> @BASEBOARD_FAB2_LIB.BASEBOARD_FAB2(SCH_1):GND
BW12    GND VSS<544> @BASEBOARD_FAB2_LIB.BASEBOARD_FAB2(SCH_1):GND
BW14    GND VSS<543> @BASEBOARD_FAB2_LIB.BASEBOARD_FAB2(SCH_1):GND
BW16    GND VSS<542> @BASEBOARD_FAB2_LIB.BASEBOARD_FAB2(SCH_1):GND
BW18    GND VSS<541> @BASEBOARD_FAB2_LIB.BASEBOARD_FAB2(SCH_1):GND
BW26    GND VSS<540> @BASEBOARD_FAB2_LIB.BASEBOARD_FAB2(SCH_1):GND
BW72    GND VSS<539> @BASEBOARD_FAB2_LIB.BASEBOARD_FAB2(SCH_1):GND
BW74    GND VSS<538> @BASEBOARD_FAB2_LIB.BASEBOARD_FAB2(SCH_1):GND
BW76    GND VSS<537> @BASEBOARD_FAB2_LIB.BASEBOARD_FAB2(SCH_1):GND
BW78    GND VSS<536> @BASEBOARD_FAB2_LIB.BASEBOARD_FAB2(SCH_1):GND
BW80    GND VSS<535> @BASEBOARD_FAB2_LIB.BASEBOARD_FAB2(SCH_1):GND
BW82    GND VSS<534> @BASEBOARD_FAB2_LIB.BASEBOARD_FAB2(SCH_1):GND
BY11    GND VSS<533> @BASEBOARD_FAB2_LIB.BASEBOARD_FAB2(SCH_1):GND
BY13    GND VSS<532> @BASEBOARD_FAB2_LIB.BASEBOARD_FAB2(SCH_1):GND
BY23    GND VSS<531> @BASEBOARD_FAB2_LIB.BASEBOARD_FAB2(SCH_1):GND
BY63    GND VSS<530> @BASEBOARD_FAB2_LIB.BASEBOARD_FAB2(SCH_1):GND
BY65    GND VSS<529> @BASEBOARD_FAB2_LIB.BASEBOARD_FAB2(SCH_1):GND
BY67    GND VSS<528> @BASEBOARD_FAB2_LIB.BASEBOARD_FAB2(SCH_1):GND
BY69    GND VSS<527> @BASEBOARD_FAB2_LIB.BASEBOARD_FAB2(SCH_1):GND
BY71    GND VSS<526> @BASEBOARD_FAB2_LIB.BASEBOARD_FAB2(SCH_1):GND
 CA2    GND VSS<525> @BASEBOARD_FAB2_LIB.BASEBOARD_FAB2(SCH_1):GND
 CA6    GND VSS<524> @BASEBOARD_FAB2_LIB.BASEBOARD_FAB2(SCH_1):GND
 CA8    GND VSS<523> @BASEBOARD_FAB2_LIB.BASEBOARD_FAB2(SCH_1):GND
CA10    GND VSS<522> @BASEBOARD_FAB2_LIB.BASEBOARD_FAB2(SCH_1):GND
CA14    GND VSS<521> @BASEBOARD_FAB2_LIB.BASEBOARD_FAB2(SCH_1):GND
CA18    GND VSS<520> @BASEBOARD_FAB2_LIB.BASEBOARD_FAB2(SCH_1):GND
CA26    GND VSS<519> @BASEBOARD_FAB2_LIB.BASEBOARD_FAB2(SCH_1):GND
CA64    GND VSS<518> @BASEBOARD_FAB2_LIB.BASEBOARD_FAB2(SCH_1):GND
CA66    GND VSS<517> @BASEBOARD_FAB2_LIB.BASEBOARD_FAB2(SCH_1):GND
CA68    GND VSS<516> @BASEBOARD_FAB2_LIB.BASEBOARD_FAB2(SCH_1):GND
CA70    GND VSS<515> @BASEBOARD_FAB2_LIB.BASEBOARD_FAB2(SCH_1):GND
 CB7    GND VSS<514> @BASEBOARD_FAB2_LIB.BASEBOARD_FAB2(SCH_1):GND
 CB9    GND VSS<513> @BASEBOARD_FAB2_LIB.BASEBOARD_FAB2(SCH_1):GND
CB27    GND VSS<512> @BASEBOARD_FAB2_LIB.BASEBOARD_FAB2(SCH_1):GND
CB63    GND VSS<511> @BASEBOARD_FAB2_LIB.BASEBOARD_FAB2(SCH_1):GND
CB71    GND VSS<510> @BASEBOARD_FAB2_LIB.BASEBOARD_FAB2(SCH_1):GND
 CC4    GND VSS<509> @BASEBOARD_FAB2_LIB.BASEBOARD_FAB2(SCH_1):GND
CC16    GND VSS<508> @BASEBOARD_FAB2_LIB.BASEBOARD_FAB2(SCH_1):GND
CC18    GND VSS<507> @BASEBOARD_FAB2_LIB.BASEBOARD_FAB2(SCH_1):GND
CC24    GND VSS<506> @BASEBOARD_FAB2_LIB.BASEBOARD_FAB2(SCH_1):GND
CC64    GND VSS<505> @BASEBOARD_FAB2_LIB.BASEBOARD_FAB2(SCH_1):GND
CC72    GND VSS<504> @BASEBOARD_FAB2_LIB.BASEBOARD_FAB2(SCH_1):GND
CC74    GND VSS<503> @BASEBOARD_FAB2_LIB.BASEBOARD_FAB2(SCH_1):GND
CC76    GND VSS<502> @BASEBOARD_FAB2_LIB.BASEBOARD_FAB2(SCH_1):GND
CC78    GND VSS<501> @BASEBOARD_FAB2_LIB.BASEBOARD_FAB2(SCH_1):GND
CC80    GND VSS<500> @BASEBOARD_FAB2_LIB.BASEBOARD_FAB2(SCH_1):GND
CC82    GND VSS<499> @BASEBOARD_FAB2_LIB.BASEBOARD_FAB2(SCH_1):GND
 CD5    GND VSS<498> @BASEBOARD_FAB2_LIB.BASEBOARD_FAB2(SCH_1):GND
CD13    GND VSS<497> @BASEBOARD_FAB2_LIB.BASEBOARD_FAB2(SCH_1):GND
CD63    GND VSS<496> @BASEBOARD_FAB2_LIB.BASEBOARD_FAB2(SCH_1):GND
CD73    GND VSS<495> @BASEBOARD_FAB2_LIB.BASEBOARD_FAB2(SCH_1):GND
CD75    GND VSS<494> @BASEBOARD_FAB2_LIB.BASEBOARD_FAB2(SCH_1):GND
CD77    GND VSS<493> @BASEBOARD_FAB2_LIB.BASEBOARD_FAB2(SCH_1):GND
CD79    GND VSS<492> @BASEBOARD_FAB2_LIB.BASEBOARD_FAB2(SCH_1):GND
CD81    GND VSS<491> @BASEBOARD_FAB2_LIB.BASEBOARD_FAB2(SCH_1):GND
CE10    GND VSS<490> @BASEBOARD_FAB2_LIB.BASEBOARD_FAB2(SCH_1):GND
CE14    GND VSS<489> @BASEBOARD_FAB2_LIB.BASEBOARD_FAB2(SCH_1):GND
CE20    GND VSS<488> @BASEBOARD_FAB2_LIB.BASEBOARD_FAB2(SCH_1):GND
CE26    GND VSS<487> @BASEBOARD_FAB2_LIB.BASEBOARD_FAB2(SCH_1):GND
CE62    GND VSS<486> @BASEBOARD_FAB2_LIB.BASEBOARD_FAB2(SCH_1):GND
CE70    GND VSS<485> @BASEBOARD_FAB2_LIB.BASEBOARD_FAB2(SCH_1):GND
CE82    GND VSS<484> @BASEBOARD_FAB2_LIB.BASEBOARD_FAB2(SCH_1):GND
 P53    GND VSS<483> @BASEBOARD_FAB2_LIB.BASEBOARD_FAB2(SCH_1):GND
 CF9    GND VSS<482> @BASEBOARD_FAB2_LIB.BASEBOARD_FAB2(SCH_1):GND
CF63    GND VSS<481> @BASEBOARD_FAB2_LIB.BASEBOARD_FAB2(SCH_1):GND
CF69    GND VSS<480> @BASEBOARD_FAB2_LIB.BASEBOARD_FAB2(SCH_1):GND
CF71    GND VSS<479> @BASEBOARD_FAB2_LIB.BASEBOARD_FAB2(SCH_1):GND
CF77    GND VSS<478> @BASEBOARD_FAB2_LIB.BASEBOARD_FAB2(SCH_1):GND
CF83    GND VSS<477> @BASEBOARD_FAB2_LIB.BASEBOARD_FAB2(SCH_1):GND
 P51    GND VSS<476> @BASEBOARD_FAB2_LIB.BASEBOARD_FAB2(SCH_1):GND
CG18    GND VSS<475> @BASEBOARD_FAB2_LIB.BASEBOARD_FAB2(SCH_1):GND
CG22    GND VSS<474> @BASEBOARD_FAB2_LIB.BASEBOARD_FAB2(SCH_1):GND
CG62    GND VSS<473> @BASEBOARD_FAB2_LIB.BASEBOARD_FAB2(SCH_1):GND
CG68    GND VSS<472> @BASEBOARD_FAB2_LIB.BASEBOARD_FAB2(SCH_1):GND
CG72    GND VSS<471> @BASEBOARD_FAB2_LIB.BASEBOARD_FAB2(SCH_1):GND
CG80    GND VSS<470> @BASEBOARD_FAB2_LIB.BASEBOARD_FAB2(SCH_1):GND
 CH1    GND VSS<469> @BASEBOARD_FAB2_LIB.BASEBOARD_FAB2(SCH_1):GND
 CH3    GND VSS<468> @BASEBOARD_FAB2_LIB.BASEBOARD_FAB2(SCH_1):GND
CH15    GND VSS<467> @BASEBOARD_FAB2_LIB.BASEBOARD_FAB2(SCH_1):GND
CH19    GND VSS<466> @BASEBOARD_FAB2_LIB.BASEBOARD_FAB2(SCH_1):GND
CH63    GND VSS<465> @BASEBOARD_FAB2_LIB.BASEBOARD_FAB2(SCH_1):GND
CH67    GND VSS<464> @BASEBOARD_FAB2_LIB.BASEBOARD_FAB2(SCH_1):GND
CH73    GND VSS<463> @BASEBOARD_FAB2_LIB.BASEBOARD_FAB2(SCH_1):GND
CH79    GND VSS<462> @BASEBOARD_FAB2_LIB.BASEBOARD_FAB2(SCH_1):GND
CH81    GND VSS<461> @BASEBOARD_FAB2_LIB.BASEBOARD_FAB2(SCH_1):GND
CH83    GND VSS<460> @BASEBOARD_FAB2_LIB.BASEBOARD_FAB2(SCH_1):GND
 CJ2    GND VSS<459> @BASEBOARD_FAB2_LIB.BASEBOARD_FAB2(SCH_1):GND
 CJ6    GND VSS<458> @BASEBOARD_FAB2_LIB.BASEBOARD_FAB2(SCH_1):GND
 CJ8    GND VSS<457> @BASEBOARD_FAB2_LIB.BASEBOARD_FAB2(SCH_1):GND
CJ10    GND VSS<456> @BASEBOARD_FAB2_LIB.BASEBOARD_FAB2(SCH_1):GND
CJ12    GND VSS<455> @BASEBOARD_FAB2_LIB.BASEBOARD_FAB2(SCH_1):GND
 P49    GND VSS<454> @BASEBOARD_FAB2_LIB.BASEBOARD_FAB2(SCH_1):GND

SKX_EXT_B_BGA1-IC,TBD  I284  U5D1
 P47    GND VSS<453> @BASEBOARD_FAB2_LIB.BASEBOARD_FAB2(SCH_1):GND
CJ62    GND VSS<452> @BASEBOARD_FAB2_LIB.BASEBOARD_FAB2(SCH_1):GND
CJ74    GND VSS<451> @BASEBOARD_FAB2_LIB.BASEBOARD_FAB2(SCH_1):GND
CJ76    GND VSS<450> @BASEBOARD_FAB2_LIB.BASEBOARD_FAB2(SCH_1):GND
CJ78    GND VSS<449> @BASEBOARD_FAB2_LIB.BASEBOARD_FAB2(SCH_1):GND
CJ82    GND VSS<448> @BASEBOARD_FAB2_LIB.BASEBOARD_FAB2(SCH_1):GND
CJ84    GND VSS<447> @BASEBOARD_FAB2_LIB.BASEBOARD_FAB2(SCH_1):GND
CJ86    GND VSS<446> @BASEBOARD_FAB2_LIB.BASEBOARD_FAB2(SCH_1):GND
CK11    GND VSS<445> @BASEBOARD_FAB2_LIB.BASEBOARD_FAB2(SCH_1):GND
CK15    GND VSS<444> @BASEBOARD_FAB2_LIB.BASEBOARD_FAB2(SCH_1):GND
CK21    GND VSS<443> @BASEBOARD_FAB2_LIB.BASEBOARD_FAB2(SCH_1):GND
CK27    GND VSS<442> @BASEBOARD_FAB2_LIB.BASEBOARD_FAB2(SCH_1):GND
CK63    GND VSS<441> @BASEBOARD_FAB2_LIB.BASEBOARD_FAB2(SCH_1):GND
CK65    GND VSS<440> @BASEBOARD_FAB2_LIB.BASEBOARD_FAB2(SCH_1):GND
CK67    GND VSS<439> @BASEBOARD_FAB2_LIB.BASEBOARD_FAB2(SCH_1):GND
CK69    GND VSS<438> @BASEBOARD_FAB2_LIB.BASEBOARD_FAB2(SCH_1):GND
CK71    GND VSS<437> @BASEBOARD_FAB2_LIB.BASEBOARD_FAB2(SCH_1):GND
CK73    GND VSS<436> @BASEBOARD_FAB2_LIB.BASEBOARD_FAB2(SCH_1):GND
CK75    GND VSS<435> @BASEBOARD_FAB2_LIB.BASEBOARD_FAB2(SCH_1):GND
CK83    GND VSS<434> @BASEBOARD_FAB2_LIB.BASEBOARD_FAB2(SCH_1):GND
CK85    GND VSS<433> @BASEBOARD_FAB2_LIB.BASEBOARD_FAB2(SCH_1):GND
 CL8    GND VSS<432> @BASEBOARD_FAB2_LIB.BASEBOARD_FAB2(SCH_1):GND
CL14    GND VSS<431> @BASEBOARD_FAB2_LIB.BASEBOARD_FAB2(SCH_1):GND
CL18    GND VSS<430> @BASEBOARD_FAB2_LIB.BASEBOARD_FAB2(SCH_1):GND
 P45    GND VSS<429> @BASEBOARD_FAB2_LIB.BASEBOARD_FAB2(SCH_1):GND
 H63    GND VSS<428> @BASEBOARD_FAB2_LIB.BASEBOARD_FAB2(SCH_1):GND
CL62    GND VSS<427> @BASEBOARD_FAB2_LIB.BASEBOARD_FAB2(SCH_1):GND
CL64    GND VSS<426> @BASEBOARD_FAB2_LIB.BASEBOARD_FAB2(SCH_1):GND
CL66    GND VSS<425> @BASEBOARD_FAB2_LIB.BASEBOARD_FAB2(SCH_1):GND
CL74    GND VSS<424> @BASEBOARD_FAB2_LIB.BASEBOARD_FAB2(SCH_1):GND
CL76    GND VSS<423> @BASEBOARD_FAB2_LIB.BASEBOARD_FAB2(SCH_1):GND
CL78    GND VSS<422> @BASEBOARD_FAB2_LIB.BASEBOARD_FAB2(SCH_1):GND
CL80    GND VSS<421> @BASEBOARD_FAB2_LIB.BASEBOARD_FAB2(SCH_1):GND
CM19    GND VSS<420> @BASEBOARD_FAB2_LIB.BASEBOARD_FAB2(SCH_1):GND
CM29    GND VSS<419> @BASEBOARD_FAB2_LIB.BASEBOARD_FAB2(SCH_1):GND
 CM5    GND VSS<418> @BASEBOARD_FAB2_LIB.BASEBOARD_FAB2(SCH_1):GND
CM31    GND VSS<417> @BASEBOARD_FAB2_LIB.BASEBOARD_FAB2(SCH_1):GND
CM61    GND VSS<416> @BASEBOARD_FAB2_LIB.BASEBOARD_FAB2(SCH_1):GND
CM63    GND VSS<415> @BASEBOARD_FAB2_LIB.BASEBOARD_FAB2(SCH_1):GND
CM67    GND VSS<414> @BASEBOARD_FAB2_LIB.BASEBOARD_FAB2(SCH_1):GND
CM73    GND VSS<413> @BASEBOARD_FAB2_LIB.BASEBOARD_FAB2(SCH_1):GND
CM77    GND VSS<412> @BASEBOARD_FAB2_LIB.BASEBOARD_FAB2(SCH_1):GND
CM83    GND VSS<411> @BASEBOARD_FAB2_LIB.BASEBOARD_FAB2(SCH_1):GND
CM85    GND VSS<410> @BASEBOARD_FAB2_LIB.BASEBOARD_FAB2(SCH_1):GND
 CN2    GND VSS<409> @BASEBOARD_FAB2_LIB.BASEBOARD_FAB2(SCH_1):GND
CN12    GND VSS<408> @BASEBOARD_FAB2_LIB.BASEBOARD_FAB2(SCH_1):GND
 H61    GND VSS<407> @BASEBOARD_FAB2_LIB.BASEBOARD_FAB2(SCH_1):GND
CN26    GND VSS<406> @BASEBOARD_FAB2_LIB.BASEBOARD_FAB2(SCH_1):GND
CN32    GND VSS<405> @BASEBOARD_FAB2_LIB.BASEBOARD_FAB2(SCH_1):GND
CN60    GND VSS<404> @BASEBOARD_FAB2_LIB.BASEBOARD_FAB2(SCH_1):GND
CN62    GND VSS<403> @BASEBOARD_FAB2_LIB.BASEBOARD_FAB2(SCH_1):GND
CN68    GND VSS<402> @BASEBOARD_FAB2_LIB.BASEBOARD_FAB2(SCH_1):GND
CN78    GND VSS<401> @BASEBOARD_FAB2_LIB.BASEBOARD_FAB2(SCH_1):GND
 CP1    GND VSS<400> @BASEBOARD_FAB2_LIB.BASEBOARD_FAB2(SCH_1):GND
 H59    GND VSS<399> @BASEBOARD_FAB2_LIB.BASEBOARD_FAB2(SCH_1):GND
CP25    GND VSS<398> @BASEBOARD_FAB2_LIB.BASEBOARD_FAB2(SCH_1):GND
CP59    GND VSS<397> @BASEBOARD_FAB2_LIB.BASEBOARD_FAB2(SCH_1):GND
CP69    GND VSS<396> @BASEBOARD_FAB2_LIB.BASEBOARD_FAB2(SCH_1):GND
CP73    GND VSS<395> @BASEBOARD_FAB2_LIB.BASEBOARD_FAB2(SCH_1):GND
CP75    GND VSS<394> @BASEBOARD_FAB2_LIB.BASEBOARD_FAB2(SCH_1):GND
CP81    GND VSS<393> @BASEBOARD_FAB2_LIB.BASEBOARD_FAB2(SCH_1):GND
CP83    GND VSS<392> @BASEBOARD_FAB2_LIB.BASEBOARD_FAB2(SCH_1):GND
 CR6    GND VSS<391> @BASEBOARD_FAB2_LIB.BASEBOARD_FAB2(SCH_1):GND
CR10    GND VSS<390> @BASEBOARD_FAB2_LIB.BASEBOARD_FAB2(SCH_1):GND
CR22    GND VSS<389> @BASEBOARD_FAB2_LIB.BASEBOARD_FAB2(SCH_1):GND
CR24    GND VSS<388> @BASEBOARD_FAB2_LIB.BASEBOARD_FAB2(SCH_1):GND
CR32    GND VSS<387> @BASEBOARD_FAB2_LIB.BASEBOARD_FAB2(SCH_1):GND
CR58    GND VSS<386> @BASEBOARD_FAB2_LIB.BASEBOARD_FAB2(SCH_1):GND
CR62    GND VSS<385> @BASEBOARD_FAB2_LIB.BASEBOARD_FAB2(SCH_1):GND
CR64    GND VSS<384> @BASEBOARD_FAB2_LIB.BASEBOARD_FAB2(SCH_1):GND
CR66    GND VSS<383> @BASEBOARD_FAB2_LIB.BASEBOARD_FAB2(SCH_1):GND
CR68    GND VSS<382> @BASEBOARD_FAB2_LIB.BASEBOARD_FAB2(SCH_1):GND
CR78    GND VSS<381> @BASEBOARD_FAB2_LIB.BASEBOARD_FAB2(SCH_1):GND
CR86    GND VSS<380> @BASEBOARD_FAB2_LIB.BASEBOARD_FAB2(SCH_1):GND
 H57    GND VSS<379> @BASEBOARD_FAB2_LIB.BASEBOARD_FAB2(SCH_1):GND
CT13    GND VSS<378> @BASEBOARD_FAB2_LIB.BASEBOARD_FAB2(SCH_1):GND
CT19    GND VSS<377> @BASEBOARD_FAB2_LIB.BASEBOARD_FAB2(SCH_1):GND
CT27    GND VSS<376> @BASEBOARD_FAB2_LIB.BASEBOARD_FAB2(SCH_1):GND
CT29    GND VSS<375> @BASEBOARD_FAB2_LIB.BASEBOARD_FAB2(SCH_1):GND
CT33    GND VSS<374> @BASEBOARD_FAB2_LIB.BASEBOARD_FAB2(SCH_1):GND
CT35    GND VSS<373> @BASEBOARD_FAB2_LIB.BASEBOARD_FAB2(SCH_1):GND
CT57    GND VSS<372> @BASEBOARD_FAB2_LIB.BASEBOARD_FAB2(SCH_1):GND
CT73    GND VSS<371> @BASEBOARD_FAB2_LIB.BASEBOARD_FAB2(SCH_1):GND
CT79    GND VSS<370> @BASEBOARD_FAB2_LIB.BASEBOARD_FAB2(SCH_1):GND
CT83    GND VSS<369> @BASEBOARD_FAB2_LIB.BASEBOARD_FAB2(SCH_1):GND
CT85    GND VSS<368> @BASEBOARD_FAB2_LIB.BASEBOARD_FAB2(SCH_1):GND
 CU4    GND VSS<367> @BASEBOARD_FAB2_LIB.BASEBOARD_FAB2(SCH_1):GND
CU22    GND VSS<366> @BASEBOARD_FAB2_LIB.BASEBOARD_FAB2(SCH_1):GND
CU28    GND VSS<365> @BASEBOARD_FAB2_LIB.BASEBOARD_FAB2(SCH_1):GND
CU30    GND VSS<364> @BASEBOARD_FAB2_LIB.BASEBOARD_FAB2(SCH_1):GND
CU34    GND VSS<363> @BASEBOARD_FAB2_LIB.BASEBOARD_FAB2(SCH_1):GND
CU36    GND VSS<362> @BASEBOARD_FAB2_LIB.BASEBOARD_FAB2(SCH_1):GND
CU56    GND VSS<361> @BASEBOARD_FAB2_LIB.BASEBOARD_FAB2(SCH_1):GND
CU62    GND VSS<360> @BASEBOARD_FAB2_LIB.BASEBOARD_FAB2(SCH_1):GND
CU68    GND VSS<359> @BASEBOARD_FAB2_LIB.BASEBOARD_FAB2(SCH_1):GND
CU76    GND VSS<358> @BASEBOARD_FAB2_LIB.BASEBOARD_FAB2(SCH_1):GND
CU78    GND VSS<357> @BASEBOARD_FAB2_LIB.BASEBOARD_FAB2(SCH_1):GND
CU80    GND VSS<356> @BASEBOARD_FAB2_LIB.BASEBOARD_FAB2(SCH_1):GND
CU82    GND VSS<355> @BASEBOARD_FAB2_LIB.BASEBOARD_FAB2(SCH_1):GND
CU86    GND VSS<354> @BASEBOARD_FAB2_LIB.BASEBOARD_FAB2(SCH_1):GND
 CV1    GND VSS<353> @BASEBOARD_FAB2_LIB.BASEBOARD_FAB2(SCH_1):GND
 H55    GND VSS<352> @BASEBOARD_FAB2_LIB.BASEBOARD_FAB2(SCH_1):GND
CV17    GND VSS<351> @BASEBOARD_FAB2_LIB.BASEBOARD_FAB2(SCH_1):GND
CV25    GND VSS<350> @BASEBOARD_FAB2_LIB.BASEBOARD_FAB2(SCH_1):GND
CV27    GND VSS<349> @BASEBOARD_FAB2_LIB.BASEBOARD_FAB2(SCH_1):GND
CV31    GND VSS<348> @BASEBOARD_FAB2_LIB.BASEBOARD_FAB2(SCH_1):GND
CV33    GND VSS<347> @BASEBOARD_FAB2_LIB.BASEBOARD_FAB2(SCH_1):GND
CV37    GND VSS<346> @BASEBOARD_FAB2_LIB.BASEBOARD_FAB2(SCH_1):GND
CV39    GND VSS<345> @BASEBOARD_FAB2_LIB.BASEBOARD_FAB2(SCH_1):GND
CV41    GND VSS<344> @BASEBOARD_FAB2_LIB.BASEBOARD_FAB2(SCH_1):GND
CV53    GND VSS<343> @BASEBOARD_FAB2_LIB.BASEBOARD_FAB2(SCH_1):GND
CV55    GND VSS<342> @BASEBOARD_FAB2_LIB.BASEBOARD_FAB2(SCH_1):GND
CV63    GND VSS<341> @BASEBOARD_FAB2_LIB.BASEBOARD_FAB2(SCH_1):GND
CV67    GND VSS<340> @BASEBOARD_FAB2_LIB.BASEBOARD_FAB2(SCH_1):GND
CV73    GND VSS<339> @BASEBOARD_FAB2_LIB.BASEBOARD_FAB2(SCH_1):GND
CV79    GND VSS<338> @BASEBOARD_FAB2_LIB.BASEBOARD_FAB2(SCH_1):GND
CV81    GND VSS<337> @BASEBOARD_FAB2_LIB.BASEBOARD_FAB2(SCH_1):GND
CV83    GND VSS<336> @BASEBOARD_FAB2_LIB.BASEBOARD_FAB2(SCH_1):GND
CW12    GND VSS<335> @BASEBOARD_FAB2_LIB.BASEBOARD_FAB2(SCH_1):GND
CW26    GND VSS<334> @BASEBOARD_FAB2_LIB.BASEBOARD_FAB2(SCH_1):GND
CW32    GND VSS<333> @BASEBOARD_FAB2_LIB.BASEBOARD_FAB2(SCH_1):GND
CW38    GND VSS<332> @BASEBOARD_FAB2_LIB.BASEBOARD_FAB2(SCH_1):GND
CW40    GND VSS<331> @BASEBOARD_FAB2_LIB.BASEBOARD_FAB2(SCH_1):GND
CW42    GND VSS<330> @BASEBOARD_FAB2_LIB.BASEBOARD_FAB2(SCH_1):GND
CW52    GND VSS<329> @BASEBOARD_FAB2_LIB.BASEBOARD_FAB2(SCH_1):GND
CW54    GND VSS<328> @BASEBOARD_FAB2_LIB.BASEBOARD_FAB2(SCH_1):GND
CW64    GND VSS<327> @BASEBOARD_FAB2_LIB.BASEBOARD_FAB2(SCH_1):GND
CW66    GND VSS<326> @BASEBOARD_FAB2_LIB.BASEBOARD_FAB2(SCH_1):GND
CW68    GND VSS<325> @BASEBOARD_FAB2_LIB.BASEBOARD_FAB2(SCH_1):GND
CW74    GND VSS<324> @BASEBOARD_FAB2_LIB.BASEBOARD_FAB2(SCH_1):GND
CW78    GND VSS<323> @BASEBOARD_FAB2_LIB.BASEBOARD_FAB2(SCH_1):GND
CW82    GND VSS<322> @BASEBOARD_FAB2_LIB.BASEBOARD_FAB2(SCH_1):GND
 CY1    GND VSS<321> @BASEBOARD_FAB2_LIB.BASEBOARD_FAB2(SCH_1):GND
 CY9    GND VSS<320> @BASEBOARD_FAB2_LIB.BASEBOARD_FAB2(SCH_1):GND
CY13    GND VSS<319> @BASEBOARD_FAB2_LIB.BASEBOARD_FAB2(SCH_1):GND
CY15    GND VSS<318> @BASEBOARD_FAB2_LIB.BASEBOARD_FAB2(SCH_1):GND
CY21    GND VSS<317> @BASEBOARD_FAB2_LIB.BASEBOARD_FAB2(SCH_1):GND
CY41    GND VSS<316> @BASEBOARD_FAB2_LIB.BASEBOARD_FAB2(SCH_1):GND
CY45    GND VSS<315> @BASEBOARD_FAB2_LIB.BASEBOARD_FAB2(SCH_1):GND
CY51    GND VSS<314> @BASEBOARD_FAB2_LIB.BASEBOARD_FAB2(SCH_1):GND
CY59    GND VSS<313> @BASEBOARD_FAB2_LIB.BASEBOARD_FAB2(SCH_1):GND
CY61    GND VSS<312> @BASEBOARD_FAB2_LIB.BASEBOARD_FAB2(SCH_1):GND
CY65    GND VSS<311> @BASEBOARD_FAB2_LIB.BASEBOARD_FAB2(SCH_1):GND
CY69    GND VSS<310> @BASEBOARD_FAB2_LIB.BASEBOARD_FAB2(SCH_1):GND
CY75    GND VSS<309> @BASEBOARD_FAB2_LIB.BASEBOARD_FAB2(SCH_1):GND
CY77    GND VSS<308> @BASEBOARD_FAB2_LIB.BASEBOARD_FAB2(SCH_1):GND
CY83    GND VSS<307> @BASEBOARD_FAB2_LIB.BASEBOARD_FAB2(SCH_1):GND
CY85    GND VSS<306> @BASEBOARD_FAB2_LIB.BASEBOARD_FAB2(SCH_1):GND
 DA6    GND VSS<305> @BASEBOARD_FAB2_LIB.BASEBOARD_FAB2(SCH_1):GND
 H53    GND VSS<304> @BASEBOARD_FAB2_LIB.BASEBOARD_FAB2(SCH_1):GND
DA18    GND VSS<303> @BASEBOARD_FAB2_LIB.BASEBOARD_FAB2(SCH_1):GND
DA26    GND VSS<302> @BASEBOARD_FAB2_LIB.BASEBOARD_FAB2(SCH_1):GND
DA28    GND VSS<301> @BASEBOARD_FAB2_LIB.BASEBOARD_FAB2(SCH_1):GND
DA30    GND VSS<300> @BASEBOARD_FAB2_LIB.BASEBOARD_FAB2(SCH_1):GND
DA32    GND VSS<299> @BASEBOARD_FAB2_LIB.BASEBOARD_FAB2(SCH_1):GND
DA34    GND VSS<298> @BASEBOARD_FAB2_LIB.BASEBOARD_FAB2(SCH_1):GND
DA36    GND VSS<297> @BASEBOARD_FAB2_LIB.BASEBOARD_FAB2(SCH_1):GND
DA38    GND VSS<296> @BASEBOARD_FAB2_LIB.BASEBOARD_FAB2(SCH_1):GND
DA44    GND VSS<295> @BASEBOARD_FAB2_LIB.BASEBOARD_FAB2(SCH_1):GND
DA46    GND VSS<294> @BASEBOARD_FAB2_LIB.BASEBOARD_FAB2(SCH_1):GND

SKX_EXT_B_BGA1-IC,TBD  I285  U5D1
DA48    GND VSS<293> @BASEBOARD_FAB2_LIB.BASEBOARD_FAB2(SCH_1):GND
DA50    GND VSS<292> @BASEBOARD_FAB2_LIB.BASEBOARD_FAB2(SCH_1):GND
DA64    GND VSS<291> @BASEBOARD_FAB2_LIB.BASEBOARD_FAB2(SCH_1):GND
DA70    GND VSS<290> @BASEBOARD_FAB2_LIB.BASEBOARD_FAB2(SCH_1):GND
DA74    GND VSS<289> @BASEBOARD_FAB2_LIB.BASEBOARD_FAB2(SCH_1):GND
DA76    GND VSS<288> @BASEBOARD_FAB2_LIB.BASEBOARD_FAB2(SCH_1):GND
DA78    GND VSS<287> @BASEBOARD_FAB2_LIB.BASEBOARD_FAB2(SCH_1):GND
DA80    GND VSS<286> @BASEBOARD_FAB2_LIB.BASEBOARD_FAB2(SCH_1):GND
 DB3    GND VSS<285> @BASEBOARD_FAB2_LIB.BASEBOARD_FAB2(SCH_1):GND
DB13    GND VSS<284> @BASEBOARD_FAB2_LIB.BASEBOARD_FAB2(SCH_1):GND
DB17    GND VSS<283> @BASEBOARD_FAB2_LIB.BASEBOARD_FAB2(SCH_1):GND
DB23    GND VSS<282> @BASEBOARD_FAB2_LIB.BASEBOARD_FAB2(SCH_1):GND
DB25    GND VSS<281> @BASEBOARD_FAB2_LIB.BASEBOARD_FAB2(SCH_1):GND
DB39    GND VSS<280> @BASEBOARD_FAB2_LIB.BASEBOARD_FAB2(SCH_1):GND
DB41    GND VSS<279> @BASEBOARD_FAB2_LIB.BASEBOARD_FAB2(SCH_1):GND
DB47    GND VSS<278> @BASEBOARD_FAB2_LIB.BASEBOARD_FAB2(SCH_1):GND
DB49    GND VSS<277> @BASEBOARD_FAB2_LIB.BASEBOARD_FAB2(SCH_1):GND
DB73    GND VSS<276> @BASEBOARD_FAB2_LIB.BASEBOARD_FAB2(SCH_1):GND
DB77    GND VSS<275> @BASEBOARD_FAB2_LIB.BASEBOARD_FAB2(SCH_1):GND
DB83    GND VSS<274> @BASEBOARD_FAB2_LIB.BASEBOARD_FAB2(SCH_1):GND
DB85    GND VSS<273> @BASEBOARD_FAB2_LIB.BASEBOARD_FAB2(SCH_1):GND
DC14    GND VSS<272> @BASEBOARD_FAB2_LIB.BASEBOARD_FAB2(SCH_1):GND
DC24    GND VSS<271> @BASEBOARD_FAB2_LIB.BASEBOARD_FAB2(SCH_1):GND
DC26    GND VSS<270> @BASEBOARD_FAB2_LIB.BASEBOARD_FAB2(SCH_1):GND
DC32    GND VSS<269> @BASEBOARD_FAB2_LIB.BASEBOARD_FAB2(SCH_1):GND
DC38    GND VSS<268> @BASEBOARD_FAB2_LIB.BASEBOARD_FAB2(SCH_1):GND
DC42    GND VSS<267> @BASEBOARD_FAB2_LIB.BASEBOARD_FAB2(SCH_1):GND
DC64    GND VSS<266> @BASEBOARD_FAB2_LIB.BASEBOARD_FAB2(SCH_1):GND
DC66    GND VSS<265> @BASEBOARD_FAB2_LIB.BASEBOARD_FAB2(SCH_1):GND
DC68    GND VSS<264> @BASEBOARD_FAB2_LIB.BASEBOARD_FAB2(SCH_1):GND
DC70    GND VSS<263> @BASEBOARD_FAB2_LIB.BASEBOARD_FAB2(SCH_1):GND
DC78    GND VSS<262> @BASEBOARD_FAB2_LIB.BASEBOARD_FAB2(SCH_1):GND
DC84    GND VSS<261> @BASEBOARD_FAB2_LIB.BASEBOARD_FAB2(SCH_1):GND
DC86    GND VSS<260> @BASEBOARD_FAB2_LIB.BASEBOARD_FAB2(SCH_1):GND
DD11    GND VSS<259> @BASEBOARD_FAB2_LIB.BASEBOARD_FAB2(SCH_1):GND
DD23    GND VSS<258> @BASEBOARD_FAB2_LIB.BASEBOARD_FAB2(SCH_1):GND
DD27    GND VSS<257> @BASEBOARD_FAB2_LIB.BASEBOARD_FAB2(SCH_1):GND
DD31    GND VSS<256> @BASEBOARD_FAB2_LIB.BASEBOARD_FAB2(SCH_1):GND
DD33    GND VSS<255> @BASEBOARD_FAB2_LIB.BASEBOARD_FAB2(SCH_1):GND
DD37    GND VSS<254> @BASEBOARD_FAB2_LIB.BASEBOARD_FAB2(SCH_1):GND
DD71    GND VSS<253> @BASEBOARD_FAB2_LIB.BASEBOARD_FAB2(SCH_1):GND
DD73    GND VSS<252> @BASEBOARD_FAB2_LIB.BASEBOARD_FAB2(SCH_1):GND
DD75    GND VSS<251> @BASEBOARD_FAB2_LIB.BASEBOARD_FAB2(SCH_1):GND
DD81    GND VSS<250> @BASEBOARD_FAB2_LIB.BASEBOARD_FAB2(SCH_1):GND
DD83    GND VSS<249> @BASEBOARD_FAB2_LIB.BASEBOARD_FAB2(SCH_1):GND
 DE6    GND VSS<248> @BASEBOARD_FAB2_LIB.BASEBOARD_FAB2(SCH_1):GND
 DE8    GND VSS<247> @BASEBOARD_FAB2_LIB.BASEBOARD_FAB2(SCH_1):GND
DE18    GND VSS<246> @BASEBOARD_FAB2_LIB.BASEBOARD_FAB2(SCH_1):GND
DE20    GND VSS<245> @BASEBOARD_FAB2_LIB.BASEBOARD_FAB2(SCH_1):GND
DE24    GND VSS<244> @BASEBOARD_FAB2_LIB.BASEBOARD_FAB2(SCH_1):GND
DE28    GND VSS<243> @BASEBOARD_FAB2_LIB.BASEBOARD_FAB2(SCH_1):GND
DE30    GND VSS<242> @BASEBOARD_FAB2_LIB.BASEBOARD_FAB2(SCH_1):GND
DE34    GND VSS<241> @BASEBOARD_FAB2_LIB.BASEBOARD_FAB2(SCH_1):GND
DE36    GND VSS<240> @BASEBOARD_FAB2_LIB.BASEBOARD_FAB2(SCH_1):GND
DE64    GND VSS<239> @BASEBOARD_FAB2_LIB.BASEBOARD_FAB2(SCH_1):GND
DE70    GND VSS<238> @BASEBOARD_FAB2_LIB.BASEBOARD_FAB2(SCH_1):GND
DE72    GND VSS<237> @BASEBOARD_FAB2_LIB.BASEBOARD_FAB2(SCH_1):GND
DE78    GND VSS<236> @BASEBOARD_FAB2_LIB.BASEBOARD_FAB2(SCH_1):GND
 DF5    GND VSS<235> @BASEBOARD_FAB2_LIB.BASEBOARD_FAB2(SCH_1):GND
 DF7    GND VSS<234> @BASEBOARD_FAB2_LIB.BASEBOARD_FAB2(SCH_1):GND
 H51    GND VSS<233> @BASEBOARD_FAB2_LIB.BASEBOARD_FAB2(SCH_1):GND
DF19    GND VSS<232> @BASEBOARD_FAB2_LIB.BASEBOARD_FAB2(SCH_1):GND
DF29    GND VSS<231> @BASEBOARD_FAB2_LIB.BASEBOARD_FAB2(SCH_1):GND
DF35    GND VSS<230> @BASEBOARD_FAB2_LIB.BASEBOARD_FAB2(SCH_1):GND
DF37    GND VSS<229> @BASEBOARD_FAB2_LIB.BASEBOARD_FAB2(SCH_1):GND
DF39    GND VSS<228> @BASEBOARD_FAB2_LIB.BASEBOARD_FAB2(SCH_1):GND
DF41    GND VSS<227> @BASEBOARD_FAB2_LIB.BASEBOARD_FAB2(SCH_1):GND
DF65    GND VSS<226> @BASEBOARD_FAB2_LIB.BASEBOARD_FAB2(SCH_1):GND
DF69    GND VSS<225> @BASEBOARD_FAB2_LIB.BASEBOARD_FAB2(SCH_1):GND
DF73    GND VSS<224> @BASEBOARD_FAB2_LIB.BASEBOARD_FAB2(SCH_1):GND
DF79    GND VSS<223> @BASEBOARD_FAB2_LIB.BASEBOARD_FAB2(SCH_1):GND
DF83    GND VSS<222> @BASEBOARD_FAB2_LIB.BASEBOARD_FAB2(SCH_1):GND
DF85    GND VSS<221> @BASEBOARD_FAB2_LIB.BASEBOARD_FAB2(SCH_1):GND
 DG2    GND VSS<220> @BASEBOARD_FAB2_LIB.BASEBOARD_FAB2(SCH_1):GND
 H49    GND VSS<219> @BASEBOARD_FAB2_LIB.BASEBOARD_FAB2(SCH_1):GND
DG14    GND VSS<218> @BASEBOARD_FAB2_LIB.BASEBOARD_FAB2(SCH_1):GND
DG16    GND VSS<217> @BASEBOARD_FAB2_LIB.BASEBOARD_FAB2(SCH_1):GND
DG24    GND VSS<216> @BASEBOARD_FAB2_LIB.BASEBOARD_FAB2(SCH_1):GND
DG66    GND VSS<215> @BASEBOARD_FAB2_LIB.BASEBOARD_FAB2(SCH_1):GND
DG68    GND VSS<214> @BASEBOARD_FAB2_LIB.BASEBOARD_FAB2(SCH_1):GND
DG76    GND VSS<213> @BASEBOARD_FAB2_LIB.BASEBOARD_FAB2(SCH_1):GND
DG78    GND VSS<212> @BASEBOARD_FAB2_LIB.BASEBOARD_FAB2(SCH_1):GND
DG80    GND VSS<211> @BASEBOARD_FAB2_LIB.BASEBOARD_FAB2(SCH_1):GND
DG82    GND VSS<210> @BASEBOARD_FAB2_LIB.BASEBOARD_FAB2(SCH_1):GND
DH13    GND VSS<209> @BASEBOARD_FAB2_LIB.BASEBOARD_FAB2(SCH_1):GND
DH15    GND VSS<208> @BASEBOARD_FAB2_LIB.BASEBOARD_FAB2(SCH_1):GND
DH23    GND VSS<207> @BASEBOARD_FAB2_LIB.BASEBOARD_FAB2(SCH_1):GND
DH25    GND VSS<206> @BASEBOARD_FAB2_LIB.BASEBOARD_FAB2(SCH_1):GND
DH27    GND VSS<205> @BASEBOARD_FAB2_LIB.BASEBOARD_FAB2(SCH_1):GND
DH29    GND VSS<204> @BASEBOARD_FAB2_LIB.BASEBOARD_FAB2(SCH_1):GND
DH31    GND VSS<203> @BASEBOARD_FAB2_LIB.BASEBOARD_FAB2(SCH_1):GND
DH33    GND VSS<202> @BASEBOARD_FAB2_LIB.BASEBOARD_FAB2(SCH_1):GND
DH35    GND VSS<201> @BASEBOARD_FAB2_LIB.BASEBOARD_FAB2(SCH_1):GND
DH37    GND VSS<200> @BASEBOARD_FAB2_LIB.BASEBOARD_FAB2(SCH_1):GND
DH41    GND VSS<199> @BASEBOARD_FAB2_LIB.BASEBOARD_FAB2(SCH_1):GND
DH67    GND VSS<198> @BASEBOARD_FAB2_LIB.BASEBOARD_FAB2(SCH_1):GND
DH71    GND VSS<197> @BASEBOARD_FAB2_LIB.BASEBOARD_FAB2(SCH_1):GND
DH73    GND VSS<196> @BASEBOARD_FAB2_LIB.BASEBOARD_FAB2(SCH_1):GND
DH79    GND VSS<195> @BASEBOARD_FAB2_LIB.BASEBOARD_FAB2(SCH_1):GND
DH81    GND VSS<194> @BASEBOARD_FAB2_LIB.BASEBOARD_FAB2(SCH_1):GND
DH83    GND VSS<193> @BASEBOARD_FAB2_LIB.BASEBOARD_FAB2(SCH_1):GND
 DJ2    GND VSS<192> @BASEBOARD_FAB2_LIB.BASEBOARD_FAB2(SCH_1):GND
DJ10    GND VSS<191> @BASEBOARD_FAB2_LIB.BASEBOARD_FAB2(SCH_1):GND
 H47    GND VSS<190> @BASEBOARD_FAB2_LIB.BASEBOARD_FAB2(SCH_1):GND
DJ22    GND VSS<189> @BASEBOARD_FAB2_LIB.BASEBOARD_FAB2(SCH_1):GND
DJ38    GND VSS<188> @BASEBOARD_FAB2_LIB.BASEBOARD_FAB2(SCH_1):GND
DJ42    GND VSS<187> @BASEBOARD_FAB2_LIB.BASEBOARD_FAB2(SCH_1):GND
DJ68    GND VSS<186> @BASEBOARD_FAB2_LIB.BASEBOARD_FAB2(SCH_1):GND
DJ74    GND VSS<185> @BASEBOARD_FAB2_LIB.BASEBOARD_FAB2(SCH_1):GND
DJ78    GND VSS<184> @BASEBOARD_FAB2_LIB.BASEBOARD_FAB2(SCH_1):GND
DJ82    GND VSS<183> @BASEBOARD_FAB2_LIB.BASEBOARD_FAB2(SCH_1):GND
DJ84    GND VSS<182> @BASEBOARD_FAB2_LIB.BASEBOARD_FAB2(SCH_1):GND
 DK7    GND VSS<181> @BASEBOARD_FAB2_LIB.BASEBOARD_FAB2(SCH_1):GND
DK23    GND VSS<180> @BASEBOARD_FAB2_LIB.BASEBOARD_FAB2(SCH_1):GND
DK29    GND VSS<179> @BASEBOARD_FAB2_LIB.BASEBOARD_FAB2(SCH_1):GND
DK35    GND VSS<178> @BASEBOARD_FAB2_LIB.BASEBOARD_FAB2(SCH_1):GND
DK39    GND VSS<177> @BASEBOARD_FAB2_LIB.BASEBOARD_FAB2(SCH_1):GND
DK41    GND VSS<176> @BASEBOARD_FAB2_LIB.BASEBOARD_FAB2(SCH_1):GND
DK73    GND VSS<175> @BASEBOARD_FAB2_LIB.BASEBOARD_FAB2(SCH_1):GND
DK75    GND VSS<174> @BASEBOARD_FAB2_LIB.BASEBOARD_FAB2(SCH_1):GND
DK77    GND VSS<173> @BASEBOARD_FAB2_LIB.BASEBOARD_FAB2(SCH_1):GND
DK83    GND VSS<172> @BASEBOARD_FAB2_LIB.BASEBOARD_FAB2(SCH_1):GND
DK85    GND VSS<171> @BASEBOARD_FAB2_LIB.BASEBOARD_FAB2(SCH_1):GND
DL16    GND VSS<170> @BASEBOARD_FAB2_LIB.BASEBOARD_FAB2(SCH_1):GND
DL18    GND VSS<169> @BASEBOARD_FAB2_LIB.BASEBOARD_FAB2(SCH_1):GND
 DL4    GND VSS<168> @BASEBOARD_FAB2_LIB.BASEBOARD_FAB2(SCH_1):GND
DL22    GND VSS<167> @BASEBOARD_FAB2_LIB.BASEBOARD_FAB2(SCH_1):GND
DL24    GND VSS<166> @BASEBOARD_FAB2_LIB.BASEBOARD_FAB2(SCH_1):GND
DL28    GND VSS<165> @BASEBOARD_FAB2_LIB.BASEBOARD_FAB2(SCH_1):GND
DL30    GND VSS<164> @BASEBOARD_FAB2_LIB.BASEBOARD_FAB2(SCH_1):GND
DL34    GND VSS<163> @BASEBOARD_FAB2_LIB.BASEBOARD_FAB2(SCH_1):GND
DL36    GND VSS<162> @BASEBOARD_FAB2_LIB.BASEBOARD_FAB2(SCH_1):GND
DL40    GND VSS<161> @BASEBOARD_FAB2_LIB.BASEBOARD_FAB2(SCH_1):GND
DL68    GND VSS<160> @BASEBOARD_FAB2_LIB.BASEBOARD_FAB2(SCH_1):GND
DL70    GND VSS<159> @BASEBOARD_FAB2_LIB.BASEBOARD_FAB2(SCH_1):GND
DL74    GND VSS<158> @BASEBOARD_FAB2_LIB.BASEBOARD_FAB2(SCH_1):GND
DL76    GND VSS<157> @BASEBOARD_FAB2_LIB.BASEBOARD_FAB2(SCH_1):GND
DL78    GND VSS<156> @BASEBOARD_FAB2_LIB.BASEBOARD_FAB2(SCH_1):GND
DL80    GND VSS<155> @BASEBOARD_FAB2_LIB.BASEBOARD_FAB2(SCH_1):GND
DM15    GND VSS<154> @BASEBOARD_FAB2_LIB.BASEBOARD_FAB2(SCH_1):GND
 H45    GND VSS<153> @BASEBOARD_FAB2_LIB.BASEBOARD_FAB2(SCH_1):GND
DM25    GND VSS<152> @BASEBOARD_FAB2_LIB.BASEBOARD_FAB2(SCH_1):GND
DM27    GND VSS<151> @BASEBOARD_FAB2_LIB.BASEBOARD_FAB2(SCH_1):GND
DM31    GND VSS<150> @BASEBOARD_FAB2_LIB.BASEBOARD_FAB2(SCH_1):GND
DM33    GND VSS<149> @BASEBOARD_FAB2_LIB.BASEBOARD_FAB2(SCH_1):GND
DM37    GND VSS<148> @BASEBOARD_FAB2_LIB.BASEBOARD_FAB2(SCH_1):GND
DM39    GND VSS<147> @BASEBOARD_FAB2_LIB.BASEBOARD_FAB2(SCH_1):GND
DM65    GND VSS<146> @BASEBOARD_FAB2_LIB.BASEBOARD_FAB2(SCH_1):GND
DM73    GND VSS<145> @BASEBOARD_FAB2_LIB.BASEBOARD_FAB2(SCH_1):GND
DM77    GND VSS<144> @BASEBOARD_FAB2_LIB.BASEBOARD_FAB2(SCH_1):GND
DM83    GND VSS<143> @BASEBOARD_FAB2_LIB.BASEBOARD_FAB2(SCH_1):GND
 DN2    GND VSS<142> @BASEBOARD_FAB2_LIB.BASEBOARD_FAB2(SCH_1):GND
BH17    GND VSS<141> @BASEBOARD_FAB2_LIB.BASEBOARD_FAB2(SCH_1):GND
DN12    GND VSS<140> @BASEBOARD_FAB2_LIB.BASEBOARD_FAB2(SCH_1):GND
DN22    GND VSS<139> @BASEBOARD_FAB2_LIB.BASEBOARD_FAB2(SCH_1):GND
DN26    GND VSS<138> @BASEBOARD_FAB2_LIB.BASEBOARD_FAB2(SCH_1):GND
DN32    GND VSS<137> @BASEBOARD_FAB2_LIB.BASEBOARD_FAB2(SCH_1):GND
DN38    GND VSS<136> @BASEBOARD_FAB2_LIB.BASEBOARD_FAB2(SCH_1):GND
DN68    GND VSS<135> @BASEBOARD_FAB2_LIB.BASEBOARD_FAB2(SCH_1):GND
DN72    GND VSS<134> @BASEBOARD_FAB2_LIB.BASEBOARD_FAB2(SCH_1):GND

SKX_EXT_B_BGA1-IC,TBD  I286  U5D1
DN78    GND VSS<133> @BASEBOARD_FAB2_LIB.BASEBOARD_FAB2(SCH_1):GND
DP67    GND VSS<132> @BASEBOARD_FAB2_LIB.BASEBOARD_FAB2(SCH_1):GND
DP69    GND VSS<131> @BASEBOARD_FAB2_LIB.BASEBOARD_FAB2(SCH_1):GND
DP71    GND VSS<130> @BASEBOARD_FAB2_LIB.BASEBOARD_FAB2(SCH_1):GND
DP81    GND VSS<129> @BASEBOARD_FAB2_LIB.BASEBOARD_FAB2(SCH_1):GND
DP83    GND VSS<128> @BASEBOARD_FAB2_LIB.BASEBOARD_FAB2(SCH_1):GND
BR26    GND VSS<127> @BASEBOARD_FAB2_LIB.BASEBOARD_FAB2(SCH_1):GND
 DR6    GND VSS<126> @BASEBOARD_FAB2_LIB.BASEBOARD_FAB2(SCH_1):GND
CA20    GND VSS<125> @BASEBOARD_FAB2_LIB.BASEBOARD_FAB2(SCH_1):GND
CL22    GND VSS<124> @BASEBOARD_FAB2_LIB.BASEBOARD_FAB2(SCH_1):GND
DR20    GND VSS<123> @BASEBOARD_FAB2_LIB.BASEBOARD_FAB2(SCH_1):GND
DR22    GND VSS<122> @BASEBOARD_FAB2_LIB.BASEBOARD_FAB2(SCH_1):GND
DR24    GND VSS<121> @BASEBOARD_FAB2_LIB.BASEBOARD_FAB2(SCH_1):GND
DR26    GND VSS<120> @BASEBOARD_FAB2_LIB.BASEBOARD_FAB2(SCH_1):GND
DR28    GND VSS<119> @BASEBOARD_FAB2_LIB.BASEBOARD_FAB2(SCH_1):GND
DR30    GND VSS<118> @BASEBOARD_FAB2_LIB.BASEBOARD_FAB2(SCH_1):GND
DR32    GND VSS<117> @BASEBOARD_FAB2_LIB.BASEBOARD_FAB2(SCH_1):GND
DR34    GND VSS<116> @BASEBOARD_FAB2_LIB.BASEBOARD_FAB2(SCH_1):GND
DR36    GND VSS<115> @BASEBOARD_FAB2_LIB.BASEBOARD_FAB2(SCH_1):GND
DR38    GND VSS<114> @BASEBOARD_FAB2_LIB.BASEBOARD_FAB2(SCH_1):GND
DR40    GND VSS<113> @BASEBOARD_FAB2_LIB.BASEBOARD_FAB2(SCH_1):GND
DR42    GND VSS<112> @BASEBOARD_FAB2_LIB.BASEBOARD_FAB2(SCH_1):GND
DR66    GND VSS<111> @BASEBOARD_FAB2_LIB.BASEBOARD_FAB2(SCH_1):GND
DR68    GND VSS<110> @BASEBOARD_FAB2_LIB.BASEBOARD_FAB2(SCH_1):GND
DR70    GND VSS<109> @BASEBOARD_FAB2_LIB.BASEBOARD_FAB2(SCH_1):GND
DR72    GND VSS<108> @BASEBOARD_FAB2_LIB.BASEBOARD_FAB2(SCH_1):GND
DR74    GND VSS<107> @BASEBOARD_FAB2_LIB.BASEBOARD_FAB2(SCH_1):GND
DR76    GND VSS<106> @BASEBOARD_FAB2_LIB.BASEBOARD_FAB2(SCH_1):GND
DR78    GND VSS<105> @BASEBOARD_FAB2_LIB.BASEBOARD_FAB2(SCH_1):GND
 DT3    GND VSS<104> @BASEBOARD_FAB2_LIB.BASEBOARD_FAB2(SCH_1):GND
DT17    GND VSS<103> @BASEBOARD_FAB2_LIB.BASEBOARD_FAB2(SCH_1):GND
DH21    GND VSS<102> @BASEBOARD_FAB2_LIB.BASEBOARD_FAB2(SCH_1):GND
DT65    GND VSS<101> @BASEBOARD_FAB2_LIB.BASEBOARD_FAB2(SCH_1):GND
DT69    GND VSS<100> @BASEBOARD_FAB2_LIB.BASEBOARD_FAB2(SCH_1):GND
DT79    GND VSS<99> @BASEBOARD_FAB2_LIB.BASEBOARD_FAB2(SCH_1):GND
DT83    GND VSS<98> @BASEBOARD_FAB2_LIB.BASEBOARD_FAB2(SCH_1):GND
DT85    GND VSS<97> @BASEBOARD_FAB2_LIB.BASEBOARD_FAB2(SCH_1):GND
DU10    GND VSS<96> @BASEBOARD_FAB2_LIB.BASEBOARD_FAB2(SCH_1):GND
DU14    GND VSS<95> @BASEBOARD_FAB2_LIB.BASEBOARD_FAB2(SCH_1):GND
CN14    GND VSS<94> @BASEBOARD_FAB2_LIB.BASEBOARD_FAB2(SCH_1):GND
DU22    GND VSS<93> @BASEBOARD_FAB2_LIB.BASEBOARD_FAB2(SCH_1):GND
DU26    GND VSS<92> @BASEBOARD_FAB2_LIB.BASEBOARD_FAB2(SCH_1):GND
DU32    GND VSS<91> @BASEBOARD_FAB2_LIB.BASEBOARD_FAB2(SCH_1):GND
DU38    GND VSS<90> @BASEBOARD_FAB2_LIB.BASEBOARD_FAB2(SCH_1):GND
DU70    GND VSS<89> @BASEBOARD_FAB2_LIB.BASEBOARD_FAB2(SCH_1):GND
DU72    GND VSS<88> @BASEBOARD_FAB2_LIB.BASEBOARD_FAB2(SCH_1):GND
DU78    GND VSS<87> @BASEBOARD_FAB2_LIB.BASEBOARD_FAB2(SCH_1):GND
DU80    GND VSS<86> @BASEBOARD_FAB2_LIB.BASEBOARD_FAB2(SCH_1):GND
DU82    GND VSS<85> @BASEBOARD_FAB2_LIB.BASEBOARD_FAB2(SCH_1):GND
DU84    GND VSS<84> @BASEBOARD_FAB2_LIB.BASEBOARD_FAB2(SCH_1):GND
DV21    GND VSS<83> @BASEBOARD_FAB2_LIB.BASEBOARD_FAB2(SCH_1):GND
DV25    GND VSS<82> @BASEBOARD_FAB2_LIB.BASEBOARD_FAB2(SCH_1):GND
DV27    GND VSS<81> @BASEBOARD_FAB2_LIB.BASEBOARD_FAB2(SCH_1):GND
DV31    GND VSS<80> @BASEBOARD_FAB2_LIB.BASEBOARD_FAB2(SCH_1):GND
DV33    GND VSS<79> @BASEBOARD_FAB2_LIB.BASEBOARD_FAB2(SCH_1):GND
DV37    GND VSS<78> @BASEBOARD_FAB2_LIB.BASEBOARD_FAB2(SCH_1):GND
DV39    GND VSS<77> @BASEBOARD_FAB2_LIB.BASEBOARD_FAB2(SCH_1):GND
DV73    GND VSS<76> @BASEBOARD_FAB2_LIB.BASEBOARD_FAB2(SCH_1):GND
DV77    GND VSS<75> @BASEBOARD_FAB2_LIB.BASEBOARD_FAB2(SCH_1):GND
DV81    GND VSS<74> @BASEBOARD_FAB2_LIB.BASEBOARD_FAB2(SCH_1):GND
DW12    GND VSS<73> @BASEBOARD_FAB2_LIB.BASEBOARD_FAB2(SCH_1):GND
DW20    GND VSS<72> @BASEBOARD_FAB2_LIB.BASEBOARD_FAB2(SCH_1):GND
DW24    GND VSS<71> @BASEBOARD_FAB2_LIB.BASEBOARD_FAB2(SCH_1):GND
DW28    GND VSS<70> @BASEBOARD_FAB2_LIB.BASEBOARD_FAB2(SCH_1):GND
DW30    GND VSS<69> @BASEBOARD_FAB2_LIB.BASEBOARD_FAB2(SCH_1):GND
DW34    GND VSS<68> @BASEBOARD_FAB2_LIB.BASEBOARD_FAB2(SCH_1):GND
DW36    GND VSS<67> @BASEBOARD_FAB2_LIB.BASEBOARD_FAB2(SCH_1):GND
DW40    GND VSS<66> @BASEBOARD_FAB2_LIB.BASEBOARD_FAB2(SCH_1):GND
DW64    GND VSS<65> @BASEBOARD_FAB2_LIB.BASEBOARD_FAB2(SCH_1):GND
DW66    GND VSS<64> @BASEBOARD_FAB2_LIB.BASEBOARD_FAB2(SCH_1):GND
DW68    GND VSS<63> @BASEBOARD_FAB2_LIB.BASEBOARD_FAB2(SCH_1):GND
DW70    GND VSS<62> @BASEBOARD_FAB2_LIB.BASEBOARD_FAB2(SCH_1):GND
DW72    GND VSS<61> @BASEBOARD_FAB2_LIB.BASEBOARD_FAB2(SCH_1):GND
DW74    GND VSS<60> @BASEBOARD_FAB2_LIB.BASEBOARD_FAB2(SCH_1):GND
DW76    GND VSS<59> @BASEBOARD_FAB2_LIB.BASEBOARD_FAB2(SCH_1):GND
 DW8    GND VSS<58> @BASEBOARD_FAB2_LIB.BASEBOARD_FAB2(SCH_1):GND
DW82    GND VSS<57> @BASEBOARD_FAB2_LIB.BASEBOARD_FAB2(SCH_1):GND
DW84    GND VSS<56> @BASEBOARD_FAB2_LIB.BASEBOARD_FAB2(SCH_1):GND
 DY5    GND VSS<55> @BASEBOARD_FAB2_LIB.BASEBOARD_FAB2(SCH_1):GND
DY19    GND VSS<54> @BASEBOARD_FAB2_LIB.BASEBOARD_FAB2(SCH_1):GND
DY23    GND VSS<53> @BASEBOARD_FAB2_LIB.BASEBOARD_FAB2(SCH_1):GND
DY29    GND VSS<52> @BASEBOARD_FAB2_LIB.BASEBOARD_FAB2(SCH_1):GND
DY35    GND VSS<51> @BASEBOARD_FAB2_LIB.BASEBOARD_FAB2(SCH_1):GND
DY41    GND VSS<50> @BASEBOARD_FAB2_LIB.BASEBOARD_FAB2(SCH_1):GND
DY71    GND VSS<49> @BASEBOARD_FAB2_LIB.BASEBOARD_FAB2(SCH_1):GND
DY75    GND VSS<48> @BASEBOARD_FAB2_LIB.BASEBOARD_FAB2(SCH_1):GND
 EA6    GND VSS<47> @BASEBOARD_FAB2_LIB.BASEBOARD_FAB2(SCH_1):GND
 J16    GND VSS<46> @BASEBOARD_FAB2_LIB.BASEBOARD_FAB2(SCH_1):GND
EA16    GND VSS<45> @BASEBOARD_FAB2_LIB.BASEBOARD_FAB2(SCH_1):GND
EA20    GND VSS<44> @BASEBOARD_FAB2_LIB.BASEBOARD_FAB2(SCH_1):GND
EA22    GND VSS<43> @BASEBOARD_FAB2_LIB.BASEBOARD_FAB2(SCH_1):GND
EA42    GND VSS<42> @BASEBOARD_FAB2_LIB.BASEBOARD_FAB2(SCH_1):GND
EA64    GND VSS<41> @BASEBOARD_FAB2_LIB.BASEBOARD_FAB2(SCH_1):GND
EA70    GND VSS<40> @BASEBOARD_FAB2_LIB.BASEBOARD_FAB2(SCH_1):GND
EA76    GND VSS<39> @BASEBOARD_FAB2_LIB.BASEBOARD_FAB2(SCH_1):GND
EA78    GND VSS<38> @BASEBOARD_FAB2_LIB.BASEBOARD_FAB2(SCH_1):GND
EA80    GND VSS<37> @BASEBOARD_FAB2_LIB.BASEBOARD_FAB2(SCH_1):GND
EA82    GND VSS<36> @BASEBOARD_FAB2_LIB.BASEBOARD_FAB2(SCH_1):GND
EB13    GND VSS<35> @BASEBOARD_FAB2_LIB.BASEBOARD_FAB2(SCH_1):GND
BR18    GND VSS<34> @BASEBOARD_FAB2_LIB.BASEBOARD_FAB2(SCH_1):GND
EB23    GND VSS<33> @BASEBOARD_FAB2_LIB.BASEBOARD_FAB2(SCH_1):GND
EB25    GND VSS<32> @BASEBOARD_FAB2_LIB.BASEBOARD_FAB2(SCH_1):GND
EB27    GND VSS<31> @BASEBOARD_FAB2_LIB.BASEBOARD_FAB2(SCH_1):GND
EB29    GND VSS<30> @BASEBOARD_FAB2_LIB.BASEBOARD_FAB2(SCH_1):GND
EB31    GND VSS<29> @BASEBOARD_FAB2_LIB.BASEBOARD_FAB2(SCH_1):GND
EB33    GND VSS<28> @BASEBOARD_FAB2_LIB.BASEBOARD_FAB2(SCH_1):GND
EB35    GND VSS<27> @BASEBOARD_FAB2_LIB.BASEBOARD_FAB2(SCH_1):GND
EB37    GND VSS<26> @BASEBOARD_FAB2_LIB.BASEBOARD_FAB2(SCH_1):GND
EB39    GND VSS<25> @BASEBOARD_FAB2_LIB.BASEBOARD_FAB2(SCH_1):GND
EB41    GND VSS<24> @BASEBOARD_FAB2_LIB.BASEBOARD_FAB2(SCH_1):GND
EB65    GND VSS<23> @BASEBOARD_FAB2_LIB.BASEBOARD_FAB2(SCH_1):GND
EB69    GND VSS<22> @BASEBOARD_FAB2_LIB.BASEBOARD_FAB2(SCH_1):GND
EC10    GND VSS<21> @BASEBOARD_FAB2_LIB.BASEBOARD_FAB2(SCH_1):GND
EC70    GND VSS<20> @BASEBOARD_FAB2_LIB.BASEBOARD_FAB2(SCH_1):GND
EC72    GND VSS<19> @BASEBOARD_FAB2_LIB.BASEBOARD_FAB2(SCH_1):GND
EC74    GND VSS<18> @BASEBOARD_FAB2_LIB.BASEBOARD_FAB2(SCH_1):GND
EC76    GND VSS<17> @BASEBOARD_FAB2_LIB.BASEBOARD_FAB2(SCH_1):GND
ED11    GND VSS<16> @BASEBOARD_FAB2_LIB.BASEBOARD_FAB2(SCH_1):GND
ED15    GND VSS<15> @BASEBOARD_FAB2_LIB.BASEBOARD_FAB2(SCH_1):GND
ED23    GND VSS<14> @BASEBOARD_FAB2_LIB.BASEBOARD_FAB2(SCH_1):GND
ED29    GND VSS<13> @BASEBOARD_FAB2_LIB.BASEBOARD_FAB2(SCH_1):GND
ED35    GND VSS<12> @BASEBOARD_FAB2_LIB.BASEBOARD_FAB2(SCH_1):GND
ED77    GND VSS<11> @BASEBOARD_FAB2_LIB.BASEBOARD_FAB2(SCH_1):GND
EE24    GND VSS<10> @BASEBOARD_FAB2_LIB.BASEBOARD_FAB2(SCH_1):GND
EE28    GND VSS<9> @BASEBOARD_FAB2_LIB.BASEBOARD_FAB2(SCH_1):GND
EE30    GND VSS<8> @BASEBOARD_FAB2_LIB.BASEBOARD_FAB2(SCH_1):GND
EE34    GND VSS<7> @BASEBOARD_FAB2_LIB.BASEBOARD_FAB2(SCH_1):GND
EE36    GND VSS<6> @BASEBOARD_FAB2_LIB.BASEBOARD_FAB2(SCH_1):GND
EE70    GND VSS<5> @BASEBOARD_FAB2_LIB.BASEBOARD_FAB2(SCH_1):GND
EE76    GND VSS<4> @BASEBOARD_FAB2_LIB.BASEBOARD_FAB2(SCH_1):GND
EE78    GND VSS<3> @BASEBOARD_FAB2_LIB.BASEBOARD_FAB2(SCH_1):GND
EF71    GND VSS<2> @BASEBOARD_FAB2_LIB.BASEBOARD_FAB2(SCH_1):GND
EF75    GND VSS<1> @BASEBOARD_FAB2_LIB.BASEBOARD_FAB2(SCH_1):GND
EF79    GND VSS<0> @BASEBOARD_FAB2_LIB.BASEBOARD_FAB2(SCH_1):GND


DRAWING: @BASEBOARD_FAB2_LIB.BASEBOARD_FAB2(SCH_1):PAGE42 

CAP_0805-47UF,4V,20%,X6S,C9533A  I2  C5P18
   1 PVCCMCP_CPU0      A @BASEBOARD_FAB2_LIB.BASEBOARD_FAB2(SCH_1):PVCCMCP_CPU0
   2    GND      B @BASEBOARD_FAB2_LIB.BASEBOARD_FAB2(SCH_1):GND

CAP_0805-47UF,4V,20%,X6S,C9533A  I3  C5P28
   1 PVCCMCP_CPU0      A @BASEBOARD_FAB2_LIB.BASEBOARD_FAB2(SCH_1):PVCCMCP_CPU0
   2    GND      B @BASEBOARD_FAB2_LIB.BASEBOARD_FAB2(SCH_1):GND

CAP_0805-47UF,4V,20%,X6S,C9533A  I4  C5P11
   1 PVCCMCP_CPU0      A @BASEBOARD_FAB2_LIB.BASEBOARD_FAB2(SCH_1):PVCCMCP_CPU0
   2    GND      B @BASEBOARD_FAB2_LIB.BASEBOARD_FAB2(SCH_1):GND

CAP_0805-47UF,4V,20%,X6S,C9533A  I6  C5P10
   1 PVCCMCP_CPU0      A @BASEBOARD_FAB2_LIB.BASEBOARD_FAB2(SCH_1):PVCCMCP_CPU0
   2    GND      B @BASEBOARD_FAB2_LIB.BASEBOARD_FAB2(SCH_1):GND

CAP_0805-47UF,4V,20%,X6S,C9533A  I8  C4P3
   1 PVCCMCP_CPU0      A @BASEBOARD_FAB2_LIB.BASEBOARD_FAB2(SCH_1):PVCCMCP_CPU0
   2    GND      B @BASEBOARD_FAB2_LIB.BASEBOARD_FAB2(SCH_1):GND

CAP_0805-47UF,4V,20%,X6S,C9533A  I9  C4P7
   1 PVCCMCP_CPU0      A @BASEBOARD_FAB2_LIB.BASEBOARD_FAB2(SCH_1):PVCCMCP_CPU0
   2    GND      B @BASEBOARD_FAB2_LIB.BASEBOARD_FAB2(SCH_1):GND

CAP_0805-47UF,4V,20%,X6S,C9533A  I10  C4P1
   1 PVCCIO_CPU0      A @BASEBOARD_FAB2_LIB.BASEBOARD_FAB2(SCH_1):PVCCIO_CPU0
   2    GND      B @BASEBOARD_FAB2_LIB.BASEBOARD_FAB2(SCH_1):GND

CAP_0805-47UF,4V,20%,X6S,C9533A  I12  C4P9
   1 PVCCIO_CPU0      A @BASEBOARD_FAB2_LIB.BASEBOARD_FAB2(SCH_1):PVCCIO_CPU0
   2    GND      B @BASEBOARD_FAB2_LIB.BASEBOARD_FAB2(SCH_1):GND

CAP_0805-47UF,4V,20%,X6S,C9533A  I13  C5P19
   1 PVCCMCP_CPU0      A @BASEBOARD_FAB2_LIB.BASEBOARD_FAB2(SCH_1):PVCCMCP_CPU0
   2    GND      B @BASEBOARD_FAB2_LIB.BASEBOARD_FAB2(SCH_1):GND

CAP_0805-47UF,4V,20%,X6S,C9533A  I14  C4P4
   1 PVCCMCP_CPU0      A @BASEBOARD_FAB2_LIB.BASEBOARD_FAB2(SCH_1):PVCCMCP_CPU0
   2    GND      B @BASEBOARD_FAB2_LIB.BASEBOARD_FAB2(SCH_1):GND

CAP_0805-47UF,4V,20%,X6S,C9533A  I17  C4P10
   1 PVCCIO_CPU0      A @BASEBOARD_FAB2_LIB.BASEBOARD_FAB2(SCH_1):PVCCIO_CPU0
   2    GND      B @BASEBOARD_FAB2_LIB.BASEBOARD_FAB2(SCH_1):GND

CAP_0805LF-22UF,4V,20%,X6S,C95A  I18  C5P9
   1 PVSA_CPU0      A @BASEBOARD_FAB2_LIB.BASEBOARD_FAB2(SCH_1):PVSA_CPU0
   2    GND      B @BASEBOARD_FAB2_LIB.BASEBOARD_FAB2(SCH_1):GND

CAP_0805LF-22UF,4V,20%,X6S,C95A  I19  C5P8
   1 PVSA_CPU0      A @BASEBOARD_FAB2_LIB.BASEBOARD_FAB2(SCH_1):PVSA_CPU0
   2    GND      B @BASEBOARD_FAB2_LIB.BASEBOARD_FAB2(SCH_1):GND

CAP_0805LF-22UF,4V,20%,X6S,C95A  I25  C5P7
   1 PVSA_CPU0      A @BASEBOARD_FAB2_LIB.BASEBOARD_FAB2(SCH_1):PVSA_CPU0
   2    GND      B @BASEBOARD_FAB2_LIB.BASEBOARD_FAB2(SCH_1):GND

CAP_0805-47UF,4V,20%,X6S,C9533A  I27  C5P4
   1 PVCCIN_CPU0      A @BASEBOARD_FAB2_LIB.BASEBOARD_FAB2(SCH_1):PVCCIN_CPU0
   2    GND      B @BASEBOARD_FAB2_LIB.BASEBOARD_FAB2(SCH_1):GND

CAP_0805-47UF,4V,20%,X6S,C9533A  I28  C5P23
   1 PVCCIN_CPU0      A @BASEBOARD_FAB2_LIB.BASEBOARD_FAB2(SCH_1):PVCCIN_CPU0
   2    GND      B @BASEBOARD_FAB2_LIB.BASEBOARD_FAB2(SCH_1):GND

CAP_0805-47UF,4V,20%,X6S,C9533A  I33  C5P24
   1 PVCCIN_CPU0      A @BASEBOARD_FAB2_LIB.BASEBOARD_FAB2(SCH_1):PVCCIN_CPU0
   2    GND      B @BASEBOARD_FAB2_LIB.BASEBOARD_FAB2(SCH_1):GND

CAP_0805-47UF,4V,20%,X6S,C9533A  I37  C5P25
   1 PVCCIN_CPU0      A @BASEBOARD_FAB2_LIB.BASEBOARD_FAB2(SCH_1):PVCCIN_CPU0
   2    GND      B @BASEBOARD_FAB2_LIB.BASEBOARD_FAB2(SCH_1):GND

CAP_0805-47UF,4V,20%,X6S,C9533A  I38  C5P6
   1 PVCCIN_CPU0      A @BASEBOARD_FAB2_LIB.BASEBOARD_FAB2(SCH_1):PVCCIN_CPU0
   2    GND      B @BASEBOARD_FAB2_LIB.BASEBOARD_FAB2(SCH_1):GND

CAP_0805-47UF,4V,20%,X6S,C9533A  I40  C5P41
   1 PVCCIN_CPU0      A @BASEBOARD_FAB2_LIB.BASEBOARD_FAB2(SCH_1):PVCCIN_CPU0
   2    GND      B @BASEBOARD_FAB2_LIB.BASEBOARD_FAB2(SCH_1):GND

CAP_0805-47UF,4V,20%,X6S,C9533A  I41  C5P14
   1 PVCCIN_CPU0      A @BASEBOARD_FAB2_LIB.BASEBOARD_FAB2(SCH_1):PVCCIN_CPU0
   2    GND      B @BASEBOARD_FAB2_LIB.BASEBOARD_FAB2(SCH_1):GND

CAP_0805-47UF,4V,20%,X6S,C9533A  I42  C5P5
   1 PVCCIN_CPU0      A @BASEBOARD_FAB2_LIB.BASEBOARD_FAB2(SCH_1):PVCCIN_CPU0
   2    GND      B @BASEBOARD_FAB2_LIB.BASEBOARD_FAB2(SCH_1):GND

CAP_0805-47UF,4V,20%,X6S,C9533A  I44  C5P27
   1 PVCCIN_CPU0      A @BASEBOARD_FAB2_LIB.BASEBOARD_FAB2(SCH_1):PVCCIN_CPU0
   2    GND      B @BASEBOARD_FAB2_LIB.BASEBOARD_FAB2(SCH_1):GND

CAP_0805-47UF,4V,20%,X6S,C9533A  I50  C5P33
   1 PVCCIN_CPU0      A @BASEBOARD_FAB2_LIB.BASEBOARD_FAB2(SCH_1):PVCCIN_CPU0
   2    GND      B @BASEBOARD_FAB2_LIB.BASEBOARD_FAB2(SCH_1):GND

CAP_0805-47UF,4V,20%,X6S,C9533A  I51  C5P35
   1 PVCCIN_CPU0      A @BASEBOARD_FAB2_LIB.BASEBOARD_FAB2(SCH_1):PVCCIN_CPU0
   2    GND      B @BASEBOARD_FAB2_LIB.BASEBOARD_FAB2(SCH_1):GND

CAP_0805-47UF,4V,20%,X6S,C9533A  I53  C5P32
   1 PVCCIN_CPU0      A @BASEBOARD_FAB2_LIB.BASEBOARD_FAB2(SCH_1):PVCCIN_CPU0
   2    GND      B @BASEBOARD_FAB2_LIB.BASEBOARD_FAB2(SCH_1):GND

CAP_0805-47UF,4V,20%,X6S,C9533A  I54  C5P34
   1 PVCCIN_CPU0      A @BASEBOARD_FAB2_LIB.BASEBOARD_FAB2(SCH_1):PVCCIN_CPU0
   2    GND      B @BASEBOARD_FAB2_LIB.BASEBOARD_FAB2(SCH_1):GND

CAP_0805-47UF,4V,20%,X6S,C9533A  I55  C5P22
   1 PVCCIN_CPU0      A @BASEBOARD_FAB2_LIB.BASEBOARD_FAB2(SCH_1):PVCCIN_CPU0
   2    GND      B @BASEBOARD_FAB2_LIB.BASEBOARD_FAB2(SCH_1):GND

CAP_0805-47UF,4V,20%,X6S,C9533A  I56  C5P26
   1 PVCCIN_CPU0      A @BASEBOARD_FAB2_LIB.BASEBOARD_FAB2(SCH_1):PVCCIN_CPU0
   2    GND      B @BASEBOARD_FAB2_LIB.BASEBOARD_FAB2(SCH_1):GND

CAP_0805-47UF,4V,20%,X6S,C9533A  I57  C5P40
   1 PVCCIN_CPU0      A @BASEBOARD_FAB2_LIB.BASEBOARD_FAB2(SCH_1):PVCCIN_CPU0
   2    GND      B @BASEBOARD_FAB2_LIB.BASEBOARD_FAB2(SCH_1):GND

CAP_0805-47UF,4V,20%,X6S,C9533A  I59  C5P42
   1 PVCCIN_CPU0      A @BASEBOARD_FAB2_LIB.BASEBOARD_FAB2(SCH_1):PVCCIN_CPU0
   2    GND      B @BASEBOARD_FAB2_LIB.BASEBOARD_FAB2(SCH_1):GND

CAP_0805-47UF,4V,20%,X6S,C9533A  I60  C5P43
   1 PVCCIN_CPU0      A @BASEBOARD_FAB2_LIB.BASEBOARD_FAB2(SCH_1):PVCCIN_CPU0
   2    GND      B @BASEBOARD_FAB2_LIB.BASEBOARD_FAB2(SCH_1):GND

CAP_0805-47UF,4V,20%,X6S,C9533A  I61  C5P44
   1 PVCCIN_CPU0      A @BASEBOARD_FAB2_LIB.BASEBOARD_FAB2(SCH_1):PVCCIN_CPU0
   2    GND      B @BASEBOARD_FAB2_LIB.BASEBOARD_FAB2(SCH_1):GND

CAP_0805-47UF,4V,20%,X6S,C9533A  I63  C5P37
   1 PVCCIN_CPU0      A @BASEBOARD_FAB2_LIB.BASEBOARD_FAB2(SCH_1):PVCCIN_CPU0
   2    GND      B @BASEBOARD_FAB2_LIB.BASEBOARD_FAB2(SCH_1):GND

CAP_0805-47UF,4V,20%,X6S,C9533A  I65  C5P36
   1 PVCCIN_CPU0      A @BASEBOARD_FAB2_LIB.BASEBOARD_FAB2(SCH_1):PVCCIN_CPU0
   2    GND      B @BASEBOARD_FAB2_LIB.BASEBOARD_FAB2(SCH_1):GND

CAP_A_0603V-22.0UF,4V,20%,X6S,A  I68  C6D8
   1 PVCCMCP_CPU0      A @BASEBOARD_FAB2_LIB.BASEBOARD_FAB2(SCH_1):PVCCMCP_CPU0
   2    GND      B @BASEBOARD_FAB2_LIB.BASEBOARD_FAB2(SCH_1):GND

CAP_A_0603V-22.0UF,4V,20%,X6S,A  I69  C5D38
   1 PVCCMCP_CPU0      A @BASEBOARD_FAB2_LIB.BASEBOARD_FAB2(SCH_1):PVCCMCP_CPU0
   2    GND      B @BASEBOARD_FAB2_LIB.BASEBOARD_FAB2(SCH_1):GND

CAP_A_0603V-22.0UF,4V,20%,X6S,A  I70  C5D37
   1 PVCCMCP_CPU0      A @BASEBOARD_FAB2_LIB.BASEBOARD_FAB2(SCH_1):PVCCMCP_CPU0
   2    GND      B @BASEBOARD_FAB2_LIB.BASEBOARD_FAB2(SCH_1):GND

CAP_A_0603V-22.0UF,4V,20%,X6S,A  I72  C6D7
   1 PVCCIO_CPU0      A @BASEBOARD_FAB2_LIB.BASEBOARD_FAB2(SCH_1):PVCCIO_CPU0
   2    GND      B @BASEBOARD_FAB2_LIB.BASEBOARD_FAB2(SCH_1):GND

CAP_A_0603V-22.0UF,4V,20%,X6S,A  I74  C6D4
   1 PVCCIO_CPU0      A @BASEBOARD_FAB2_LIB.BASEBOARD_FAB2(SCH_1):PVCCIO_CPU0
   2    GND      B @BASEBOARD_FAB2_LIB.BASEBOARD_FAB2(SCH_1):GND

CAP_A_0603V-22.0UF,4V,20%,X6S,A  I75  C6D5
   1 PVCCMCP_CPU0      A @BASEBOARD_FAB2_LIB.BASEBOARD_FAB2(SCH_1):PVCCMCP_CPU0
   2    GND      B @BASEBOARD_FAB2_LIB.BASEBOARD_FAB2(SCH_1):GND

CAP_A_0603V-22.0UF,4V,20%,X6S,A  I77  C6D2
   1 PVCCMCP_CPU0      A @BASEBOARD_FAB2_LIB.BASEBOARD_FAB2(SCH_1):PVCCMCP_CPU0
   2    GND      B @BASEBOARD_FAB2_LIB.BASEBOARD_FAB2(SCH_1):GND

CAP_A_0603V-22.0UF,4V,20%,X6S,A  I80  C6D3
   1 PVCCIO_CPU0      A @BASEBOARD_FAB2_LIB.BASEBOARD_FAB2(SCH_1):PVCCIO_CPU0
   2    GND      B @BASEBOARD_FAB2_LIB.BASEBOARD_FAB2(SCH_1):GND

CAP_A_0603V-22.0UF,4V,20%,X6S,A  I81  C6D6
   1 PVCCIO_CPU0      A @BASEBOARD_FAB2_LIB.BASEBOARD_FAB2(SCH_1):PVCCIO_CPU0
   2    GND      B @BASEBOARD_FAB2_LIB.BASEBOARD_FAB2(SCH_1):GND

CAP_A_0603V-22.0UF,4V,20%,X6S,A  I83  C5D51
   1 PVCCMCP_CPU0      A @BASEBOARD_FAB2_LIB.BASEBOARD_FAB2(SCH_1):PVCCMCP_CPU0
   2    GND      B @BASEBOARD_FAB2_LIB.BASEBOARD_FAB2(SCH_1):GND

CAP_A_0603V-22.0UF,4V,20%,X6S,A  I88  C5D21
   1 PVCCMCP_CPU0      A @BASEBOARD_FAB2_LIB.BASEBOARD_FAB2(SCH_1):PVCCMCP_CPU0
   2    GND      B @BASEBOARD_FAB2_LIB.BASEBOARD_FAB2(SCH_1):GND

CAP_A_0603V-22.0UF,4V,20%,X6S,A  I89  C5D50
   1 PVCCMCP_CPU0      A @BASEBOARD_FAB2_LIB.BASEBOARD_FAB2(SCH_1):PVCCMCP_CPU0
   2    GND      B @BASEBOARD_FAB2_LIB.BASEBOARD_FAB2(SCH_1):GND

CAP_A_0603V-22.0UF,4V,20%,X6S,A  I90  C5D48
   1 PVCCMCP_CPU0      A @BASEBOARD_FAB2_LIB.BASEBOARD_FAB2(SCH_1):PVCCMCP_CPU0
   2    GND      B @BASEBOARD_FAB2_LIB.BASEBOARD_FAB2(SCH_1):GND

CAP_0603LF-10UF,4V,20%,X6S,E15A  I91  C5D13
   1 PVSA_CPU0      A @BASEBOARD_FAB2_LIB.BASEBOARD_FAB2(SCH_1):PVSA_CPU0
   2    GND      B @BASEBOARD_FAB2_LIB.BASEBOARD_FAB2(SCH_1):GND

CAP_0603LF-10UF,4V,20%,X6S,E15A  I93  C5D11
   1 PVSA_CPU0      A @BASEBOARD_FAB2_LIB.BASEBOARD_FAB2(SCH_1):PVSA_CPU0
   2    GND      B @BASEBOARD_FAB2_LIB.BASEBOARD_FAB2(SCH_1):GND

CAP_0603LF-10UF,4V,20%,X6S,E15A  I94  C5D12
   1 PVSA_CPU0      A @BASEBOARD_FAB2_LIB.BASEBOARD_FAB2(SCH_1):PVSA_CPU0
   2    GND      B @BASEBOARD_FAB2_LIB.BASEBOARD_FAB2(SCH_1):GND

CAP_A_0603V-22.0UF,4V,20%,X6S,A  I98  C5D23
   1 PVCCMCP_CPU0      A @BASEBOARD_FAB2_LIB.BASEBOARD_FAB2(SCH_1):PVCCMCP_CPU0
   2    GND      B @BASEBOARD_FAB2_LIB.BASEBOARD_FAB2(SCH_1):GND

CAP_A_0603V-22.0UF,4V,20%,X6S,A  I100  C5D28
   1 PVCCIN_CPU0      A @BASEBOARD_FAB2_LIB.BASEBOARD_FAB2(SCH_1):PVCCIN_CPU0
   2    GND      B @BASEBOARD_FAB2_LIB.BASEBOARD_FAB2(SCH_1):GND

CAP_A_0603V-22.0UF,4V,20%,X6S,A  I102  C5D29
   1 PVCCIN_CPU0      A @BASEBOARD_FAB2_LIB.BASEBOARD_FAB2(SCH_1):PVCCIN_CPU0
   2    GND      B @BASEBOARD_FAB2_LIB.BASEBOARD_FAB2(SCH_1):GND

CAP_A_0603V-22.0UF,4V,20%,X6S,A  I103  C5D32
   1 PVCCIN_CPU0      A @BASEBOARD_FAB2_LIB.BASEBOARD_FAB2(SCH_1):PVCCIN_CPU0
   2    GND      B @BASEBOARD_FAB2_LIB.BASEBOARD_FAB2(SCH_1):GND

CAP_A_0603V-22.0UF,4V,20%,X6S,A  I104  C5D47
   1 PVCCIN_CPU0      A @BASEBOARD_FAB2_LIB.BASEBOARD_FAB2(SCH_1):PVCCIN_CPU0
   2    GND      B @BASEBOARD_FAB2_LIB.BASEBOARD_FAB2(SCH_1):GND

CAP_A_0603V-22.0UF,4V,20%,X6S,A  I106  C5D31
   1 PVCCIN_CPU0      A @BASEBOARD_FAB2_LIB.BASEBOARD_FAB2(SCH_1):PVCCIN_CPU0
   2    GND      B @BASEBOARD_FAB2_LIB.BASEBOARD_FAB2(SCH_1):GND

CAP_A_0603V-22.0UF,4V,20%,X6S,A  I107  C5D46
   1 PVCCIN_CPU0      A @BASEBOARD_FAB2_LIB.BASEBOARD_FAB2(SCH_1):PVCCIN_CPU0
   2    GND      B @BASEBOARD_FAB2_LIB.BASEBOARD_FAB2(SCH_1):GND

CAP_0603LF-10UF,4V,20%,X6S,E15A  I108  C5D10
   1 PVSA_CPU0      A @BASEBOARD_FAB2_LIB.BASEBOARD_FAB2(SCH_1):PVSA_CPU0
   2    GND      B @BASEBOARD_FAB2_LIB.BASEBOARD_FAB2(SCH_1):GND

CAP_A_0603V-22.0UF,4V,20%,X6S,A  I109  C5D27
   1 PVCCIN_CPU0      A @BASEBOARD_FAB2_LIB.BASEBOARD_FAB2(SCH_1):PVCCIN_CPU0
   2    GND      B @BASEBOARD_FAB2_LIB.BASEBOARD_FAB2(SCH_1):GND

CAP_A_0603V-22.0UF,4V,20%,X6S,A  I111  C5D30
   1 PVCCIN_CPU0      A @BASEBOARD_FAB2_LIB.BASEBOARD_FAB2(SCH_1):PVCCIN_CPU0
   2    GND      B @BASEBOARD_FAB2_LIB.BASEBOARD_FAB2(SCH_1):GND

CAP_A_0603V-22.0UF,4V,20%,X6S,A  I112  C5D60
   1 PVCCIN_CPU0      A @BASEBOARD_FAB2_LIB.BASEBOARD_FAB2(SCH_1):PVCCIN_CPU0
   2    GND      B @BASEBOARD_FAB2_LIB.BASEBOARD_FAB2(SCH_1):GND

CAP_A_0603V-22.0UF,4V,20%,X6S,A  I113  C5D61
   1 PVCCIN_CPU0      A @BASEBOARD_FAB2_LIB.BASEBOARD_FAB2(SCH_1):PVCCIN_CPU0
   2    GND      B @BASEBOARD_FAB2_LIB.BASEBOARD_FAB2(SCH_1):GND

CAP_A_0603V-22.0UF,4V,20%,X6S,A  I114  C5D41
   1 PVCCIN_CPU0      A @BASEBOARD_FAB2_LIB.BASEBOARD_FAB2(SCH_1):PVCCIN_CPU0
   2    GND      B @BASEBOARD_FAB2_LIB.BASEBOARD_FAB2(SCH_1):GND

CAP_A_0603V-22.0UF,4V,20%,X6S,A  I115  C5D40
   1 PVCCIN_CPU0      A @BASEBOARD_FAB2_LIB.BASEBOARD_FAB2(SCH_1):PVCCIN_CPU0
   2    GND      B @BASEBOARD_FAB2_LIB.BASEBOARD_FAB2(SCH_1):GND

CAP_A_0603V-22.0UF,4V,20%,X6S,A  I117  C5D14
   1 PVCCIN_CPU0      A @BASEBOARD_FAB2_LIB.BASEBOARD_FAB2(SCH_1):PVCCIN_CPU0
   2    GND      B @BASEBOARD_FAB2_LIB.BASEBOARD_FAB2(SCH_1):GND

CAP_A_0603V-22.0UF,4V,20%,X6S,A  I118  C5D17
   1 PVCCIN_CPU0      A @BASEBOARD_FAB2_LIB.BASEBOARD_FAB2(SCH_1):PVCCIN_CPU0
   2    GND      B @BASEBOARD_FAB2_LIB.BASEBOARD_FAB2(SCH_1):GND

CAP_A_0603V-22.0UF,4V,20%,X6S,A  I120  C5D58
   1 PVCCIN_CPU0      A @BASEBOARD_FAB2_LIB.BASEBOARD_FAB2(SCH_1):PVCCIN_CPU0
   2    GND      B @BASEBOARD_FAB2_LIB.BASEBOARD_FAB2(SCH_1):GND

CAP_A_0603V-22.0UF,4V,20%,X6S,A  I123  C5D16
   1 PVCCIN_CPU0      A @BASEBOARD_FAB2_LIB.BASEBOARD_FAB2(SCH_1):PVCCIN_CPU0
   2    GND      B @BASEBOARD_FAB2_LIB.BASEBOARD_FAB2(SCH_1):GND

CAP_A_0603V-22.0UF,4V,20%,X6S,A  I125  C5D5
   1 PVCCIN_CPU0      A @BASEBOARD_FAB2_LIB.BASEBOARD_FAB2(SCH_1):PVCCIN_CPU0
   2    GND      B @BASEBOARD_FAB2_LIB.BASEBOARD_FAB2(SCH_1):GND

CAP_A_0603V-22.0UF,4V,20%,X6S,A  I126  C5D1
   1 PVCCIN_CPU0      A @BASEBOARD_FAB2_LIB.BASEBOARD_FAB2(SCH_1):PVCCIN_CPU0
   2    GND      B @BASEBOARD_FAB2_LIB.BASEBOARD_FAB2(SCH_1):GND

CAP_A_0603V-22.0UF,4V,20%,X6S,A  I127  C5D4
   1 PVCCIN_CPU0      A @BASEBOARD_FAB2_LIB.BASEBOARD_FAB2(SCH_1):PVCCIN_CPU0
   2    GND      B @BASEBOARD_FAB2_LIB.BASEBOARD_FAB2(SCH_1):GND

CAP_A_0603V-22.0UF,4V,20%,X6S,A  I128  C5D19
   1 PVCCIN_CPU0      A @BASEBOARD_FAB2_LIB.BASEBOARD_FAB2(SCH_1):PVCCIN_CPU0
   2    GND      B @BASEBOARD_FAB2_LIB.BASEBOARD_FAB2(SCH_1):GND

CAP_A_0603V-22.0UF,4V,20%,X6S,A  I129  C5D59
   1 PVCCIN_CPU0      A @BASEBOARD_FAB2_LIB.BASEBOARD_FAB2(SCH_1):PVCCIN_CPU0
   2    GND      B @BASEBOARD_FAB2_LIB.BASEBOARD_FAB2(SCH_1):GND

CAP_A_0603V-22.0UF,4V,20%,X6S,A  I130  C5D3
   1 PVCCIN_CPU0      A @BASEBOARD_FAB2_LIB.BASEBOARD_FAB2(SCH_1):PVCCIN_CPU0
   2    GND      B @BASEBOARD_FAB2_LIB.BASEBOARD_FAB2(SCH_1):GND

CAP_A_0603V-22.0UF,4V,20%,X6S,A  I131  C5D43
   1 PVCCIN_CPU0      A @BASEBOARD_FAB2_LIB.BASEBOARD_FAB2(SCH_1):PVCCIN_CPU0
   2    GND      B @BASEBOARD_FAB2_LIB.BASEBOARD_FAB2(SCH_1):GND

CAP_A_0603V-22.0UF,4V,20%,X6S,A  I132  C5D15
   1 PVCCIN_CPU0      A @BASEBOARD_FAB2_LIB.BASEBOARD_FAB2(SCH_1):PVCCIN_CPU0
   2    GND      B @BASEBOARD_FAB2_LIB.BASEBOARD_FAB2(SCH_1):GND

CAP_A_0603V-22.0UF,4V,20%,X6S,A  I134  C5D18
   1 PVCCIN_CPU0      A @BASEBOARD_FAB2_LIB.BASEBOARD_FAB2(SCH_1):PVCCIN_CPU0
   2    GND      B @BASEBOARD_FAB2_LIB.BASEBOARD_FAB2(SCH_1):GND

CAP_A_0603V-22.0UF,4V,20%,X6S,A  I135  C5D42
   1 PVCCIN_CPU0      A @BASEBOARD_FAB2_LIB.BASEBOARD_FAB2(SCH_1):PVCCIN_CPU0
   2    GND      B @BASEBOARD_FAB2_LIB.BASEBOARD_FAB2(SCH_1):GND

CAP_A_0603V-22.0UF,4V,20%,X6S,A  I136  C5D2
   1 PVCCIN_CPU0      A @BASEBOARD_FAB2_LIB.BASEBOARD_FAB2(SCH_1):PVCCIN_CPU0
   2    GND      B @BASEBOARD_FAB2_LIB.BASEBOARD_FAB2(SCH_1):GND

CAP_A_0603V-22.0UF,4V,20%,X6S,A  I138  C5D24
   1 PVCCIN_CPU0      A @BASEBOARD_FAB2_LIB.BASEBOARD_FAB2(SCH_1):PVCCIN_CPU0
   2    GND      B @BASEBOARD_FAB2_LIB.BASEBOARD_FAB2(SCH_1):GND

CAP_A_0603V-22.0UF,4V,20%,X6S,A  I140  C5D39
   1 PVCCIN_CPU0      A @BASEBOARD_FAB2_LIB.BASEBOARD_FAB2(SCH_1):PVCCIN_CPU0
   2    GND      B @BASEBOARD_FAB2_LIB.BASEBOARD_FAB2(SCH_1):GND

CAP_A_0603V-22.0UF,4V,20%,X6S,A  I142  C5D44
   1 PVCCIN_CPU0      A @BASEBOARD_FAB2_LIB.BASEBOARD_FAB2(SCH_1):PVCCIN_CPU0
   2    GND      B @BASEBOARD_FAB2_LIB.BASEBOARD_FAB2(SCH_1):GND

CAP_A_0603V-22.0UF,4V,20%,X6S,A  I145  C6D9
   1 PVCCIO_CPU0      A @BASEBOARD_FAB2_LIB.BASEBOARD_FAB2(SCH_1):PVCCIO_CPU0
   2    GND      B @BASEBOARD_FAB2_LIB.BASEBOARD_FAB2(SCH_1):GND

CAP_A_0603V-22.0UF,4V,20%,X6S,A  I147  C6D10
   1 PVCCIO_CPU0      A @BASEBOARD_FAB2_LIB.BASEBOARD_FAB2(SCH_1):PVCCIO_CPU0
   2    GND      B @BASEBOARD_FAB2_LIB.BASEBOARD_FAB2(SCH_1):GND

CAP_0805-47UF,4V,20%,X6S,C9533A  I148  C5P30
   1 PVCCMCP_CPU0      A @BASEBOARD_FAB2_LIB.BASEBOARD_FAB2(SCH_1):PVCCMCP_CPU0
   2    GND      B @BASEBOARD_FAB2_LIB.BASEBOARD_FAB2(SCH_1):GND

CAP_0805-47UF,4V,20%,X6S,C9533A  I149  C5P29
   1 PVCCMCP_CPU0      A @BASEBOARD_FAB2_LIB.BASEBOARD_FAB2(SCH_1):PVCCMCP_CPU0
   2    GND      B @BASEBOARD_FAB2_LIB.BASEBOARD_FAB2(SCH_1):GND

CAP_A_0603V-22.0UF,4V,20%,X6S,A  I151  C5D36
   1 PVCCMCP_CPU0      A @BASEBOARD_FAB2_LIB.BASEBOARD_FAB2(SCH_1):PVCCMCP_CPU0
   2    GND      B @BASEBOARD_FAB2_LIB.BASEBOARD_FAB2(SCH_1):GND

CAP_A_0603V-22.0UF,4V,20%,X6S,A  I152  C5D49
   1 PVCCMCP_CPU0      A @BASEBOARD_FAB2_LIB.BASEBOARD_FAB2(SCH_1):PVCCMCP_CPU0
   2    GND      B @BASEBOARD_FAB2_LIB.BASEBOARD_FAB2(SCH_1):GND

CAP_A_0603V-22.0UF,4V,20%,X6S,A  I153  C5D22
   1 PVCCMCP_CPU0      A @BASEBOARD_FAB2_LIB.BASEBOARD_FAB2(SCH_1):PVCCMCP_CPU0
   2    GND      B @BASEBOARD_FAB2_LIB.BASEBOARD_FAB2(SCH_1):GND

CAP_A_0603V-22.0UF,4V,20%,X6S,A  I154  C5D26
   1 PVCCIN_CPU0      A @BASEBOARD_FAB2_LIB.BASEBOARD_FAB2(SCH_1):PVCCIN_CPU0
   2    GND      B @BASEBOARD_FAB2_LIB.BASEBOARD_FAB2(SCH_1):GND

CAP_A_0603V-22.0UF,4V,20%,X6S,A  I155  C5D25
   1 PVCCIN_CPU0      A @BASEBOARD_FAB2_LIB.BASEBOARD_FAB2(SCH_1):PVCCIN_CPU0
   2    GND      B @BASEBOARD_FAB2_LIB.BASEBOARD_FAB2(SCH_1):GND

CAP_A_0603V-22.0UF,4V,20%,X6S,A  I156  C5D45
   1 PVCCIN_CPU0      A @BASEBOARD_FAB2_LIB.BASEBOARD_FAB2(SCH_1):PVCCIN_CPU0
   2    GND      B @BASEBOARD_FAB2_LIB.BASEBOARD_FAB2(SCH_1):GND

CAP_0805-47UF,4V,20%,X6S,C9533A  I162  C5P31
   1 PVCCMCP_CPU0      A @BASEBOARD_FAB2_LIB.BASEBOARD_FAB2(SCH_1):PVCCMCP_CPU0
   2    GND      B @BASEBOARD_FAB2_LIB.BASEBOARD_FAB2(SCH_1):GND

CAP_0805-47UF,4V,20%,X6S,C9533A  I163  C4P2
   1 PVCCMCP_CPU0      A @BASEBOARD_FAB2_LIB.BASEBOARD_FAB2(SCH_1):PVCCMCP_CPU0
   2    GND      B @BASEBOARD_FAB2_LIB.BASEBOARD_FAB2(SCH_1):GND

CAP_A_0603V-22.0UF,4V,20%,X6S,A  I164  C4P6
   1 PVCCIO_CPU0      A @BASEBOARD_FAB2_LIB.BASEBOARD_FAB2(SCH_1):PVCCIO_CPU0
   2    GND      B @BASEBOARD_FAB2_LIB.BASEBOARD_FAB2(SCH_1):GND

CAP_0805-47UF,4V,20%,X6S,C9533A  I172  C4P5
   1 PVCCMCP_CPU0      A @BASEBOARD_FAB2_LIB.BASEBOARD_FAB2(SCH_1):PVCCMCP_CPU0
   2    GND      B @BASEBOARD_FAB2_LIB.BASEBOARD_FAB2(SCH_1):GND

CAP_A_0603V-22.0UF,4V,20%,X6S,A  I173  C5D20
   1 PVCCMCP_CPU0      A @BASEBOARD_FAB2_LIB.BASEBOARD_FAB2(SCH_1):PVCCMCP_CPU0
   2    GND      B @BASEBOARD_FAB2_LIB.BASEBOARD_FAB2(SCH_1):GND

CAP_A_0603V-22.0UF,4V,20%,X6S,A  I174  C5D33
   1 PVCCMCP_CPU0      A @BASEBOARD_FAB2_LIB.BASEBOARD_FAB2(SCH_1):PVCCMCP_CPU0
   2    GND      B @BASEBOARD_FAB2_LIB.BASEBOARD_FAB2(SCH_1):GND

CAP_A_0603V-22.0UF,4V,20%,X6S,A  I175  C5D34
   1 PVCCMCP_CPU0      A @BASEBOARD_FAB2_LIB.BASEBOARD_FAB2(SCH_1):PVCCMCP_CPU0
   2    GND      B @BASEBOARD_FAB2_LIB.BASEBOARD_FAB2(SCH_1):GND

CAP_A_0603V-22.0UF,4V,20%,X6S,A  I176  C5D35
   1 PVCCMCP_CPU0      A @BASEBOARD_FAB2_LIB.BASEBOARD_FAB2(SCH_1):PVCCMCP_CPU0
   2    GND      B @BASEBOARD_FAB2_LIB.BASEBOARD_FAB2(SCH_1):GND

CAP_A_0603V-22.0UF,4V,20%,X6S,A  I178  C4P8
   1 PVCCIO_CPU0      A @BASEBOARD_FAB2_LIB.BASEBOARD_FAB2(SCH_1):PVCCIO_CPU0
   2    GND      B @BASEBOARD_FAB2_LIB.BASEBOARD_FAB2(SCH_1):GND

CAP_A_0603V-22.0UF,4V,20%,X6S,A  I179  C5D53
   1 PVCCMCP_CPU0      A @BASEBOARD_FAB2_LIB.BASEBOARD_FAB2(SCH_1):PVCCMCP_CPU0
   2    GND      B @BASEBOARD_FAB2_LIB.BASEBOARD_FAB2(SCH_1):GND

CAP_A_0603V-22.0UF,4V,20%,X6S,A  I180  C5D52
   1 PVCCMCP_CPU0      A @BASEBOARD_FAB2_LIB.BASEBOARD_FAB2(SCH_1):PVCCMCP_CPU0
   2    GND      B @BASEBOARD_FAB2_LIB.BASEBOARD_FAB2(SCH_1):GND

CAP_0805-47UF,4V,20%,X6S,C9533A  I183  C5P12
   1 PVCCMCP_CPU0      A @BASEBOARD_FAB2_LIB.BASEBOARD_FAB2(SCH_1):PVCCMCP_CPU0
   2    GND      B @BASEBOARD_FAB2_LIB.BASEBOARD_FAB2(SCH_1):GND

CAP_0805-47UF,4V,20%,X6S,C9533A  I184  C5P21
   1 PVCCMCP_CPU0      A @BASEBOARD_FAB2_LIB.BASEBOARD_FAB2(SCH_1):PVCCMCP_CPU0
   2    GND      B @BASEBOARD_FAB2_LIB.BASEBOARD_FAB2(SCH_1):GND

CAP_0805-47UF,4V,20%,X6S,C9533A  I185  C5P20
   1 PVCCMCP_CPU0      A @BASEBOARD_FAB2_LIB.BASEBOARD_FAB2(SCH_1):PVCCMCP_CPU0
   2    GND      B @BASEBOARD_FAB2_LIB.BASEBOARD_FAB2(SCH_1):GND

CAP_0805-47UF,4V,20%,X6S,C9533A  I186  C5P13
   1 PVCCMCP_CPU0      A @BASEBOARD_FAB2_LIB.BASEBOARD_FAB2(SCH_1):PVCCMCP_CPU0
   2    GND      B @BASEBOARD_FAB2_LIB.BASEBOARD_FAB2(SCH_1):GND

CAP_0805-47UF,4V,20%,X6S,C9533A  I187  C5P15
   1 PVCCIN_CPU0      A @BASEBOARD_FAB2_LIB.BASEBOARD_FAB2(SCH_1):PVCCIN_CPU0
   2    GND      B @BASEBOARD_FAB2_LIB.BASEBOARD_FAB2(SCH_1):GND

CAP_0805-47UF,4V,20%,X6S,C9533A  I188  C5P16
   1 PVCCIN_CPU0      A @BASEBOARD_FAB2_LIB.BASEBOARD_FAB2(SCH_1):PVCCIN_CPU0
   2    GND      B @BASEBOARD_FAB2_LIB.BASEBOARD_FAB2(SCH_1):GND

CAP_0805-47UF,4V,20%,X6S,C9533A  I189  C5P3
   1 PVCCIN_CPU0      A @BASEBOARD_FAB2_LIB.BASEBOARD_FAB2(SCH_1):PVCCIN_CPU0
   2    GND      B @BASEBOARD_FAB2_LIB.BASEBOARD_FAB2(SCH_1):GND

CAP_0805-47UF,4V,20%,X6S,C9533A  I190  C5P17
   1 PVCCIN_CPU0      A @BASEBOARD_FAB2_LIB.BASEBOARD_FAB2(SCH_1):PVCCIN_CPU0
   2    GND      B @BASEBOARD_FAB2_LIB.BASEBOARD_FAB2(SCH_1):GND


DRAWING: @BASEBOARD_FAB2_LIB.BASEBOARD_FAB2(SCH_1):PAGE43 

SCONN288_H44441004_PIP-SCONN,HA  I1  J4G1
  79 M_A_MA<0>     A0 @BASEBOARD_FAB2_LIB.BASEBOARD_FAB2(SCH_1):M_A_MA(0)
  72 M_A_MA<1>     A1 @BASEBOARD_FAB2_LIB.BASEBOARD_FAB2(SCH_1):M_A_MA(1)
 225 M_A_MA<10>    A10 @BASEBOARD_FAB2_LIB.BASEBOARD_FAB2(SCH_1):M_A_MA(10)
 210 M_A_MA<11>    A11 @BASEBOARD_FAB2_LIB.BASEBOARD_FAB2(SCH_1):M_A_MA(11)
  65 M_A_MA<12>    A12 @BASEBOARD_FAB2_LIB.BASEBOARD_FAB2(SCH_1):M_A_MA(12)
 232 M_A_MA<13>    A13 @BASEBOARD_FAB2_LIB.BASEBOARD_FAB2(SCH_1):M_A_MA(13)
 228 M_A_MA<14> A14_WE_N @BASEBOARD_FAB2_LIB.BASEBOARD_FAB2(SCH_1):M_A_MA(14)
  86 M_A_MA<15> A15_CAS_N @BASEBOARD_FAB2_LIB.BASEBOARD_FAB2(SCH_1):M_A_MA(15)
  82 M_A_MA<16> A16_RAS_N @BASEBOARD_FAB2_LIB.BASEBOARD_FAB2(SCH_1):M_A_MA(16)
 234 M_A_MA<17>    A17 @BASEBOARD_FAB2_LIB.BASEBOARD_FAB2(SCH_1):M_A_MA(17)
 216 M_A_MA<2>     A2 @BASEBOARD_FAB2_LIB.BASEBOARD_FAB2(SCH_1):M_A_MA(2)
  71 M_A_MA<3>     A3 @BASEBOARD_FAB2_LIB.BASEBOARD_FAB2(SCH_1):M_A_MA(3)
 214 M_A_MA<4>     A4 @BASEBOARD_FAB2_LIB.BASEBOARD_FAB2(SCH_1):M_A_MA(4)
 213 M_A_MA<5>     A5 @BASEBOARD_FAB2_LIB.BASEBOARD_FAB2(SCH_1):M_A_MA(5)
  69 M_A_MA<6>     A6 @BASEBOARD_FAB2_LIB.BASEBOARD_FAB2(SCH_1):M_A_MA(6)
 211 M_A_MA<7>     A7 @BASEBOARD_FAB2_LIB.BASEBOARD_FAB2(SCH_1):M_A_MA(7)
  68 M_A_MA<8>     A8 @BASEBOARD_FAB2_LIB.BASEBOARD_FAB2(SCH_1):M_A_MA(8)
  66 M_A_MA<9>     A9 @BASEBOARD_FAB2_LIB.BASEBOARD_FAB2(SCH_1):M_A_MA(9)
  62 M_A_ACT_N  ACT_N @BASEBOARD_FAB2_LIB.BASEBOARD_FAB2(SCH_1):M_A_ACT_N
 208 M_A_ALERT_N ALERT_N @BASEBOARD_FAB2_LIB.BASEBOARD_FAB2(SCH_1):M_A_ALERT_N
 224 M_A_BA<1>  BA<1> @BASEBOARD_FAB2_LIB.BASEBOARD_FAB2(SCH_1):M_A_BA(1)
  81 M_A_BA<0>  BA<0> @BASEBOARD_FAB2_LIB.BASEBOARD_FAB2(SCH_1):M_A_BA(0)
 207 M_A_BG<1>  BG<1> @BASEBOARD_FAB2_LIB.BASEBOARD_FAB2(SCH_1):M_A_BG(1)
  63 M_A_BG<0>  BG<0> @BASEBOARD_FAB2_LIB.BASEBOARD_FAB2(SCH_1):M_A_BG(0)
 235 M_A_C<2>   C<2> @BASEBOARD_FAB2_LIB.BASEBOARD_FAB2(SCH_1):M_A_C(2)
 199 M_A_ECC<6>  CB<7> @BASEBOARD_FAB2_LIB.BASEBOARD_FAB2(SCH_1):M_A_ECC(6)
  54 M_A_ECC<7>  CB<6> @BASEBOARD_FAB2_LIB.BASEBOARD_FAB2(SCH_1):M_A_ECC(7)
 192 M_A_ECC<4>  CB<5> @BASEBOARD_FAB2_LIB.BASEBOARD_FAB2(SCH_1):M_A_ECC(4)
  47 M_A_ECC<5>  CB<4> @BASEBOARD_FAB2_LIB.BASEBOARD_FAB2(SCH_1):M_A_ECC(5)
 201 M_A_ECC<2>  CB<3> @BASEBOARD_FAB2_LIB.BASEBOARD_FAB2(SCH_1):M_A_ECC(2)
  56 M_A_ECC<3>  CB<2> @BASEBOARD_FAB2_LIB.BASEBOARD_FAB2(SCH_1):M_A_ECC(3)
 194 M_A_ECC<0>  CB<1> @BASEBOARD_FAB2_LIB.BASEBOARD_FAB2(SCH_1):M_A_ECC(0)
  49 M_A_ECC<1>  CB<0> @BASEBOARD_FAB2_LIB.BASEBOARD_FAB2(SCH_1):M_A_ECC(1)
  75 M_A_CLK_DN<0>   CK0N @BASEBOARD_FAB2_LIB.BASEBOARD_FAB2(SCH_1):M_A_CLK_DN(0)
  74 M_A_CLK_DP<0>   CK0P @BASEBOARD_FAB2_LIB.BASEBOARD_FAB2(SCH_1):M_A_CLK_DP(0)
 219 M_A_CLK_DN<1>   CK1N @BASEBOARD_FAB2_LIB.BASEBOARD_FAB2(SCH_1):M_A_CLK_DN(1)
 218 M_A_CLK_DP<1>   CK1P @BASEBOARD_FAB2_LIB.BASEBOARD_FAB2(SCH_1):M_A_CLK_DP(1)
 203 M_A_CKE<1> CKE<1> @BASEBOARD_FAB2_LIB.BASEBOARD_FAB2(SCH_1):M_A_CKE(1)
  60 M_A_CKE<0> CKE<0> @BASEBOARD_FAB2_LIB.BASEBOARD_FAB2(SCH_1):M_A_CKE(0)
 280 M_A_DQ<62> DQ<63> @BASEBOARD_FAB2_LIB.BASEBOARD_FAB2(SCH_1):M_A_DQ(62)
 135 M_A_DQ<63> DQ<62> @BASEBOARD_FAB2_LIB.BASEBOARD_FAB2(SCH_1):M_A_DQ(63)
 273 M_A_DQ<60> DQ<61> @BASEBOARD_FAB2_LIB.BASEBOARD_FAB2(SCH_1):M_A_DQ(60)
 128 M_A_DQ<61> DQ<60> @BASEBOARD_FAB2_LIB.BASEBOARD_FAB2(SCH_1):M_A_DQ(61)
 282 M_A_DQ<58> DQ<59> @BASEBOARD_FAB2_LIB.BASEBOARD_FAB2(SCH_1):M_A_DQ(58)
 137 M_A_DQ<59> DQ<58> @BASEBOARD_FAB2_LIB.BASEBOARD_FAB2(SCH_1):M_A_DQ(59)
 275 M_A_DQ<56> DQ<57> @BASEBOARD_FAB2_LIB.BASEBOARD_FAB2(SCH_1):M_A_DQ(56)
 130 M_A_DQ<57> DQ<56> @BASEBOARD_FAB2_LIB.BASEBOARD_FAB2(SCH_1):M_A_DQ(57)
 269 M_A_DQ<54> DQ<55> @BASEBOARD_FAB2_LIB.BASEBOARD_FAB2(SCH_1):M_A_DQ(54)
 124 M_A_DQ<55> DQ<54> @BASEBOARD_FAB2_LIB.BASEBOARD_FAB2(SCH_1):M_A_DQ(55)
 262 M_A_DQ<52> DQ<53> @BASEBOARD_FAB2_LIB.BASEBOARD_FAB2(SCH_1):M_A_DQ(52)
 117 M_A_DQ<53> DQ<52> @BASEBOARD_FAB2_LIB.BASEBOARD_FAB2(SCH_1):M_A_DQ(53)
 271 M_A_DQ<50> DQ<51> @BASEBOARD_FAB2_LIB.BASEBOARD_FAB2(SCH_1):M_A_DQ(50)
 126 M_A_DQ<51> DQ<50> @BASEBOARD_FAB2_LIB.BASEBOARD_FAB2(SCH_1):M_A_DQ(51)
 264 M_A_DQ<48> DQ<49> @BASEBOARD_FAB2_LIB.BASEBOARD_FAB2(SCH_1):M_A_DQ(48)
 119 M_A_DQ<49> DQ<48> @BASEBOARD_FAB2_LIB.BASEBOARD_FAB2(SCH_1):M_A_DQ(49)
 258 M_A_DQ<46> DQ<47> @BASEBOARD_FAB2_LIB.BASEBOARD_FAB2(SCH_1):M_A_DQ(46)
 113 M_A_DQ<47> DQ<46> @BASEBOARD_FAB2_LIB.BASEBOARD_FAB2(SCH_1):M_A_DQ(47)
 251 M_A_DQ<44> DQ<45> @BASEBOARD_FAB2_LIB.BASEBOARD_FAB2(SCH_1):M_A_DQ(44)
 106 M_A_DQ<45> DQ<44> @BASEBOARD_FAB2_LIB.BASEBOARD_FAB2(SCH_1):M_A_DQ(45)
 260 M_A_DQ<42> DQ<43> @BASEBOARD_FAB2_LIB.BASEBOARD_FAB2(SCH_1):M_A_DQ(42)
 115 M_A_DQ<43> DQ<42> @BASEBOARD_FAB2_LIB.BASEBOARD_FAB2(SCH_1):M_A_DQ(43)
 253 M_A_DQ<40> DQ<41> @BASEBOARD_FAB2_LIB.BASEBOARD_FAB2(SCH_1):M_A_DQ(40)
 108 M_A_DQ<41> DQ<40> @BASEBOARD_FAB2_LIB.BASEBOARD_FAB2(SCH_1):M_A_DQ(41)
 247 M_A_DQ<38> DQ<39> @BASEBOARD_FAB2_LIB.BASEBOARD_FAB2(SCH_1):M_A_DQ(38)
 102 M_A_DQ<39> DQ<38> @BASEBOARD_FAB2_LIB.BASEBOARD_FAB2(SCH_1):M_A_DQ(39)
 240 M_A_DQ<36> DQ<37> @BASEBOARD_FAB2_LIB.BASEBOARD_FAB2(SCH_1):M_A_DQ(36)
  95 M_A_DQ<37> DQ<36> @BASEBOARD_FAB2_LIB.BASEBOARD_FAB2(SCH_1):M_A_DQ(37)
 249 M_A_DQ<34> DQ<35> @BASEBOARD_FAB2_LIB.BASEBOARD_FAB2(SCH_1):M_A_DQ(34)
 104 M_A_DQ<35> DQ<34> @BASEBOARD_FAB2_LIB.BASEBOARD_FAB2(SCH_1):M_A_DQ(35)
 242 M_A_DQ<32> DQ<33> @BASEBOARD_FAB2_LIB.BASEBOARD_FAB2(SCH_1):M_A_DQ(32)
  97 M_A_DQ<33> DQ<32> @BASEBOARD_FAB2_LIB.BASEBOARD_FAB2(SCH_1):M_A_DQ(33)
 188 M_A_DQ<30> DQ<31> @BASEBOARD_FAB2_LIB.BASEBOARD_FAB2(SCH_1):M_A_DQ(30)
  43 M_A_DQ<31> DQ<30> @BASEBOARD_FAB2_LIB.BASEBOARD_FAB2(SCH_1):M_A_DQ(31)
 181 M_A_DQ<28> DQ<29> @BASEBOARD_FAB2_LIB.BASEBOARD_FAB2(SCH_1):M_A_DQ(28)
  36 M_A_DQ<29> DQ<28> @BASEBOARD_FAB2_LIB.BASEBOARD_FAB2(SCH_1):M_A_DQ(29)
 190 M_A_DQ<26> DQ<27> @BASEBOARD_FAB2_LIB.BASEBOARD_FAB2(SCH_1):M_A_DQ(26)
  45 M_A_DQ<27> DQ<26> @BASEBOARD_FAB2_LIB.BASEBOARD_FAB2(SCH_1):M_A_DQ(27)
 183 M_A_DQ<24> DQ<25> @BASEBOARD_FAB2_LIB.BASEBOARD_FAB2(SCH_1):M_A_DQ(24)
  38 M_A_DQ<25> DQ<24> @BASEBOARD_FAB2_LIB.BASEBOARD_FAB2(SCH_1):M_A_DQ(25)
 177 M_A_DQ<22> DQ<23> @BASEBOARD_FAB2_LIB.BASEBOARD_FAB2(SCH_1):M_A_DQ(22)
  32 M_A_DQ<23> DQ<22> @BASEBOARD_FAB2_LIB.BASEBOARD_FAB2(SCH_1):M_A_DQ(23)
 170 M_A_DQ<20> DQ<21> @BASEBOARD_FAB2_LIB.BASEBOARD_FAB2(SCH_1):M_A_DQ(20)
  25 M_A_DQ<21> DQ<20> @BASEBOARD_FAB2_LIB.BASEBOARD_FAB2(SCH_1):M_A_DQ(21)
 179 M_A_DQ<18> DQ<19> @BASEBOARD_FAB2_LIB.BASEBOARD_FAB2(SCH_1):M_A_DQ(18)
  34 M_A_DQ<19> DQ<18> @BASEBOARD_FAB2_LIB.BASEBOARD_FAB2(SCH_1):M_A_DQ(19)
 172 M_A_DQ<16> DQ<17> @BASEBOARD_FAB2_LIB.BASEBOARD_FAB2(SCH_1):M_A_DQ(16)
  27 M_A_DQ<17> DQ<16> @BASEBOARD_FAB2_LIB.BASEBOARD_FAB2(SCH_1):M_A_DQ(17)
 166 M_A_DQ<14> DQ<15> @BASEBOARD_FAB2_LIB.BASEBOARD_FAB2(SCH_1):M_A_DQ(14)
  21 M_A_DQ<15> DQ<14> @BASEBOARD_FAB2_LIB.BASEBOARD_FAB2(SCH_1):M_A_DQ(15)
 159 M_A_DQ<12> DQ<13> @BASEBOARD_FAB2_LIB.BASEBOARD_FAB2(SCH_1):M_A_DQ(12)
  14 M_A_DQ<13> DQ<12> @BASEBOARD_FAB2_LIB.BASEBOARD_FAB2(SCH_1):M_A_DQ(13)
 168 M_A_DQ<10> DQ<11> @BASEBOARD_FAB2_LIB.BASEBOARD_FAB2(SCH_1):M_A_DQ(10)
  23 M_A_DQ<11> DQ<10> @BASEBOARD_FAB2_LIB.BASEBOARD_FAB2(SCH_1):M_A_DQ(11)
 161 M_A_DQ<8>  DQ<9> @BASEBOARD_FAB2_LIB.BASEBOARD_FAB2(SCH_1):M_A_DQ(8)
  16 M_A_DQ<9>  DQ<8> @BASEBOARD_FAB2_LIB.BASEBOARD_FAB2(SCH_1):M_A_DQ(9)
 155 M_A_DQ<6>  DQ<7> @BASEBOARD_FAB2_LIB.BASEBOARD_FAB2(SCH_1):M_A_DQ(6)
  10 M_A_DQ<7>  DQ<6> @BASEBOARD_FAB2_LIB.BASEBOARD_FAB2(SCH_1):M_A_DQ(7)
 148 M_A_DQ<4>  DQ<5> @BASEBOARD_FAB2_LIB.BASEBOARD_FAB2(SCH_1):M_A_DQ(4)
   3 M_A_DQ<5>  DQ<4> @BASEBOARD_FAB2_LIB.BASEBOARD_FAB2(SCH_1):M_A_DQ(5)
 157 M_A_DQ<2>  DQ<3> @BASEBOARD_FAB2_LIB.BASEBOARD_FAB2(SCH_1):M_A_DQ(2)
  12 M_A_DQ<3>  DQ<2> @BASEBOARD_FAB2_LIB.BASEBOARD_FAB2(SCH_1):M_A_DQ(3)
 150 M_A_DQ<0>  DQ<1> @BASEBOARD_FAB2_LIB.BASEBOARD_FAB2(SCH_1):M_A_DQ(0)
   5 M_A_DQ<1>  DQ<0> @BASEBOARD_FAB2_LIB.BASEBOARD_FAB2(SCH_1):M_A_DQ(1)
  78 FM_DIMM_EVENT_COD_N EVENT_N @BASEBOARD_FAB2_LIB.BASEBOARD_FAB2(SCH_1):FM_DIMM_EVENT_COD_N
  91 M_A_ODT<1> ODT<1> @BASEBOARD_FAB2_LIB.BASEBOARD_FAB2(SCH_1):M_A_ODT(1)
  87 M_A_ODT<0> ODT<0> @BASEBOARD_FAB2_LIB.BASEBOARD_FAB2(SCH_1):M_A_ODT(0)
 222 M_A_PAR    PAR @BASEBOARD_FAB2_LIB.BASEBOARD_FAB2(SCH_1):M_A_PAR
  58 M_ABC_RST_N RESET_N @BASEBOARD_FAB2_LIB.BASEBOARD_FAB2(SCH_1):M_ABC_RST_N
 144 TP_CH_A_DIMM_A0_RFU_2 RFU<2> @BASEBOARD_FAB2_LIB.BASEBOARD_FAB2(SCH_1):TP_CH_A_DIMM_A0_RFU_2
 227 TP_CH_A_DIMM_A0_RFU_1 RFU<1> @BASEBOARD_FAB2_LIB.BASEBOARD_FAB2(SCH_1):TP_CH_A_DIMM_A0_RFU_1
 205 TP_CH_A_DIMM_A0_RFU_0 RFU<0> @BASEBOARD_FAB2_LIB.BASEBOARD_FAB2(SCH_1):TP_CH_A_DIMM_A0_RFU_0
  84 M_A_CS_N<0>   S0_N @BASEBOARD_FAB2_LIB.BASEBOARD_FAB2(SCH_1):M_A_CS_N(0)
  89 M_A_CS_N<1>   S1_N @BASEBOARD_FAB2_LIB.BASEBOARD_FAB2(SCH_1):M_A_CS_N(1)
  93 M_A_CS_N<2> S2_N_C<0> @BASEBOARD_FAB2_LIB.BASEBOARD_FAB2(SCH_1):M_A_CS_N(2)
 237 M_A_CS_N<3> S3_N_C<1> @BASEBOARD_FAB2_LIB.BASEBOARD_FAB2(SCH_1):M_A_CS_N(3)
 238    GND  SA<2> @BASEBOARD_FAB2_LIB.BASEBOARD_FAB2(SCH_1):GND
 140    GND  SA<1> @BASEBOARD_FAB2_LIB.BASEBOARD_FAB2(SCH_1):GND
 139    GND  SA<0> @BASEBOARD_FAB2_LIB.BASEBOARD_FAB2(SCH_1):GND
 230 FM_ADR_COMPLETE_ABC_N SAVE_N_NC @BASEBOARD_FAB2_LIB.BASEBOARD_FAB2(SCH_1):FM_ADR_COMPLETE_ABC_N
 141 SMB_DDR_ABC_VPP_SCL    SCL @BASEBOARD_FAB2_LIB.BASEBOARD_FAB2(SCH_1):SMB_DDR_ABC_VPP_SCL
 285 SMB_DDR_ABC_VPP_SDA    SDA @BASEBOARD_FAB2_LIB.BASEBOARD_FAB2(SCH_1):SMB_DDR_ABC_VPP_SDA
 284 PVPP_ABC VDDSPD @BASEBOARD_FAB2_LIB.BASEBOARD_FAB2(SCH_1):PVPP_ABC
 146 M_A_VREF VREFCA @BASEBOARD_FAB2_LIB.BASEBOARD_FAB2(SCH_1):M_A_VREF

SCONN288_H44441004_PIP-SCONN,HA  I2  J4G1
 152 M_A_DQS_DN<0>  DQS0N @BASEBOARD_FAB2_LIB.BASEBOARD_FAB2(SCH_1):M_A_DQS_DN(0)
 153 M_A_DQS_DP<0>  DQS0P @BASEBOARD_FAB2_LIB.BASEBOARD_FAB2(SCH_1):M_A_DQS_DP(0)
  19 M_A_DQS_DN<10> DQS10N @BASEBOARD_FAB2_LIB.BASEBOARD_FAB2(SCH_1):M_A_DQS_DN(10)
  18 M_A_DQS_DP<10> DQS10P @BASEBOARD_FAB2_LIB.BASEBOARD_FAB2(SCH_1):M_A_DQS_DP(10)
  30 M_A_DQS_DN<11> DQS11N @BASEBOARD_FAB2_LIB.BASEBOARD_FAB2(SCH_1):M_A_DQS_DN(11)
  29 M_A_DQS_DP<11> DQS11P @BASEBOARD_FAB2_LIB.BASEBOARD_FAB2(SCH_1):M_A_DQS_DP(11)
  41 M_A_DQS_DN<12> DQS12N @BASEBOARD_FAB2_LIB.BASEBOARD_FAB2(SCH_1):M_A_DQS_DN(12)
  40 M_A_DQS_DP<12> DQS12P @BASEBOARD_FAB2_LIB.BASEBOARD_FAB2(SCH_1):M_A_DQS_DP(12)
 100 M_A_DQS_DN<13> DQS13N @BASEBOARD_FAB2_LIB.BASEBOARD_FAB2(SCH_1):M_A_DQS_DN(13)
  99 M_A_DQS_DP<13> DQS13P @BASEBOARD_FAB2_LIB.BASEBOARD_FAB2(SCH_1):M_A_DQS_DP(13)
 111 M_A_DQS_DN<14> DQS14N @BASEBOARD_FAB2_LIB.BASEBOARD_FAB2(SCH_1):M_A_DQS_DN(14)
 110 M_A_DQS_DP<14> DQS14P @BASEBOARD_FAB2_LIB.BASEBOARD_FAB2(SCH_1):M_A_DQS_DP(14)
 122 M_A_DQS_DN<15> DQS15N @BASEBOARD_FAB2_LIB.BASEBOARD_FAB2(SCH_1):M_A_DQS_DN(15)
 121 M_A_DQS_DP<15> DQS15P @BASEBOARD_FAB2_LIB.BASEBOARD_FAB2(SCH_1):M_A_DQS_DP(15)
 133 M_A_DQS_DN<16> DQS16N @BASEBOARD_FAB2_LIB.BASEBOARD_FAB2(SCH_1):M_A_DQS_DN(16)
 132 M_A_DQS_DP<16> DQS16P @BASEBOARD_FAB2_LIB.BASEBOARD_FAB2(SCH_1):M_A_DQS_DP(16)
  52 M_A_DQS_DN<17> DQS17N @BASEBOARD_FAB2_LIB.BASEBOARD_FAB2(SCH_1):M_A_DQS_DN(17)
  51 M_A_DQS_DP<17> DQS17P @BASEBOARD_FAB2_LIB.BASEBOARD_FAB2(SCH_1):M_A_DQS_DP(17)
 163 M_A_DQS_DN<1>  DQS1N @BASEBOARD_FAB2_LIB.BASEBOARD_FAB2(SCH_1):M_A_DQS_DN(1)
 164 M_A_DQS_DP<1>  DQS1P @BASEBOARD_FAB2_LIB.BASEBOARD_FAB2(SCH_1):M_A_DQS_DP(1)
 174 M_A_DQS_DN<2>  DQS2N @BASEBOARD_FAB2_LIB.BASEBOARD_FAB2(SCH_1):M_A_DQS_DN(2)
 175 M_A_DQS_DP<2>  DQS2P @BASEBOARD_FAB2_LIB.BASEBOARD_FAB2(SCH_1):M_A_DQS_DP(2)
 185 M_A_DQS_DN<3>  DQS3N @BASEBOARD_FAB2_LIB.BASEBOARD_FAB2(SCH_1):M_A_DQS_DN(3)
 186 M_A_DQS_DP<3>  DQS3P @BASEBOARD_FAB2_LIB.BASEBOARD_FAB2(SCH_1):M_A_DQS_DP(3)
 244 M_A_DQS_DN<4>  DQS4N @BASEBOARD_FAB2_LIB.BASEBOARD_FAB2(SCH_1):M_A_DQS_DN(4)
 245 M_A_DQS_DP<4>  DQS4P @BASEBOARD_FAB2_LIB.BASEBOARD_FAB2(SCH_1):M_A_DQS_DP(4)
 255 M_A_DQS_DN<5>  DQS5N @BASEBOARD_FAB2_LIB.BASEBOARD_FAB2(SCH_1):M_A_DQS_DN(5)
 256 M_A_DQS_DP<5>  DQS5P @BASEBOARD_FAB2_LIB.BASEBOARD_FAB2(SCH_1):M_A_DQS_DP(5)
 266 M_A_DQS_DN<6>  DQS6N @BASEBOARD_FAB2_LIB.BASEBOARD_FAB2(SCH_1):M_A_DQS_DN(6)
 267 M_A_DQS_DP<6>  DQS6P @BASEBOARD_FAB2_LIB.BASEBOARD_FAB2(SCH_1):M_A_DQS_DP(6)
 277 M_A_DQS_DN<7>  DQS7N @BASEBOARD_FAB2_LIB.BASEBOARD_FAB2(SCH_1):M_A_DQS_DN(7)
 278 M_A_DQS_DP<7>  DQS7P @BASEBOARD_FAB2_LIB.BASEBOARD_FAB2(SCH_1):M_A_DQS_DP(7)
 196 M_A_DQS_DN<8>  DQS8N @BASEBOARD_FAB2_LIB.BASEBOARD_FAB2(SCH_1):M_A_DQS_DN(8)
 197 M_A_DQS_DP<8>  DQS8P @BASEBOARD_FAB2_LIB.BASEBOARD_FAB2(SCH_1):M_A_DQS_DP(8)
   8 M_A_DQS_DN<9>  DQS9N @BASEBOARD_FAB2_LIB.BASEBOARD_FAB2(SCH_1):M_A_DQS_DN(9)
   7 M_A_DQS_DP<9>  DQS9P @BASEBOARD_FAB2_LIB.BASEBOARD_FAB2(SCH_1):M_A_DQS_DP(9)

SCONN288_H44441004_PIP-SCONN,HA  I259  J4G1
   2    GND VSS<93> @BASEBOARD_FAB2_LIB.BASEBOARD_FAB2(SCH_1):GND
   4    GND VSS<92> @BASEBOARD_FAB2_LIB.BASEBOARD_FAB2(SCH_1):GND
   6    GND VSS<91> @BASEBOARD_FAB2_LIB.BASEBOARD_FAB2(SCH_1):GND
   9    GND VSS<90> @BASEBOARD_FAB2_LIB.BASEBOARD_FAB2(SCH_1):GND
  11    GND VSS<89> @BASEBOARD_FAB2_LIB.BASEBOARD_FAB2(SCH_1):GND
  13    GND VSS<88> @BASEBOARD_FAB2_LIB.BASEBOARD_FAB2(SCH_1):GND
  15    GND VSS<87> @BASEBOARD_FAB2_LIB.BASEBOARD_FAB2(SCH_1):GND
  17    GND VSS<86> @BASEBOARD_FAB2_LIB.BASEBOARD_FAB2(SCH_1):GND
  20    GND VSS<85> @BASEBOARD_FAB2_LIB.BASEBOARD_FAB2(SCH_1):GND
  22    GND VSS<84> @BASEBOARD_FAB2_LIB.BASEBOARD_FAB2(SCH_1):GND
  24    GND VSS<83> @BASEBOARD_FAB2_LIB.BASEBOARD_FAB2(SCH_1):GND
  26    GND VSS<82> @BASEBOARD_FAB2_LIB.BASEBOARD_FAB2(SCH_1):GND
  28    GND VSS<81> @BASEBOARD_FAB2_LIB.BASEBOARD_FAB2(SCH_1):GND
  31    GND VSS<80> @BASEBOARD_FAB2_LIB.BASEBOARD_FAB2(SCH_1):GND
  33    GND VSS<79> @BASEBOARD_FAB2_LIB.BASEBOARD_FAB2(SCH_1):GND
  35    GND VSS<78> @BASEBOARD_FAB2_LIB.BASEBOARD_FAB2(SCH_1):GND
  37    GND VSS<77> @BASEBOARD_FAB2_LIB.BASEBOARD_FAB2(SCH_1):GND
  39    GND VSS<76> @BASEBOARD_FAB2_LIB.BASEBOARD_FAB2(SCH_1):GND
  42    GND VSS<75> @BASEBOARD_FAB2_LIB.BASEBOARD_FAB2(SCH_1):GND
  44    GND VSS<74> @BASEBOARD_FAB2_LIB.BASEBOARD_FAB2(SCH_1):GND
  46    GND VSS<73> @BASEBOARD_FAB2_LIB.BASEBOARD_FAB2(SCH_1):GND
  48    GND VSS<72> @BASEBOARD_FAB2_LIB.BASEBOARD_FAB2(SCH_1):GND
  50    GND VSS<71> @BASEBOARD_FAB2_LIB.BASEBOARD_FAB2(SCH_1):GND
  53    GND VSS<70> @BASEBOARD_FAB2_LIB.BASEBOARD_FAB2(SCH_1):GND
  55    GND VSS<69> @BASEBOARD_FAB2_LIB.BASEBOARD_FAB2(SCH_1):GND
  57    GND VSS<68> @BASEBOARD_FAB2_LIB.BASEBOARD_FAB2(SCH_1):GND
  94    GND VSS<67> @BASEBOARD_FAB2_LIB.BASEBOARD_FAB2(SCH_1):GND
  96    GND VSS<66> @BASEBOARD_FAB2_LIB.BASEBOARD_FAB2(SCH_1):GND
  98    GND VSS<65> @BASEBOARD_FAB2_LIB.BASEBOARD_FAB2(SCH_1):GND
 101    GND VSS<64> @BASEBOARD_FAB2_LIB.BASEBOARD_FAB2(SCH_1):GND
 103    GND VSS<63> @BASEBOARD_FAB2_LIB.BASEBOARD_FAB2(SCH_1):GND
 105    GND VSS<62> @BASEBOARD_FAB2_LIB.BASEBOARD_FAB2(SCH_1):GND
 107    GND VSS<61> @BASEBOARD_FAB2_LIB.BASEBOARD_FAB2(SCH_1):GND
 109    GND VSS<60> @BASEBOARD_FAB2_LIB.BASEBOARD_FAB2(SCH_1):GND
 112    GND VSS<59> @BASEBOARD_FAB2_LIB.BASEBOARD_FAB2(SCH_1):GND
 114    GND VSS<58> @BASEBOARD_FAB2_LIB.BASEBOARD_FAB2(SCH_1):GND
 116    GND VSS<57> @BASEBOARD_FAB2_LIB.BASEBOARD_FAB2(SCH_1):GND
 118    GND VSS<56> @BASEBOARD_FAB2_LIB.BASEBOARD_FAB2(SCH_1):GND
 120    GND VSS<55> @BASEBOARD_FAB2_LIB.BASEBOARD_FAB2(SCH_1):GND
 123    GND VSS<54> @BASEBOARD_FAB2_LIB.BASEBOARD_FAB2(SCH_1):GND
 125    GND VSS<53> @BASEBOARD_FAB2_LIB.BASEBOARD_FAB2(SCH_1):GND
 127    GND VSS<52> @BASEBOARD_FAB2_LIB.BASEBOARD_FAB2(SCH_1):GND
 129    GND VSS<51> @BASEBOARD_FAB2_LIB.BASEBOARD_FAB2(SCH_1):GND
 131    GND VSS<50> @BASEBOARD_FAB2_LIB.BASEBOARD_FAB2(SCH_1):GND
 134    GND VSS<49> @BASEBOARD_FAB2_LIB.BASEBOARD_FAB2(SCH_1):GND
 136    GND VSS<48> @BASEBOARD_FAB2_LIB.BASEBOARD_FAB2(SCH_1):GND
 138    GND VSS<47> @BASEBOARD_FAB2_LIB.BASEBOARD_FAB2(SCH_1):GND
 147    GND VSS<46> @BASEBOARD_FAB2_LIB.BASEBOARD_FAB2(SCH_1):GND
 149    GND VSS<45> @BASEBOARD_FAB2_LIB.BASEBOARD_FAB2(SCH_1):GND
 151    GND VSS<44> @BASEBOARD_FAB2_LIB.BASEBOARD_FAB2(SCH_1):GND
 154    GND VSS<43> @BASEBOARD_FAB2_LIB.BASEBOARD_FAB2(SCH_1):GND
 156    GND VSS<42> @BASEBOARD_FAB2_LIB.BASEBOARD_FAB2(SCH_1):GND
 158    GND VSS<41> @BASEBOARD_FAB2_LIB.BASEBOARD_FAB2(SCH_1):GND
 160    GND VSS<40> @BASEBOARD_FAB2_LIB.BASEBOARD_FAB2(SCH_1):GND
 162    GND VSS<39> @BASEBOARD_FAB2_LIB.BASEBOARD_FAB2(SCH_1):GND
 165    GND VSS<38> @BASEBOARD_FAB2_LIB.BASEBOARD_FAB2(SCH_1):GND
 167    GND VSS<37> @BASEBOARD_FAB2_LIB.BASEBOARD_FAB2(SCH_1):GND
 169    GND VSS<36> @BASEBOARD_FAB2_LIB.BASEBOARD_FAB2(SCH_1):GND
 171    GND VSS<35> @BASEBOARD_FAB2_LIB.BASEBOARD_FAB2(SCH_1):GND
 173    GND VSS<34> @BASEBOARD_FAB2_LIB.BASEBOARD_FAB2(SCH_1):GND
 176    GND VSS<33> @BASEBOARD_FAB2_LIB.BASEBOARD_FAB2(SCH_1):GND
 178    GND VSS<32> @BASEBOARD_FAB2_LIB.BASEBOARD_FAB2(SCH_1):GND
 180    GND VSS<31> @BASEBOARD_FAB2_LIB.BASEBOARD_FAB2(SCH_1):GND
 182    GND VSS<30> @BASEBOARD_FAB2_LIB.BASEBOARD_FAB2(SCH_1):GND
 184    GND VSS<29> @BASEBOARD_FAB2_LIB.BASEBOARD_FAB2(SCH_1):GND
 187    GND VSS<28> @BASEBOARD_FAB2_LIB.BASEBOARD_FAB2(SCH_1):GND
 189    GND VSS<27> @BASEBOARD_FAB2_LIB.BASEBOARD_FAB2(SCH_1):GND
 191    GND VSS<26> @BASEBOARD_FAB2_LIB.BASEBOARD_FAB2(SCH_1):GND
 193    GND VSS<25> @BASEBOARD_FAB2_LIB.BASEBOARD_FAB2(SCH_1):GND
 195    GND VSS<24> @BASEBOARD_FAB2_LIB.BASEBOARD_FAB2(SCH_1):GND
 198    GND VSS<23> @BASEBOARD_FAB2_LIB.BASEBOARD_FAB2(SCH_1):GND
 200    GND VSS<22> @BASEBOARD_FAB2_LIB.BASEBOARD_FAB2(SCH_1):GND
 202    GND VSS<21> @BASEBOARD_FAB2_LIB.BASEBOARD_FAB2(SCH_1):GND
 239    GND VSS<20> @BASEBOARD_FAB2_LIB.BASEBOARD_FAB2(SCH_1):GND
 241    GND VSS<19> @BASEBOARD_FAB2_LIB.BASEBOARD_FAB2(SCH_1):GND
 243    GND VSS<18> @BASEBOARD_FAB2_LIB.BASEBOARD_FAB2(SCH_1):GND
 246    GND VSS<17> @BASEBOARD_FAB2_LIB.BASEBOARD_FAB2(SCH_1):GND
 248    GND VSS<16> @BASEBOARD_FAB2_LIB.BASEBOARD_FAB2(SCH_1):GND
 250    GND VSS<15> @BASEBOARD_FAB2_LIB.BASEBOARD_FAB2(SCH_1):GND
 252    GND VSS<14> @BASEBOARD_FAB2_LIB.BASEBOARD_FAB2(SCH_1):GND
 254    GND VSS<13> @BASEBOARD_FAB2_LIB.BASEBOARD_FAB2(SCH_1):GND
 257    GND VSS<12> @BASEBOARD_FAB2_LIB.BASEBOARD_FAB2(SCH_1):GND
 259    GND VSS<11> @BASEBOARD_FAB2_LIB.BASEBOARD_FAB2(SCH_1):GND
 261    GND VSS<10> @BASEBOARD_FAB2_LIB.BASEBOARD_FAB2(SCH_1):GND
 263    GND VSS<9> @BASEBOARD_FAB2_LIB.BASEBOARD_FAB2(SCH_1):GND
 265    GND VSS<8> @BASEBOARD_FAB2_LIB.BASEBOARD_FAB2(SCH_1):GND
 268    GND VSS<7> @BASEBOARD_FAB2_LIB.BASEBOARD_FAB2(SCH_1):GND
 270    GND VSS<6> @BASEBOARD_FAB2_LIB.BASEBOARD_FAB2(SCH_1):GND
 272    GND VSS<5> @BASEBOARD_FAB2_LIB.BASEBOARD_FAB2(SCH_1):GND
 274    GND VSS<4> @BASEBOARD_FAB2_LIB.BASEBOARD_FAB2(SCH_1):GND
 276    GND VSS<3> @BASEBOARD_FAB2_LIB.BASEBOARD_FAB2(SCH_1):GND
 279    GND VSS<2> @BASEBOARD_FAB2_LIB.BASEBOARD_FAB2(SCH_1):GND
 281    GND VSS<1> @BASEBOARD_FAB2_LIB.BASEBOARD_FAB2(SCH_1):GND
 283    GND VSS<0> @BASEBOARD_FAB2_LIB.BASEBOARD_FAB2(SCH_1):GND

SCONN288_H44441004_PIP-SCONN,HA  I260  J4G1
   1 P12V_NVDIMM_ABC 12V<1> @BASEBOARD_FAB2_LIB.BASEBOARD_FAB2(SCH_1):P12V_NVDIMM_ABC
 145 P12V_NVDIMM_ABC 12V<0> @BASEBOARD_FAB2_LIB.BASEBOARD_FAB2(SCH_1):P12V_NVDIMM_ABC
  59 PVDDQ_ABC VDD<25> @BASEBOARD_FAB2_LIB.BASEBOARD_FAB2(SCH_1):PVDDQ_ABC
  61 PVDDQ_ABC VDD<24> @BASEBOARD_FAB2_LIB.BASEBOARD_FAB2(SCH_1):PVDDQ_ABC
  64 PVDDQ_ABC VDD<23> @BASEBOARD_FAB2_LIB.BASEBOARD_FAB2(SCH_1):PVDDQ_ABC
  67 PVDDQ_ABC VDD<22> @BASEBOARD_FAB2_LIB.BASEBOARD_FAB2(SCH_1):PVDDQ_ABC
  70 PVDDQ_ABC VDD<21> @BASEBOARD_FAB2_LIB.BASEBOARD_FAB2(SCH_1):PVDDQ_ABC
  73 PVDDQ_ABC VDD<20> @BASEBOARD_FAB2_LIB.BASEBOARD_FAB2(SCH_1):PVDDQ_ABC
  76 PVDDQ_ABC VDD<19> @BASEBOARD_FAB2_LIB.BASEBOARD_FAB2(SCH_1):PVDDQ_ABC
  80 PVDDQ_ABC VDD<18> @BASEBOARD_FAB2_LIB.BASEBOARD_FAB2(SCH_1):PVDDQ_ABC
  83 PVDDQ_ABC VDD<17> @BASEBOARD_FAB2_LIB.BASEBOARD_FAB2(SCH_1):PVDDQ_ABC
  85 PVDDQ_ABC VDD<16> @BASEBOARD_FAB2_LIB.BASEBOARD_FAB2(SCH_1):PVDDQ_ABC
  88 PVDDQ_ABC VDD<15> @BASEBOARD_FAB2_LIB.BASEBOARD_FAB2(SCH_1):PVDDQ_ABC
  90 PVDDQ_ABC VDD<14> @BASEBOARD_FAB2_LIB.BASEBOARD_FAB2(SCH_1):PVDDQ_ABC
  92 PVDDQ_ABC VDD<13> @BASEBOARD_FAB2_LIB.BASEBOARD_FAB2(SCH_1):PVDDQ_ABC
 204 PVDDQ_ABC VDD<12> @BASEBOARD_FAB2_LIB.BASEBOARD_FAB2(SCH_1):PVDDQ_ABC
 206 PVDDQ_ABC VDD<11> @BASEBOARD_FAB2_LIB.BASEBOARD_FAB2(SCH_1):PVDDQ_ABC
 209 PVDDQ_ABC VDD<10> @BASEBOARD_FAB2_LIB.BASEBOARD_FAB2(SCH_1):PVDDQ_ABC
 212 PVDDQ_ABC VDD<9> @BASEBOARD_FAB2_LIB.BASEBOARD_FAB2(SCH_1):PVDDQ_ABC
 215 PVDDQ_ABC VDD<8> @BASEBOARD_FAB2_LIB.BASEBOARD_FAB2(SCH_1):PVDDQ_ABC
 217 PVDDQ_ABC VDD<7> @BASEBOARD_FAB2_LIB.BASEBOARD_FAB2(SCH_1):PVDDQ_ABC
 220 PVDDQ_ABC VDD<6> @BASEBOARD_FAB2_LIB.BASEBOARD_FAB2(SCH_1):PVDDQ_ABC
 223 PVDDQ_ABC VDD<5> @BASEBOARD_FAB2_LIB.BASEBOARD_FAB2(SCH_1):PVDDQ_ABC
 226 PVDDQ_ABC VDD<4> @BASEBOARD_FAB2_LIB.BASEBOARD_FAB2(SCH_1):PVDDQ_ABC
 229 PVDDQ_ABC VDD<3> @BASEBOARD_FAB2_LIB.BASEBOARD_FAB2(SCH_1):PVDDQ_ABC
 231 PVDDQ_ABC VDD<2> @BASEBOARD_FAB2_LIB.BASEBOARD_FAB2(SCH_1):PVDDQ_ABC
 233 PVDDQ_ABC VDD<1> @BASEBOARD_FAB2_LIB.BASEBOARD_FAB2(SCH_1):PVDDQ_ABC
 236 PVDDQ_ABC VDD<0> @BASEBOARD_FAB2_LIB.BASEBOARD_FAB2(SCH_1):PVDDQ_ABC
 142 PVPP_ABC VPP<4> @BASEBOARD_FAB2_LIB.BASEBOARD_FAB2(SCH_1):PVPP_ABC
 143 PVPP_ABC VPP<3> @BASEBOARD_FAB2_LIB.BASEBOARD_FAB2(SCH_1):PVPP_ABC
 288 PVPP_ABC VPP<2> @BASEBOARD_FAB2_LIB.BASEBOARD_FAB2(SCH_1):PVPP_ABC
 286 PVPP_ABC VPP<1> @BASEBOARD_FAB2_LIB.BASEBOARD_FAB2(SCH_1):PVPP_ABC
 287 PVPP_ABC VPP<0> @BASEBOARD_FAB2_LIB.BASEBOARD_FAB2(SCH_1):PVPP_ABC
  77 PVTT_ABC VTT<1> @BASEBOARD_FAB2_LIB.BASEBOARD_FAB2(SCH_1):PVTT_ABC
 221 PVTT_ABC VTT<0> @BASEBOARD_FAB2_LIB.BASEBOARD_FAB2(SCH_1):PVTT_ABC

CAP_A_0402V-0.01UF,25V,10%,X7RA  I272  C4F10
   1 M_A_VREF      A @BASEBOARD_FAB2_LIB.BASEBOARD_FAB2(SCH_1):M_A_VREF
   2    GND      B @BASEBOARD_FAB2_LIB.BASEBOARD_FAB2(SCH_1):GND


DRAWING: @BASEBOARD_FAB2_LIB.BASEBOARD_FAB2(SCH_1):PAGE44 

CAP_A_0402V-0.01UF,25V,10%,X7RA  I2  C6T1
   1 M_A_VREF      A @BASEBOARD_FAB2_LIB.BASEBOARD_FAB2(SCH_1):M_A_VREF
   2    GND      B @BASEBOARD_FAB2_LIB.BASEBOARD_FAB2(SCH_1):GND

SCONN288_H44441003_PIP-SCONN,HA  I13  J6T1
  79 M_A_MA<0>     A0 @BASEBOARD_FAB2_LIB.BASEBOARD_FAB2(SCH_1):M_A_MA(0)
  72 M_A_MA<1>     A1 @BASEBOARD_FAB2_LIB.BASEBOARD_FAB2(SCH_1):M_A_MA(1)
 225 M_A_MA<10>    A10 @BASEBOARD_FAB2_LIB.BASEBOARD_FAB2(SCH_1):M_A_MA(10)
 210 M_A_MA<11>    A11 @BASEBOARD_FAB2_LIB.BASEBOARD_FAB2(SCH_1):M_A_MA(11)
  65 M_A_MA<12>    A12 @BASEBOARD_FAB2_LIB.BASEBOARD_FAB2(SCH_1):M_A_MA(12)
 232 M_A_MA<13>    A13 @BASEBOARD_FAB2_LIB.BASEBOARD_FAB2(SCH_1):M_A_MA(13)
 228 M_A_MA<14> A14_WE_N @BASEBOARD_FAB2_LIB.BASEBOARD_FAB2(SCH_1):M_A_MA(14)
  86 M_A_MA<15> A15_CAS_N @BASEBOARD_FAB2_LIB.BASEBOARD_FAB2(SCH_1):M_A_MA(15)
  82 M_A_MA<16> A16_RAS_N @BASEBOARD_FAB2_LIB.BASEBOARD_FAB2(SCH_1):M_A_MA(16)
 234 M_A_MA<17>    A17 @BASEBOARD_FAB2_LIB.BASEBOARD_FAB2(SCH_1):M_A_MA(17)
 216 M_A_MA<2>     A2 @BASEBOARD_FAB2_LIB.BASEBOARD_FAB2(SCH_1):M_A_MA(2)
  71 M_A_MA<3>     A3 @BASEBOARD_FAB2_LIB.BASEBOARD_FAB2(SCH_1):M_A_MA(3)
 214 M_A_MA<4>     A4 @BASEBOARD_FAB2_LIB.BASEBOARD_FAB2(SCH_1):M_A_MA(4)
 213 M_A_MA<5>     A5 @BASEBOARD_FAB2_LIB.BASEBOARD_FAB2(SCH_1):M_A_MA(5)
  69 M_A_MA<6>     A6 @BASEBOARD_FAB2_LIB.BASEBOARD_FAB2(SCH_1):M_A_MA(6)
 211 M_A_MA<7>     A7 @BASEBOARD_FAB2_LIB.BASEBOARD_FAB2(SCH_1):M_A_MA(7)
  68 M_A_MA<8>     A8 @BASEBOARD_FAB2_LIB.BASEBOARD_FAB2(SCH_1):M_A_MA(8)
  66 M_A_MA<9>     A9 @BASEBOARD_FAB2_LIB.BASEBOARD_FAB2(SCH_1):M_A_MA(9)
  62 M_A_ACT_N  ACT_N @BASEBOARD_FAB2_LIB.BASEBOARD_FAB2(SCH_1):M_A_ACT_N
 208 M_A_ALERT_N ALERT_N @BASEBOARD_FAB2_LIB.BASEBOARD_FAB2(SCH_1):M_A_ALERT_N
 224 M_A_BA<1>  BA<1> @BASEBOARD_FAB2_LIB.BASEBOARD_FAB2(SCH_1):M_A_BA(1)
  81 M_A_BA<0>  BA<0> @BASEBOARD_FAB2_LIB.BASEBOARD_FAB2(SCH_1):M_A_BA(0)
 207 M_A_BG<1>  BG<1> @BASEBOARD_FAB2_LIB.BASEBOARD_FAB2(SCH_1):M_A_BG(1)
  63 M_A_BG<0>  BG<0> @BASEBOARD_FAB2_LIB.BASEBOARD_FAB2(SCH_1):M_A_BG(0)
 235 M_A_C<2>   C<2> @BASEBOARD_FAB2_LIB.BASEBOARD_FAB2(SCH_1):M_A_C(2)
 199 M_A_ECC<7>  CB<7> @BASEBOARD_FAB2_LIB.BASEBOARD_FAB2(SCH_1):M_A_ECC(7)
  54 M_A_ECC<6>  CB<6> @BASEBOARD_FAB2_LIB.BASEBOARD_FAB2(SCH_1):M_A_ECC(6)
 192 M_A_ECC<5>  CB<5> @BASEBOARD_FAB2_LIB.BASEBOARD_FAB2(SCH_1):M_A_ECC(5)
  47 M_A_ECC<4>  CB<4> @BASEBOARD_FAB2_LIB.BASEBOARD_FAB2(SCH_1):M_A_ECC(4)
 201 M_A_ECC<3>  CB<3> @BASEBOARD_FAB2_LIB.BASEBOARD_FAB2(SCH_1):M_A_ECC(3)
  56 M_A_ECC<2>  CB<2> @BASEBOARD_FAB2_LIB.BASEBOARD_FAB2(SCH_1):M_A_ECC(2)
 194 M_A_ECC<1>  CB<1> @BASEBOARD_FAB2_LIB.BASEBOARD_FAB2(SCH_1):M_A_ECC(1)
  49 M_A_ECC<0>  CB<0> @BASEBOARD_FAB2_LIB.BASEBOARD_FAB2(SCH_1):M_A_ECC(0)
  75 M_A_CLK_DN<2>   CK0N @BASEBOARD_FAB2_LIB.BASEBOARD_FAB2(SCH_1):M_A_CLK_DN(2)
  74 M_A_CLK_DP<2>   CK0P @BASEBOARD_FAB2_LIB.BASEBOARD_FAB2(SCH_1):M_A_CLK_DP(2)
 219 M_A_CLK_DN<3>   CK1N @BASEBOARD_FAB2_LIB.BASEBOARD_FAB2(SCH_1):M_A_CLK_DN(3)
 218 M_A_CLK_DP<3>   CK1P @BASEBOARD_FAB2_LIB.BASEBOARD_FAB2(SCH_1):M_A_CLK_DP(3)
 203 M_A_CKE<3> CKE<1> @BASEBOARD_FAB2_LIB.BASEBOARD_FAB2(SCH_1):M_A_CKE(3)
  60 M_A_CKE<2> CKE<0> @BASEBOARD_FAB2_LIB.BASEBOARD_FAB2(SCH_1):M_A_CKE(2)
 280 M_A_DQ<63> DQ<63> @BASEBOARD_FAB2_LIB.BASEBOARD_FAB2(SCH_1):M_A_DQ(63)
 135 M_A_DQ<62> DQ<62> @BASEBOARD_FAB2_LIB.BASEBOARD_FAB2(SCH_1):M_A_DQ(62)
 273 M_A_DQ<61> DQ<61> @BASEBOARD_FAB2_LIB.BASEBOARD_FAB2(SCH_1):M_A_DQ(61)
 128 M_A_DQ<60> DQ<60> @BASEBOARD_FAB2_LIB.BASEBOARD_FAB2(SCH_1):M_A_DQ(60)
 282 M_A_DQ<59> DQ<59> @BASEBOARD_FAB2_LIB.BASEBOARD_FAB2(SCH_1):M_A_DQ(59)
 137 M_A_DQ<58> DQ<58> @BASEBOARD_FAB2_LIB.BASEBOARD_FAB2(SCH_1):M_A_DQ(58)
 275 M_A_DQ<57> DQ<57> @BASEBOARD_FAB2_LIB.BASEBOARD_FAB2(SCH_1):M_A_DQ(57)
 130 M_A_DQ<56> DQ<56> @BASEBOARD_FAB2_LIB.BASEBOARD_FAB2(SCH_1):M_A_DQ(56)
 269 M_A_DQ<55> DQ<55> @BASEBOARD_FAB2_LIB.BASEBOARD_FAB2(SCH_1):M_A_DQ(55)
 124 M_A_DQ<54> DQ<54> @BASEBOARD_FAB2_LIB.BASEBOARD_FAB2(SCH_1):M_A_DQ(54)
 262 M_A_DQ<53> DQ<53> @BASEBOARD_FAB2_LIB.BASEBOARD_FAB2(SCH_1):M_A_DQ(53)
 117 M_A_DQ<52> DQ<52> @BASEBOARD_FAB2_LIB.BASEBOARD_FAB2(SCH_1):M_A_DQ(52)
 271 M_A_DQ<51> DQ<51> @BASEBOARD_FAB2_LIB.BASEBOARD_FAB2(SCH_1):M_A_DQ(51)
 126 M_A_DQ<50> DQ<50> @BASEBOARD_FAB2_LIB.BASEBOARD_FAB2(SCH_1):M_A_DQ(50)
 264 M_A_DQ<49> DQ<49> @BASEBOARD_FAB2_LIB.BASEBOARD_FAB2(SCH_1):M_A_DQ(49)
 119 M_A_DQ<48> DQ<48> @BASEBOARD_FAB2_LIB.BASEBOARD_FAB2(SCH_1):M_A_DQ(48)
 258 M_A_DQ<47> DQ<47> @BASEBOARD_FAB2_LIB.BASEBOARD_FAB2(SCH_1):M_A_DQ(47)
 113 M_A_DQ<46> DQ<46> @BASEBOARD_FAB2_LIB.BASEBOARD_FAB2(SCH_1):M_A_DQ(46)
 251 M_A_DQ<45> DQ<45> @BASEBOARD_FAB2_LIB.BASEBOARD_FAB2(SCH_1):M_A_DQ(45)
 106 M_A_DQ<44> DQ<44> @BASEBOARD_FAB2_LIB.BASEBOARD_FAB2(SCH_1):M_A_DQ(44)
 260 M_A_DQ<43> DQ<43> @BASEBOARD_FAB2_LIB.BASEBOARD_FAB2(SCH_1):M_A_DQ(43)
 115 M_A_DQ<42> DQ<42> @BASEBOARD_FAB2_LIB.BASEBOARD_FAB2(SCH_1):M_A_DQ(42)
 253 M_A_DQ<41> DQ<41> @BASEBOARD_FAB2_LIB.BASEBOARD_FAB2(SCH_1):M_A_DQ(41)
 108 M_A_DQ<40> DQ<40> @BASEBOARD_FAB2_LIB.BASEBOARD_FAB2(SCH_1):M_A_DQ(40)
 247 M_A_DQ<39> DQ<39> @BASEBOARD_FAB2_LIB.BASEBOARD_FAB2(SCH_1):M_A_DQ(39)
 102 M_A_DQ<38> DQ<38> @BASEBOARD_FAB2_LIB.BASEBOARD_FAB2(SCH_1):M_A_DQ(38)
 240 M_A_DQ<37> DQ<37> @BASEBOARD_FAB2_LIB.BASEBOARD_FAB2(SCH_1):M_A_DQ(37)
  95 M_A_DQ<36> DQ<36> @BASEBOARD_FAB2_LIB.BASEBOARD_FAB2(SCH_1):M_A_DQ(36)
 249 M_A_DQ<35> DQ<35> @BASEBOARD_FAB2_LIB.BASEBOARD_FAB2(SCH_1):M_A_DQ(35)
 104 M_A_DQ<34> DQ<34> @BASEBOARD_FAB2_LIB.BASEBOARD_FAB2(SCH_1):M_A_DQ(34)
 242 M_A_DQ<33> DQ<33> @BASEBOARD_FAB2_LIB.BASEBOARD_FAB2(SCH_1):M_A_DQ(33)
  97 M_A_DQ<32> DQ<32> @BASEBOARD_FAB2_LIB.BASEBOARD_FAB2(SCH_1):M_A_DQ(32)
 188 M_A_DQ<31> DQ<31> @BASEBOARD_FAB2_LIB.BASEBOARD_FAB2(SCH_1):M_A_DQ(31)
  43 M_A_DQ<30> DQ<30> @BASEBOARD_FAB2_LIB.BASEBOARD_FAB2(SCH_1):M_A_DQ(30)
 181 M_A_DQ<29> DQ<29> @BASEBOARD_FAB2_LIB.BASEBOARD_FAB2(SCH_1):M_A_DQ(29)
  36 M_A_DQ<28> DQ<28> @BASEBOARD_FAB2_LIB.BASEBOARD_FAB2(SCH_1):M_A_DQ(28)
 190 M_A_DQ<27> DQ<27> @BASEBOARD_FAB2_LIB.BASEBOARD_FAB2(SCH_1):M_A_DQ(27)
  45 M_A_DQ<26> DQ<26> @BASEBOARD_FAB2_LIB.BASEBOARD_FAB2(SCH_1):M_A_DQ(26)
 183 M_A_DQ<25> DQ<25> @BASEBOARD_FAB2_LIB.BASEBOARD_FAB2(SCH_1):M_A_DQ(25)
  38 M_A_DQ<24> DQ<24> @BASEBOARD_FAB2_LIB.BASEBOARD_FAB2(SCH_1):M_A_DQ(24)
 177 M_A_DQ<23> DQ<23> @BASEBOARD_FAB2_LIB.BASEBOARD_FAB2(SCH_1):M_A_DQ(23)
  32 M_A_DQ<22> DQ<22> @BASEBOARD_FAB2_LIB.BASEBOARD_FAB2(SCH_1):M_A_DQ(22)
 170 M_A_DQ<21> DQ<21> @BASEBOARD_FAB2_LIB.BASEBOARD_FAB2(SCH_1):M_A_DQ(21)
  25 M_A_DQ<20> DQ<20> @BASEBOARD_FAB2_LIB.BASEBOARD_FAB2(SCH_1):M_A_DQ(20)
 179 M_A_DQ<19> DQ<19> @BASEBOARD_FAB2_LIB.BASEBOARD_FAB2(SCH_1):M_A_DQ(19)
  34 M_A_DQ<18> DQ<18> @BASEBOARD_FAB2_LIB.BASEBOARD_FAB2(SCH_1):M_A_DQ(18)
 172 M_A_DQ<17> DQ<17> @BASEBOARD_FAB2_LIB.BASEBOARD_FAB2(SCH_1):M_A_DQ(17)
  27 M_A_DQ<16> DQ<16> @BASEBOARD_FAB2_LIB.BASEBOARD_FAB2(SCH_1):M_A_DQ(16)
 166 M_A_DQ<15> DQ<15> @BASEBOARD_FAB2_LIB.BASEBOARD_FAB2(SCH_1):M_A_DQ(15)
  21 M_A_DQ<14> DQ<14> @BASEBOARD_FAB2_LIB.BASEBOARD_FAB2(SCH_1):M_A_DQ(14)
 159 M_A_DQ<13> DQ<13> @BASEBOARD_FAB2_LIB.BASEBOARD_FAB2(SCH_1):M_A_DQ(13)
  14 M_A_DQ<12> DQ<12> @BASEBOARD_FAB2_LIB.BASEBOARD_FAB2(SCH_1):M_A_DQ(12)
 168 M_A_DQ<11> DQ<11> @BASEBOARD_FAB2_LIB.BASEBOARD_FAB2(SCH_1):M_A_DQ(11)
  23 M_A_DQ<10> DQ<10> @BASEBOARD_FAB2_LIB.BASEBOARD_FAB2(SCH_1):M_A_DQ(10)
 161 M_A_DQ<9>  DQ<9> @BASEBOARD_FAB2_LIB.BASEBOARD_FAB2(SCH_1):M_A_DQ(9)
  16 M_A_DQ<8>  DQ<8> @BASEBOARD_FAB2_LIB.BASEBOARD_FAB2(SCH_1):M_A_DQ(8)
 155 M_A_DQ<7>  DQ<7> @BASEBOARD_FAB2_LIB.BASEBOARD_FAB2(SCH_1):M_A_DQ(7)
  10 M_A_DQ<6>  DQ<6> @BASEBOARD_FAB2_LIB.BASEBOARD_FAB2(SCH_1):M_A_DQ(6)
 148 M_A_DQ<5>  DQ<5> @BASEBOARD_FAB2_LIB.BASEBOARD_FAB2(SCH_1):M_A_DQ(5)
   3 M_A_DQ<4>  DQ<4> @BASEBOARD_FAB2_LIB.BASEBOARD_FAB2(SCH_1):M_A_DQ(4)
 157 M_A_DQ<3>  DQ<3> @BASEBOARD_FAB2_LIB.BASEBOARD_FAB2(SCH_1):M_A_DQ(3)
  12 M_A_DQ<2>  DQ<2> @BASEBOARD_FAB2_LIB.BASEBOARD_FAB2(SCH_1):M_A_DQ(2)
 150 M_A_DQ<1>  DQ<1> @BASEBOARD_FAB2_LIB.BASEBOARD_FAB2(SCH_1):M_A_DQ(1)
   5 M_A_DQ<0>  DQ<0> @BASEBOARD_FAB2_LIB.BASEBOARD_FAB2(SCH_1):M_A_DQ(0)
  78 FM_DIMM_EVENT_COD_N EVENT_N @BASEBOARD_FAB2_LIB.BASEBOARD_FAB2(SCH_1):FM_DIMM_EVENT_COD_N
  91 M_A_ODT<3> ODT<1> @BASEBOARD_FAB2_LIB.BASEBOARD_FAB2(SCH_1):M_A_ODT(3)
  87 M_A_ODT<2> ODT<0> @BASEBOARD_FAB2_LIB.BASEBOARD_FAB2(SCH_1):M_A_ODT(2)
 222 M_A_PAR    PAR @BASEBOARD_FAB2_LIB.BASEBOARD_FAB2(SCH_1):M_A_PAR
  58 M_ABC_RST_N RESET_N @BASEBOARD_FAB2_LIB.BASEBOARD_FAB2(SCH_1):M_ABC_RST_N
 144 TP_CH_A_DIMM_A1_RFU_2 RFU<2> @BASEBOARD_FAB2_LIB.BASEBOARD_FAB2(SCH_1):TP_CH_A_DIMM_A1_RFU_2
 227 TP_CH_A_DIMM_A1_RFU_1 RFU<1> @BASEBOARD_FAB2_LIB.BASEBOARD_FAB2(SCH_1):TP_CH_A_DIMM_A1_RFU_1
 205 TP_CH_A_DIMM_A1_RFU_0 RFU<0> @BASEBOARD_FAB2_LIB.BASEBOARD_FAB2(SCH_1):TP_CH_A_DIMM_A1_RFU_0
  84 M_A_CS_N<4>   S0_N @BASEBOARD_FAB2_LIB.BASEBOARD_FAB2(SCH_1):M_A_CS_N(4)
  89 M_A_CS_N<5>   S1_N @BASEBOARD_FAB2_LIB.BASEBOARD_FAB2(SCH_1):M_A_CS_N(5)
  93 M_A_CS_N<6> S2_N_C<0> @BASEBOARD_FAB2_LIB.BASEBOARD_FAB2(SCH_1):M_A_CS_N(6)
 237 M_A_CS_N<7> S3_N_C<1> @BASEBOARD_FAB2_LIB.BASEBOARD_FAB2(SCH_1):M_A_CS_N(7)
 238    GND  SA<2> @BASEBOARD_FAB2_LIB.BASEBOARD_FAB2(SCH_1):GND
 140    GND  SA<1> @BASEBOARD_FAB2_LIB.BASEBOARD_FAB2(SCH_1):GND
 139 PVPP_ABC  SA<0> @BASEBOARD_FAB2_LIB.BASEBOARD_FAB2(SCH_1):PVPP_ABC
 230 FM_ADR_COMPLETE_ABC_N SAVE_N_NC @BASEBOARD_FAB2_LIB.BASEBOARD_FAB2(SCH_1):FM_ADR_COMPLETE_ABC_N
 141 SMB_DDR_ABC_VPP_SCL    SCL @BASEBOARD_FAB2_LIB.BASEBOARD_FAB2(SCH_1):SMB_DDR_ABC_VPP_SCL
 285 SMB_DDR_ABC_VPP_SDA    SDA @BASEBOARD_FAB2_LIB.BASEBOARD_FAB2(SCH_1):SMB_DDR_ABC_VPP_SDA
 284 PVPP_ABC VDDSPD @BASEBOARD_FAB2_LIB.BASEBOARD_FAB2(SCH_1):PVPP_ABC
 146 M_A_VREF VREFCA @BASEBOARD_FAB2_LIB.BASEBOARD_FAB2(SCH_1):M_A_VREF

SCONN288_H44441003_PIP-SCONN,HA  I75  J6T1
   1 P12V_NVDIMM_ABC 12V<1> @BASEBOARD_FAB2_LIB.BASEBOARD_FAB2(SCH_1):P12V_NVDIMM_ABC
 145 P12V_NVDIMM_ABC 12V<0> @BASEBOARD_FAB2_LIB.BASEBOARD_FAB2(SCH_1):P12V_NVDIMM_ABC
  59 PVDDQ_ABC VDD<25> @BASEBOARD_FAB2_LIB.BASEBOARD_FAB2(SCH_1):PVDDQ_ABC
  61 PVDDQ_ABC VDD<24> @BASEBOARD_FAB2_LIB.BASEBOARD_FAB2(SCH_1):PVDDQ_ABC
  64 PVDDQ_ABC VDD<23> @BASEBOARD_FAB2_LIB.BASEBOARD_FAB2(SCH_1):PVDDQ_ABC
  67 PVDDQ_ABC VDD<22> @BASEBOARD_FAB2_LIB.BASEBOARD_FAB2(SCH_1):PVDDQ_ABC
  70 PVDDQ_ABC VDD<21> @BASEBOARD_FAB2_LIB.BASEBOARD_FAB2(SCH_1):PVDDQ_ABC
  73 PVDDQ_ABC VDD<20> @BASEBOARD_FAB2_LIB.BASEBOARD_FAB2(SCH_1):PVDDQ_ABC
  76 PVDDQ_ABC VDD<19> @BASEBOARD_FAB2_LIB.BASEBOARD_FAB2(SCH_1):PVDDQ_ABC
  80 PVDDQ_ABC VDD<18> @BASEBOARD_FAB2_LIB.BASEBOARD_FAB2(SCH_1):PVDDQ_ABC
  83 PVDDQ_ABC VDD<17> @BASEBOARD_FAB2_LIB.BASEBOARD_FAB2(SCH_1):PVDDQ_ABC
  85 PVDDQ_ABC VDD<16> @BASEBOARD_FAB2_LIB.BASEBOARD_FAB2(SCH_1):PVDDQ_ABC
  88 PVDDQ_ABC VDD<15> @BASEBOARD_FAB2_LIB.BASEBOARD_FAB2(SCH_1):PVDDQ_ABC
  90 PVDDQ_ABC VDD<14> @BASEBOARD_FAB2_LIB.BASEBOARD_FAB2(SCH_1):PVDDQ_ABC
  92 PVDDQ_ABC VDD<13> @BASEBOARD_FAB2_LIB.BASEBOARD_FAB2(SCH_1):PVDDQ_ABC
 204 PVDDQ_ABC VDD<12> @BASEBOARD_FAB2_LIB.BASEBOARD_FAB2(SCH_1):PVDDQ_ABC
 206 PVDDQ_ABC VDD<11> @BASEBOARD_FAB2_LIB.BASEBOARD_FAB2(SCH_1):PVDDQ_ABC
 209 PVDDQ_ABC VDD<10> @BASEBOARD_FAB2_LIB.BASEBOARD_FAB2(SCH_1):PVDDQ_ABC
 212 PVDDQ_ABC VDD<9> @BASEBOARD_FAB2_LIB.BASEBOARD_FAB2(SCH_1):PVDDQ_ABC
 215 PVDDQ_ABC VDD<8> @BASEBOARD_FAB2_LIB.BASEBOARD_FAB2(SCH_1):PVDDQ_ABC
 217 PVDDQ_ABC VDD<7> @BASEBOARD_FAB2_LIB.BASEBOARD_FAB2(SCH_1):PVDDQ_ABC
 220 PVDDQ_ABC VDD<6> @BASEBOARD_FAB2_LIB.BASEBOARD_FAB2(SCH_1):PVDDQ_ABC
 223 PVDDQ_ABC VDD<5> @BASEBOARD_FAB2_LIB.BASEBOARD_FAB2(SCH_1):PVDDQ_ABC
 226 PVDDQ_ABC VDD<4> @BASEBOARD_FAB2_LIB.BASEBOARD_FAB2(SCH_1):PVDDQ_ABC
 229 PVDDQ_ABC VDD<3> @BASEBOARD_FAB2_LIB.BASEBOARD_FAB2(SCH_1):PVDDQ_ABC
 231 PVDDQ_ABC VDD<2> @BASEBOARD_FAB2_LIB.BASEBOARD_FAB2(SCH_1):PVDDQ_ABC
 233 PVDDQ_ABC VDD<1> @BASEBOARD_FAB2_LIB.BASEBOARD_FAB2(SCH_1):PVDDQ_ABC
 236 PVDDQ_ABC VDD<0> @BASEBOARD_FAB2_LIB.BASEBOARD_FAB2(SCH_1):PVDDQ_ABC
 142 PVPP_ABC VPP<4> @BASEBOARD_FAB2_LIB.BASEBOARD_FAB2(SCH_1):PVPP_ABC
 143 PVPP_ABC VPP<3> @BASEBOARD_FAB2_LIB.BASEBOARD_FAB2(SCH_1):PVPP_ABC
 288 PVPP_ABC VPP<2> @BASEBOARD_FAB2_LIB.BASEBOARD_FAB2(SCH_1):PVPP_ABC
 286 PVPP_ABC VPP<1> @BASEBOARD_FAB2_LIB.BASEBOARD_FAB2(SCH_1):PVPP_ABC
 287 PVPP_ABC VPP<0> @BASEBOARD_FAB2_LIB.BASEBOARD_FAB2(SCH_1):PVPP_ABC
  77 PVTT_ABC VTT<1> @BASEBOARD_FAB2_LIB.BASEBOARD_FAB2(SCH_1):PVTT_ABC
 221 PVTT_ABC VTT<0> @BASEBOARD_FAB2_LIB.BASEBOARD_FAB2(SCH_1):PVTT_ABC

SCONN288_H44441003_PIP-SCONN,HA  I120  J6T1
 152 M_A_DQS_DN<0>  DQS0N @BASEBOARD_FAB2_LIB.BASEBOARD_FAB2(SCH_1):M_A_DQS_DN(0)
 153 M_A_DQS_DP<0>  DQS0P @BASEBOARD_FAB2_LIB.BASEBOARD_FAB2(SCH_1):M_A_DQS_DP(0)
  19 M_A_DQS_DN<10> DQS10N @BASEBOARD_FAB2_LIB.BASEBOARD_FAB2(SCH_1):M_A_DQS_DN(10)
  18 M_A_DQS_DP<10> DQS10P @BASEBOARD_FAB2_LIB.BASEBOARD_FAB2(SCH_1):M_A_DQS_DP(10)
  30 M_A_DQS_DN<11> DQS11N @BASEBOARD_FAB2_LIB.BASEBOARD_FAB2(SCH_1):M_A_DQS_DN(11)
  29 M_A_DQS_DP<11> DQS11P @BASEBOARD_FAB2_LIB.BASEBOARD_FAB2(SCH_1):M_A_DQS_DP(11)
  41 M_A_DQS_DN<12> DQS12N @BASEBOARD_FAB2_LIB.BASEBOARD_FAB2(SCH_1):M_A_DQS_DN(12)
  40 M_A_DQS_DP<12> DQS12P @BASEBOARD_FAB2_LIB.BASEBOARD_FAB2(SCH_1):M_A_DQS_DP(12)
 100 M_A_DQS_DN<13> DQS13N @BASEBOARD_FAB2_LIB.BASEBOARD_FAB2(SCH_1):M_A_DQS_DN(13)
  99 M_A_DQS_DP<13> DQS13P @BASEBOARD_FAB2_LIB.BASEBOARD_FAB2(SCH_1):M_A_DQS_DP(13)
 111 M_A_DQS_DN<14> DQS14N @BASEBOARD_FAB2_LIB.BASEBOARD_FAB2(SCH_1):M_A_DQS_DN(14)
 110 M_A_DQS_DP<14> DQS14P @BASEBOARD_FAB2_LIB.BASEBOARD_FAB2(SCH_1):M_A_DQS_DP(14)
 122 M_A_DQS_DN<15> DQS15N @BASEBOARD_FAB2_LIB.BASEBOARD_FAB2(SCH_1):M_A_DQS_DN(15)
 121 M_A_DQS_DP<15> DQS15P @BASEBOARD_FAB2_LIB.BASEBOARD_FAB2(SCH_1):M_A_DQS_DP(15)
 133 M_A_DQS_DN<16> DQS16N @BASEBOARD_FAB2_LIB.BASEBOARD_FAB2(SCH_1):M_A_DQS_DN(16)
 132 M_A_DQS_DP<16> DQS16P @BASEBOARD_FAB2_LIB.BASEBOARD_FAB2(SCH_1):M_A_DQS_DP(16)
  52 M_A_DQS_DN<17> DQS17N @BASEBOARD_FAB2_LIB.BASEBOARD_FAB2(SCH_1):M_A_DQS_DN(17)
  51 M_A_DQS_DP<17> DQS17P @BASEBOARD_FAB2_LIB.BASEBOARD_FAB2(SCH_1):M_A_DQS_DP(17)
 163 M_A_DQS_DN<1>  DQS1N @BASEBOARD_FAB2_LIB.BASEBOARD_FAB2(SCH_1):M_A_DQS_DN(1)
 164 M_A_DQS_DP<1>  DQS1P @BASEBOARD_FAB2_LIB.BASEBOARD_FAB2(SCH_1):M_A_DQS_DP(1)
 174 M_A_DQS_DN<2>  DQS2N @BASEBOARD_FAB2_LIB.BASEBOARD_FAB2(SCH_1):M_A_DQS_DN(2)
 175 M_A_DQS_DP<2>  DQS2P @BASEBOARD_FAB2_LIB.BASEBOARD_FAB2(SCH_1):M_A_DQS_DP(2)
 185 M_A_DQS_DN<3>  DQS3N @BASEBOARD_FAB2_LIB.BASEBOARD_FAB2(SCH_1):M_A_DQS_DN(3)
 186 M_A_DQS_DP<3>  DQS3P @BASEBOARD_FAB2_LIB.BASEBOARD_FAB2(SCH_1):M_A_DQS_DP(3)
 244 M_A_DQS_DN<4>  DQS4N @BASEBOARD_FAB2_LIB.BASEBOARD_FAB2(SCH_1):M_A_DQS_DN(4)
 245 M_A_DQS_DP<4>  DQS4P @BASEBOARD_FAB2_LIB.BASEBOARD_FAB2(SCH_1):M_A_DQS_DP(4)
 255 M_A_DQS_DN<5>  DQS5N @BASEBOARD_FAB2_LIB.BASEBOARD_FAB2(SCH_1):M_A_DQS_DN(5)
 256 M_A_DQS_DP<5>  DQS5P @BASEBOARD_FAB2_LIB.BASEBOARD_FAB2(SCH_1):M_A_DQS_DP(5)
 266 M_A_DQS_DN<6>  DQS6N @BASEBOARD_FAB2_LIB.BASEBOARD_FAB2(SCH_1):M_A_DQS_DN(6)
 267 M_A_DQS_DP<6>  DQS6P @BASEBOARD_FAB2_LIB.BASEBOARD_FAB2(SCH_1):M_A_DQS_DP(6)
 277 M_A_DQS_DN<7>  DQS7N @BASEBOARD_FAB2_LIB.BASEBOARD_FAB2(SCH_1):M_A_DQS_DN(7)
 278 M_A_DQS_DP<7>  DQS7P @BASEBOARD_FAB2_LIB.BASEBOARD_FAB2(SCH_1):M_A_DQS_DP(7)
 196 M_A_DQS_DN<8>  DQS8N @BASEBOARD_FAB2_LIB.BASEBOARD_FAB2(SCH_1):M_A_DQS_DN(8)
 197 M_A_DQS_DP<8>  DQS8P @BASEBOARD_FAB2_LIB.BASEBOARD_FAB2(SCH_1):M_A_DQS_DP(8)
   8 M_A_DQS_DN<9>  DQS9N @BASEBOARD_FAB2_LIB.BASEBOARD_FAB2(SCH_1):M_A_DQS_DN(9)
   7 M_A_DQS_DP<9>  DQS9P @BASEBOARD_FAB2_LIB.BASEBOARD_FAB2(SCH_1):M_A_DQS_DP(9)

SCONN288_H44441003_PIP-SCONN,HA  I139  J6T1
   2    GND VSS<93> @BASEBOARD_FAB2_LIB.BASEBOARD_FAB2(SCH_1):GND
   4    GND VSS<92> @BASEBOARD_FAB2_LIB.BASEBOARD_FAB2(SCH_1):GND
   6    GND VSS<91> @BASEBOARD_FAB2_LIB.BASEBOARD_FAB2(SCH_1):GND
   9    GND VSS<90> @BASEBOARD_FAB2_LIB.BASEBOARD_FAB2(SCH_1):GND
  11    GND VSS<89> @BASEBOARD_FAB2_LIB.BASEBOARD_FAB2(SCH_1):GND
  13    GND VSS<88> @BASEBOARD_FAB2_LIB.BASEBOARD_FAB2(SCH_1):GND
  15    GND VSS<87> @BASEBOARD_FAB2_LIB.BASEBOARD_FAB2(SCH_1):GND
  17    GND VSS<86> @BASEBOARD_FAB2_LIB.BASEBOARD_FAB2(SCH_1):GND
  20    GND VSS<85> @BASEBOARD_FAB2_LIB.BASEBOARD_FAB2(SCH_1):GND
  22    GND VSS<84> @BASEBOARD_FAB2_LIB.BASEBOARD_FAB2(SCH_1):GND
  24    GND VSS<83> @BASEBOARD_FAB2_LIB.BASEBOARD_FAB2(SCH_1):GND
  26    GND VSS<82> @BASEBOARD_FAB2_LIB.BASEBOARD_FAB2(SCH_1):GND
  28    GND VSS<81> @BASEBOARD_FAB2_LIB.BASEBOARD_FAB2(SCH_1):GND
  31    GND VSS<80> @BASEBOARD_FAB2_LIB.BASEBOARD_FAB2(SCH_1):GND
  33    GND VSS<79> @BASEBOARD_FAB2_LIB.BASEBOARD_FAB2(SCH_1):GND
  35    GND VSS<78> @BASEBOARD_FAB2_LIB.BASEBOARD_FAB2(SCH_1):GND
  37    GND VSS<77> @BASEBOARD_FAB2_LIB.BASEBOARD_FAB2(SCH_1):GND
  39    GND VSS<76> @BASEBOARD_FAB2_LIB.BASEBOARD_FAB2(SCH_1):GND
  42    GND VSS<75> @BASEBOARD_FAB2_LIB.BASEBOARD_FAB2(SCH_1):GND
  44    GND VSS<74> @BASEBOARD_FAB2_LIB.BASEBOARD_FAB2(SCH_1):GND
  46    GND VSS<73> @BASEBOARD_FAB2_LIB.BASEBOARD_FAB2(SCH_1):GND
  48    GND VSS<72> @BASEBOARD_FAB2_LIB.BASEBOARD_FAB2(SCH_1):GND
  50    GND VSS<71> @BASEBOARD_FAB2_LIB.BASEBOARD_FAB2(SCH_1):GND
  53    GND VSS<70> @BASEBOARD_FAB2_LIB.BASEBOARD_FAB2(SCH_1):GND
  55    GND VSS<69> @BASEBOARD_FAB2_LIB.BASEBOARD_FAB2(SCH_1):GND
  57    GND VSS<68> @BASEBOARD_FAB2_LIB.BASEBOARD_FAB2(SCH_1):GND
  94    GND VSS<67> @BASEBOARD_FAB2_LIB.BASEBOARD_FAB2(SCH_1):GND
  96    GND VSS<66> @BASEBOARD_FAB2_LIB.BASEBOARD_FAB2(SCH_1):GND
  98    GND VSS<65> @BASEBOARD_FAB2_LIB.BASEBOARD_FAB2(SCH_1):GND
 101    GND VSS<64> @BASEBOARD_FAB2_LIB.BASEBOARD_FAB2(SCH_1):GND
 103    GND VSS<63> @BASEBOARD_FAB2_LIB.BASEBOARD_FAB2(SCH_1):GND
 105    GND VSS<62> @BASEBOARD_FAB2_LIB.BASEBOARD_FAB2(SCH_1):GND
 107    GND VSS<61> @BASEBOARD_FAB2_LIB.BASEBOARD_FAB2(SCH_1):GND
 109    GND VSS<60> @BASEBOARD_FAB2_LIB.BASEBOARD_FAB2(SCH_1):GND
 112    GND VSS<59> @BASEBOARD_FAB2_LIB.BASEBOARD_FAB2(SCH_1):GND
 114    GND VSS<58> @BASEBOARD_FAB2_LIB.BASEBOARD_FAB2(SCH_1):GND
 116    GND VSS<57> @BASEBOARD_FAB2_LIB.BASEBOARD_FAB2(SCH_1):GND
 118    GND VSS<56> @BASEBOARD_FAB2_LIB.BASEBOARD_FAB2(SCH_1):GND
 120    GND VSS<55> @BASEBOARD_FAB2_LIB.BASEBOARD_FAB2(SCH_1):GND
 123    GND VSS<54> @BASEBOARD_FAB2_LIB.BASEBOARD_FAB2(SCH_1):GND
 125    GND VSS<53> @BASEBOARD_FAB2_LIB.BASEBOARD_FAB2(SCH_1):GND
 127    GND VSS<52> @BASEBOARD_FAB2_LIB.BASEBOARD_FAB2(SCH_1):GND
 129    GND VSS<51> @BASEBOARD_FAB2_LIB.BASEBOARD_FAB2(SCH_1):GND
 131    GND VSS<50> @BASEBOARD_FAB2_LIB.BASEBOARD_FAB2(SCH_1):GND
 134    GND VSS<49> @BASEBOARD_FAB2_LIB.BASEBOARD_FAB2(SCH_1):GND
 136    GND VSS<48> @BASEBOARD_FAB2_LIB.BASEBOARD_FAB2(SCH_1):GND
 138    GND VSS<47> @BASEBOARD_FAB2_LIB.BASEBOARD_FAB2(SCH_1):GND
 147    GND VSS<46> @BASEBOARD_FAB2_LIB.BASEBOARD_FAB2(SCH_1):GND
 149    GND VSS<45> @BASEBOARD_FAB2_LIB.BASEBOARD_FAB2(SCH_1):GND
 151    GND VSS<44> @BASEBOARD_FAB2_LIB.BASEBOARD_FAB2(SCH_1):GND
 154    GND VSS<43> @BASEBOARD_FAB2_LIB.BASEBOARD_FAB2(SCH_1):GND
 156    GND VSS<42> @BASEBOARD_FAB2_LIB.BASEBOARD_FAB2(SCH_1):GND
 158    GND VSS<41> @BASEBOARD_FAB2_LIB.BASEBOARD_FAB2(SCH_1):GND
 160    GND VSS<40> @BASEBOARD_FAB2_LIB.BASEBOARD_FAB2(SCH_1):GND
 162    GND VSS<39> @BASEBOARD_FAB2_LIB.BASEBOARD_FAB2(SCH_1):GND
 165    GND VSS<38> @BASEBOARD_FAB2_LIB.BASEBOARD_FAB2(SCH_1):GND
 167    GND VSS<37> @BASEBOARD_FAB2_LIB.BASEBOARD_FAB2(SCH_1):GND
 169    GND VSS<36> @BASEBOARD_FAB2_LIB.BASEBOARD_FAB2(SCH_1):GND
 171    GND VSS<35> @BASEBOARD_FAB2_LIB.BASEBOARD_FAB2(SCH_1):GND
 173    GND VSS<34> @BASEBOARD_FAB2_LIB.BASEBOARD_FAB2(SCH_1):GND
 176    GND VSS<33> @BASEBOARD_FAB2_LIB.BASEBOARD_FAB2(SCH_1):GND
 178    GND VSS<32> @BASEBOARD_FAB2_LIB.BASEBOARD_FAB2(SCH_1):GND
 180    GND VSS<31> @BASEBOARD_FAB2_LIB.BASEBOARD_FAB2(SCH_1):GND
 182    GND VSS<30> @BASEBOARD_FAB2_LIB.BASEBOARD_FAB2(SCH_1):GND
 184    GND VSS<29> @BASEBOARD_FAB2_LIB.BASEBOARD_FAB2(SCH_1):GND
 187    GND VSS<28> @BASEBOARD_FAB2_LIB.BASEBOARD_FAB2(SCH_1):GND
 189    GND VSS<27> @BASEBOARD_FAB2_LIB.BASEBOARD_FAB2(SCH_1):GND
 191    GND VSS<26> @BASEBOARD_FAB2_LIB.BASEBOARD_FAB2(SCH_1):GND
 193    GND VSS<25> @BASEBOARD_FAB2_LIB.BASEBOARD_FAB2(SCH_1):GND
 195    GND VSS<24> @BASEBOARD_FAB2_LIB.BASEBOARD_FAB2(SCH_1):GND
 198    GND VSS<23> @BASEBOARD_FAB2_LIB.BASEBOARD_FAB2(SCH_1):GND
 200    GND VSS<22> @BASEBOARD_FAB2_LIB.BASEBOARD_FAB2(SCH_1):GND
 202    GND VSS<21> @BASEBOARD_FAB2_LIB.BASEBOARD_FAB2(SCH_1):GND
 239    GND VSS<20> @BASEBOARD_FAB2_LIB.BASEBOARD_FAB2(SCH_1):GND
 241    GND VSS<19> @BASEBOARD_FAB2_LIB.BASEBOARD_FAB2(SCH_1):GND
 243    GND VSS<18> @BASEBOARD_FAB2_LIB.BASEBOARD_FAB2(SCH_1):GND
 246    GND VSS<17> @BASEBOARD_FAB2_LIB.BASEBOARD_FAB2(SCH_1):GND
 248    GND VSS<16> @BASEBOARD_FAB2_LIB.BASEBOARD_FAB2(SCH_1):GND
 250    GND VSS<15> @BASEBOARD_FAB2_LIB.BASEBOARD_FAB2(SCH_1):GND
 252    GND VSS<14> @BASEBOARD_FAB2_LIB.BASEBOARD_FAB2(SCH_1):GND
 254    GND VSS<13> @BASEBOARD_FAB2_LIB.BASEBOARD_FAB2(SCH_1):GND
 257    GND VSS<12> @BASEBOARD_FAB2_LIB.BASEBOARD_FAB2(SCH_1):GND
 259    GND VSS<11> @BASEBOARD_FAB2_LIB.BASEBOARD_FAB2(SCH_1):GND
 261    GND VSS<10> @BASEBOARD_FAB2_LIB.BASEBOARD_FAB2(SCH_1):GND
 263    GND VSS<9> @BASEBOARD_FAB2_LIB.BASEBOARD_FAB2(SCH_1):GND
 265    GND VSS<8> @BASEBOARD_FAB2_LIB.BASEBOARD_FAB2(SCH_1):GND
 268    GND VSS<7> @BASEBOARD_FAB2_LIB.BASEBOARD_FAB2(SCH_1):GND
 270    GND VSS<6> @BASEBOARD_FAB2_LIB.BASEBOARD_FAB2(SCH_1):GND
 272    GND VSS<5> @BASEBOARD_FAB2_LIB.BASEBOARD_FAB2(SCH_1):GND
 274    GND VSS<4> @BASEBOARD_FAB2_LIB.BASEBOARD_FAB2(SCH_1):GND
 276    GND VSS<3> @BASEBOARD_FAB2_LIB.BASEBOARD_FAB2(SCH_1):GND
 279    GND VSS<2> @BASEBOARD_FAB2_LIB.BASEBOARD_FAB2(SCH_1):GND
 281    GND VSS<1> @BASEBOARD_FAB2_LIB.BASEBOARD_FAB2(SCH_1):GND
 283    GND VSS<0> @BASEBOARD_FAB2_LIB.BASEBOARD_FAB2(SCH_1):GND


DRAWING: @BASEBOARD_FAB2_LIB.BASEBOARD_FAB2(SCH_1):PAGE45 

SCONN288_H44441004_PIP-SCONN,HA  I43  J4G2
   2    GND VSS<93> @BASEBOARD_FAB2_LIB.BASEBOARD_FAB2(SCH_1):GND
   4    GND VSS<92> @BASEBOARD_FAB2_LIB.BASEBOARD_FAB2(SCH_1):GND
   6    GND VSS<91> @BASEBOARD_FAB2_LIB.BASEBOARD_FAB2(SCH_1):GND
   9    GND VSS<90> @BASEBOARD_FAB2_LIB.BASEBOARD_FAB2(SCH_1):GND
  11    GND VSS<89> @BASEBOARD_FAB2_LIB.BASEBOARD_FAB2(SCH_1):GND
  13    GND VSS<88> @BASEBOARD_FAB2_LIB.BASEBOARD_FAB2(SCH_1):GND
  15    GND VSS<87> @BASEBOARD_FAB2_LIB.BASEBOARD_FAB2(SCH_1):GND
  17    GND VSS<86> @BASEBOARD_FAB2_LIB.BASEBOARD_FAB2(SCH_1):GND
  20    GND VSS<85> @BASEBOARD_FAB2_LIB.BASEBOARD_FAB2(SCH_1):GND
  22    GND VSS<84> @BASEBOARD_FAB2_LIB.BASEBOARD_FAB2(SCH_1):GND
  24    GND VSS<83> @BASEBOARD_FAB2_LIB.BASEBOARD_FAB2(SCH_1):GND
  26    GND VSS<82> @BASEBOARD_FAB2_LIB.BASEBOARD_FAB2(SCH_1):GND
  28    GND VSS<81> @BASEBOARD_FAB2_LIB.BASEBOARD_FAB2(SCH_1):GND
  31    GND VSS<80> @BASEBOARD_FAB2_LIB.BASEBOARD_FAB2(SCH_1):GND
  33    GND VSS<79> @BASEBOARD_FAB2_LIB.BASEBOARD_FAB2(SCH_1):GND
  35    GND VSS<78> @BASEBOARD_FAB2_LIB.BASEBOARD_FAB2(SCH_1):GND
  37    GND VSS<77> @BASEBOARD_FAB2_LIB.BASEBOARD_FAB2(SCH_1):GND
  39    GND VSS<76> @BASEBOARD_FAB2_LIB.BASEBOARD_FAB2(SCH_1):GND
  42    GND VSS<75> @BASEBOARD_FAB2_LIB.BASEBOARD_FAB2(SCH_1):GND
  44    GND VSS<74> @BASEBOARD_FAB2_LIB.BASEBOARD_FAB2(SCH_1):GND
  46    GND VSS<73> @BASEBOARD_FAB2_LIB.BASEBOARD_FAB2(SCH_1):GND
  48    GND VSS<72> @BASEBOARD_FAB2_LIB.BASEBOARD_FAB2(SCH_1):GND
  50    GND VSS<71> @BASEBOARD_FAB2_LIB.BASEBOARD_FAB2(SCH_1):GND
  53    GND VSS<70> @BASEBOARD_FAB2_LIB.BASEBOARD_FAB2(SCH_1):GND
  55    GND VSS<69> @BASEBOARD_FAB2_LIB.BASEBOARD_FAB2(SCH_1):GND
  57    GND VSS<68> @BASEBOARD_FAB2_LIB.BASEBOARD_FAB2(SCH_1):GND
  94    GND VSS<67> @BASEBOARD_FAB2_LIB.BASEBOARD_FAB2(SCH_1):GND
  96    GND VSS<66> @BASEBOARD_FAB2_LIB.BASEBOARD_FAB2(SCH_1):GND
  98    GND VSS<65> @BASEBOARD_FAB2_LIB.BASEBOARD_FAB2(SCH_1):GND
 101    GND VSS<64> @BASEBOARD_FAB2_LIB.BASEBOARD_FAB2(SCH_1):GND
 103    GND VSS<63> @BASEBOARD_FAB2_LIB.BASEBOARD_FAB2(SCH_1):GND
 105    GND VSS<62> @BASEBOARD_FAB2_LIB.BASEBOARD_FAB2(SCH_1):GND
 107    GND VSS<61> @BASEBOARD_FAB2_LIB.BASEBOARD_FAB2(SCH_1):GND
 109    GND VSS<60> @BASEBOARD_FAB2_LIB.BASEBOARD_FAB2(SCH_1):GND
 112    GND VSS<59> @BASEBOARD_FAB2_LIB.BASEBOARD_FAB2(SCH_1):GND
 114    GND VSS<58> @BASEBOARD_FAB2_LIB.BASEBOARD_FAB2(SCH_1):GND
 116    GND VSS<57> @BASEBOARD_FAB2_LIB.BASEBOARD_FAB2(SCH_1):GND
 118    GND VSS<56> @BASEBOARD_FAB2_LIB.BASEBOARD_FAB2(SCH_1):GND
 120    GND VSS<55> @BASEBOARD_FAB2_LIB.BASEBOARD_FAB2(SCH_1):GND
 123    GND VSS<54> @BASEBOARD_FAB2_LIB.BASEBOARD_FAB2(SCH_1):GND
 125    GND VSS<53> @BASEBOARD_FAB2_LIB.BASEBOARD_FAB2(SCH_1):GND
 127    GND VSS<52> @BASEBOARD_FAB2_LIB.BASEBOARD_FAB2(SCH_1):GND
 129    GND VSS<51> @BASEBOARD_FAB2_LIB.BASEBOARD_FAB2(SCH_1):GND
 131    GND VSS<50> @BASEBOARD_FAB2_LIB.BASEBOARD_FAB2(SCH_1):GND
 134    GND VSS<49> @BASEBOARD_FAB2_LIB.BASEBOARD_FAB2(SCH_1):GND
 136    GND VSS<48> @BASEBOARD_FAB2_LIB.BASEBOARD_FAB2(SCH_1):GND
 138    GND VSS<47> @BASEBOARD_FAB2_LIB.BASEBOARD_FAB2(SCH_1):GND
 147    GND VSS<46> @BASEBOARD_FAB2_LIB.BASEBOARD_FAB2(SCH_1):GND
 149    GND VSS<45> @BASEBOARD_FAB2_LIB.BASEBOARD_FAB2(SCH_1):GND
 151    GND VSS<44> @BASEBOARD_FAB2_LIB.BASEBOARD_FAB2(SCH_1):GND
 154    GND VSS<43> @BASEBOARD_FAB2_LIB.BASEBOARD_FAB2(SCH_1):GND
 156    GND VSS<42> @BASEBOARD_FAB2_LIB.BASEBOARD_FAB2(SCH_1):GND
 158    GND VSS<41> @BASEBOARD_FAB2_LIB.BASEBOARD_FAB2(SCH_1):GND
 160    GND VSS<40> @BASEBOARD_FAB2_LIB.BASEBOARD_FAB2(SCH_1):GND
 162    GND VSS<39> @BASEBOARD_FAB2_LIB.BASEBOARD_FAB2(SCH_1):GND
 165    GND VSS<38> @BASEBOARD_FAB2_LIB.BASEBOARD_FAB2(SCH_1):GND
 167    GND VSS<37> @BASEBOARD_FAB2_LIB.BASEBOARD_FAB2(SCH_1):GND
 169    GND VSS<36> @BASEBOARD_FAB2_LIB.BASEBOARD_FAB2(SCH_1):GND
 171    GND VSS<35> @BASEBOARD_FAB2_LIB.BASEBOARD_FAB2(SCH_1):GND
 173    GND VSS<34> @BASEBOARD_FAB2_LIB.BASEBOARD_FAB2(SCH_1):GND
 176    GND VSS<33> @BASEBOARD_FAB2_LIB.BASEBOARD_FAB2(SCH_1):GND
 178    GND VSS<32> @BASEBOARD_FAB2_LIB.BASEBOARD_FAB2(SCH_1):GND
 180    GND VSS<31> @BASEBOARD_FAB2_LIB.BASEBOARD_FAB2(SCH_1):GND
 182    GND VSS<30> @BASEBOARD_FAB2_LIB.BASEBOARD_FAB2(SCH_1):GND
 184    GND VSS<29> @BASEBOARD_FAB2_LIB.BASEBOARD_FAB2(SCH_1):GND
 187    GND VSS<28> @BASEBOARD_FAB2_LIB.BASEBOARD_FAB2(SCH_1):GND
 189    GND VSS<27> @BASEBOARD_FAB2_LIB.BASEBOARD_FAB2(SCH_1):GND
 191    GND VSS<26> @BASEBOARD_FAB2_LIB.BASEBOARD_FAB2(SCH_1):GND
 193    GND VSS<25> @BASEBOARD_FAB2_LIB.BASEBOARD_FAB2(SCH_1):GND
 195    GND VSS<24> @BASEBOARD_FAB2_LIB.BASEBOARD_FAB2(SCH_1):GND
 198    GND VSS<23> @BASEBOARD_FAB2_LIB.BASEBOARD_FAB2(SCH_1):GND
 200    GND VSS<22> @BASEBOARD_FAB2_LIB.BASEBOARD_FAB2(SCH_1):GND
 202    GND VSS<21> @BASEBOARD_FAB2_LIB.BASEBOARD_FAB2(SCH_1):GND
 239    GND VSS<20> @BASEBOARD_FAB2_LIB.BASEBOARD_FAB2(SCH_1):GND
 241    GND VSS<19> @BASEBOARD_FAB2_LIB.BASEBOARD_FAB2(SCH_1):GND
 243    GND VSS<18> @BASEBOARD_FAB2_LIB.BASEBOARD_FAB2(SCH_1):GND
 246    GND VSS<17> @BASEBOARD_FAB2_LIB.BASEBOARD_FAB2(SCH_1):GND
 248    GND VSS<16> @BASEBOARD_FAB2_LIB.BASEBOARD_FAB2(SCH_1):GND
 250    GND VSS<15> @BASEBOARD_FAB2_LIB.BASEBOARD_FAB2(SCH_1):GND
 252    GND VSS<14> @BASEBOARD_FAB2_LIB.BASEBOARD_FAB2(SCH_1):GND
 254    GND VSS<13> @BASEBOARD_FAB2_LIB.BASEBOARD_FAB2(SCH_1):GND
 257    GND VSS<12> @BASEBOARD_FAB2_LIB.BASEBOARD_FAB2(SCH_1):GND
 259    GND VSS<11> @BASEBOARD_FAB2_LIB.BASEBOARD_FAB2(SCH_1):GND
 261    GND VSS<10> @BASEBOARD_FAB2_LIB.BASEBOARD_FAB2(SCH_1):GND
 263    GND VSS<9> @BASEBOARD_FAB2_LIB.BASEBOARD_FAB2(SCH_1):GND
 265    GND VSS<8> @BASEBOARD_FAB2_LIB.BASEBOARD_FAB2(SCH_1):GND
 268    GND VSS<7> @BASEBOARD_FAB2_LIB.BASEBOARD_FAB2(SCH_1):GND
 270    GND VSS<6> @BASEBOARD_FAB2_LIB.BASEBOARD_FAB2(SCH_1):GND
 272    GND VSS<5> @BASEBOARD_FAB2_LIB.BASEBOARD_FAB2(SCH_1):GND
 274    GND VSS<4> @BASEBOARD_FAB2_LIB.BASEBOARD_FAB2(SCH_1):GND
 276    GND VSS<3> @BASEBOARD_FAB2_LIB.BASEBOARD_FAB2(SCH_1):GND
 279    GND VSS<2> @BASEBOARD_FAB2_LIB.BASEBOARD_FAB2(SCH_1):GND
 281    GND VSS<1> @BASEBOARD_FAB2_LIB.BASEBOARD_FAB2(SCH_1):GND
 283    GND VSS<0> @BASEBOARD_FAB2_LIB.BASEBOARD_FAB2(SCH_1):GND

SCONN288_H44441004_PIP-SCONN,HA  I61  J4G2
 152 M_B_DQS_DN<0>  DQS0N @BASEBOARD_FAB2_LIB.BASEBOARD_FAB2(SCH_1):M_B_DQS_DN(0)
 153 M_B_DQS_DP<0>  DQS0P @BASEBOARD_FAB2_LIB.BASEBOARD_FAB2(SCH_1):M_B_DQS_DP(0)
  19 M_B_DQS_DN<10> DQS10N @BASEBOARD_FAB2_LIB.BASEBOARD_FAB2(SCH_1):M_B_DQS_DN(10)
  18 M_B_DQS_DP<10> DQS10P @BASEBOARD_FAB2_LIB.BASEBOARD_FAB2(SCH_1):M_B_DQS_DP(10)
  30 M_B_DQS_DN<11> DQS11N @BASEBOARD_FAB2_LIB.BASEBOARD_FAB2(SCH_1):M_B_DQS_DN(11)
  29 M_B_DQS_DP<11> DQS11P @BASEBOARD_FAB2_LIB.BASEBOARD_FAB2(SCH_1):M_B_DQS_DP(11)
  41 M_B_DQS_DN<12> DQS12N @BASEBOARD_FAB2_LIB.BASEBOARD_FAB2(SCH_1):M_B_DQS_DN(12)
  40 M_B_DQS_DP<12> DQS12P @BASEBOARD_FAB2_LIB.BASEBOARD_FAB2(SCH_1):M_B_DQS_DP(12)
 100 M_B_DQS_DN<13> DQS13N @BASEBOARD_FAB2_LIB.BASEBOARD_FAB2(SCH_1):M_B_DQS_DN(13)
  99 M_B_DQS_DP<13> DQS13P @BASEBOARD_FAB2_LIB.BASEBOARD_FAB2(SCH_1):M_B_DQS_DP(13)
 111 M_B_DQS_DN<14> DQS14N @BASEBOARD_FAB2_LIB.BASEBOARD_FAB2(SCH_1):M_B_DQS_DN(14)
 110 M_B_DQS_DP<14> DQS14P @BASEBOARD_FAB2_LIB.BASEBOARD_FAB2(SCH_1):M_B_DQS_DP(14)
 122 M_B_DQS_DN<15> DQS15N @BASEBOARD_FAB2_LIB.BASEBOARD_FAB2(SCH_1):M_B_DQS_DN(15)
 121 M_B_DQS_DP<15> DQS15P @BASEBOARD_FAB2_LIB.BASEBOARD_FAB2(SCH_1):M_B_DQS_DP(15)
 133 M_B_DQS_DN<16> DQS16N @BASEBOARD_FAB2_LIB.BASEBOARD_FAB2(SCH_1):M_B_DQS_DN(16)
 132 M_B_DQS_DP<16> DQS16P @BASEBOARD_FAB2_LIB.BASEBOARD_FAB2(SCH_1):M_B_DQS_DP(16)
  52 M_B_DQS_DN<17> DQS17N @BASEBOARD_FAB2_LIB.BASEBOARD_FAB2(SCH_1):M_B_DQS_DN(17)
  51 M_B_DQS_DP<17> DQS17P @BASEBOARD_FAB2_LIB.BASEBOARD_FAB2(SCH_1):M_B_DQS_DP(17)
 163 M_B_DQS_DN<1>  DQS1N @BASEBOARD_FAB2_LIB.BASEBOARD_FAB2(SCH_1):M_B_DQS_DN(1)
 164 M_B_DQS_DP<1>  DQS1P @BASEBOARD_FAB2_LIB.BASEBOARD_FAB2(SCH_1):M_B_DQS_DP(1)
 174 M_B_DQS_DN<2>  DQS2N @BASEBOARD_FAB2_LIB.BASEBOARD_FAB2(SCH_1):M_B_DQS_DN(2)
 175 M_B_DQS_DP<2>  DQS2P @BASEBOARD_FAB2_LIB.BASEBOARD_FAB2(SCH_1):M_B_DQS_DP(2)
 185 M_B_DQS_DN<3>  DQS3N @BASEBOARD_FAB2_LIB.BASEBOARD_FAB2(SCH_1):M_B_DQS_DN(3)
 186 M_B_DQS_DP<3>  DQS3P @BASEBOARD_FAB2_LIB.BASEBOARD_FAB2(SCH_1):M_B_DQS_DP(3)
 244 M_B_DQS_DN<4>  DQS4N @BASEBOARD_FAB2_LIB.BASEBOARD_FAB2(SCH_1):M_B_DQS_DN(4)
 245 M_B_DQS_DP<4>  DQS4P @BASEBOARD_FAB2_LIB.BASEBOARD_FAB2(SCH_1):M_B_DQS_DP(4)
 255 M_B_DQS_DN<5>  DQS5N @BASEBOARD_FAB2_LIB.BASEBOARD_FAB2(SCH_1):M_B_DQS_DN(5)
 256 M_B_DQS_DP<5>  DQS5P @BASEBOARD_FAB2_LIB.BASEBOARD_FAB2(SCH_1):M_B_DQS_DP(5)
 266 M_B_DQS_DN<6>  DQS6N @BASEBOARD_FAB2_LIB.BASEBOARD_FAB2(SCH_1):M_B_DQS_DN(6)
 267 M_B_DQS_DP<6>  DQS6P @BASEBOARD_FAB2_LIB.BASEBOARD_FAB2(SCH_1):M_B_DQS_DP(6)
 277 M_B_DQS_DN<7>  DQS7N @BASEBOARD_FAB2_LIB.BASEBOARD_FAB2(SCH_1):M_B_DQS_DN(7)
 278 M_B_DQS_DP<7>  DQS7P @BASEBOARD_FAB2_LIB.BASEBOARD_FAB2(SCH_1):M_B_DQS_DP(7)
 196 M_B_DQS_DN<8>  DQS8N @BASEBOARD_FAB2_LIB.BASEBOARD_FAB2(SCH_1):M_B_DQS_DN(8)
 197 M_B_DQS_DP<8>  DQS8P @BASEBOARD_FAB2_LIB.BASEBOARD_FAB2(SCH_1):M_B_DQS_DP(8)
   8 M_B_DQS_DN<9>  DQS9N @BASEBOARD_FAB2_LIB.BASEBOARD_FAB2(SCH_1):M_B_DQS_DN(9)
   7 M_B_DQS_DP<9>  DQS9P @BASEBOARD_FAB2_LIB.BASEBOARD_FAB2(SCH_1):M_B_DQS_DP(9)

SCONN288_H44441004_PIP-SCONN,HA  I111  J4G2
  79 M_B_MA<0>     A0 @BASEBOARD_FAB2_LIB.BASEBOARD_FAB2(SCH_1):M_B_MA(0)
  72 M_B_MA<1>     A1 @BASEBOARD_FAB2_LIB.BASEBOARD_FAB2(SCH_1):M_B_MA(1)
 225 M_B_MA<10>    A10 @BASEBOARD_FAB2_LIB.BASEBOARD_FAB2(SCH_1):M_B_MA(10)
 210 M_B_MA<11>    A11 @BASEBOARD_FAB2_LIB.BASEBOARD_FAB2(SCH_1):M_B_MA(11)
  65 M_B_MA<12>    A12 @BASEBOARD_FAB2_LIB.BASEBOARD_FAB2(SCH_1):M_B_MA(12)
 232 M_B_MA<13>    A13 @BASEBOARD_FAB2_LIB.BASEBOARD_FAB2(SCH_1):M_B_MA(13)
 228 M_B_MA<14> A14_WE_N @BASEBOARD_FAB2_LIB.BASEBOARD_FAB2(SCH_1):M_B_MA(14)
  86 M_B_MA<15> A15_CAS_N @BASEBOARD_FAB2_LIB.BASEBOARD_FAB2(SCH_1):M_B_MA(15)
  82 M_B_MA<16> A16_RAS_N @BASEBOARD_FAB2_LIB.BASEBOARD_FAB2(SCH_1):M_B_MA(16)
 234 M_B_MA<17>    A17 @BASEBOARD_FAB2_LIB.BASEBOARD_FAB2(SCH_1):M_B_MA(17)
 216 M_B_MA<2>     A2 @BASEBOARD_FAB2_LIB.BASEBOARD_FAB2(SCH_1):M_B_MA(2)
  71 M_B_MA<3>     A3 @BASEBOARD_FAB2_LIB.BASEBOARD_FAB2(SCH_1):M_B_MA(3)
 214 M_B_MA<4>     A4 @BASEBOARD_FAB2_LIB.BASEBOARD_FAB2(SCH_1):M_B_MA(4)
 213 M_B_MA<5>     A5 @BASEBOARD_FAB2_LIB.BASEBOARD_FAB2(SCH_1):M_B_MA(5)
  69 M_B_MA<6>     A6 @BASEBOARD_FAB2_LIB.BASEBOARD_FAB2(SCH_1):M_B_MA(6)
 211 M_B_MA<7>     A7 @BASEBOARD_FAB2_LIB.BASEBOARD_FAB2(SCH_1):M_B_MA(7)
  68 M_B_MA<8>     A8 @BASEBOARD_FAB2_LIB.BASEBOARD_FAB2(SCH_1):M_B_MA(8)
  66 M_B_MA<9>     A9 @BASEBOARD_FAB2_LIB.BASEBOARD_FAB2(SCH_1):M_B_MA(9)
  62 M_B_ACT_N  ACT_N @BASEBOARD_FAB2_LIB.BASEBOARD_FAB2(SCH_1):M_B_ACT_N
 208 M_B_ALERT_N ALERT_N @BASEBOARD_FAB2_LIB.BASEBOARD_FAB2(SCH_1):M_B_ALERT_N
 224 M_B_BA<1>  BA<1> @BASEBOARD_FAB2_LIB.BASEBOARD_FAB2(SCH_1):M_B_BA(1)
  81 M_B_BA<0>  BA<0> @BASEBOARD_FAB2_LIB.BASEBOARD_FAB2(SCH_1):M_B_BA(0)
 207 M_B_BG<1>  BG<1> @BASEBOARD_FAB2_LIB.BASEBOARD_FAB2(SCH_1):M_B_BG(1)
  63 M_B_BG<0>  BG<0> @BASEBOARD_FAB2_LIB.BASEBOARD_FAB2(SCH_1):M_B_BG(0)
 235 M_B_C<2>   C<2> @BASEBOARD_FAB2_LIB.BASEBOARD_FAB2(SCH_1):M_B_C(2)
 199 M_B_ECC<6>  CB<7> @BASEBOARD_FAB2_LIB.BASEBOARD_FAB2(SCH_1):M_B_ECC(6)
  54 M_B_ECC<7>  CB<6> @BASEBOARD_FAB2_LIB.BASEBOARD_FAB2(SCH_1):M_B_ECC(7)
 192 M_B_ECC<4>  CB<5> @BASEBOARD_FAB2_LIB.BASEBOARD_FAB2(SCH_1):M_B_ECC(4)
  47 M_B_ECC<5>  CB<4> @BASEBOARD_FAB2_LIB.BASEBOARD_FAB2(SCH_1):M_B_ECC(5)
 201 M_B_ECC<2>  CB<3> @BASEBOARD_FAB2_LIB.BASEBOARD_FAB2(SCH_1):M_B_ECC(2)
  56 M_B_ECC<3>  CB<2> @BASEBOARD_FAB2_LIB.BASEBOARD_FAB2(SCH_1):M_B_ECC(3)
 194 M_B_ECC<0>  CB<1> @BASEBOARD_FAB2_LIB.BASEBOARD_FAB2(SCH_1):M_B_ECC(0)
  49 M_B_ECC<1>  CB<0> @BASEBOARD_FAB2_LIB.BASEBOARD_FAB2(SCH_1):M_B_ECC(1)
  75 M_B_CLK_DN<0>   CK0N @BASEBOARD_FAB2_LIB.BASEBOARD_FAB2(SCH_1):M_B_CLK_DN(0)
  74 M_B_CLK_DP<0>   CK0P @BASEBOARD_FAB2_LIB.BASEBOARD_FAB2(SCH_1):M_B_CLK_DP(0)
 219 M_B_CLK_DN<1>   CK1N @BASEBOARD_FAB2_LIB.BASEBOARD_FAB2(SCH_1):M_B_CLK_DN(1)
 218 M_B_CLK_DP<1>   CK1P @BASEBOARD_FAB2_LIB.BASEBOARD_FAB2(SCH_1):M_B_CLK_DP(1)
 203 M_B_CKE<1> CKE<1> @BASEBOARD_FAB2_LIB.BASEBOARD_FAB2(SCH_1):M_B_CKE(1)
  60 M_B_CKE<0> CKE<0> @BASEBOARD_FAB2_LIB.BASEBOARD_FAB2(SCH_1):M_B_CKE(0)
 280 M_B_DQ<62> DQ<63> @BASEBOARD_FAB2_LIB.BASEBOARD_FAB2(SCH_1):M_B_DQ(62)
 135 M_B_DQ<63> DQ<62> @BASEBOARD_FAB2_LIB.BASEBOARD_FAB2(SCH_1):M_B_DQ(63)
 273 M_B_DQ<60> DQ<61> @BASEBOARD_FAB2_LIB.BASEBOARD_FAB2(SCH_1):M_B_DQ(60)
 128 M_B_DQ<61> DQ<60> @BASEBOARD_FAB2_LIB.BASEBOARD_FAB2(SCH_1):M_B_DQ(61)
 282 M_B_DQ<58> DQ<59> @BASEBOARD_FAB2_LIB.BASEBOARD_FAB2(SCH_1):M_B_DQ(58)
 137 M_B_DQ<59> DQ<58> @BASEBOARD_FAB2_LIB.BASEBOARD_FAB2(SCH_1):M_B_DQ(59)
 275 M_B_DQ<56> DQ<57> @BASEBOARD_FAB2_LIB.BASEBOARD_FAB2(SCH_1):M_B_DQ(56)
 130 M_B_DQ<57> DQ<56> @BASEBOARD_FAB2_LIB.BASEBOARD_FAB2(SCH_1):M_B_DQ(57)
 269 M_B_DQ<54> DQ<55> @BASEBOARD_FAB2_LIB.BASEBOARD_FAB2(SCH_1):M_B_DQ(54)
 124 M_B_DQ<55> DQ<54> @BASEBOARD_FAB2_LIB.BASEBOARD_FAB2(SCH_1):M_B_DQ(55)
 262 M_B_DQ<52> DQ<53> @BASEBOARD_FAB2_LIB.BASEBOARD_FAB2(SCH_1):M_B_DQ(52)
 117 M_B_DQ<53> DQ<52> @BASEBOARD_FAB2_LIB.BASEBOARD_FAB2(SCH_1):M_B_DQ(53)
 271 M_B_DQ<50> DQ<51> @BASEBOARD_FAB2_LIB.BASEBOARD_FAB2(SCH_1):M_B_DQ(50)
 126 M_B_DQ<51> DQ<50> @BASEBOARD_FAB2_LIB.BASEBOARD_FAB2(SCH_1):M_B_DQ(51)
 264 M_B_DQ<48> DQ<49> @BASEBOARD_FAB2_LIB.BASEBOARD_FAB2(SCH_1):M_B_DQ(48)
 119 M_B_DQ<49> DQ<48> @BASEBOARD_FAB2_LIB.BASEBOARD_FAB2(SCH_1):M_B_DQ(49)
 258 M_B_DQ<46> DQ<47> @BASEBOARD_FAB2_LIB.BASEBOARD_FAB2(SCH_1):M_B_DQ(46)
 113 M_B_DQ<47> DQ<46> @BASEBOARD_FAB2_LIB.BASEBOARD_FAB2(SCH_1):M_B_DQ(47)
 251 M_B_DQ<44> DQ<45> @BASEBOARD_FAB2_LIB.BASEBOARD_FAB2(SCH_1):M_B_DQ(44)
 106 M_B_DQ<45> DQ<44> @BASEBOARD_FAB2_LIB.BASEBOARD_FAB2(SCH_1):M_B_DQ(45)
 260 M_B_DQ<42> DQ<43> @BASEBOARD_FAB2_LIB.BASEBOARD_FAB2(SCH_1):M_B_DQ(42)
 115 M_B_DQ<43> DQ<42> @BASEBOARD_FAB2_LIB.BASEBOARD_FAB2(SCH_1):M_B_DQ(43)
 253 M_B_DQ<40> DQ<41> @BASEBOARD_FAB2_LIB.BASEBOARD_FAB2(SCH_1):M_B_DQ(40)
 108 M_B_DQ<41> DQ<40> @BASEBOARD_FAB2_LIB.BASEBOARD_FAB2(SCH_1):M_B_DQ(41)
 247 M_B_DQ<38> DQ<39> @BASEBOARD_FAB2_LIB.BASEBOARD_FAB2(SCH_1):M_B_DQ(38)
 102 M_B_DQ<39> DQ<38> @BASEBOARD_FAB2_LIB.BASEBOARD_FAB2(SCH_1):M_B_DQ(39)
 240 M_B_DQ<36> DQ<37> @BASEBOARD_FAB2_LIB.BASEBOARD_FAB2(SCH_1):M_B_DQ(36)
  95 M_B_DQ<37> DQ<36> @BASEBOARD_FAB2_LIB.BASEBOARD_FAB2(SCH_1):M_B_DQ(37)
 249 M_B_DQ<34> DQ<35> @BASEBOARD_FAB2_LIB.BASEBOARD_FAB2(SCH_1):M_B_DQ(34)
 104 M_B_DQ<35> DQ<34> @BASEBOARD_FAB2_LIB.BASEBOARD_FAB2(SCH_1):M_B_DQ(35)
 242 M_B_DQ<32> DQ<33> @BASEBOARD_FAB2_LIB.BASEBOARD_FAB2(SCH_1):M_B_DQ(32)
  97 M_B_DQ<33> DQ<32> @BASEBOARD_FAB2_LIB.BASEBOARD_FAB2(SCH_1):M_B_DQ(33)
 188 M_B_DQ<30> DQ<31> @BASEBOARD_FAB2_LIB.BASEBOARD_FAB2(SCH_1):M_B_DQ(30)
  43 M_B_DQ<31> DQ<30> @BASEBOARD_FAB2_LIB.BASEBOARD_FAB2(SCH_1):M_B_DQ(31)
 181 M_B_DQ<28> DQ<29> @BASEBOARD_FAB2_LIB.BASEBOARD_FAB2(SCH_1):M_B_DQ(28)
  36 M_B_DQ<29> DQ<28> @BASEBOARD_FAB2_LIB.BASEBOARD_FAB2(SCH_1):M_B_DQ(29)
 190 M_B_DQ<26> DQ<27> @BASEBOARD_FAB2_LIB.BASEBOARD_FAB2(SCH_1):M_B_DQ(26)
  45 M_B_DQ<27> DQ<26> @BASEBOARD_FAB2_LIB.BASEBOARD_FAB2(SCH_1):M_B_DQ(27)
 183 M_B_DQ<24> DQ<25> @BASEBOARD_FAB2_LIB.BASEBOARD_FAB2(SCH_1):M_B_DQ(24)
  38 M_B_DQ<25> DQ<24> @BASEBOARD_FAB2_LIB.BASEBOARD_FAB2(SCH_1):M_B_DQ(25)
 177 M_B_DQ<22> DQ<23> @BASEBOARD_FAB2_LIB.BASEBOARD_FAB2(SCH_1):M_B_DQ(22)
  32 M_B_DQ<23> DQ<22> @BASEBOARD_FAB2_LIB.BASEBOARD_FAB2(SCH_1):M_B_DQ(23)
 170 M_B_DQ<20> DQ<21> @BASEBOARD_FAB2_LIB.BASEBOARD_FAB2(SCH_1):M_B_DQ(20)
  25 M_B_DQ<21> DQ<20> @BASEBOARD_FAB2_LIB.BASEBOARD_FAB2(SCH_1):M_B_DQ(21)
 179 M_B_DQ<18> DQ<19> @BASEBOARD_FAB2_LIB.BASEBOARD_FAB2(SCH_1):M_B_DQ(18)
  34 M_B_DQ<19> DQ<18> @BASEBOARD_FAB2_LIB.BASEBOARD_FAB2(SCH_1):M_B_DQ(19)
 172 M_B_DQ<16> DQ<17> @BASEBOARD_FAB2_LIB.BASEBOARD_FAB2(SCH_1):M_B_DQ(16)
  27 M_B_DQ<17> DQ<16> @BASEBOARD_FAB2_LIB.BASEBOARD_FAB2(SCH_1):M_B_DQ(17)
 166 M_B_DQ<14> DQ<15> @BASEBOARD_FAB2_LIB.BASEBOARD_FAB2(SCH_1):M_B_DQ(14)
  21 M_B_DQ<15> DQ<14> @BASEBOARD_FAB2_LIB.BASEBOARD_FAB2(SCH_1):M_B_DQ(15)
 159 M_B_DQ<12> DQ<13> @BASEBOARD_FAB2_LIB.BASEBOARD_FAB2(SCH_1):M_B_DQ(12)
  14 M_B_DQ<13> DQ<12> @BASEBOARD_FAB2_LIB.BASEBOARD_FAB2(SCH_1):M_B_DQ(13)
 168 M_B_DQ<10> DQ<11> @BASEBOARD_FAB2_LIB.BASEBOARD_FAB2(SCH_1):M_B_DQ(10)
  23 M_B_DQ<11> DQ<10> @BASEBOARD_FAB2_LIB.BASEBOARD_FAB2(SCH_1):M_B_DQ(11)
 161 M_B_DQ<8>  DQ<9> @BASEBOARD_FAB2_LIB.BASEBOARD_FAB2(SCH_1):M_B_DQ(8)
  16 M_B_DQ<9>  DQ<8> @BASEBOARD_FAB2_LIB.BASEBOARD_FAB2(SCH_1):M_B_DQ(9)
 155 M_B_DQ<6>  DQ<7> @BASEBOARD_FAB2_LIB.BASEBOARD_FAB2(SCH_1):M_B_DQ(6)
  10 M_B_DQ<7>  DQ<6> @BASEBOARD_FAB2_LIB.BASEBOARD_FAB2(SCH_1):M_B_DQ(7)
 148 M_B_DQ<4>  DQ<5> @BASEBOARD_FAB2_LIB.BASEBOARD_FAB2(SCH_1):M_B_DQ(4)
   3 M_B_DQ<5>  DQ<4> @BASEBOARD_FAB2_LIB.BASEBOARD_FAB2(SCH_1):M_B_DQ(5)
 157 M_B_DQ<2>  DQ<3> @BASEBOARD_FAB2_LIB.BASEBOARD_FAB2(SCH_1):M_B_DQ(2)
  12 M_B_DQ<3>  DQ<2> @BASEBOARD_FAB2_LIB.BASEBOARD_FAB2(SCH_1):M_B_DQ(3)
 150 M_B_DQ<0>  DQ<1> @BASEBOARD_FAB2_LIB.BASEBOARD_FAB2(SCH_1):M_B_DQ(0)
   5 M_B_DQ<1>  DQ<0> @BASEBOARD_FAB2_LIB.BASEBOARD_FAB2(SCH_1):M_B_DQ(1)
  78 FM_DIMM_EVENT_COD_N EVENT_N @BASEBOARD_FAB2_LIB.BASEBOARD_FAB2(SCH_1):FM_DIMM_EVENT_COD_N
  91 M_B_ODT<1> ODT<1> @BASEBOARD_FAB2_LIB.BASEBOARD_FAB2(SCH_1):M_B_ODT(1)
  87 M_B_ODT<0> ODT<0> @BASEBOARD_FAB2_LIB.BASEBOARD_FAB2(SCH_1):M_B_ODT(0)
 222 M_B_PAR    PAR @BASEBOARD_FAB2_LIB.BASEBOARD_FAB2(SCH_1):M_B_PAR
  58 M_ABC_RST_N RESET_N @BASEBOARD_FAB2_LIB.BASEBOARD_FAB2(SCH_1):M_ABC_RST_N
 144 TP_CH_B_DIMM_B0_RFU_2 RFU<2> @BASEBOARD_FAB2_LIB.BASEBOARD_FAB2(SCH_1):TP_CH_B_DIMM_B0_RFU_2
 227 TP_CH_B_DIMM_B0_RFU_1 RFU<1> @BASEBOARD_FAB2_LIB.BASEBOARD_FAB2(SCH_1):TP_CH_B_DIMM_B0_RFU_1
 205 TP_CH_B_DIMM_B0_RFU_0 RFU<0> @BASEBOARD_FAB2_LIB.BASEBOARD_FAB2(SCH_1):TP_CH_B_DIMM_B0_RFU_0
  84 M_B_CS_N<0>   S0_N @BASEBOARD_FAB2_LIB.BASEBOARD_FAB2(SCH_1):M_B_CS_N(0)
  89 M_B_CS_N<1>   S1_N @BASEBOARD_FAB2_LIB.BASEBOARD_FAB2(SCH_1):M_B_CS_N(1)
  93 M_B_CS_N<2> S2_N_C<0> @BASEBOARD_FAB2_LIB.BASEBOARD_FAB2(SCH_1):M_B_CS_N(2)
 237 M_B_CS_N<3> S3_N_C<1> @BASEBOARD_FAB2_LIB.BASEBOARD_FAB2(SCH_1):M_B_CS_N(3)
 238    GND  SA<2> @BASEBOARD_FAB2_LIB.BASEBOARD_FAB2(SCH_1):GND
 140 PVPP_ABC  SA<1> @BASEBOARD_FAB2_LIB.BASEBOARD_FAB2(SCH_1):PVPP_ABC
 139    GND  SA<0> @BASEBOARD_FAB2_LIB.BASEBOARD_FAB2(SCH_1):GND
 230 FM_ADR_COMPLETE_ABC_N SAVE_N_NC @BASEBOARD_FAB2_LIB.BASEBOARD_FAB2(SCH_1):FM_ADR_COMPLETE_ABC_N
 141 SMB_DDR_ABC_VPP_SCL    SCL @BASEBOARD_FAB2_LIB.BASEBOARD_FAB2(SCH_1):SMB_DDR_ABC_VPP_SCL
 285 SMB_DDR_ABC_VPP_SDA    SDA @BASEBOARD_FAB2_LIB.BASEBOARD_FAB2(SCH_1):SMB_DDR_ABC_VPP_SDA
 284 PVPP_ABC VDDSPD @BASEBOARD_FAB2_LIB.BASEBOARD_FAB2(SCH_1):PVPP_ABC
 146 M_B_VREF VREFCA @BASEBOARD_FAB2_LIB.BASEBOARD_FAB2(SCH_1):M_B_VREF

SCONN288_H44441004_PIP-SCONN,HA  I169  J4G2
   1 P12V_NVDIMM_ABC 12V<1> @BASEBOARD_FAB2_LIB.BASEBOARD_FAB2(SCH_1):P12V_NVDIMM_ABC
 145 P12V_NVDIMM_ABC 12V<0> @BASEBOARD_FAB2_LIB.BASEBOARD_FAB2(SCH_1):P12V_NVDIMM_ABC
  59 PVDDQ_ABC VDD<25> @BASEBOARD_FAB2_LIB.BASEBOARD_FAB2(SCH_1):PVDDQ_ABC
  61 PVDDQ_ABC VDD<24> @BASEBOARD_FAB2_LIB.BASEBOARD_FAB2(SCH_1):PVDDQ_ABC
  64 PVDDQ_ABC VDD<23> @BASEBOARD_FAB2_LIB.BASEBOARD_FAB2(SCH_1):PVDDQ_ABC
  67 PVDDQ_ABC VDD<22> @BASEBOARD_FAB2_LIB.BASEBOARD_FAB2(SCH_1):PVDDQ_ABC
  70 PVDDQ_ABC VDD<21> @BASEBOARD_FAB2_LIB.BASEBOARD_FAB2(SCH_1):PVDDQ_ABC
  73 PVDDQ_ABC VDD<20> @BASEBOARD_FAB2_LIB.BASEBOARD_FAB2(SCH_1):PVDDQ_ABC
  76 PVDDQ_ABC VDD<19> @BASEBOARD_FAB2_LIB.BASEBOARD_FAB2(SCH_1):PVDDQ_ABC
  80 PVDDQ_ABC VDD<18> @BASEBOARD_FAB2_LIB.BASEBOARD_FAB2(SCH_1):PVDDQ_ABC
  83 PVDDQ_ABC VDD<17> @BASEBOARD_FAB2_LIB.BASEBOARD_FAB2(SCH_1):PVDDQ_ABC
  85 PVDDQ_ABC VDD<16> @BASEBOARD_FAB2_LIB.BASEBOARD_FAB2(SCH_1):PVDDQ_ABC
  88 PVDDQ_ABC VDD<15> @BASEBOARD_FAB2_LIB.BASEBOARD_FAB2(SCH_1):PVDDQ_ABC
  90 PVDDQ_ABC VDD<14> @BASEBOARD_FAB2_LIB.BASEBOARD_FAB2(SCH_1):PVDDQ_ABC
  92 PVDDQ_ABC VDD<13> @BASEBOARD_FAB2_LIB.BASEBOARD_FAB2(SCH_1):PVDDQ_ABC
 204 PVDDQ_ABC VDD<12> @BASEBOARD_FAB2_LIB.BASEBOARD_FAB2(SCH_1):PVDDQ_ABC
 206 PVDDQ_ABC VDD<11> @BASEBOARD_FAB2_LIB.BASEBOARD_FAB2(SCH_1):PVDDQ_ABC
 209 PVDDQ_ABC VDD<10> @BASEBOARD_FAB2_LIB.BASEBOARD_FAB2(SCH_1):PVDDQ_ABC
 212 PVDDQ_ABC VDD<9> @BASEBOARD_FAB2_LIB.BASEBOARD_FAB2(SCH_1):PVDDQ_ABC
 215 PVDDQ_ABC VDD<8> @BASEBOARD_FAB2_LIB.BASEBOARD_FAB2(SCH_1):PVDDQ_ABC
 217 PVDDQ_ABC VDD<7> @BASEBOARD_FAB2_LIB.BASEBOARD_FAB2(SCH_1):PVDDQ_ABC
 220 PVDDQ_ABC VDD<6> @BASEBOARD_FAB2_LIB.BASEBOARD_FAB2(SCH_1):PVDDQ_ABC
 223 PVDDQ_ABC VDD<5> @BASEBOARD_FAB2_LIB.BASEBOARD_FAB2(SCH_1):PVDDQ_ABC
 226 PVDDQ_ABC VDD<4> @BASEBOARD_FAB2_LIB.BASEBOARD_FAB2(SCH_1):PVDDQ_ABC
 229 PVDDQ_ABC VDD<3> @BASEBOARD_FAB2_LIB.BASEBOARD_FAB2(SCH_1):PVDDQ_ABC
 231 PVDDQ_ABC VDD<2> @BASEBOARD_FAB2_LIB.BASEBOARD_FAB2(SCH_1):PVDDQ_ABC
 233 PVDDQ_ABC VDD<1> @BASEBOARD_FAB2_LIB.BASEBOARD_FAB2(SCH_1):PVDDQ_ABC
 236 PVDDQ_ABC VDD<0> @BASEBOARD_FAB2_LIB.BASEBOARD_FAB2(SCH_1):PVDDQ_ABC
 142 PVPP_ABC VPP<4> @BASEBOARD_FAB2_LIB.BASEBOARD_FAB2(SCH_1):PVPP_ABC
 143 PVPP_ABC VPP<3> @BASEBOARD_FAB2_LIB.BASEBOARD_FAB2(SCH_1):PVPP_ABC
 288 PVPP_ABC VPP<2> @BASEBOARD_FAB2_LIB.BASEBOARD_FAB2(SCH_1):PVPP_ABC
 286 PVPP_ABC VPP<1> @BASEBOARD_FAB2_LIB.BASEBOARD_FAB2(SCH_1):PVPP_ABC
 287 PVPP_ABC VPP<0> @BASEBOARD_FAB2_LIB.BASEBOARD_FAB2(SCH_1):PVPP_ABC
  77 PVTT_ABC VTT<1> @BASEBOARD_FAB2_LIB.BASEBOARD_FAB2(SCH_1):PVTT_ABC
 221 PVTT_ABC VTT<0> @BASEBOARD_FAB2_LIB.BASEBOARD_FAB2(SCH_1):PVTT_ABC

CAP_A_0402V-0.01UF,25V,10%,X7RA  I179  C4G3
   1 M_B_VREF      A @BASEBOARD_FAB2_LIB.BASEBOARD_FAB2(SCH_1):M_B_VREF
   2    GND      B @BASEBOARD_FAB2_LIB.BASEBOARD_FAB2(SCH_1):GND


DRAWING: @BASEBOARD_FAB2_LIB.BASEBOARD_FAB2(SCH_1):PAGE46 

CAP_A_0402V-0.01UF,25V,10%,X7RA  I5  C6U9
   1 M_B_VREF      A @BASEBOARD_FAB2_LIB.BASEBOARD_FAB2(SCH_1):M_B_VREF
   2    GND      B @BASEBOARD_FAB2_LIB.BASEBOARD_FAB2(SCH_1):GND

SCONN288_H44441003_PIP-SCONN,HA  I14  J6U1
  79 M_B_MA<0>     A0 @BASEBOARD_FAB2_LIB.BASEBOARD_FAB2(SCH_1):M_B_MA(0)
  72 M_B_MA<1>     A1 @BASEBOARD_FAB2_LIB.BASEBOARD_FAB2(SCH_1):M_B_MA(1)
 225 M_B_MA<10>    A10 @BASEBOARD_FAB2_LIB.BASEBOARD_FAB2(SCH_1):M_B_MA(10)
 210 M_B_MA<11>    A11 @BASEBOARD_FAB2_LIB.BASEBOARD_FAB2(SCH_1):M_B_MA(11)
  65 M_B_MA<12>    A12 @BASEBOARD_FAB2_LIB.BASEBOARD_FAB2(SCH_1):M_B_MA(12)
 232 M_B_MA<13>    A13 @BASEBOARD_FAB2_LIB.BASEBOARD_FAB2(SCH_1):M_B_MA(13)
 228 M_B_MA<14> A14_WE_N @BASEBOARD_FAB2_LIB.BASEBOARD_FAB2(SCH_1):M_B_MA(14)
  86 M_B_MA<15> A15_CAS_N @BASEBOARD_FAB2_LIB.BASEBOARD_FAB2(SCH_1):M_B_MA(15)
  82 M_B_MA<16> A16_RAS_N @BASEBOARD_FAB2_LIB.BASEBOARD_FAB2(SCH_1):M_B_MA(16)
 234 M_B_MA<17>    A17 @BASEBOARD_FAB2_LIB.BASEBOARD_FAB2(SCH_1):M_B_MA(17)
 216 M_B_MA<2>     A2 @BASEBOARD_FAB2_LIB.BASEBOARD_FAB2(SCH_1):M_B_MA(2)
  71 M_B_MA<3>     A3 @BASEBOARD_FAB2_LIB.BASEBOARD_FAB2(SCH_1):M_B_MA(3)
 214 M_B_MA<4>     A4 @BASEBOARD_FAB2_LIB.BASEBOARD_FAB2(SCH_1):M_B_MA(4)
 213 M_B_MA<5>     A5 @BASEBOARD_FAB2_LIB.BASEBOARD_FAB2(SCH_1):M_B_MA(5)
  69 M_B_MA<6>     A6 @BASEBOARD_FAB2_LIB.BASEBOARD_FAB2(SCH_1):M_B_MA(6)
 211 M_B_MA<7>     A7 @BASEBOARD_FAB2_LIB.BASEBOARD_FAB2(SCH_1):M_B_MA(7)
  68 M_B_MA<8>     A8 @BASEBOARD_FAB2_LIB.BASEBOARD_FAB2(SCH_1):M_B_MA(8)
  66 M_B_MA<9>     A9 @BASEBOARD_FAB2_LIB.BASEBOARD_FAB2(SCH_1):M_B_MA(9)
  62 M_B_ACT_N  ACT_N @BASEBOARD_FAB2_LIB.BASEBOARD_FAB2(SCH_1):M_B_ACT_N
 208 M_B_ALERT_N ALERT_N @BASEBOARD_FAB2_LIB.BASEBOARD_FAB2(SCH_1):M_B_ALERT_N
 224 M_B_BA<1>  BA<1> @BASEBOARD_FAB2_LIB.BASEBOARD_FAB2(SCH_1):M_B_BA(1)
  81 M_B_BA<0>  BA<0> @BASEBOARD_FAB2_LIB.BASEBOARD_FAB2(SCH_1):M_B_BA(0)
 207 M_B_BG<1>  BG<1> @BASEBOARD_FAB2_LIB.BASEBOARD_FAB2(SCH_1):M_B_BG(1)
  63 M_B_BG<0>  BG<0> @BASEBOARD_FAB2_LIB.BASEBOARD_FAB2(SCH_1):M_B_BG(0)
 235 M_B_C<2>   C<2> @BASEBOARD_FAB2_LIB.BASEBOARD_FAB2(SCH_1):M_B_C(2)
 199 M_B_ECC<7>  CB<7> @BASEBOARD_FAB2_LIB.BASEBOARD_FAB2(SCH_1):M_B_ECC(7)
  54 M_B_ECC<6>  CB<6> @BASEBOARD_FAB2_LIB.BASEBOARD_FAB2(SCH_1):M_B_ECC(6)
 192 M_B_ECC<5>  CB<5> @BASEBOARD_FAB2_LIB.BASEBOARD_FAB2(SCH_1):M_B_ECC(5)
  47 M_B_ECC<4>  CB<4> @BASEBOARD_FAB2_LIB.BASEBOARD_FAB2(SCH_1):M_B_ECC(4)
 201 M_B_ECC<3>  CB<3> @BASEBOARD_FAB2_LIB.BASEBOARD_FAB2(SCH_1):M_B_ECC(3)
  56 M_B_ECC<2>  CB<2> @BASEBOARD_FAB2_LIB.BASEBOARD_FAB2(SCH_1):M_B_ECC(2)
 194 M_B_ECC<1>  CB<1> @BASEBOARD_FAB2_LIB.BASEBOARD_FAB2(SCH_1):M_B_ECC(1)
  49 M_B_ECC<0>  CB<0> @BASEBOARD_FAB2_LIB.BASEBOARD_FAB2(SCH_1):M_B_ECC(0)
  75 M_B_CLK_DN<2>   CK0N @BASEBOARD_FAB2_LIB.BASEBOARD_FAB2(SCH_1):M_B_CLK_DN(2)
  74 M_B_CLK_DP<2>   CK0P @BASEBOARD_FAB2_LIB.BASEBOARD_FAB2(SCH_1):M_B_CLK_DP(2)
 219 M_B_CLK_DN<3>   CK1N @BASEBOARD_FAB2_LIB.BASEBOARD_FAB2(SCH_1):M_B_CLK_DN(3)
 218 M_B_CLK_DP<3>   CK1P @BASEBOARD_FAB2_LIB.BASEBOARD_FAB2(SCH_1):M_B_CLK_DP(3)
 203 M_B_CKE<3> CKE<1> @BASEBOARD_FAB2_LIB.BASEBOARD_FAB2(SCH_1):M_B_CKE(3)
  60 M_B_CKE<2> CKE<0> @BASEBOARD_FAB2_LIB.BASEBOARD_FAB2(SCH_1):M_B_CKE(2)
 280 M_B_DQ<63> DQ<63> @BASEBOARD_FAB2_LIB.BASEBOARD_FAB2(SCH_1):M_B_DQ(63)
 135 M_B_DQ<62> DQ<62> @BASEBOARD_FAB2_LIB.BASEBOARD_FAB2(SCH_1):M_B_DQ(62)
 273 M_B_DQ<61> DQ<61> @BASEBOARD_FAB2_LIB.BASEBOARD_FAB2(SCH_1):M_B_DQ(61)
 128 M_B_DQ<60> DQ<60> @BASEBOARD_FAB2_LIB.BASEBOARD_FAB2(SCH_1):M_B_DQ(60)
 282 M_B_DQ<59> DQ<59> @BASEBOARD_FAB2_LIB.BASEBOARD_FAB2(SCH_1):M_B_DQ(59)
 137 M_B_DQ<58> DQ<58> @BASEBOARD_FAB2_LIB.BASEBOARD_FAB2(SCH_1):M_B_DQ(58)
 275 M_B_DQ<57> DQ<57> @BASEBOARD_FAB2_LIB.BASEBOARD_FAB2(SCH_1):M_B_DQ(57)
 130 M_B_DQ<56> DQ<56> @BASEBOARD_FAB2_LIB.BASEBOARD_FAB2(SCH_1):M_B_DQ(56)
 269 M_B_DQ<55> DQ<55> @BASEBOARD_FAB2_LIB.BASEBOARD_FAB2(SCH_1):M_B_DQ(55)
 124 M_B_DQ<54> DQ<54> @BASEBOARD_FAB2_LIB.BASEBOARD_FAB2(SCH_1):M_B_DQ(54)
 262 M_B_DQ<53> DQ<53> @BASEBOARD_FAB2_LIB.BASEBOARD_FAB2(SCH_1):M_B_DQ(53)
 117 M_B_DQ<52> DQ<52> @BASEBOARD_FAB2_LIB.BASEBOARD_FAB2(SCH_1):M_B_DQ(52)
 271 M_B_DQ<51> DQ<51> @BASEBOARD_FAB2_LIB.BASEBOARD_FAB2(SCH_1):M_B_DQ(51)
 126 M_B_DQ<50> DQ<50> @BASEBOARD_FAB2_LIB.BASEBOARD_FAB2(SCH_1):M_B_DQ(50)
 264 M_B_DQ<49> DQ<49> @BASEBOARD_FAB2_LIB.BASEBOARD_FAB2(SCH_1):M_B_DQ(49)
 119 M_B_DQ<48> DQ<48> @BASEBOARD_FAB2_LIB.BASEBOARD_FAB2(SCH_1):M_B_DQ(48)
 258 M_B_DQ<47> DQ<47> @BASEBOARD_FAB2_LIB.BASEBOARD_FAB2(SCH_1):M_B_DQ(47)
 113 M_B_DQ<46> DQ<46> @BASEBOARD_FAB2_LIB.BASEBOARD_FAB2(SCH_1):M_B_DQ(46)
 251 M_B_DQ<45> DQ<45> @BASEBOARD_FAB2_LIB.BASEBOARD_FAB2(SCH_1):M_B_DQ(45)
 106 M_B_DQ<44> DQ<44> @BASEBOARD_FAB2_LIB.BASEBOARD_FAB2(SCH_1):M_B_DQ(44)
 260 M_B_DQ<43> DQ<43> @BASEBOARD_FAB2_LIB.BASEBOARD_FAB2(SCH_1):M_B_DQ(43)
 115 M_B_DQ<42> DQ<42> @BASEBOARD_FAB2_LIB.BASEBOARD_FAB2(SCH_1):M_B_DQ(42)
 253 M_B_DQ<41> DQ<41> @BASEBOARD_FAB2_LIB.BASEBOARD_FAB2(SCH_1):M_B_DQ(41)
 108 M_B_DQ<40> DQ<40> @BASEBOARD_FAB2_LIB.BASEBOARD_FAB2(SCH_1):M_B_DQ(40)
 247 M_B_DQ<39> DQ<39> @BASEBOARD_FAB2_LIB.BASEBOARD_FAB2(SCH_1):M_B_DQ(39)
 102 M_B_DQ<38> DQ<38> @BASEBOARD_FAB2_LIB.BASEBOARD_FAB2(SCH_1):M_B_DQ(38)
 240 M_B_DQ<37> DQ<37> @BASEBOARD_FAB2_LIB.BASEBOARD_FAB2(SCH_1):M_B_DQ(37)
  95 M_B_DQ<36> DQ<36> @BASEBOARD_FAB2_LIB.BASEBOARD_FAB2(SCH_1):M_B_DQ(36)
 249 M_B_DQ<35> DQ<35> @BASEBOARD_FAB2_LIB.BASEBOARD_FAB2(SCH_1):M_B_DQ(35)
 104 M_B_DQ<34> DQ<34> @BASEBOARD_FAB2_LIB.BASEBOARD_FAB2(SCH_1):M_B_DQ(34)
 242 M_B_DQ<33> DQ<33> @BASEBOARD_FAB2_LIB.BASEBOARD_FAB2(SCH_1):M_B_DQ(33)
  97 M_B_DQ<32> DQ<32> @BASEBOARD_FAB2_LIB.BASEBOARD_FAB2(SCH_1):M_B_DQ(32)
 188 M_B_DQ<31> DQ<31> @BASEBOARD_FAB2_LIB.BASEBOARD_FAB2(SCH_1):M_B_DQ(31)
  43 M_B_DQ<30> DQ<30> @BASEBOARD_FAB2_LIB.BASEBOARD_FAB2(SCH_1):M_B_DQ(30)
 181 M_B_DQ<29> DQ<29> @BASEBOARD_FAB2_LIB.BASEBOARD_FAB2(SCH_1):M_B_DQ(29)
  36 M_B_DQ<28> DQ<28> @BASEBOARD_FAB2_LIB.BASEBOARD_FAB2(SCH_1):M_B_DQ(28)
 190 M_B_DQ<27> DQ<27> @BASEBOARD_FAB2_LIB.BASEBOARD_FAB2(SCH_1):M_B_DQ(27)
  45 M_B_DQ<26> DQ<26> @BASEBOARD_FAB2_LIB.BASEBOARD_FAB2(SCH_1):M_B_DQ(26)
 183 M_B_DQ<25> DQ<25> @BASEBOARD_FAB2_LIB.BASEBOARD_FAB2(SCH_1):M_B_DQ(25)
  38 M_B_DQ<24> DQ<24> @BASEBOARD_FAB2_LIB.BASEBOARD_FAB2(SCH_1):M_B_DQ(24)
 177 M_B_DQ<23> DQ<23> @BASEBOARD_FAB2_LIB.BASEBOARD_FAB2(SCH_1):M_B_DQ(23)
  32 M_B_DQ<22> DQ<22> @BASEBOARD_FAB2_LIB.BASEBOARD_FAB2(SCH_1):M_B_DQ(22)
 170 M_B_DQ<21> DQ<21> @BASEBOARD_FAB2_LIB.BASEBOARD_FAB2(SCH_1):M_B_DQ(21)
  25 M_B_DQ<20> DQ<20> @BASEBOARD_FAB2_LIB.BASEBOARD_FAB2(SCH_1):M_B_DQ(20)
 179 M_B_DQ<19> DQ<19> @BASEBOARD_FAB2_LIB.BASEBOARD_FAB2(SCH_1):M_B_DQ(19)
  34 M_B_DQ<18> DQ<18> @BASEBOARD_FAB2_LIB.BASEBOARD_FAB2(SCH_1):M_B_DQ(18)
 172 M_B_DQ<17> DQ<17> @BASEBOARD_FAB2_LIB.BASEBOARD_FAB2(SCH_1):M_B_DQ(17)
  27 M_B_DQ<16> DQ<16> @BASEBOARD_FAB2_LIB.BASEBOARD_FAB2(SCH_1):M_B_DQ(16)
 166 M_B_DQ<15> DQ<15> @BASEBOARD_FAB2_LIB.BASEBOARD_FAB2(SCH_1):M_B_DQ(15)
  21 M_B_DQ<14> DQ<14> @BASEBOARD_FAB2_LIB.BASEBOARD_FAB2(SCH_1):M_B_DQ(14)
 159 M_B_DQ<13> DQ<13> @BASEBOARD_FAB2_LIB.BASEBOARD_FAB2(SCH_1):M_B_DQ(13)
  14 M_B_DQ<12> DQ<12> @BASEBOARD_FAB2_LIB.BASEBOARD_FAB2(SCH_1):M_B_DQ(12)
 168 M_B_DQ<11> DQ<11> @BASEBOARD_FAB2_LIB.BASEBOARD_FAB2(SCH_1):M_B_DQ(11)
  23 M_B_DQ<10> DQ<10> @BASEBOARD_FAB2_LIB.BASEBOARD_FAB2(SCH_1):M_B_DQ(10)
 161 M_B_DQ<9>  DQ<9> @BASEBOARD_FAB2_LIB.BASEBOARD_FAB2(SCH_1):M_B_DQ(9)
  16 M_B_DQ<8>  DQ<8> @BASEBOARD_FAB2_LIB.BASEBOARD_FAB2(SCH_1):M_B_DQ(8)
 155 M_B_DQ<7>  DQ<7> @BASEBOARD_FAB2_LIB.BASEBOARD_FAB2(SCH_1):M_B_DQ(7)
  10 M_B_DQ<6>  DQ<6> @BASEBOARD_FAB2_LIB.BASEBOARD_FAB2(SCH_1):M_B_DQ(6)
 148 M_B_DQ<5>  DQ<5> @BASEBOARD_FAB2_LIB.BASEBOARD_FAB2(SCH_1):M_B_DQ(5)
   3 M_B_DQ<4>  DQ<4> @BASEBOARD_FAB2_LIB.BASEBOARD_FAB2(SCH_1):M_B_DQ(4)
 157 M_B_DQ<3>  DQ<3> @BASEBOARD_FAB2_LIB.BASEBOARD_FAB2(SCH_1):M_B_DQ(3)
  12 M_B_DQ<2>  DQ<2> @BASEBOARD_FAB2_LIB.BASEBOARD_FAB2(SCH_1):M_B_DQ(2)
 150 M_B_DQ<1>  DQ<1> @BASEBOARD_FAB2_LIB.BASEBOARD_FAB2(SCH_1):M_B_DQ(1)
   5 M_B_DQ<0>  DQ<0> @BASEBOARD_FAB2_LIB.BASEBOARD_FAB2(SCH_1):M_B_DQ(0)
  78 FM_DIMM_EVENT_COD_N EVENT_N @BASEBOARD_FAB2_LIB.BASEBOARD_FAB2(SCH_1):FM_DIMM_EVENT_COD_N
  91 M_B_ODT<3> ODT<1> @BASEBOARD_FAB2_LIB.BASEBOARD_FAB2(SCH_1):M_B_ODT(3)
  87 M_B_ODT<2> ODT<0> @BASEBOARD_FAB2_LIB.BASEBOARD_FAB2(SCH_1):M_B_ODT(2)
 222 M_B_PAR    PAR @BASEBOARD_FAB2_LIB.BASEBOARD_FAB2(SCH_1):M_B_PAR
  58 M_ABC_RST_N RESET_N @BASEBOARD_FAB2_LIB.BASEBOARD_FAB2(SCH_1):M_ABC_RST_N
 144 TP_CH_B_DIMM_B1_RFU_2 RFU<2> @BASEBOARD_FAB2_LIB.BASEBOARD_FAB2(SCH_1):TP_CH_B_DIMM_B1_RFU_2
 227 TP_CH_B_DIMM_B1_RFU_1 RFU<1> @BASEBOARD_FAB2_LIB.BASEBOARD_FAB2(SCH_1):TP_CH_B_DIMM_B1_RFU_1
 205 TP_CH_B_DIMM_B1_RFU_0 RFU<0> @BASEBOARD_FAB2_LIB.BASEBOARD_FAB2(SCH_1):TP_CH_B_DIMM_B1_RFU_0
  84 M_B_CS_N<4>   S0_N @BASEBOARD_FAB2_LIB.BASEBOARD_FAB2(SCH_1):M_B_CS_N(4)
  89 M_B_CS_N<5>   S1_N @BASEBOARD_FAB2_LIB.BASEBOARD_FAB2(SCH_1):M_B_CS_N(5)
  93 M_B_CS_N<6> S2_N_C<0> @BASEBOARD_FAB2_LIB.BASEBOARD_FAB2(SCH_1):M_B_CS_N(6)
 237 M_B_CS_N<7> S3_N_C<1> @BASEBOARD_FAB2_LIB.BASEBOARD_FAB2(SCH_1):M_B_CS_N(7)
 238    GND  SA<2> @BASEBOARD_FAB2_LIB.BASEBOARD_FAB2(SCH_1):GND
 140 PVPP_ABC  SA<1> @BASEBOARD_FAB2_LIB.BASEBOARD_FAB2(SCH_1):PVPP_ABC
 139 PVPP_ABC  SA<0> @BASEBOARD_FAB2_LIB.BASEBOARD_FAB2(SCH_1):PVPP_ABC
 230 FM_ADR_COMPLETE_ABC_N SAVE_N_NC @BASEBOARD_FAB2_LIB.BASEBOARD_FAB2(SCH_1):FM_ADR_COMPLETE_ABC_N
 141 SMB_DDR_ABC_VPP_SCL    SCL @BASEBOARD_FAB2_LIB.BASEBOARD_FAB2(SCH_1):SMB_DDR_ABC_VPP_SCL
 285 SMB_DDR_ABC_VPP_SDA    SDA @BASEBOARD_FAB2_LIB.BASEBOARD_FAB2(SCH_1):SMB_DDR_ABC_VPP_SDA
 284 PVPP_ABC VDDSPD @BASEBOARD_FAB2_LIB.BASEBOARD_FAB2(SCH_1):PVPP_ABC
 146 M_B_VREF VREFCA @BASEBOARD_FAB2_LIB.BASEBOARD_FAB2(SCH_1):M_B_VREF

SCONN288_H44441003_PIP-SCONN,HA  I67  J6U1
   1 P12V_NVDIMM_ABC 12V<1> @BASEBOARD_FAB2_LIB.BASEBOARD_FAB2(SCH_1):P12V_NVDIMM_ABC
 145 P12V_NVDIMM_ABC 12V<0> @BASEBOARD_FAB2_LIB.BASEBOARD_FAB2(SCH_1):P12V_NVDIMM_ABC
  59 PVDDQ_ABC VDD<25> @BASEBOARD_FAB2_LIB.BASEBOARD_FAB2(SCH_1):PVDDQ_ABC
  61 PVDDQ_ABC VDD<24> @BASEBOARD_FAB2_LIB.BASEBOARD_FAB2(SCH_1):PVDDQ_ABC
  64 PVDDQ_ABC VDD<23> @BASEBOARD_FAB2_LIB.BASEBOARD_FAB2(SCH_1):PVDDQ_ABC
  67 PVDDQ_ABC VDD<22> @BASEBOARD_FAB2_LIB.BASEBOARD_FAB2(SCH_1):PVDDQ_ABC
  70 PVDDQ_ABC VDD<21> @BASEBOARD_FAB2_LIB.BASEBOARD_FAB2(SCH_1):PVDDQ_ABC
  73 PVDDQ_ABC VDD<20> @BASEBOARD_FAB2_LIB.BASEBOARD_FAB2(SCH_1):PVDDQ_ABC
  76 PVDDQ_ABC VDD<19> @BASEBOARD_FAB2_LIB.BASEBOARD_FAB2(SCH_1):PVDDQ_ABC
  80 PVDDQ_ABC VDD<18> @BASEBOARD_FAB2_LIB.BASEBOARD_FAB2(SCH_1):PVDDQ_ABC
  83 PVDDQ_ABC VDD<17> @BASEBOARD_FAB2_LIB.BASEBOARD_FAB2(SCH_1):PVDDQ_ABC
  85 PVDDQ_ABC VDD<16> @BASEBOARD_FAB2_LIB.BASEBOARD_FAB2(SCH_1):PVDDQ_ABC
  88 PVDDQ_ABC VDD<15> @BASEBOARD_FAB2_LIB.BASEBOARD_FAB2(SCH_1):PVDDQ_ABC
  90 PVDDQ_ABC VDD<14> @BASEBOARD_FAB2_LIB.BASEBOARD_FAB2(SCH_1):PVDDQ_ABC
  92 PVDDQ_ABC VDD<13> @BASEBOARD_FAB2_LIB.BASEBOARD_FAB2(SCH_1):PVDDQ_ABC
 204 PVDDQ_ABC VDD<12> @BASEBOARD_FAB2_LIB.BASEBOARD_FAB2(SCH_1):PVDDQ_ABC
 206 PVDDQ_ABC VDD<11> @BASEBOARD_FAB2_LIB.BASEBOARD_FAB2(SCH_1):PVDDQ_ABC
 209 PVDDQ_ABC VDD<10> @BASEBOARD_FAB2_LIB.BASEBOARD_FAB2(SCH_1):PVDDQ_ABC
 212 PVDDQ_ABC VDD<9> @BASEBOARD_FAB2_LIB.BASEBOARD_FAB2(SCH_1):PVDDQ_ABC
 215 PVDDQ_ABC VDD<8> @BASEBOARD_FAB2_LIB.BASEBOARD_FAB2(SCH_1):PVDDQ_ABC
 217 PVDDQ_ABC VDD<7> @BASEBOARD_FAB2_LIB.BASEBOARD_FAB2(SCH_1):PVDDQ_ABC
 220 PVDDQ_ABC VDD<6> @BASEBOARD_FAB2_LIB.BASEBOARD_FAB2(SCH_1):PVDDQ_ABC
 223 PVDDQ_ABC VDD<5> @BASEBOARD_FAB2_LIB.BASEBOARD_FAB2(SCH_1):PVDDQ_ABC
 226 PVDDQ_ABC VDD<4> @BASEBOARD_FAB2_LIB.BASEBOARD_FAB2(SCH_1):PVDDQ_ABC
 229 PVDDQ_ABC VDD<3> @BASEBOARD_FAB2_LIB.BASEBOARD_FAB2(SCH_1):PVDDQ_ABC
 231 PVDDQ_ABC VDD<2> @BASEBOARD_FAB2_LIB.BASEBOARD_FAB2(SCH_1):PVDDQ_ABC
 233 PVDDQ_ABC VDD<1> @BASEBOARD_FAB2_LIB.BASEBOARD_FAB2(SCH_1):PVDDQ_ABC
 236 PVDDQ_ABC VDD<0> @BASEBOARD_FAB2_LIB.BASEBOARD_FAB2(SCH_1):PVDDQ_ABC
 142 PVPP_ABC VPP<4> @BASEBOARD_FAB2_LIB.BASEBOARD_FAB2(SCH_1):PVPP_ABC
 143 PVPP_ABC VPP<3> @BASEBOARD_FAB2_LIB.BASEBOARD_FAB2(SCH_1):PVPP_ABC
 288 PVPP_ABC VPP<2> @BASEBOARD_FAB2_LIB.BASEBOARD_FAB2(SCH_1):PVPP_ABC
 286 PVPP_ABC VPP<1> @BASEBOARD_FAB2_LIB.BASEBOARD_FAB2(SCH_1):PVPP_ABC
 287 PVPP_ABC VPP<0> @BASEBOARD_FAB2_LIB.BASEBOARD_FAB2(SCH_1):PVPP_ABC
  77 PVTT_ABC VTT<1> @BASEBOARD_FAB2_LIB.BASEBOARD_FAB2(SCH_1):PVTT_ABC
 221 PVTT_ABC VTT<0> @BASEBOARD_FAB2_LIB.BASEBOARD_FAB2(SCH_1):PVTT_ABC

SCONN288_H44441003_PIP-SCONN,HA  I112  J6U1
 152 M_B_DQS_DN<0>  DQS0N @BASEBOARD_FAB2_LIB.BASEBOARD_FAB2(SCH_1):M_B_DQS_DN(0)
 153 M_B_DQS_DP<0>  DQS0P @BASEBOARD_FAB2_LIB.BASEBOARD_FAB2(SCH_1):M_B_DQS_DP(0)
  19 M_B_DQS_DN<10> DQS10N @BASEBOARD_FAB2_LIB.BASEBOARD_FAB2(SCH_1):M_B_DQS_DN(10)
  18 M_B_DQS_DP<10> DQS10P @BASEBOARD_FAB2_LIB.BASEBOARD_FAB2(SCH_1):M_B_DQS_DP(10)
  30 M_B_DQS_DN<11> DQS11N @BASEBOARD_FAB2_LIB.BASEBOARD_FAB2(SCH_1):M_B_DQS_DN(11)
  29 M_B_DQS_DP<11> DQS11P @BASEBOARD_FAB2_LIB.BASEBOARD_FAB2(SCH_1):M_B_DQS_DP(11)
  41 M_B_DQS_DN<12> DQS12N @BASEBOARD_FAB2_LIB.BASEBOARD_FAB2(SCH_1):M_B_DQS_DN(12)
  40 M_B_DQS_DP<12> DQS12P @BASEBOARD_FAB2_LIB.BASEBOARD_FAB2(SCH_1):M_B_DQS_DP(12)
 100 M_B_DQS_DN<13> DQS13N @BASEBOARD_FAB2_LIB.BASEBOARD_FAB2(SCH_1):M_B_DQS_DN(13)
  99 M_B_DQS_DP<13> DQS13P @BASEBOARD_FAB2_LIB.BASEBOARD_FAB2(SCH_1):M_B_DQS_DP(13)
 111 M_B_DQS_DN<14> DQS14N @BASEBOARD_FAB2_LIB.BASEBOARD_FAB2(SCH_1):M_B_DQS_DN(14)
 110 M_B_DQS_DP<14> DQS14P @BASEBOARD_FAB2_LIB.BASEBOARD_FAB2(SCH_1):M_B_DQS_DP(14)
 122 M_B_DQS_DN<15> DQS15N @BASEBOARD_FAB2_LIB.BASEBOARD_FAB2(SCH_1):M_B_DQS_DN(15)
 121 M_B_DQS_DP<15> DQS15P @BASEBOARD_FAB2_LIB.BASEBOARD_FAB2(SCH_1):M_B_DQS_DP(15)
 133 M_B_DQS_DN<16> DQS16N @BASEBOARD_FAB2_LIB.BASEBOARD_FAB2(SCH_1):M_B_DQS_DN(16)
 132 M_B_DQS_DP<16> DQS16P @BASEBOARD_FAB2_LIB.BASEBOARD_FAB2(SCH_1):M_B_DQS_DP(16)
  52 M_B_DQS_DN<17> DQS17N @BASEBOARD_FAB2_LIB.BASEBOARD_FAB2(SCH_1):M_B_DQS_DN(17)
  51 M_B_DQS_DP<17> DQS17P @BASEBOARD_FAB2_LIB.BASEBOARD_FAB2(SCH_1):M_B_DQS_DP(17)
 163 M_B_DQS_DN<1>  DQS1N @BASEBOARD_FAB2_LIB.BASEBOARD_FAB2(SCH_1):M_B_DQS_DN(1)
 164 M_B_DQS_DP<1>  DQS1P @BASEBOARD_FAB2_LIB.BASEBOARD_FAB2(SCH_1):M_B_DQS_DP(1)
 174 M_B_DQS_DN<2>  DQS2N @BASEBOARD_FAB2_LIB.BASEBOARD_FAB2(SCH_1):M_B_DQS_DN(2)
 175 M_B_DQS_DP<2>  DQS2P @BASEBOARD_FAB2_LIB.BASEBOARD_FAB2(SCH_1):M_B_DQS_DP(2)
 185 M_B_DQS_DN<3>  DQS3N @BASEBOARD_FAB2_LIB.BASEBOARD_FAB2(SCH_1):M_B_DQS_DN(3)
 186 M_B_DQS_DP<3>  DQS3P @BASEBOARD_FAB2_LIB.BASEBOARD_FAB2(SCH_1):M_B_DQS_DP(3)
 244 M_B_DQS_DN<4>  DQS4N @BASEBOARD_FAB2_LIB.BASEBOARD_FAB2(SCH_1):M_B_DQS_DN(4)
 245 M_B_DQS_DP<4>  DQS4P @BASEBOARD_FAB2_LIB.BASEBOARD_FAB2(SCH_1):M_B_DQS_DP(4)
 255 M_B_DQS_DN<5>  DQS5N @BASEBOARD_FAB2_LIB.BASEBOARD_FAB2(SCH_1):M_B_DQS_DN(5)
 256 M_B_DQS_DP<5>  DQS5P @BASEBOARD_FAB2_LIB.BASEBOARD_FAB2(SCH_1):M_B_DQS_DP(5)
 266 M_B_DQS_DN<6>  DQS6N @BASEBOARD_FAB2_LIB.BASEBOARD_FAB2(SCH_1):M_B_DQS_DN(6)
 267 M_B_DQS_DP<6>  DQS6P @BASEBOARD_FAB2_LIB.BASEBOARD_FAB2(SCH_1):M_B_DQS_DP(6)
 277 M_B_DQS_DN<7>  DQS7N @BASEBOARD_FAB2_LIB.BASEBOARD_FAB2(SCH_1):M_B_DQS_DN(7)
 278 M_B_DQS_DP<7>  DQS7P @BASEBOARD_FAB2_LIB.BASEBOARD_FAB2(SCH_1):M_B_DQS_DP(7)
 196 M_B_DQS_DN<8>  DQS8N @BASEBOARD_FAB2_LIB.BASEBOARD_FAB2(SCH_1):M_B_DQS_DN(8)
 197 M_B_DQS_DP<8>  DQS8P @BASEBOARD_FAB2_LIB.BASEBOARD_FAB2(SCH_1):M_B_DQS_DP(8)
   8 M_B_DQS_DN<9>  DQS9N @BASEBOARD_FAB2_LIB.BASEBOARD_FAB2(SCH_1):M_B_DQS_DN(9)
   7 M_B_DQS_DP<9>  DQS9P @BASEBOARD_FAB2_LIB.BASEBOARD_FAB2(SCH_1):M_B_DQS_DP(9)

SCONN288_H44441003_PIP-SCONN,HA  I138  J6U1
   2    GND VSS<93> @BASEBOARD_FAB2_LIB.BASEBOARD_FAB2(SCH_1):GND
   4    GND VSS<92> @BASEBOARD_FAB2_LIB.BASEBOARD_FAB2(SCH_1):GND
   6    GND VSS<91> @BASEBOARD_FAB2_LIB.BASEBOARD_FAB2(SCH_1):GND
   9    GND VSS<90> @BASEBOARD_FAB2_LIB.BASEBOARD_FAB2(SCH_1):GND
  11    GND VSS<89> @BASEBOARD_FAB2_LIB.BASEBOARD_FAB2(SCH_1):GND
  13    GND VSS<88> @BASEBOARD_FAB2_LIB.BASEBOARD_FAB2(SCH_1):GND
  15    GND VSS<87> @BASEBOARD_FAB2_LIB.BASEBOARD_FAB2(SCH_1):GND
  17    GND VSS<86> @BASEBOARD_FAB2_LIB.BASEBOARD_FAB2(SCH_1):GND
  20    GND VSS<85> @BASEBOARD_FAB2_LIB.BASEBOARD_FAB2(SCH_1):GND
  22    GND VSS<84> @BASEBOARD_FAB2_LIB.BASEBOARD_FAB2(SCH_1):GND
  24    GND VSS<83> @BASEBOARD_FAB2_LIB.BASEBOARD_FAB2(SCH_1):GND
  26    GND VSS<82> @BASEBOARD_FAB2_LIB.BASEBOARD_FAB2(SCH_1):GND
  28    GND VSS<81> @BASEBOARD_FAB2_LIB.BASEBOARD_FAB2(SCH_1):GND
  31    GND VSS<80> @BASEBOARD_FAB2_LIB.BASEBOARD_FAB2(SCH_1):GND
  33    GND VSS<79> @BASEBOARD_FAB2_LIB.BASEBOARD_FAB2(SCH_1):GND
  35    GND VSS<78> @BASEBOARD_FAB2_LIB.BASEBOARD_FAB2(SCH_1):GND
  37    GND VSS<77> @BASEBOARD_FAB2_LIB.BASEBOARD_FAB2(SCH_1):GND
  39    GND VSS<76> @BASEBOARD_FAB2_LIB.BASEBOARD_FAB2(SCH_1):GND
  42    GND VSS<75> @BASEBOARD_FAB2_LIB.BASEBOARD_FAB2(SCH_1):GND
  44    GND VSS<74> @BASEBOARD_FAB2_LIB.BASEBOARD_FAB2(SCH_1):GND
  46    GND VSS<73> @BASEBOARD_FAB2_LIB.BASEBOARD_FAB2(SCH_1):GND
  48    GND VSS<72> @BASEBOARD_FAB2_LIB.BASEBOARD_FAB2(SCH_1):GND
  50    GND VSS<71> @BASEBOARD_FAB2_LIB.BASEBOARD_FAB2(SCH_1):GND
  53    GND VSS<70> @BASEBOARD_FAB2_LIB.BASEBOARD_FAB2(SCH_1):GND
  55    GND VSS<69> @BASEBOARD_FAB2_LIB.BASEBOARD_FAB2(SCH_1):GND
  57    GND VSS<68> @BASEBOARD_FAB2_LIB.BASEBOARD_FAB2(SCH_1):GND
  94    GND VSS<67> @BASEBOARD_FAB2_LIB.BASEBOARD_FAB2(SCH_1):GND
  96    GND VSS<66> @BASEBOARD_FAB2_LIB.BASEBOARD_FAB2(SCH_1):GND
  98    GND VSS<65> @BASEBOARD_FAB2_LIB.BASEBOARD_FAB2(SCH_1):GND
 101    GND VSS<64> @BASEBOARD_FAB2_LIB.BASEBOARD_FAB2(SCH_1):GND
 103    GND VSS<63> @BASEBOARD_FAB2_LIB.BASEBOARD_FAB2(SCH_1):GND
 105    GND VSS<62> @BASEBOARD_FAB2_LIB.BASEBOARD_FAB2(SCH_1):GND
 107    GND VSS<61> @BASEBOARD_FAB2_LIB.BASEBOARD_FAB2(SCH_1):GND
 109    GND VSS<60> @BASEBOARD_FAB2_LIB.BASEBOARD_FAB2(SCH_1):GND
 112    GND VSS<59> @BASEBOARD_FAB2_LIB.BASEBOARD_FAB2(SCH_1):GND
 114    GND VSS<58> @BASEBOARD_FAB2_LIB.BASEBOARD_FAB2(SCH_1):GND
 116    GND VSS<57> @BASEBOARD_FAB2_LIB.BASEBOARD_FAB2(SCH_1):GND
 118    GND VSS<56> @BASEBOARD_FAB2_LIB.BASEBOARD_FAB2(SCH_1):GND
 120    GND VSS<55> @BASEBOARD_FAB2_LIB.BASEBOARD_FAB2(SCH_1):GND
 123    GND VSS<54> @BASEBOARD_FAB2_LIB.BASEBOARD_FAB2(SCH_1):GND
 125    GND VSS<53> @BASEBOARD_FAB2_LIB.BASEBOARD_FAB2(SCH_1):GND
 127    GND VSS<52> @BASEBOARD_FAB2_LIB.BASEBOARD_FAB2(SCH_1):GND
 129    GND VSS<51> @BASEBOARD_FAB2_LIB.BASEBOARD_FAB2(SCH_1):GND
 131    GND VSS<50> @BASEBOARD_FAB2_LIB.BASEBOARD_FAB2(SCH_1):GND
 134    GND VSS<49> @BASEBOARD_FAB2_LIB.BASEBOARD_FAB2(SCH_1):GND
 136    GND VSS<48> @BASEBOARD_FAB2_LIB.BASEBOARD_FAB2(SCH_1):GND
 138    GND VSS<47> @BASEBOARD_FAB2_LIB.BASEBOARD_FAB2(SCH_1):GND
 147    GND VSS<46> @BASEBOARD_FAB2_LIB.BASEBOARD_FAB2(SCH_1):GND
 149    GND VSS<45> @BASEBOARD_FAB2_LIB.BASEBOARD_FAB2(SCH_1):GND
 151    GND VSS<44> @BASEBOARD_FAB2_LIB.BASEBOARD_FAB2(SCH_1):GND
 154    GND VSS<43> @BASEBOARD_FAB2_LIB.BASEBOARD_FAB2(SCH_1):GND
 156    GND VSS<42> @BASEBOARD_FAB2_LIB.BASEBOARD_FAB2(SCH_1):GND
 158    GND VSS<41> @BASEBOARD_FAB2_LIB.BASEBOARD_FAB2(SCH_1):GND
 160    GND VSS<40> @BASEBOARD_FAB2_LIB.BASEBOARD_FAB2(SCH_1):GND
 162    GND VSS<39> @BASEBOARD_FAB2_LIB.BASEBOARD_FAB2(SCH_1):GND
 165    GND VSS<38> @BASEBOARD_FAB2_LIB.BASEBOARD_FAB2(SCH_1):GND
 167    GND VSS<37> @BASEBOARD_FAB2_LIB.BASEBOARD_FAB2(SCH_1):GND
 169    GND VSS<36> @BASEBOARD_FAB2_LIB.BASEBOARD_FAB2(SCH_1):GND
 171    GND VSS<35> @BASEBOARD_FAB2_LIB.BASEBOARD_FAB2(SCH_1):GND
 173    GND VSS<34> @BASEBOARD_FAB2_LIB.BASEBOARD_FAB2(SCH_1):GND
 176    GND VSS<33> @BASEBOARD_FAB2_LIB.BASEBOARD_FAB2(SCH_1):GND
 178    GND VSS<32> @BASEBOARD_FAB2_LIB.BASEBOARD_FAB2(SCH_1):GND
 180    GND VSS<31> @BASEBOARD_FAB2_LIB.BASEBOARD_FAB2(SCH_1):GND
 182    GND VSS<30> @BASEBOARD_FAB2_LIB.BASEBOARD_FAB2(SCH_1):GND
 184    GND VSS<29> @BASEBOARD_FAB2_LIB.BASEBOARD_FAB2(SCH_1):GND
 187    GND VSS<28> @BASEBOARD_FAB2_LIB.BASEBOARD_FAB2(SCH_1):GND
 189    GND VSS<27> @BASEBOARD_FAB2_LIB.BASEBOARD_FAB2(SCH_1):GND
 191    GND VSS<26> @BASEBOARD_FAB2_LIB.BASEBOARD_FAB2(SCH_1):GND
 193    GND VSS<25> @BASEBOARD_FAB2_LIB.BASEBOARD_FAB2(SCH_1):GND
 195    GND VSS<24> @BASEBOARD_FAB2_LIB.BASEBOARD_FAB2(SCH_1):GND
 198    GND VSS<23> @BASEBOARD_FAB2_LIB.BASEBOARD_FAB2(SCH_1):GND
 200    GND VSS<22> @BASEBOARD_FAB2_LIB.BASEBOARD_FAB2(SCH_1):GND
 202    GND VSS<21> @BASEBOARD_FAB2_LIB.BASEBOARD_FAB2(SCH_1):GND
 239    GND VSS<20> @BASEBOARD_FAB2_LIB.BASEBOARD_FAB2(SCH_1):GND
 241    GND VSS<19> @BASEBOARD_FAB2_LIB.BASEBOARD_FAB2(SCH_1):GND
 243    GND VSS<18> @BASEBOARD_FAB2_LIB.BASEBOARD_FAB2(SCH_1):GND
 246    GND VSS<17> @BASEBOARD_FAB2_LIB.BASEBOARD_FAB2(SCH_1):GND
 248    GND VSS<16> @BASEBOARD_FAB2_LIB.BASEBOARD_FAB2(SCH_1):GND
 250    GND VSS<15> @BASEBOARD_FAB2_LIB.BASEBOARD_FAB2(SCH_1):GND
 252    GND VSS<14> @BASEBOARD_FAB2_LIB.BASEBOARD_FAB2(SCH_1):GND
 254    GND VSS<13> @BASEBOARD_FAB2_LIB.BASEBOARD_FAB2(SCH_1):GND
 257    GND VSS<12> @BASEBOARD_FAB2_LIB.BASEBOARD_FAB2(SCH_1):GND
 259    GND VSS<11> @BASEBOARD_FAB2_LIB.BASEBOARD_FAB2(SCH_1):GND
 261    GND VSS<10> @BASEBOARD_FAB2_LIB.BASEBOARD_FAB2(SCH_1):GND
 263    GND VSS<9> @BASEBOARD_FAB2_LIB.BASEBOARD_FAB2(SCH_1):GND
 265    GND VSS<8> @BASEBOARD_FAB2_LIB.BASEBOARD_FAB2(SCH_1):GND
 268    GND VSS<7> @BASEBOARD_FAB2_LIB.BASEBOARD_FAB2(SCH_1):GND
 270    GND VSS<6> @BASEBOARD_FAB2_LIB.BASEBOARD_FAB2(SCH_1):GND
 272    GND VSS<5> @BASEBOARD_FAB2_LIB.BASEBOARD_FAB2(SCH_1):GND
 274    GND VSS<4> @BASEBOARD_FAB2_LIB.BASEBOARD_FAB2(SCH_1):GND
 276    GND VSS<3> @BASEBOARD_FAB2_LIB.BASEBOARD_FAB2(SCH_1):GND
 279    GND VSS<2> @BASEBOARD_FAB2_LIB.BASEBOARD_FAB2(SCH_1):GND
 281    GND VSS<1> @BASEBOARD_FAB2_LIB.BASEBOARD_FAB2(SCH_1):GND
 283    GND VSS<0> @BASEBOARD_FAB2_LIB.BASEBOARD_FAB2(SCH_1):GND


DRAWING: @BASEBOARD_FAB2_LIB.BASEBOARD_FAB2(SCH_1):PAGE47 

SCONN288_H44441004_PIP-SCONN,HA  I43  J4G3
   2    GND VSS<93> @BASEBOARD_FAB2_LIB.BASEBOARD_FAB2(SCH_1):GND
   4    GND VSS<92> @BASEBOARD_FAB2_LIB.BASEBOARD_FAB2(SCH_1):GND
   6    GND VSS<91> @BASEBOARD_FAB2_LIB.BASEBOARD_FAB2(SCH_1):GND
   9    GND VSS<90> @BASEBOARD_FAB2_LIB.BASEBOARD_FAB2(SCH_1):GND
  11    GND VSS<89> @BASEBOARD_FAB2_LIB.BASEBOARD_FAB2(SCH_1):GND
  13    GND VSS<88> @BASEBOARD_FAB2_LIB.BASEBOARD_FAB2(SCH_1):GND
  15    GND VSS<87> @BASEBOARD_FAB2_LIB.BASEBOARD_FAB2(SCH_1):GND
  17    GND VSS<86> @BASEBOARD_FAB2_LIB.BASEBOARD_FAB2(SCH_1):GND
  20    GND VSS<85> @BASEBOARD_FAB2_LIB.BASEBOARD_FAB2(SCH_1):GND
  22    GND VSS<84> @BASEBOARD_FAB2_LIB.BASEBOARD_FAB2(SCH_1):GND
  24    GND VSS<83> @BASEBOARD_FAB2_LIB.BASEBOARD_FAB2(SCH_1):GND
  26    GND VSS<82> @BASEBOARD_FAB2_LIB.BASEBOARD_FAB2(SCH_1):GND
  28    GND VSS<81> @BASEBOARD_FAB2_LIB.BASEBOARD_FAB2(SCH_1):GND
  31    GND VSS<80> @BASEBOARD_FAB2_LIB.BASEBOARD_FAB2(SCH_1):GND
  33    GND VSS<79> @BASEBOARD_FAB2_LIB.BASEBOARD_FAB2(SCH_1):GND
  35    GND VSS<78> @BASEBOARD_FAB2_LIB.BASEBOARD_FAB2(SCH_1):GND
  37    GND VSS<77> @BASEBOARD_FAB2_LIB.BASEBOARD_FAB2(SCH_1):GND
  39    GND VSS<76> @BASEBOARD_FAB2_LIB.BASEBOARD_FAB2(SCH_1):GND
  42    GND VSS<75> @BASEBOARD_FAB2_LIB.BASEBOARD_FAB2(SCH_1):GND
  44    GND VSS<74> @BASEBOARD_FAB2_LIB.BASEBOARD_FAB2(SCH_1):GND
  46    GND VSS<73> @BASEBOARD_FAB2_LIB.BASEBOARD_FAB2(SCH_1):GND
  48    GND VSS<72> @BASEBOARD_FAB2_LIB.BASEBOARD_FAB2(SCH_1):GND
  50    GND VSS<71> @BASEBOARD_FAB2_LIB.BASEBOARD_FAB2(SCH_1):GND
  53    GND VSS<70> @BASEBOARD_FAB2_LIB.BASEBOARD_FAB2(SCH_1):GND
  55    GND VSS<69> @BASEBOARD_FAB2_LIB.BASEBOARD_FAB2(SCH_1):GND
  57    GND VSS<68> @BASEBOARD_FAB2_LIB.BASEBOARD_FAB2(SCH_1):GND
  94    GND VSS<67> @BASEBOARD_FAB2_LIB.BASEBOARD_FAB2(SCH_1):GND
  96    GND VSS<66> @BASEBOARD_FAB2_LIB.BASEBOARD_FAB2(SCH_1):GND
  98    GND VSS<65> @BASEBOARD_FAB2_LIB.BASEBOARD_FAB2(SCH_1):GND
 101    GND VSS<64> @BASEBOARD_FAB2_LIB.BASEBOARD_FAB2(SCH_1):GND
 103    GND VSS<63> @BASEBOARD_FAB2_LIB.BASEBOARD_FAB2(SCH_1):GND
 105    GND VSS<62> @BASEBOARD_FAB2_LIB.BASEBOARD_FAB2(SCH_1):GND
 107    GND VSS<61> @BASEBOARD_FAB2_LIB.BASEBOARD_FAB2(SCH_1):GND
 109    GND VSS<60> @BASEBOARD_FAB2_LIB.BASEBOARD_FAB2(SCH_1):GND
 112    GND VSS<59> @BASEBOARD_FAB2_LIB.BASEBOARD_FAB2(SCH_1):GND
 114    GND VSS<58> @BASEBOARD_FAB2_LIB.BASEBOARD_FAB2(SCH_1):GND
 116    GND VSS<57> @BASEBOARD_FAB2_LIB.BASEBOARD_FAB2(SCH_1):GND
 118    GND VSS<56> @BASEBOARD_FAB2_LIB.BASEBOARD_FAB2(SCH_1):GND
 120    GND VSS<55> @BASEBOARD_FAB2_LIB.BASEBOARD_FAB2(SCH_1):GND
 123    GND VSS<54> @BASEBOARD_FAB2_LIB.BASEBOARD_FAB2(SCH_1):GND
 125    GND VSS<53> @BASEBOARD_FAB2_LIB.BASEBOARD_FAB2(SCH_1):GND
 127    GND VSS<52> @BASEBOARD_FAB2_LIB.BASEBOARD_FAB2(SCH_1):GND
 129    GND VSS<51> @BASEBOARD_FAB2_LIB.BASEBOARD_FAB2(SCH_1):GND
 131    GND VSS<50> @BASEBOARD_FAB2_LIB.BASEBOARD_FAB2(SCH_1):GND
 134    GND VSS<49> @BASEBOARD_FAB2_LIB.BASEBOARD_FAB2(SCH_1):GND
 136    GND VSS<48> @BASEBOARD_FAB2_LIB.BASEBOARD_FAB2(SCH_1):GND
 138    GND VSS<47> @BASEBOARD_FAB2_LIB.BASEBOARD_FAB2(SCH_1):GND
 147    GND VSS<46> @BASEBOARD_FAB2_LIB.BASEBOARD_FAB2(SCH_1):GND
 149    GND VSS<45> @BASEBOARD_FAB2_LIB.BASEBOARD_FAB2(SCH_1):GND
 151    GND VSS<44> @BASEBOARD_FAB2_LIB.BASEBOARD_FAB2(SCH_1):GND
 154    GND VSS<43> @BASEBOARD_FAB2_LIB.BASEBOARD_FAB2(SCH_1):GND
 156    GND VSS<42> @BASEBOARD_FAB2_LIB.BASEBOARD_FAB2(SCH_1):GND
 158    GND VSS<41> @BASEBOARD_FAB2_LIB.BASEBOARD_FAB2(SCH_1):GND
 160    GND VSS<40> @BASEBOARD_FAB2_LIB.BASEBOARD_FAB2(SCH_1):GND
 162    GND VSS<39> @BASEBOARD_FAB2_LIB.BASEBOARD_FAB2(SCH_1):GND
 165    GND VSS<38> @BASEBOARD_FAB2_LIB.BASEBOARD_FAB2(SCH_1):GND
 167    GND VSS<37> @BASEBOARD_FAB2_LIB.BASEBOARD_FAB2(SCH_1):GND
 169    GND VSS<36> @BASEBOARD_FAB2_LIB.BASEBOARD_FAB2(SCH_1):GND
 171    GND VSS<35> @BASEBOARD_FAB2_LIB.BASEBOARD_FAB2(SCH_1):GND
 173    GND VSS<34> @BASEBOARD_FAB2_LIB.BASEBOARD_FAB2(SCH_1):GND
 176    GND VSS<33> @BASEBOARD_FAB2_LIB.BASEBOARD_FAB2(SCH_1):GND
 178    GND VSS<32> @BASEBOARD_FAB2_LIB.BASEBOARD_FAB2(SCH_1):GND
 180    GND VSS<31> @BASEBOARD_FAB2_LIB.BASEBOARD_FAB2(SCH_1):GND
 182    GND VSS<30> @BASEBOARD_FAB2_LIB.BASEBOARD_FAB2(SCH_1):GND
 184    GND VSS<29> @BASEBOARD_FAB2_LIB.BASEBOARD_FAB2(SCH_1):GND
 187    GND VSS<28> @BASEBOARD_FAB2_LIB.BASEBOARD_FAB2(SCH_1):GND
 189    GND VSS<27> @BASEBOARD_FAB2_LIB.BASEBOARD_FAB2(SCH_1):GND
 191    GND VSS<26> @BASEBOARD_FAB2_LIB.BASEBOARD_FAB2(SCH_1):GND
 193    GND VSS<25> @BASEBOARD_FAB2_LIB.BASEBOARD_FAB2(SCH_1):GND
 195    GND VSS<24> @BASEBOARD_FAB2_LIB.BASEBOARD_FAB2(SCH_1):GND
 198    GND VSS<23> @BASEBOARD_FAB2_LIB.BASEBOARD_FAB2(SCH_1):GND
 200    GND VSS<22> @BASEBOARD_FAB2_LIB.BASEBOARD_FAB2(SCH_1):GND
 202    GND VSS<21> @BASEBOARD_FAB2_LIB.BASEBOARD_FAB2(SCH_1):GND
 239    GND VSS<20> @BASEBOARD_FAB2_LIB.BASEBOARD_FAB2(SCH_1):GND
 241    GND VSS<19> @BASEBOARD_FAB2_LIB.BASEBOARD_FAB2(SCH_1):GND
 243    GND VSS<18> @BASEBOARD_FAB2_LIB.BASEBOARD_FAB2(SCH_1):GND
 246    GND VSS<17> @BASEBOARD_FAB2_LIB.BASEBOARD_FAB2(SCH_1):GND
 248    GND VSS<16> @BASEBOARD_FAB2_LIB.BASEBOARD_FAB2(SCH_1):GND
 250    GND VSS<15> @BASEBOARD_FAB2_LIB.BASEBOARD_FAB2(SCH_1):GND
 252    GND VSS<14> @BASEBOARD_FAB2_LIB.BASEBOARD_FAB2(SCH_1):GND
 254    GND VSS<13> @BASEBOARD_FAB2_LIB.BASEBOARD_FAB2(SCH_1):GND
 257    GND VSS<12> @BASEBOARD_FAB2_LIB.BASEBOARD_FAB2(SCH_1):GND
 259    GND VSS<11> @BASEBOARD_FAB2_LIB.BASEBOARD_FAB2(SCH_1):GND
 261    GND VSS<10> @BASEBOARD_FAB2_LIB.BASEBOARD_FAB2(SCH_1):GND
 263    GND VSS<9> @BASEBOARD_FAB2_LIB.BASEBOARD_FAB2(SCH_1):GND
 265    GND VSS<8> @BASEBOARD_FAB2_LIB.BASEBOARD_FAB2(SCH_1):GND
 268    GND VSS<7> @BASEBOARD_FAB2_LIB.BASEBOARD_FAB2(SCH_1):GND
 270    GND VSS<6> @BASEBOARD_FAB2_LIB.BASEBOARD_FAB2(SCH_1):GND
 272    GND VSS<5> @BASEBOARD_FAB2_LIB.BASEBOARD_FAB2(SCH_1):GND
 274    GND VSS<4> @BASEBOARD_FAB2_LIB.BASEBOARD_FAB2(SCH_1):GND
 276    GND VSS<3> @BASEBOARD_FAB2_LIB.BASEBOARD_FAB2(SCH_1):GND
 279    GND VSS<2> @BASEBOARD_FAB2_LIB.BASEBOARD_FAB2(SCH_1):GND
 281    GND VSS<1> @BASEBOARD_FAB2_LIB.BASEBOARD_FAB2(SCH_1):GND
 283    GND VSS<0> @BASEBOARD_FAB2_LIB.BASEBOARD_FAB2(SCH_1):GND

SCONN288_H44441004_PIP-SCONN,HA  I61  J4G3
 152 M_C_DQS_DN<0>  DQS0N @BASEBOARD_FAB2_LIB.BASEBOARD_FAB2(SCH_1):M_C_DQS_DN(0)
 153 M_C_DQS_DP<0>  DQS0P @BASEBOARD_FAB2_LIB.BASEBOARD_FAB2(SCH_1):M_C_DQS_DP(0)
  19 M_C_DQS_DN<10> DQS10N @BASEBOARD_FAB2_LIB.BASEBOARD_FAB2(SCH_1):M_C_DQS_DN(10)
  18 M_C_DQS_DP<10> DQS10P @BASEBOARD_FAB2_LIB.BASEBOARD_FAB2(SCH_1):M_C_DQS_DP(10)
  30 M_C_DQS_DN<11> DQS11N @BASEBOARD_FAB2_LIB.BASEBOARD_FAB2(SCH_1):M_C_DQS_DN(11)
  29 M_C_DQS_DP<11> DQS11P @BASEBOARD_FAB2_LIB.BASEBOARD_FAB2(SCH_1):M_C_DQS_DP(11)
  41 M_C_DQS_DN<12> DQS12N @BASEBOARD_FAB2_LIB.BASEBOARD_FAB2(SCH_1):M_C_DQS_DN(12)
  40 M_C_DQS_DP<12> DQS12P @BASEBOARD_FAB2_LIB.BASEBOARD_FAB2(SCH_1):M_C_DQS_DP(12)
 100 M_C_DQS_DN<13> DQS13N @BASEBOARD_FAB2_LIB.BASEBOARD_FAB2(SCH_1):M_C_DQS_DN(13)
  99 M_C_DQS_DP<13> DQS13P @BASEBOARD_FAB2_LIB.BASEBOARD_FAB2(SCH_1):M_C_DQS_DP(13)
 111 M_C_DQS_DN<14> DQS14N @BASEBOARD_FAB2_LIB.BASEBOARD_FAB2(SCH_1):M_C_DQS_DN(14)
 110 M_C_DQS_DP<14> DQS14P @BASEBOARD_FAB2_LIB.BASEBOARD_FAB2(SCH_1):M_C_DQS_DP(14)
 122 M_C_DQS_DN<15> DQS15N @BASEBOARD_FAB2_LIB.BASEBOARD_FAB2(SCH_1):M_C_DQS_DN(15)
 121 M_C_DQS_DP<15> DQS15P @BASEBOARD_FAB2_LIB.BASEBOARD_FAB2(SCH_1):M_C_DQS_DP(15)
 133 M_C_DQS_DN<16> DQS16N @BASEBOARD_FAB2_LIB.BASEBOARD_FAB2(SCH_1):M_C_DQS_DN(16)
 132 M_C_DQS_DP<16> DQS16P @BASEBOARD_FAB2_LIB.BASEBOARD_FAB2(SCH_1):M_C_DQS_DP(16)
  52 M_C_DQS_DN<17> DQS17N @BASEBOARD_FAB2_LIB.BASEBOARD_FAB2(SCH_1):M_C_DQS_DN(17)
  51 M_C_DQS_DP<17> DQS17P @BASEBOARD_FAB2_LIB.BASEBOARD_FAB2(SCH_1):M_C_DQS_DP(17)
 163 M_C_DQS_DN<1>  DQS1N @BASEBOARD_FAB2_LIB.BASEBOARD_FAB2(SCH_1):M_C_DQS_DN(1)
 164 M_C_DQS_DP<1>  DQS1P @BASEBOARD_FAB2_LIB.BASEBOARD_FAB2(SCH_1):M_C_DQS_DP(1)
 174 M_C_DQS_DN<2>  DQS2N @BASEBOARD_FAB2_LIB.BASEBOARD_FAB2(SCH_1):M_C_DQS_DN(2)
 175 M_C_DQS_DP<2>  DQS2P @BASEBOARD_FAB2_LIB.BASEBOARD_FAB2(SCH_1):M_C_DQS_DP(2)
 185 M_C_DQS_DN<3>  DQS3N @BASEBOARD_FAB2_LIB.BASEBOARD_FAB2(SCH_1):M_C_DQS_DN(3)
 186 M_C_DQS_DP<3>  DQS3P @BASEBOARD_FAB2_LIB.BASEBOARD_FAB2(SCH_1):M_C_DQS_DP(3)
 244 M_C_DQS_DN<4>  DQS4N @BASEBOARD_FAB2_LIB.BASEBOARD_FAB2(SCH_1):M_C_DQS_DN(4)
 245 M_C_DQS_DP<4>  DQS4P @BASEBOARD_FAB2_LIB.BASEBOARD_FAB2(SCH_1):M_C_DQS_DP(4)
 255 M_C_DQS_DN<5>  DQS5N @BASEBOARD_FAB2_LIB.BASEBOARD_FAB2(SCH_1):M_C_DQS_DN(5)
 256 M_C_DQS_DP<5>  DQS5P @BASEBOARD_FAB2_LIB.BASEBOARD_FAB2(SCH_1):M_C_DQS_DP(5)
 266 M_C_DQS_DN<6>  DQS6N @BASEBOARD_FAB2_LIB.BASEBOARD_FAB2(SCH_1):M_C_DQS_DN(6)
 267 M_C_DQS_DP<6>  DQS6P @BASEBOARD_FAB2_LIB.BASEBOARD_FAB2(SCH_1):M_C_DQS_DP(6)
 277 M_C_DQS_DN<7>  DQS7N @BASEBOARD_FAB2_LIB.BASEBOARD_FAB2(SCH_1):M_C_DQS_DN(7)
 278 M_C_DQS_DP<7>  DQS7P @BASEBOARD_FAB2_LIB.BASEBOARD_FAB2(SCH_1):M_C_DQS_DP(7)
 196 M_C_DQS_DN<8>  DQS8N @BASEBOARD_FAB2_LIB.BASEBOARD_FAB2(SCH_1):M_C_DQS_DN(8)
 197 M_C_DQS_DP<8>  DQS8P @BASEBOARD_FAB2_LIB.BASEBOARD_FAB2(SCH_1):M_C_DQS_DP(8)
   8 M_C_DQS_DN<9>  DQS9N @BASEBOARD_FAB2_LIB.BASEBOARD_FAB2(SCH_1):M_C_DQS_DN(9)
   7 M_C_DQS_DP<9>  DQS9P @BASEBOARD_FAB2_LIB.BASEBOARD_FAB2(SCH_1):M_C_DQS_DP(9)

SCONN288_H44441004_PIP-SCONN,HA  I111  J4G3
  79 M_C_MA<0>     A0 @BASEBOARD_FAB2_LIB.BASEBOARD_FAB2(SCH_1):M_C_MA(0)
  72 M_C_MA<1>     A1 @BASEBOARD_FAB2_LIB.BASEBOARD_FAB2(SCH_1):M_C_MA(1)
 225 M_C_MA<10>    A10 @BASEBOARD_FAB2_LIB.BASEBOARD_FAB2(SCH_1):M_C_MA(10)
 210 M_C_MA<11>    A11 @BASEBOARD_FAB2_LIB.BASEBOARD_FAB2(SCH_1):M_C_MA(11)
  65 M_C_MA<12>    A12 @BASEBOARD_FAB2_LIB.BASEBOARD_FAB2(SCH_1):M_C_MA(12)
 232 M_C_MA<13>    A13 @BASEBOARD_FAB2_LIB.BASEBOARD_FAB2(SCH_1):M_C_MA(13)
 228 M_C_MA<14> A14_WE_N @BASEBOARD_FAB2_LIB.BASEBOARD_FAB2(SCH_1):M_C_MA(14)
  86 M_C_MA<15> A15_CAS_N @BASEBOARD_FAB2_LIB.BASEBOARD_FAB2(SCH_1):M_C_MA(15)
  82 M_C_MA<16> A16_RAS_N @BASEBOARD_FAB2_LIB.BASEBOARD_FAB2(SCH_1):M_C_MA(16)
 234 M_C_MA<17>    A17 @BASEBOARD_FAB2_LIB.BASEBOARD_FAB2(SCH_1):M_C_MA(17)
 216 M_C_MA<2>     A2 @BASEBOARD_FAB2_LIB.BASEBOARD_FAB2(SCH_1):M_C_MA(2)
  71 M_C_MA<3>     A3 @BASEBOARD_FAB2_LIB.BASEBOARD_FAB2(SCH_1):M_C_MA(3)
 214 M_C_MA<4>     A4 @BASEBOARD_FAB2_LIB.BASEBOARD_FAB2(SCH_1):M_C_MA(4)
 213 M_C_MA<5>     A5 @BASEBOARD_FAB2_LIB.BASEBOARD_FAB2(SCH_1):M_C_MA(5)
  69 M_C_MA<6>     A6 @BASEBOARD_FAB2_LIB.BASEBOARD_FAB2(SCH_1):M_C_MA(6)
 211 M_C_MA<7>     A7 @BASEBOARD_FAB2_LIB.BASEBOARD_FAB2(SCH_1):M_C_MA(7)
  68 M_C_MA<8>     A8 @BASEBOARD_FAB2_LIB.BASEBOARD_FAB2(SCH_1):M_C_MA(8)
  66 M_C_MA<9>     A9 @BASEBOARD_FAB2_LIB.BASEBOARD_FAB2(SCH_1):M_C_MA(9)
  62 M_C_ACT_N  ACT_N @BASEBOARD_FAB2_LIB.BASEBOARD_FAB2(SCH_1):M_C_ACT_N
 208 M_C_ALERT_N ALERT_N @BASEBOARD_FAB2_LIB.BASEBOARD_FAB2(SCH_1):M_C_ALERT_N
 224 M_C_BA<1>  BA<1> @BASEBOARD_FAB2_LIB.BASEBOARD_FAB2(SCH_1):M_C_BA(1)
  81 M_C_BA<0>  BA<0> @BASEBOARD_FAB2_LIB.BASEBOARD_FAB2(SCH_1):M_C_BA(0)
 207 M_C_BG<1>  BG<1> @BASEBOARD_FAB2_LIB.BASEBOARD_FAB2(SCH_1):M_C_BG(1)
  63 M_C_BG<0>  BG<0> @BASEBOARD_FAB2_LIB.BASEBOARD_FAB2(SCH_1):M_C_BG(0)
 235 M_C_C<2>   C<2> @BASEBOARD_FAB2_LIB.BASEBOARD_FAB2(SCH_1):M_C_C(2)
 199 M_C_ECC<6>  CB<7> @BASEBOARD_FAB2_LIB.BASEBOARD_FAB2(SCH_1):M_C_ECC(6)
  54 M_C_ECC<7>  CB<6> @BASEBOARD_FAB2_LIB.BASEBOARD_FAB2(SCH_1):M_C_ECC(7)
 192 M_C_ECC<4>  CB<5> @BASEBOARD_FAB2_LIB.BASEBOARD_FAB2(SCH_1):M_C_ECC(4)
  47 M_C_ECC<5>  CB<4> @BASEBOARD_FAB2_LIB.BASEBOARD_FAB2(SCH_1):M_C_ECC(5)
 201 M_C_ECC<2>  CB<3> @BASEBOARD_FAB2_LIB.BASEBOARD_FAB2(SCH_1):M_C_ECC(2)
  56 M_C_ECC<3>  CB<2> @BASEBOARD_FAB2_LIB.BASEBOARD_FAB2(SCH_1):M_C_ECC(3)
 194 M_C_ECC<0>  CB<1> @BASEBOARD_FAB2_LIB.BASEBOARD_FAB2(SCH_1):M_C_ECC(0)
  49 M_C_ECC<1>  CB<0> @BASEBOARD_FAB2_LIB.BASEBOARD_FAB2(SCH_1):M_C_ECC(1)
  75 M_C_CLK_DN<0>   CK0N @BASEBOARD_FAB2_LIB.BASEBOARD_FAB2(SCH_1):M_C_CLK_DN(0)
  74 M_C_CLK_DP<0>   CK0P @BASEBOARD_FAB2_LIB.BASEBOARD_FAB2(SCH_1):M_C_CLK_DP(0)
 219 M_C_CLK_DN<1>   CK1N @BASEBOARD_FAB2_LIB.BASEBOARD_FAB2(SCH_1):M_C_CLK_DN(1)
 218 M_C_CLK_DP<1>   CK1P @BASEBOARD_FAB2_LIB.BASEBOARD_FAB2(SCH_1):M_C_CLK_DP(1)
 203 M_C_CKE<1> CKE<1> @BASEBOARD_FAB2_LIB.BASEBOARD_FAB2(SCH_1):M_C_CKE(1)
  60 M_C_CKE<0> CKE<0> @BASEBOARD_FAB2_LIB.BASEBOARD_FAB2(SCH_1):M_C_CKE(0)
 280 M_C_DQ<62> DQ<63> @BASEBOARD_FAB2_LIB.BASEBOARD_FAB2(SCH_1):M_C_DQ(62)
 135 M_C_DQ<63> DQ<62> @BASEBOARD_FAB2_LIB.BASEBOARD_FAB2(SCH_1):M_C_DQ(63)
 273 M_C_DQ<60> DQ<61> @BASEBOARD_FAB2_LIB.BASEBOARD_FAB2(SCH_1):M_C_DQ(60)
 128 M_C_DQ<61> DQ<60> @BASEBOARD_FAB2_LIB.BASEBOARD_FAB2(SCH_1):M_C_DQ(61)
 282 M_C_DQ<58> DQ<59> @BASEBOARD_FAB2_LIB.BASEBOARD_FAB2(SCH_1):M_C_DQ(58)
 137 M_C_DQ<59> DQ<58> @BASEBOARD_FAB2_LIB.BASEBOARD_FAB2(SCH_1):M_C_DQ(59)
 275 M_C_DQ<56> DQ<57> @BASEBOARD_FAB2_LIB.BASEBOARD_FAB2(SCH_1):M_C_DQ(56)
 130 M_C_DQ<57> DQ<56> @BASEBOARD_FAB2_LIB.BASEBOARD_FAB2(SCH_1):M_C_DQ(57)
 269 M_C_DQ<54> DQ<55> @BASEBOARD_FAB2_LIB.BASEBOARD_FAB2(SCH_1):M_C_DQ(54)
 124 M_C_DQ<55> DQ<54> @BASEBOARD_FAB2_LIB.BASEBOARD_FAB2(SCH_1):M_C_DQ(55)
 262 M_C_DQ<52> DQ<53> @BASEBOARD_FAB2_LIB.BASEBOARD_FAB2(SCH_1):M_C_DQ(52)
 117 M_C_DQ<53> DQ<52> @BASEBOARD_FAB2_LIB.BASEBOARD_FAB2(SCH_1):M_C_DQ(53)
 271 M_C_DQ<50> DQ<51> @BASEBOARD_FAB2_LIB.BASEBOARD_FAB2(SCH_1):M_C_DQ(50)
 126 M_C_DQ<51> DQ<50> @BASEBOARD_FAB2_LIB.BASEBOARD_FAB2(SCH_1):M_C_DQ(51)
 264 M_C_DQ<48> DQ<49> @BASEBOARD_FAB2_LIB.BASEBOARD_FAB2(SCH_1):M_C_DQ(48)
 119 M_C_DQ<49> DQ<48> @BASEBOARD_FAB2_LIB.BASEBOARD_FAB2(SCH_1):M_C_DQ(49)
 258 M_C_DQ<46> DQ<47> @BASEBOARD_FAB2_LIB.BASEBOARD_FAB2(SCH_1):M_C_DQ(46)
 113 M_C_DQ<47> DQ<46> @BASEBOARD_FAB2_LIB.BASEBOARD_FAB2(SCH_1):M_C_DQ(47)
 251 M_C_DQ<44> DQ<45> @BASEBOARD_FAB2_LIB.BASEBOARD_FAB2(SCH_1):M_C_DQ(44)
 106 M_C_DQ<45> DQ<44> @BASEBOARD_FAB2_LIB.BASEBOARD_FAB2(SCH_1):M_C_DQ(45)
 260 M_C_DQ<42> DQ<43> @BASEBOARD_FAB2_LIB.BASEBOARD_FAB2(SCH_1):M_C_DQ(42)
 115 M_C_DQ<43> DQ<42> @BASEBOARD_FAB2_LIB.BASEBOARD_FAB2(SCH_1):M_C_DQ(43)
 253 M_C_DQ<40> DQ<41> @BASEBOARD_FAB2_LIB.BASEBOARD_FAB2(SCH_1):M_C_DQ(40)
 108 M_C_DQ<41> DQ<40> @BASEBOARD_FAB2_LIB.BASEBOARD_FAB2(SCH_1):M_C_DQ(41)
 247 M_C_DQ<38> DQ<39> @BASEBOARD_FAB2_LIB.BASEBOARD_FAB2(SCH_1):M_C_DQ(38)
 102 M_C_DQ<39> DQ<38> @BASEBOARD_FAB2_LIB.BASEBOARD_FAB2(SCH_1):M_C_DQ(39)
 240 M_C_DQ<36> DQ<37> @BASEBOARD_FAB2_LIB.BASEBOARD_FAB2(SCH_1):M_C_DQ(36)
  95 M_C_DQ<37> DQ<36> @BASEBOARD_FAB2_LIB.BASEBOARD_FAB2(SCH_1):M_C_DQ(37)
 249 M_C_DQ<34> DQ<35> @BASEBOARD_FAB2_LIB.BASEBOARD_FAB2(SCH_1):M_C_DQ(34)
 104 M_C_DQ<35> DQ<34> @BASEBOARD_FAB2_LIB.BASEBOARD_FAB2(SCH_1):M_C_DQ(35)
 242 M_C_DQ<32> DQ<33> @BASEBOARD_FAB2_LIB.BASEBOARD_FAB2(SCH_1):M_C_DQ(32)
  97 M_C_DQ<33> DQ<32> @BASEBOARD_FAB2_LIB.BASEBOARD_FAB2(SCH_1):M_C_DQ(33)
 188 M_C_DQ<30> DQ<31> @BASEBOARD_FAB2_LIB.BASEBOARD_FAB2(SCH_1):M_C_DQ(30)
  43 M_C_DQ<31> DQ<30> @BASEBOARD_FAB2_LIB.BASEBOARD_FAB2(SCH_1):M_C_DQ(31)
 181 M_C_DQ<28> DQ<29> @BASEBOARD_FAB2_LIB.BASEBOARD_FAB2(SCH_1):M_C_DQ(28)
  36 M_C_DQ<29> DQ<28> @BASEBOARD_FAB2_LIB.BASEBOARD_FAB2(SCH_1):M_C_DQ(29)
 190 M_C_DQ<26> DQ<27> @BASEBOARD_FAB2_LIB.BASEBOARD_FAB2(SCH_1):M_C_DQ(26)
  45 M_C_DQ<27> DQ<26> @BASEBOARD_FAB2_LIB.BASEBOARD_FAB2(SCH_1):M_C_DQ(27)
 183 M_C_DQ<24> DQ<25> @BASEBOARD_FAB2_LIB.BASEBOARD_FAB2(SCH_1):M_C_DQ(24)
  38 M_C_DQ<25> DQ<24> @BASEBOARD_FAB2_LIB.BASEBOARD_FAB2(SCH_1):M_C_DQ(25)
 177 M_C_DQ<22> DQ<23> @BASEBOARD_FAB2_LIB.BASEBOARD_FAB2(SCH_1):M_C_DQ(22)
  32 M_C_DQ<23> DQ<22> @BASEBOARD_FAB2_LIB.BASEBOARD_FAB2(SCH_1):M_C_DQ(23)
 170 M_C_DQ<20> DQ<21> @BASEBOARD_FAB2_LIB.BASEBOARD_FAB2(SCH_1):M_C_DQ(20)
  25 M_C_DQ<21> DQ<20> @BASEBOARD_FAB2_LIB.BASEBOARD_FAB2(SCH_1):M_C_DQ(21)
 179 M_C_DQ<18> DQ<19> @BASEBOARD_FAB2_LIB.BASEBOARD_FAB2(SCH_1):M_C_DQ(18)
  34 M_C_DQ<19> DQ<18> @BASEBOARD_FAB2_LIB.BASEBOARD_FAB2(SCH_1):M_C_DQ(19)
 172 M_C_DQ<16> DQ<17> @BASEBOARD_FAB2_LIB.BASEBOARD_FAB2(SCH_1):M_C_DQ(16)
  27 M_C_DQ<17> DQ<16> @BASEBOARD_FAB2_LIB.BASEBOARD_FAB2(SCH_1):M_C_DQ(17)
 166 M_C_DQ<14> DQ<15> @BASEBOARD_FAB2_LIB.BASEBOARD_FAB2(SCH_1):M_C_DQ(14)
  21 M_C_DQ<15> DQ<14> @BASEBOARD_FAB2_LIB.BASEBOARD_FAB2(SCH_1):M_C_DQ(15)
 159 M_C_DQ<12> DQ<13> @BASEBOARD_FAB2_LIB.BASEBOARD_FAB2(SCH_1):M_C_DQ(12)
  14 M_C_DQ<13> DQ<12> @BASEBOARD_FAB2_LIB.BASEBOARD_FAB2(SCH_1):M_C_DQ(13)
 168 M_C_DQ<10> DQ<11> @BASEBOARD_FAB2_LIB.BASEBOARD_FAB2(SCH_1):M_C_DQ(10)
  23 M_C_DQ<11> DQ<10> @BASEBOARD_FAB2_LIB.BASEBOARD_FAB2(SCH_1):M_C_DQ(11)
 161 M_C_DQ<8>  DQ<9> @BASEBOARD_FAB2_LIB.BASEBOARD_FAB2(SCH_1):M_C_DQ(8)
  16 M_C_DQ<9>  DQ<8> @BASEBOARD_FAB2_LIB.BASEBOARD_FAB2(SCH_1):M_C_DQ(9)
 155 M_C_DQ<6>  DQ<7> @BASEBOARD_FAB2_LIB.BASEBOARD_FAB2(SCH_1):M_C_DQ(6)
  10 M_C_DQ<7>  DQ<6> @BASEBOARD_FAB2_LIB.BASEBOARD_FAB2(SCH_1):M_C_DQ(7)
 148 M_C_DQ<4>  DQ<5> @BASEBOARD_FAB2_LIB.BASEBOARD_FAB2(SCH_1):M_C_DQ(4)
   3 M_C_DQ<5>  DQ<4> @BASEBOARD_FAB2_LIB.BASEBOARD_FAB2(SCH_1):M_C_DQ(5)
 157 M_C_DQ<2>  DQ<3> @BASEBOARD_FAB2_LIB.BASEBOARD_FAB2(SCH_1):M_C_DQ(2)
  12 M_C_DQ<3>  DQ<2> @BASEBOARD_FAB2_LIB.BASEBOARD_FAB2(SCH_1):M_C_DQ(3)
 150 M_C_DQ<0>  DQ<1> @BASEBOARD_FAB2_LIB.BASEBOARD_FAB2(SCH_1):M_C_DQ(0)
   5 M_C_DQ<1>  DQ<0> @BASEBOARD_FAB2_LIB.BASEBOARD_FAB2(SCH_1):M_C_DQ(1)
  78 FM_DIMM_EVENT_COD_N EVENT_N @BASEBOARD_FAB2_LIB.BASEBOARD_FAB2(SCH_1):FM_DIMM_EVENT_COD_N
  91 M_C_ODT<1> ODT<1> @BASEBOARD_FAB2_LIB.BASEBOARD_FAB2(SCH_1):M_C_ODT(1)
  87 M_C_ODT<0> ODT<0> @BASEBOARD_FAB2_LIB.BASEBOARD_FAB2(SCH_1):M_C_ODT(0)
 222 M_C_PAR    PAR @BASEBOARD_FAB2_LIB.BASEBOARD_FAB2(SCH_1):M_C_PAR
  58 M_ABC_RST_N RESET_N @BASEBOARD_FAB2_LIB.BASEBOARD_FAB2(SCH_1):M_ABC_RST_N
 144 TP_CH_C_DIMM_C0_RFU_2 RFU<2> @BASEBOARD_FAB2_LIB.BASEBOARD_FAB2(SCH_1):TP_CH_C_DIMM_C0_RFU_2
 227 TP_CH_C_DIMM_C0_RFU_1 RFU<1> @BASEBOARD_FAB2_LIB.BASEBOARD_FAB2(SCH_1):TP_CH_C_DIMM_C0_RFU_1
 205 TP_CH_C_DIMM_C0_RFU_0 RFU<0> @BASEBOARD_FAB2_LIB.BASEBOARD_FAB2(SCH_1):TP_CH_C_DIMM_C0_RFU_0
  84 M_C_CS_N<0>   S0_N @BASEBOARD_FAB2_LIB.BASEBOARD_FAB2(SCH_1):M_C_CS_N(0)
  89 M_C_CS_N<1>   S1_N @BASEBOARD_FAB2_LIB.BASEBOARD_FAB2(SCH_1):M_C_CS_N(1)
  93 M_C_CS_N<2> S2_N_C<0> @BASEBOARD_FAB2_LIB.BASEBOARD_FAB2(SCH_1):M_C_CS_N(2)
 237 M_C_CS_N<3> S3_N_C<1> @BASEBOARD_FAB2_LIB.BASEBOARD_FAB2(SCH_1):M_C_CS_N(3)
 238 PVPP_ABC  SA<2> @BASEBOARD_FAB2_LIB.BASEBOARD_FAB2(SCH_1):PVPP_ABC
 140    GND  SA<1> @BASEBOARD_FAB2_LIB.BASEBOARD_FAB2(SCH_1):GND
 139    GND  SA<0> @BASEBOARD_FAB2_LIB.BASEBOARD_FAB2(SCH_1):GND
 230 FM_ADR_COMPLETE_ABC_N SAVE_N_NC @BASEBOARD_FAB2_LIB.BASEBOARD_FAB2(SCH_1):FM_ADR_COMPLETE_ABC_N
 141 SMB_DDR_ABC_VPP_SCL    SCL @BASEBOARD_FAB2_LIB.BASEBOARD_FAB2(SCH_1):SMB_DDR_ABC_VPP_SCL
 285 SMB_DDR_ABC_VPP_SDA    SDA @BASEBOARD_FAB2_LIB.BASEBOARD_FAB2(SCH_1):SMB_DDR_ABC_VPP_SDA
 284 PVPP_ABC VDDSPD @BASEBOARD_FAB2_LIB.BASEBOARD_FAB2(SCH_1):PVPP_ABC
 146 M_C_VREF VREFCA @BASEBOARD_FAB2_LIB.BASEBOARD_FAB2(SCH_1):M_C_VREF

SCONN288_H44441004_PIP-SCONN,HA  I179  J4G3
   1 P12V_NVDIMM_ABC 12V<1> @BASEBOARD_FAB2_LIB.BASEBOARD_FAB2(SCH_1):P12V_NVDIMM_ABC
 145 P12V_NVDIMM_ABC 12V<0> @BASEBOARD_FAB2_LIB.BASEBOARD_FAB2(SCH_1):P12V_NVDIMM_ABC
  59 PVDDQ_ABC VDD<25> @BASEBOARD_FAB2_LIB.BASEBOARD_FAB2(SCH_1):PVDDQ_ABC
  61 PVDDQ_ABC VDD<24> @BASEBOARD_FAB2_LIB.BASEBOARD_FAB2(SCH_1):PVDDQ_ABC
  64 PVDDQ_ABC VDD<23> @BASEBOARD_FAB2_LIB.BASEBOARD_FAB2(SCH_1):PVDDQ_ABC
  67 PVDDQ_ABC VDD<22> @BASEBOARD_FAB2_LIB.BASEBOARD_FAB2(SCH_1):PVDDQ_ABC
  70 PVDDQ_ABC VDD<21> @BASEBOARD_FAB2_LIB.BASEBOARD_FAB2(SCH_1):PVDDQ_ABC
  73 PVDDQ_ABC VDD<20> @BASEBOARD_FAB2_LIB.BASEBOARD_FAB2(SCH_1):PVDDQ_ABC
  76 PVDDQ_ABC VDD<19> @BASEBOARD_FAB2_LIB.BASEBOARD_FAB2(SCH_1):PVDDQ_ABC
  80 PVDDQ_ABC VDD<18> @BASEBOARD_FAB2_LIB.BASEBOARD_FAB2(SCH_1):PVDDQ_ABC
  83 PVDDQ_ABC VDD<17> @BASEBOARD_FAB2_LIB.BASEBOARD_FAB2(SCH_1):PVDDQ_ABC
  85 PVDDQ_ABC VDD<16> @BASEBOARD_FAB2_LIB.BASEBOARD_FAB2(SCH_1):PVDDQ_ABC
  88 PVDDQ_ABC VDD<15> @BASEBOARD_FAB2_LIB.BASEBOARD_FAB2(SCH_1):PVDDQ_ABC
  90 PVDDQ_ABC VDD<14> @BASEBOARD_FAB2_LIB.BASEBOARD_FAB2(SCH_1):PVDDQ_ABC
  92 PVDDQ_ABC VDD<13> @BASEBOARD_FAB2_LIB.BASEBOARD_FAB2(SCH_1):PVDDQ_ABC
 204 PVDDQ_ABC VDD<12> @BASEBOARD_FAB2_LIB.BASEBOARD_FAB2(SCH_1):PVDDQ_ABC
 206 PVDDQ_ABC VDD<11> @BASEBOARD_FAB2_LIB.BASEBOARD_FAB2(SCH_1):PVDDQ_ABC
 209 PVDDQ_ABC VDD<10> @BASEBOARD_FAB2_LIB.BASEBOARD_FAB2(SCH_1):PVDDQ_ABC
 212 PVDDQ_ABC VDD<9> @BASEBOARD_FAB2_LIB.BASEBOARD_FAB2(SCH_1):PVDDQ_ABC
 215 PVDDQ_ABC VDD<8> @BASEBOARD_FAB2_LIB.BASEBOARD_FAB2(SCH_1):PVDDQ_ABC
 217 PVDDQ_ABC VDD<7> @BASEBOARD_FAB2_LIB.BASEBOARD_FAB2(SCH_1):PVDDQ_ABC
 220 PVDDQ_ABC VDD<6> @BASEBOARD_FAB2_LIB.BASEBOARD_FAB2(SCH_1):PVDDQ_ABC
 223 PVDDQ_ABC VDD<5> @BASEBOARD_FAB2_LIB.BASEBOARD_FAB2(SCH_1):PVDDQ_ABC
 226 PVDDQ_ABC VDD<4> @BASEBOARD_FAB2_LIB.BASEBOARD_FAB2(SCH_1):PVDDQ_ABC
 229 PVDDQ_ABC VDD<3> @BASEBOARD_FAB2_LIB.BASEBOARD_FAB2(SCH_1):PVDDQ_ABC
 231 PVDDQ_ABC VDD<2> @BASEBOARD_FAB2_LIB.BASEBOARD_FAB2(SCH_1):PVDDQ_ABC
 233 PVDDQ_ABC VDD<1> @BASEBOARD_FAB2_LIB.BASEBOARD_FAB2(SCH_1):PVDDQ_ABC
 236 PVDDQ_ABC VDD<0> @BASEBOARD_FAB2_LIB.BASEBOARD_FAB2(SCH_1):PVDDQ_ABC
 142 PVPP_ABC VPP<4> @BASEBOARD_FAB2_LIB.BASEBOARD_FAB2(SCH_1):PVPP_ABC
 143 PVPP_ABC VPP<3> @BASEBOARD_FAB2_LIB.BASEBOARD_FAB2(SCH_1):PVPP_ABC
 288 PVPP_ABC VPP<2> @BASEBOARD_FAB2_LIB.BASEBOARD_FAB2(SCH_1):PVPP_ABC
 286 PVPP_ABC VPP<1> @BASEBOARD_FAB2_LIB.BASEBOARD_FAB2(SCH_1):PVPP_ABC
 287 PVPP_ABC VPP<0> @BASEBOARD_FAB2_LIB.BASEBOARD_FAB2(SCH_1):PVPP_ABC
  77 PVTT_ABC VTT<1> @BASEBOARD_FAB2_LIB.BASEBOARD_FAB2(SCH_1):PVTT_ABC
 221 PVTT_ABC VTT<0> @BASEBOARD_FAB2_LIB.BASEBOARD_FAB2(SCH_1):PVTT_ABC

CAP_A_0402V-0.01UF,25V,10%,X7RA  I188  C4G19
   1 M_C_VREF      A @BASEBOARD_FAB2_LIB.BASEBOARD_FAB2(SCH_1):M_C_VREF
   2    GND      B @BASEBOARD_FAB2_LIB.BASEBOARD_FAB2(SCH_1):GND


DRAWING: @BASEBOARD_FAB2_LIB.BASEBOARD_FAB2(SCH_1):PAGE48 

SCONN288_H44441003_PIP-SCONN,HA  I43  J6U2
   2    GND VSS<93> @BASEBOARD_FAB2_LIB.BASEBOARD_FAB2(SCH_1):GND
   4    GND VSS<92> @BASEBOARD_FAB2_LIB.BASEBOARD_FAB2(SCH_1):GND
   6    GND VSS<91> @BASEBOARD_FAB2_LIB.BASEBOARD_FAB2(SCH_1):GND
   9    GND VSS<90> @BASEBOARD_FAB2_LIB.BASEBOARD_FAB2(SCH_1):GND
  11    GND VSS<89> @BASEBOARD_FAB2_LIB.BASEBOARD_FAB2(SCH_1):GND
  13    GND VSS<88> @BASEBOARD_FAB2_LIB.BASEBOARD_FAB2(SCH_1):GND
  15    GND VSS<87> @BASEBOARD_FAB2_LIB.BASEBOARD_FAB2(SCH_1):GND
  17    GND VSS<86> @BASEBOARD_FAB2_LIB.BASEBOARD_FAB2(SCH_1):GND
  20    GND VSS<85> @BASEBOARD_FAB2_LIB.BASEBOARD_FAB2(SCH_1):GND
  22    GND VSS<84> @BASEBOARD_FAB2_LIB.BASEBOARD_FAB2(SCH_1):GND
  24    GND VSS<83> @BASEBOARD_FAB2_LIB.BASEBOARD_FAB2(SCH_1):GND
  26    GND VSS<82> @BASEBOARD_FAB2_LIB.BASEBOARD_FAB2(SCH_1):GND
  28    GND VSS<81> @BASEBOARD_FAB2_LIB.BASEBOARD_FAB2(SCH_1):GND
  31    GND VSS<80> @BASEBOARD_FAB2_LIB.BASEBOARD_FAB2(SCH_1):GND
  33    GND VSS<79> @BASEBOARD_FAB2_LIB.BASEBOARD_FAB2(SCH_1):GND
  35    GND VSS<78> @BASEBOARD_FAB2_LIB.BASEBOARD_FAB2(SCH_1):GND
  37    GND VSS<77> @BASEBOARD_FAB2_LIB.BASEBOARD_FAB2(SCH_1):GND
  39    GND VSS<76> @BASEBOARD_FAB2_LIB.BASEBOARD_FAB2(SCH_1):GND
  42    GND VSS<75> @BASEBOARD_FAB2_LIB.BASEBOARD_FAB2(SCH_1):GND
  44    GND VSS<74> @BASEBOARD_FAB2_LIB.BASEBOARD_FAB2(SCH_1):GND
  46    GND VSS<73> @BASEBOARD_FAB2_LIB.BASEBOARD_FAB2(SCH_1):GND
  48    GND VSS<72> @BASEBOARD_FAB2_LIB.BASEBOARD_FAB2(SCH_1):GND
  50    GND VSS<71> @BASEBOARD_FAB2_LIB.BASEBOARD_FAB2(SCH_1):GND
  53    GND VSS<70> @BASEBOARD_FAB2_LIB.BASEBOARD_FAB2(SCH_1):GND
  55    GND VSS<69> @BASEBOARD_FAB2_LIB.BASEBOARD_FAB2(SCH_1):GND
  57    GND VSS<68> @BASEBOARD_FAB2_LIB.BASEBOARD_FAB2(SCH_1):GND
  94    GND VSS<67> @BASEBOARD_FAB2_LIB.BASEBOARD_FAB2(SCH_1):GND
  96    GND VSS<66> @BASEBOARD_FAB2_LIB.BASEBOARD_FAB2(SCH_1):GND
  98    GND VSS<65> @BASEBOARD_FAB2_LIB.BASEBOARD_FAB2(SCH_1):GND
 101    GND VSS<64> @BASEBOARD_FAB2_LIB.BASEBOARD_FAB2(SCH_1):GND
 103    GND VSS<63> @BASEBOARD_FAB2_LIB.BASEBOARD_FAB2(SCH_1):GND
 105    GND VSS<62> @BASEBOARD_FAB2_LIB.BASEBOARD_FAB2(SCH_1):GND
 107    GND VSS<61> @BASEBOARD_FAB2_LIB.BASEBOARD_FAB2(SCH_1):GND
 109    GND VSS<60> @BASEBOARD_FAB2_LIB.BASEBOARD_FAB2(SCH_1):GND
 112    GND VSS<59> @BASEBOARD_FAB2_LIB.BASEBOARD_FAB2(SCH_1):GND
 114    GND VSS<58> @BASEBOARD_FAB2_LIB.BASEBOARD_FAB2(SCH_1):GND
 116    GND VSS<57> @BASEBOARD_FAB2_LIB.BASEBOARD_FAB2(SCH_1):GND
 118    GND VSS<56> @BASEBOARD_FAB2_LIB.BASEBOARD_FAB2(SCH_1):GND
 120    GND VSS<55> @BASEBOARD_FAB2_LIB.BASEBOARD_FAB2(SCH_1):GND
 123    GND VSS<54> @BASEBOARD_FAB2_LIB.BASEBOARD_FAB2(SCH_1):GND
 125    GND VSS<53> @BASEBOARD_FAB2_LIB.BASEBOARD_FAB2(SCH_1):GND
 127    GND VSS<52> @BASEBOARD_FAB2_LIB.BASEBOARD_FAB2(SCH_1):GND
 129    GND VSS<51> @BASEBOARD_FAB2_LIB.BASEBOARD_FAB2(SCH_1):GND
 131    GND VSS<50> @BASEBOARD_FAB2_LIB.BASEBOARD_FAB2(SCH_1):GND
 134    GND VSS<49> @BASEBOARD_FAB2_LIB.BASEBOARD_FAB2(SCH_1):GND
 136    GND VSS<48> @BASEBOARD_FAB2_LIB.BASEBOARD_FAB2(SCH_1):GND
 138    GND VSS<47> @BASEBOARD_FAB2_LIB.BASEBOARD_FAB2(SCH_1):GND
 147    GND VSS<46> @BASEBOARD_FAB2_LIB.BASEBOARD_FAB2(SCH_1):GND
 149    GND VSS<45> @BASEBOARD_FAB2_LIB.BASEBOARD_FAB2(SCH_1):GND
 151    GND VSS<44> @BASEBOARD_FAB2_LIB.BASEBOARD_FAB2(SCH_1):GND
 154    GND VSS<43> @BASEBOARD_FAB2_LIB.BASEBOARD_FAB2(SCH_1):GND
 156    GND VSS<42> @BASEBOARD_FAB2_LIB.BASEBOARD_FAB2(SCH_1):GND
 158    GND VSS<41> @BASEBOARD_FAB2_LIB.BASEBOARD_FAB2(SCH_1):GND
 160    GND VSS<40> @BASEBOARD_FAB2_LIB.BASEBOARD_FAB2(SCH_1):GND
 162    GND VSS<39> @BASEBOARD_FAB2_LIB.BASEBOARD_FAB2(SCH_1):GND
 165    GND VSS<38> @BASEBOARD_FAB2_LIB.BASEBOARD_FAB2(SCH_1):GND
 167    GND VSS<37> @BASEBOARD_FAB2_LIB.BASEBOARD_FAB2(SCH_1):GND
 169    GND VSS<36> @BASEBOARD_FAB2_LIB.BASEBOARD_FAB2(SCH_1):GND
 171    GND VSS<35> @BASEBOARD_FAB2_LIB.BASEBOARD_FAB2(SCH_1):GND
 173    GND VSS<34> @BASEBOARD_FAB2_LIB.BASEBOARD_FAB2(SCH_1):GND
 176    GND VSS<33> @BASEBOARD_FAB2_LIB.BASEBOARD_FAB2(SCH_1):GND
 178    GND VSS<32> @BASEBOARD_FAB2_LIB.BASEBOARD_FAB2(SCH_1):GND
 180    GND VSS<31> @BASEBOARD_FAB2_LIB.BASEBOARD_FAB2(SCH_1):GND
 182    GND VSS<30> @BASEBOARD_FAB2_LIB.BASEBOARD_FAB2(SCH_1):GND
 184    GND VSS<29> @BASEBOARD_FAB2_LIB.BASEBOARD_FAB2(SCH_1):GND
 187    GND VSS<28> @BASEBOARD_FAB2_LIB.BASEBOARD_FAB2(SCH_1):GND
 189    GND VSS<27> @BASEBOARD_FAB2_LIB.BASEBOARD_FAB2(SCH_1):GND
 191    GND VSS<26> @BASEBOARD_FAB2_LIB.BASEBOARD_FAB2(SCH_1):GND
 193    GND VSS<25> @BASEBOARD_FAB2_LIB.BASEBOARD_FAB2(SCH_1):GND
 195    GND VSS<24> @BASEBOARD_FAB2_LIB.BASEBOARD_FAB2(SCH_1):GND
 198    GND VSS<23> @BASEBOARD_FAB2_LIB.BASEBOARD_FAB2(SCH_1):GND
 200    GND VSS<22> @BASEBOARD_FAB2_LIB.BASEBOARD_FAB2(SCH_1):GND
 202    GND VSS<21> @BASEBOARD_FAB2_LIB.BASEBOARD_FAB2(SCH_1):GND
 239    GND VSS<20> @BASEBOARD_FAB2_LIB.BASEBOARD_FAB2(SCH_1):GND
 241    GND VSS<19> @BASEBOARD_FAB2_LIB.BASEBOARD_FAB2(SCH_1):GND
 243    GND VSS<18> @BASEBOARD_FAB2_LIB.BASEBOARD_FAB2(SCH_1):GND
 246    GND VSS<17> @BASEBOARD_FAB2_LIB.BASEBOARD_FAB2(SCH_1):GND
 248    GND VSS<16> @BASEBOARD_FAB2_LIB.BASEBOARD_FAB2(SCH_1):GND
 250    GND VSS<15> @BASEBOARD_FAB2_LIB.BASEBOARD_FAB2(SCH_1):GND
 252    GND VSS<14> @BASEBOARD_FAB2_LIB.BASEBOARD_FAB2(SCH_1):GND
 254    GND VSS<13> @BASEBOARD_FAB2_LIB.BASEBOARD_FAB2(SCH_1):GND
 257    GND VSS<12> @BASEBOARD_FAB2_LIB.BASEBOARD_FAB2(SCH_1):GND
 259    GND VSS<11> @BASEBOARD_FAB2_LIB.BASEBOARD_FAB2(SCH_1):GND
 261    GND VSS<10> @BASEBOARD_FAB2_LIB.BASEBOARD_FAB2(SCH_1):GND
 263    GND VSS<9> @BASEBOARD_FAB2_LIB.BASEBOARD_FAB2(SCH_1):GND
 265    GND VSS<8> @BASEBOARD_FAB2_LIB.BASEBOARD_FAB2(SCH_1):GND
 268    GND VSS<7> @BASEBOARD_FAB2_LIB.BASEBOARD_FAB2(SCH_1):GND
 270    GND VSS<6> @BASEBOARD_FAB2_LIB.BASEBOARD_FAB2(SCH_1):GND
 272    GND VSS<5> @BASEBOARD_FAB2_LIB.BASEBOARD_FAB2(SCH_1):GND
 274    GND VSS<4> @BASEBOARD_FAB2_LIB.BASEBOARD_FAB2(SCH_1):GND
 276    GND VSS<3> @BASEBOARD_FAB2_LIB.BASEBOARD_FAB2(SCH_1):GND
 279    GND VSS<2> @BASEBOARD_FAB2_LIB.BASEBOARD_FAB2(SCH_1):GND
 281    GND VSS<1> @BASEBOARD_FAB2_LIB.BASEBOARD_FAB2(SCH_1):GND
 283    GND VSS<0> @BASEBOARD_FAB2_LIB.BASEBOARD_FAB2(SCH_1):GND

SCONN288_H44441003_PIP-SCONN,HA  I61  J6U2
 152 M_C_DQS_DN<0>  DQS0N @BASEBOARD_FAB2_LIB.BASEBOARD_FAB2(SCH_1):M_C_DQS_DN(0)
 153 M_C_DQS_DP<0>  DQS0P @BASEBOARD_FAB2_LIB.BASEBOARD_FAB2(SCH_1):M_C_DQS_DP(0)
  19 M_C_DQS_DN<10> DQS10N @BASEBOARD_FAB2_LIB.BASEBOARD_FAB2(SCH_1):M_C_DQS_DN(10)
  18 M_C_DQS_DP<10> DQS10P @BASEBOARD_FAB2_LIB.BASEBOARD_FAB2(SCH_1):M_C_DQS_DP(10)
  30 M_C_DQS_DN<11> DQS11N @BASEBOARD_FAB2_LIB.BASEBOARD_FAB2(SCH_1):M_C_DQS_DN(11)
  29 M_C_DQS_DP<11> DQS11P @BASEBOARD_FAB2_LIB.BASEBOARD_FAB2(SCH_1):M_C_DQS_DP(11)
  41 M_C_DQS_DN<12> DQS12N @BASEBOARD_FAB2_LIB.BASEBOARD_FAB2(SCH_1):M_C_DQS_DN(12)
  40 M_C_DQS_DP<12> DQS12P @BASEBOARD_FAB2_LIB.BASEBOARD_FAB2(SCH_1):M_C_DQS_DP(12)
 100 M_C_DQS_DN<13> DQS13N @BASEBOARD_FAB2_LIB.BASEBOARD_FAB2(SCH_1):M_C_DQS_DN(13)
  99 M_C_DQS_DP<13> DQS13P @BASEBOARD_FAB2_LIB.BASEBOARD_FAB2(SCH_1):M_C_DQS_DP(13)
 111 M_C_DQS_DN<14> DQS14N @BASEBOARD_FAB2_LIB.BASEBOARD_FAB2(SCH_1):M_C_DQS_DN(14)
 110 M_C_DQS_DP<14> DQS14P @BASEBOARD_FAB2_LIB.BASEBOARD_FAB2(SCH_1):M_C_DQS_DP(14)
 122 M_C_DQS_DN<15> DQS15N @BASEBOARD_FAB2_LIB.BASEBOARD_FAB2(SCH_1):M_C_DQS_DN(15)
 121 M_C_DQS_DP<15> DQS15P @BASEBOARD_FAB2_LIB.BASEBOARD_FAB2(SCH_1):M_C_DQS_DP(15)
 133 M_C_DQS_DN<16> DQS16N @BASEBOARD_FAB2_LIB.BASEBOARD_FAB2(SCH_1):M_C_DQS_DN(16)
 132 M_C_DQS_DP<16> DQS16P @BASEBOARD_FAB2_LIB.BASEBOARD_FAB2(SCH_1):M_C_DQS_DP(16)
  52 M_C_DQS_DN<17> DQS17N @BASEBOARD_FAB2_LIB.BASEBOARD_FAB2(SCH_1):M_C_DQS_DN(17)
  51 M_C_DQS_DP<17> DQS17P @BASEBOARD_FAB2_LIB.BASEBOARD_FAB2(SCH_1):M_C_DQS_DP(17)
 163 M_C_DQS_DN<1>  DQS1N @BASEBOARD_FAB2_LIB.BASEBOARD_FAB2(SCH_1):M_C_DQS_DN(1)
 164 M_C_DQS_DP<1>  DQS1P @BASEBOARD_FAB2_LIB.BASEBOARD_FAB2(SCH_1):M_C_DQS_DP(1)
 174 M_C_DQS_DN<2>  DQS2N @BASEBOARD_FAB2_LIB.BASEBOARD_FAB2(SCH_1):M_C_DQS_DN(2)
 175 M_C_DQS_DP<2>  DQS2P @BASEBOARD_FAB2_LIB.BASEBOARD_FAB2(SCH_1):M_C_DQS_DP(2)
 185 M_C_DQS_DN<3>  DQS3N @BASEBOARD_FAB2_LIB.BASEBOARD_FAB2(SCH_1):M_C_DQS_DN(3)
 186 M_C_DQS_DP<3>  DQS3P @BASEBOARD_FAB2_LIB.BASEBOARD_FAB2(SCH_1):M_C_DQS_DP(3)
 244 M_C_DQS_DN<4>  DQS4N @BASEBOARD_FAB2_LIB.BASEBOARD_FAB2(SCH_1):M_C_DQS_DN(4)
 245 M_C_DQS_DP<4>  DQS4P @BASEBOARD_FAB2_LIB.BASEBOARD_FAB2(SCH_1):M_C_DQS_DP(4)
 255 M_C_DQS_DN<5>  DQS5N @BASEBOARD_FAB2_LIB.BASEBOARD_FAB2(SCH_1):M_C_DQS_DN(5)
 256 M_C_DQS_DP<5>  DQS5P @BASEBOARD_FAB2_LIB.BASEBOARD_FAB2(SCH_1):M_C_DQS_DP(5)
 266 M_C_DQS_DN<6>  DQS6N @BASEBOARD_FAB2_LIB.BASEBOARD_FAB2(SCH_1):M_C_DQS_DN(6)
 267 M_C_DQS_DP<6>  DQS6P @BASEBOARD_FAB2_LIB.BASEBOARD_FAB2(SCH_1):M_C_DQS_DP(6)
 277 M_C_DQS_DN<7>  DQS7N @BASEBOARD_FAB2_LIB.BASEBOARD_FAB2(SCH_1):M_C_DQS_DN(7)
 278 M_C_DQS_DP<7>  DQS7P @BASEBOARD_FAB2_LIB.BASEBOARD_FAB2(SCH_1):M_C_DQS_DP(7)
 196 M_C_DQS_DN<8>  DQS8N @BASEBOARD_FAB2_LIB.BASEBOARD_FAB2(SCH_1):M_C_DQS_DN(8)
 197 M_C_DQS_DP<8>  DQS8P @BASEBOARD_FAB2_LIB.BASEBOARD_FAB2(SCH_1):M_C_DQS_DP(8)
   8 M_C_DQS_DN<9>  DQS9N @BASEBOARD_FAB2_LIB.BASEBOARD_FAB2(SCH_1):M_C_DQS_DN(9)
   7 M_C_DQS_DP<9>  DQS9P @BASEBOARD_FAB2_LIB.BASEBOARD_FAB2(SCH_1):M_C_DQS_DP(9)

SCONN288_H44441003_PIP-SCONN,HA  I111  J6U2
  79 M_C_MA<0>     A0 @BASEBOARD_FAB2_LIB.BASEBOARD_FAB2(SCH_1):M_C_MA(0)
  72 M_C_MA<1>     A1 @BASEBOARD_FAB2_LIB.BASEBOARD_FAB2(SCH_1):M_C_MA(1)
 225 M_C_MA<10>    A10 @BASEBOARD_FAB2_LIB.BASEBOARD_FAB2(SCH_1):M_C_MA(10)
 210 M_C_MA<11>    A11 @BASEBOARD_FAB2_LIB.BASEBOARD_FAB2(SCH_1):M_C_MA(11)
  65 M_C_MA<12>    A12 @BASEBOARD_FAB2_LIB.BASEBOARD_FAB2(SCH_1):M_C_MA(12)
 232 M_C_MA<13>    A13 @BASEBOARD_FAB2_LIB.BASEBOARD_FAB2(SCH_1):M_C_MA(13)
 228 M_C_MA<14> A14_WE_N @BASEBOARD_FAB2_LIB.BASEBOARD_FAB2(SCH_1):M_C_MA(14)
  86 M_C_MA<15> A15_CAS_N @BASEBOARD_FAB2_LIB.BASEBOARD_FAB2(SCH_1):M_C_MA(15)
  82 M_C_MA<16> A16_RAS_N @BASEBOARD_FAB2_LIB.BASEBOARD_FAB2(SCH_1):M_C_MA(16)
 234 M_C_MA<17>    A17 @BASEBOARD_FAB2_LIB.BASEBOARD_FAB2(SCH_1):M_C_MA(17)
 216 M_C_MA<2>     A2 @BASEBOARD_FAB2_LIB.BASEBOARD_FAB2(SCH_1):M_C_MA(2)
  71 M_C_MA<3>     A3 @BASEBOARD_FAB2_LIB.BASEBOARD_FAB2(SCH_1):M_C_MA(3)
 214 M_C_MA<4>     A4 @BASEBOARD_FAB2_LIB.BASEBOARD_FAB2(SCH_1):M_C_MA(4)
 213 M_C_MA<5>     A5 @BASEBOARD_FAB2_LIB.BASEBOARD_FAB2(SCH_1):M_C_MA(5)
  69 M_C_MA<6>     A6 @BASEBOARD_FAB2_LIB.BASEBOARD_FAB2(SCH_1):M_C_MA(6)
 211 M_C_MA<7>     A7 @BASEBOARD_FAB2_LIB.BASEBOARD_FAB2(SCH_1):M_C_MA(7)
  68 M_C_MA<8>     A8 @BASEBOARD_FAB2_LIB.BASEBOARD_FAB2(SCH_1):M_C_MA(8)
  66 M_C_MA<9>     A9 @BASEBOARD_FAB2_LIB.BASEBOARD_FAB2(SCH_1):M_C_MA(9)
  62 M_C_ACT_N  ACT_N @BASEBOARD_FAB2_LIB.BASEBOARD_FAB2(SCH_1):M_C_ACT_N
 208 M_C_ALERT_N ALERT_N @BASEBOARD_FAB2_LIB.BASEBOARD_FAB2(SCH_1):M_C_ALERT_N
 224 M_C_BA<1>  BA<1> @BASEBOARD_FAB2_LIB.BASEBOARD_FAB2(SCH_1):M_C_BA(1)
  81 M_C_BA<0>  BA<0> @BASEBOARD_FAB2_LIB.BASEBOARD_FAB2(SCH_1):M_C_BA(0)
 207 M_C_BG<1>  BG<1> @BASEBOARD_FAB2_LIB.BASEBOARD_FAB2(SCH_1):M_C_BG(1)
  63 M_C_BG<0>  BG<0> @BASEBOARD_FAB2_LIB.BASEBOARD_FAB2(SCH_1):M_C_BG(0)
 235 M_C_C<2>   C<2> @BASEBOARD_FAB2_LIB.BASEBOARD_FAB2(SCH_1):M_C_C(2)
 199 M_C_ECC<7>  CB<7> @BASEBOARD_FAB2_LIB.BASEBOARD_FAB2(SCH_1):M_C_ECC(7)
  54 M_C_ECC<6>  CB<6> @BASEBOARD_FAB2_LIB.BASEBOARD_FAB2(SCH_1):M_C_ECC(6)
 192 M_C_ECC<5>  CB<5> @BASEBOARD_FAB2_LIB.BASEBOARD_FAB2(SCH_1):M_C_ECC(5)
  47 M_C_ECC<4>  CB<4> @BASEBOARD_FAB2_LIB.BASEBOARD_FAB2(SCH_1):M_C_ECC(4)
 201 M_C_ECC<3>  CB<3> @BASEBOARD_FAB2_LIB.BASEBOARD_FAB2(SCH_1):M_C_ECC(3)
  56 M_C_ECC<2>  CB<2> @BASEBOARD_FAB2_LIB.BASEBOARD_FAB2(SCH_1):M_C_ECC(2)
 194 M_C_ECC<1>  CB<1> @BASEBOARD_FAB2_LIB.BASEBOARD_FAB2(SCH_1):M_C_ECC(1)
  49 M_C_ECC<0>  CB<0> @BASEBOARD_FAB2_LIB.BASEBOARD_FAB2(SCH_1):M_C_ECC(0)
  75 M_C_CLK_DN<2>   CK0N @BASEBOARD_FAB2_LIB.BASEBOARD_FAB2(SCH_1):M_C_CLK_DN(2)
  74 M_C_CLK_DP<2>   CK0P @BASEBOARD_FAB2_LIB.BASEBOARD_FAB2(SCH_1):M_C_CLK_DP(2)
 219 M_C_CLK_DN<3>   CK1N @BASEBOARD_FAB2_LIB.BASEBOARD_FAB2(SCH_1):M_C_CLK_DN(3)
 218 M_C_CLK_DP<3>   CK1P @BASEBOARD_FAB2_LIB.BASEBOARD_FAB2(SCH_1):M_C_CLK_DP(3)
 203 M_C_CKE<3> CKE<1> @BASEBOARD_FAB2_LIB.BASEBOARD_FAB2(SCH_1):M_C_CKE(3)
  60 M_C_CKE<2> CKE<0> @BASEBOARD_FAB2_LIB.BASEBOARD_FAB2(SCH_1):M_C_CKE(2)
 280 M_C_DQ<63> DQ<63> @BASEBOARD_FAB2_LIB.BASEBOARD_FAB2(SCH_1):M_C_DQ(63)
 135 M_C_DQ<62> DQ<62> @BASEBOARD_FAB2_LIB.BASEBOARD_FAB2(SCH_1):M_C_DQ(62)
 273 M_C_DQ<61> DQ<61> @BASEBOARD_FAB2_LIB.BASEBOARD_FAB2(SCH_1):M_C_DQ(61)
 128 M_C_DQ<60> DQ<60> @BASEBOARD_FAB2_LIB.BASEBOARD_FAB2(SCH_1):M_C_DQ(60)
 282 M_C_DQ<59> DQ<59> @BASEBOARD_FAB2_LIB.BASEBOARD_FAB2(SCH_1):M_C_DQ(59)
 137 M_C_DQ<58> DQ<58> @BASEBOARD_FAB2_LIB.BASEBOARD_FAB2(SCH_1):M_C_DQ(58)
 275 M_C_DQ<57> DQ<57> @BASEBOARD_FAB2_LIB.BASEBOARD_FAB2(SCH_1):M_C_DQ(57)
 130 M_C_DQ<56> DQ<56> @BASEBOARD_FAB2_LIB.BASEBOARD_FAB2(SCH_1):M_C_DQ(56)
 269 M_C_DQ<55> DQ<55> @BASEBOARD_FAB2_LIB.BASEBOARD_FAB2(SCH_1):M_C_DQ(55)
 124 M_C_DQ<54> DQ<54> @BASEBOARD_FAB2_LIB.BASEBOARD_FAB2(SCH_1):M_C_DQ(54)
 262 M_C_DQ<53> DQ<53> @BASEBOARD_FAB2_LIB.BASEBOARD_FAB2(SCH_1):M_C_DQ(53)
 117 M_C_DQ<52> DQ<52> @BASEBOARD_FAB2_LIB.BASEBOARD_FAB2(SCH_1):M_C_DQ(52)
 271 M_C_DQ<51> DQ<51> @BASEBOARD_FAB2_LIB.BASEBOARD_FAB2(SCH_1):M_C_DQ(51)
 126 M_C_DQ<50> DQ<50> @BASEBOARD_FAB2_LIB.BASEBOARD_FAB2(SCH_1):M_C_DQ(50)
 264 M_C_DQ<49> DQ<49> @BASEBOARD_FAB2_LIB.BASEBOARD_FAB2(SCH_1):M_C_DQ(49)
 119 M_C_DQ<48> DQ<48> @BASEBOARD_FAB2_LIB.BASEBOARD_FAB2(SCH_1):M_C_DQ(48)
 258 M_C_DQ<47> DQ<47> @BASEBOARD_FAB2_LIB.BASEBOARD_FAB2(SCH_1):M_C_DQ(47)
 113 M_C_DQ<46> DQ<46> @BASEBOARD_FAB2_LIB.BASEBOARD_FAB2(SCH_1):M_C_DQ(46)
 251 M_C_DQ<45> DQ<45> @BASEBOARD_FAB2_LIB.BASEBOARD_FAB2(SCH_1):M_C_DQ(45)
 106 M_C_DQ<44> DQ<44> @BASEBOARD_FAB2_LIB.BASEBOARD_FAB2(SCH_1):M_C_DQ(44)
 260 M_C_DQ<43> DQ<43> @BASEBOARD_FAB2_LIB.BASEBOARD_FAB2(SCH_1):M_C_DQ(43)
 115 M_C_DQ<42> DQ<42> @BASEBOARD_FAB2_LIB.BASEBOARD_FAB2(SCH_1):M_C_DQ(42)
 253 M_C_DQ<41> DQ<41> @BASEBOARD_FAB2_LIB.BASEBOARD_FAB2(SCH_1):M_C_DQ(41)
 108 M_C_DQ<40> DQ<40> @BASEBOARD_FAB2_LIB.BASEBOARD_FAB2(SCH_1):M_C_DQ(40)
 247 M_C_DQ<39> DQ<39> @BASEBOARD_FAB2_LIB.BASEBOARD_FAB2(SCH_1):M_C_DQ(39)
 102 M_C_DQ<38> DQ<38> @BASEBOARD_FAB2_LIB.BASEBOARD_FAB2(SCH_1):M_C_DQ(38)
 240 M_C_DQ<37> DQ<37> @BASEBOARD_FAB2_LIB.BASEBOARD_FAB2(SCH_1):M_C_DQ(37)
  95 M_C_DQ<36> DQ<36> @BASEBOARD_FAB2_LIB.BASEBOARD_FAB2(SCH_1):M_C_DQ(36)
 249 M_C_DQ<35> DQ<35> @BASEBOARD_FAB2_LIB.BASEBOARD_FAB2(SCH_1):M_C_DQ(35)
 104 M_C_DQ<34> DQ<34> @BASEBOARD_FAB2_LIB.BASEBOARD_FAB2(SCH_1):M_C_DQ(34)
 242 M_C_DQ<33> DQ<33> @BASEBOARD_FAB2_LIB.BASEBOARD_FAB2(SCH_1):M_C_DQ(33)
  97 M_C_DQ<32> DQ<32> @BASEBOARD_FAB2_LIB.BASEBOARD_FAB2(SCH_1):M_C_DQ(32)
 188 M_C_DQ<31> DQ<31> @BASEBOARD_FAB2_LIB.BASEBOARD_FAB2(SCH_1):M_C_DQ(31)
  43 M_C_DQ<30> DQ<30> @BASEBOARD_FAB2_LIB.BASEBOARD_FAB2(SCH_1):M_C_DQ(30)
 181 M_C_DQ<29> DQ<29> @BASEBOARD_FAB2_LIB.BASEBOARD_FAB2(SCH_1):M_C_DQ(29)
  36 M_C_DQ<28> DQ<28> @BASEBOARD_FAB2_LIB.BASEBOARD_FAB2(SCH_1):M_C_DQ(28)
 190 M_C_DQ<27> DQ<27> @BASEBOARD_FAB2_LIB.BASEBOARD_FAB2(SCH_1):M_C_DQ(27)
  45 M_C_DQ<26> DQ<26> @BASEBOARD_FAB2_LIB.BASEBOARD_FAB2(SCH_1):M_C_DQ(26)
 183 M_C_DQ<25> DQ<25> @BASEBOARD_FAB2_LIB.BASEBOARD_FAB2(SCH_1):M_C_DQ(25)
  38 M_C_DQ<24> DQ<24> @BASEBOARD_FAB2_LIB.BASEBOARD_FAB2(SCH_1):M_C_DQ(24)
 177 M_C_DQ<23> DQ<23> @BASEBOARD_FAB2_LIB.BASEBOARD_FAB2(SCH_1):M_C_DQ(23)
  32 M_C_DQ<22> DQ<22> @BASEBOARD_FAB2_LIB.BASEBOARD_FAB2(SCH_1):M_C_DQ(22)
 170 M_C_DQ<21> DQ<21> @BASEBOARD_FAB2_LIB.BASEBOARD_FAB2(SCH_1):M_C_DQ(21)
  25 M_C_DQ<20> DQ<20> @BASEBOARD_FAB2_LIB.BASEBOARD_FAB2(SCH_1):M_C_DQ(20)
 179 M_C_DQ<19> DQ<19> @BASEBOARD_FAB2_LIB.BASEBOARD_FAB2(SCH_1):M_C_DQ(19)
  34 M_C_DQ<18> DQ<18> @BASEBOARD_FAB2_LIB.BASEBOARD_FAB2(SCH_1):M_C_DQ(18)
 172 M_C_DQ<17> DQ<17> @BASEBOARD_FAB2_LIB.BASEBOARD_FAB2(SCH_1):M_C_DQ(17)
  27 M_C_DQ<16> DQ<16> @BASEBOARD_FAB2_LIB.BASEBOARD_FAB2(SCH_1):M_C_DQ(16)
 166 M_C_DQ<15> DQ<15> @BASEBOARD_FAB2_LIB.BASEBOARD_FAB2(SCH_1):M_C_DQ(15)
  21 M_C_DQ<14> DQ<14> @BASEBOARD_FAB2_LIB.BASEBOARD_FAB2(SCH_1):M_C_DQ(14)
 159 M_C_DQ<13> DQ<13> @BASEBOARD_FAB2_LIB.BASEBOARD_FAB2(SCH_1):M_C_DQ(13)
  14 M_C_DQ<12> DQ<12> @BASEBOARD_FAB2_LIB.BASEBOARD_FAB2(SCH_1):M_C_DQ(12)
 168 M_C_DQ<11> DQ<11> @BASEBOARD_FAB2_LIB.BASEBOARD_FAB2(SCH_1):M_C_DQ(11)
  23 M_C_DQ<10> DQ<10> @BASEBOARD_FAB2_LIB.BASEBOARD_FAB2(SCH_1):M_C_DQ(10)
 161 M_C_DQ<9>  DQ<9> @BASEBOARD_FAB2_LIB.BASEBOARD_FAB2(SCH_1):M_C_DQ(9)
  16 M_C_DQ<8>  DQ<8> @BASEBOARD_FAB2_LIB.BASEBOARD_FAB2(SCH_1):M_C_DQ(8)
 155 M_C_DQ<7>  DQ<7> @BASEBOARD_FAB2_LIB.BASEBOARD_FAB2(SCH_1):M_C_DQ(7)
  10 M_C_DQ<6>  DQ<6> @BASEBOARD_FAB2_LIB.BASEBOARD_FAB2(SCH_1):M_C_DQ(6)
 148 M_C_DQ<5>  DQ<5> @BASEBOARD_FAB2_LIB.BASEBOARD_FAB2(SCH_1):M_C_DQ(5)
   3 M_C_DQ<4>  DQ<4> @BASEBOARD_FAB2_LIB.BASEBOARD_FAB2(SCH_1):M_C_DQ(4)
 157 M_C_DQ<3>  DQ<3> @BASEBOARD_FAB2_LIB.BASEBOARD_FAB2(SCH_1):M_C_DQ(3)
  12 M_C_DQ<2>  DQ<2> @BASEBOARD_FAB2_LIB.BASEBOARD_FAB2(SCH_1):M_C_DQ(2)
 150 M_C_DQ<1>  DQ<1> @BASEBOARD_FAB2_LIB.BASEBOARD_FAB2(SCH_1):M_C_DQ(1)
   5 M_C_DQ<0>  DQ<0> @BASEBOARD_FAB2_LIB.BASEBOARD_FAB2(SCH_1):M_C_DQ(0)
  78 FM_DIMM_EVENT_COD_N EVENT_N @BASEBOARD_FAB2_LIB.BASEBOARD_FAB2(SCH_1):FM_DIMM_EVENT_COD_N
  91 M_C_ODT<3> ODT<1> @BASEBOARD_FAB2_LIB.BASEBOARD_FAB2(SCH_1):M_C_ODT(3)
  87 M_C_ODT<2> ODT<0> @BASEBOARD_FAB2_LIB.BASEBOARD_FAB2(SCH_1):M_C_ODT(2)
 222 M_C_PAR    PAR @BASEBOARD_FAB2_LIB.BASEBOARD_FAB2(SCH_1):M_C_PAR
  58 M_ABC_RST_N RESET_N @BASEBOARD_FAB2_LIB.BASEBOARD_FAB2(SCH_1):M_ABC_RST_N
 144 TP_CH_C_DIMM_C1_RFU_2 RFU<2> @BASEBOARD_FAB2_LIB.BASEBOARD_FAB2(SCH_1):TP_CH_C_DIMM_C1_RFU_2
 227 TP_CH_C_DIMM_C1_RFU_1 RFU<1> @BASEBOARD_FAB2_LIB.BASEBOARD_FAB2(SCH_1):TP_CH_C_DIMM_C1_RFU_1
 205 TP_CH_C_DIMM_C1_RFU_0 RFU<0> @BASEBOARD_FAB2_LIB.BASEBOARD_FAB2(SCH_1):TP_CH_C_DIMM_C1_RFU_0
  84 M_C_CS_N<4>   S0_N @BASEBOARD_FAB2_LIB.BASEBOARD_FAB2(SCH_1):M_C_CS_N(4)
  89 M_C_CS_N<5>   S1_N @BASEBOARD_FAB2_LIB.BASEBOARD_FAB2(SCH_1):M_C_CS_N(5)
  93 M_C_CS_N<6> S2_N_C<0> @BASEBOARD_FAB2_LIB.BASEBOARD_FAB2(SCH_1):M_C_CS_N(6)
 237 M_C_CS_N<7> S3_N_C<1> @BASEBOARD_FAB2_LIB.BASEBOARD_FAB2(SCH_1):M_C_CS_N(7)
 238 PVPP_ABC  SA<2> @BASEBOARD_FAB2_LIB.BASEBOARD_FAB2(SCH_1):PVPP_ABC
 140    GND  SA<1> @BASEBOARD_FAB2_LIB.BASEBOARD_FAB2(SCH_1):GND
 139 PVPP_ABC  SA<0> @BASEBOARD_FAB2_LIB.BASEBOARD_FAB2(SCH_1):PVPP_ABC
 230 FM_ADR_COMPLETE_ABC_N SAVE_N_NC @BASEBOARD_FAB2_LIB.BASEBOARD_FAB2(SCH_1):FM_ADR_COMPLETE_ABC_N
 141 SMB_DDR_ABC_VPP_SCL    SCL @BASEBOARD_FAB2_LIB.BASEBOARD_FAB2(SCH_1):SMB_DDR_ABC_VPP_SCL
 285 SMB_DDR_ABC_VPP_SDA    SDA @BASEBOARD_FAB2_LIB.BASEBOARD_FAB2(SCH_1):SMB_DDR_ABC_VPP_SDA
 284 PVPP_ABC VDDSPD @BASEBOARD_FAB2_LIB.BASEBOARD_FAB2(SCH_1):PVPP_ABC
 146 M_C_VREF VREFCA @BASEBOARD_FAB2_LIB.BASEBOARD_FAB2(SCH_1):M_C_VREF

SCONN288_H44441003_PIP-SCONN,HA  I171  J6U2
   1 P12V_NVDIMM_ABC 12V<1> @BASEBOARD_FAB2_LIB.BASEBOARD_FAB2(SCH_1):P12V_NVDIMM_ABC
 145 P12V_NVDIMM_ABC 12V<0> @BASEBOARD_FAB2_LIB.BASEBOARD_FAB2(SCH_1):P12V_NVDIMM_ABC
  59 PVDDQ_ABC VDD<25> @BASEBOARD_FAB2_LIB.BASEBOARD_FAB2(SCH_1):PVDDQ_ABC
  61 PVDDQ_ABC VDD<24> @BASEBOARD_FAB2_LIB.BASEBOARD_FAB2(SCH_1):PVDDQ_ABC
  64 PVDDQ_ABC VDD<23> @BASEBOARD_FAB2_LIB.BASEBOARD_FAB2(SCH_1):PVDDQ_ABC
  67 PVDDQ_ABC VDD<22> @BASEBOARD_FAB2_LIB.BASEBOARD_FAB2(SCH_1):PVDDQ_ABC
  70 PVDDQ_ABC VDD<21> @BASEBOARD_FAB2_LIB.BASEBOARD_FAB2(SCH_1):PVDDQ_ABC
  73 PVDDQ_ABC VDD<20> @BASEBOARD_FAB2_LIB.BASEBOARD_FAB2(SCH_1):PVDDQ_ABC
  76 PVDDQ_ABC VDD<19> @BASEBOARD_FAB2_LIB.BASEBOARD_FAB2(SCH_1):PVDDQ_ABC
  80 PVDDQ_ABC VDD<18> @BASEBOARD_FAB2_LIB.BASEBOARD_FAB2(SCH_1):PVDDQ_ABC
  83 PVDDQ_ABC VDD<17> @BASEBOARD_FAB2_LIB.BASEBOARD_FAB2(SCH_1):PVDDQ_ABC
  85 PVDDQ_ABC VDD<16> @BASEBOARD_FAB2_LIB.BASEBOARD_FAB2(SCH_1):PVDDQ_ABC
  88 PVDDQ_ABC VDD<15> @BASEBOARD_FAB2_LIB.BASEBOARD_FAB2(SCH_1):PVDDQ_ABC
  90 PVDDQ_ABC VDD<14> @BASEBOARD_FAB2_LIB.BASEBOARD_FAB2(SCH_1):PVDDQ_ABC
  92 PVDDQ_ABC VDD<13> @BASEBOARD_FAB2_LIB.BASEBOARD_FAB2(SCH_1):PVDDQ_ABC
 204 PVDDQ_ABC VDD<12> @BASEBOARD_FAB2_LIB.BASEBOARD_FAB2(SCH_1):PVDDQ_ABC
 206 PVDDQ_ABC VDD<11> @BASEBOARD_FAB2_LIB.BASEBOARD_FAB2(SCH_1):PVDDQ_ABC
 209 PVDDQ_ABC VDD<10> @BASEBOARD_FAB2_LIB.BASEBOARD_FAB2(SCH_1):PVDDQ_ABC
 212 PVDDQ_ABC VDD<9> @BASEBOARD_FAB2_LIB.BASEBOARD_FAB2(SCH_1):PVDDQ_ABC
 215 PVDDQ_ABC VDD<8> @BASEBOARD_FAB2_LIB.BASEBOARD_FAB2(SCH_1):PVDDQ_ABC
 217 PVDDQ_ABC VDD<7> @BASEBOARD_FAB2_LIB.BASEBOARD_FAB2(SCH_1):PVDDQ_ABC
 220 PVDDQ_ABC VDD<6> @BASEBOARD_FAB2_LIB.BASEBOARD_FAB2(SCH_1):PVDDQ_ABC
 223 PVDDQ_ABC VDD<5> @BASEBOARD_FAB2_LIB.BASEBOARD_FAB2(SCH_1):PVDDQ_ABC
 226 PVDDQ_ABC VDD<4> @BASEBOARD_FAB2_LIB.BASEBOARD_FAB2(SCH_1):PVDDQ_ABC
 229 PVDDQ_ABC VDD<3> @BASEBOARD_FAB2_LIB.BASEBOARD_FAB2(SCH_1):PVDDQ_ABC
 231 PVDDQ_ABC VDD<2> @BASEBOARD_FAB2_LIB.BASEBOARD_FAB2(SCH_1):PVDDQ_ABC
 233 PVDDQ_ABC VDD<1> @BASEBOARD_FAB2_LIB.BASEBOARD_FAB2(SCH_1):PVDDQ_ABC
 236 PVDDQ_ABC VDD<0> @BASEBOARD_FAB2_LIB.BASEBOARD_FAB2(SCH_1):PVDDQ_ABC
 142 PVPP_ABC VPP<4> @BASEBOARD_FAB2_LIB.BASEBOARD_FAB2(SCH_1):PVPP_ABC
 143 PVPP_ABC VPP<3> @BASEBOARD_FAB2_LIB.BASEBOARD_FAB2(SCH_1):PVPP_ABC
 288 PVPP_ABC VPP<2> @BASEBOARD_FAB2_LIB.BASEBOARD_FAB2(SCH_1):PVPP_ABC
 286 PVPP_ABC VPP<1> @BASEBOARD_FAB2_LIB.BASEBOARD_FAB2(SCH_1):PVPP_ABC
 287 PVPP_ABC VPP<0> @BASEBOARD_FAB2_LIB.BASEBOARD_FAB2(SCH_1):PVPP_ABC
  77 PVTT_ABC VTT<1> @BASEBOARD_FAB2_LIB.BASEBOARD_FAB2(SCH_1):PVTT_ABC
 221 PVTT_ABC VTT<0> @BASEBOARD_FAB2_LIB.BASEBOARD_FAB2(SCH_1):PVTT_ABC

CAP_A_0402V-0.01UF,25V,10%,X7RA  I176  C6U17
   1 M_C_VREF      A @BASEBOARD_FAB2_LIB.BASEBOARD_FAB2(SCH_1):M_C_VREF
   2    GND      B @BASEBOARD_FAB2_LIB.BASEBOARD_FAB2(SCH_1):GND


DRAWING: @BASEBOARD_FAB2_LIB.BASEBOARD_FAB2(SCH_1):PAGE49 

SCONN288_H44441004_PIP-SCONN,HA  I43  J4B1
   2    GND VSS<93> @BASEBOARD_FAB2_LIB.BASEBOARD_FAB2(SCH_1):GND
   4    GND VSS<92> @BASEBOARD_FAB2_LIB.BASEBOARD_FAB2(SCH_1):GND
   6    GND VSS<91> @BASEBOARD_FAB2_LIB.BASEBOARD_FAB2(SCH_1):GND
   9    GND VSS<90> @BASEBOARD_FAB2_LIB.BASEBOARD_FAB2(SCH_1):GND
  11    GND VSS<89> @BASEBOARD_FAB2_LIB.BASEBOARD_FAB2(SCH_1):GND
  13    GND VSS<88> @BASEBOARD_FAB2_LIB.BASEBOARD_FAB2(SCH_1):GND
  15    GND VSS<87> @BASEBOARD_FAB2_LIB.BASEBOARD_FAB2(SCH_1):GND
  17    GND VSS<86> @BASEBOARD_FAB2_LIB.BASEBOARD_FAB2(SCH_1):GND
  20    GND VSS<85> @BASEBOARD_FAB2_LIB.BASEBOARD_FAB2(SCH_1):GND
  22    GND VSS<84> @BASEBOARD_FAB2_LIB.BASEBOARD_FAB2(SCH_1):GND
  24    GND VSS<83> @BASEBOARD_FAB2_LIB.BASEBOARD_FAB2(SCH_1):GND
  26    GND VSS<82> @BASEBOARD_FAB2_LIB.BASEBOARD_FAB2(SCH_1):GND
  28    GND VSS<81> @BASEBOARD_FAB2_LIB.BASEBOARD_FAB2(SCH_1):GND
  31    GND VSS<80> @BASEBOARD_FAB2_LIB.BASEBOARD_FAB2(SCH_1):GND
  33    GND VSS<79> @BASEBOARD_FAB2_LIB.BASEBOARD_FAB2(SCH_1):GND
  35    GND VSS<78> @BASEBOARD_FAB2_LIB.BASEBOARD_FAB2(SCH_1):GND
  37    GND VSS<77> @BASEBOARD_FAB2_LIB.BASEBOARD_FAB2(SCH_1):GND
  39    GND VSS<76> @BASEBOARD_FAB2_LIB.BASEBOARD_FAB2(SCH_1):GND
  42    GND VSS<75> @BASEBOARD_FAB2_LIB.BASEBOARD_FAB2(SCH_1):GND
  44    GND VSS<74> @BASEBOARD_FAB2_LIB.BASEBOARD_FAB2(SCH_1):GND
  46    GND VSS<73> @BASEBOARD_FAB2_LIB.BASEBOARD_FAB2(SCH_1):GND
  48    GND VSS<72> @BASEBOARD_FAB2_LIB.BASEBOARD_FAB2(SCH_1):GND
  50    GND VSS<71> @BASEBOARD_FAB2_LIB.BASEBOARD_FAB2(SCH_1):GND
  53    GND VSS<70> @BASEBOARD_FAB2_LIB.BASEBOARD_FAB2(SCH_1):GND
  55    GND VSS<69> @BASEBOARD_FAB2_LIB.BASEBOARD_FAB2(SCH_1):GND
  57    GND VSS<68> @BASEBOARD_FAB2_LIB.BASEBOARD_FAB2(SCH_1):GND
  94    GND VSS<67> @BASEBOARD_FAB2_LIB.BASEBOARD_FAB2(SCH_1):GND
  96    GND VSS<66> @BASEBOARD_FAB2_LIB.BASEBOARD_FAB2(SCH_1):GND
  98    GND VSS<65> @BASEBOARD_FAB2_LIB.BASEBOARD_FAB2(SCH_1):GND
 101    GND VSS<64> @BASEBOARD_FAB2_LIB.BASEBOARD_FAB2(SCH_1):GND
 103    GND VSS<63> @BASEBOARD_FAB2_LIB.BASEBOARD_FAB2(SCH_1):GND
 105    GND VSS<62> @BASEBOARD_FAB2_LIB.BASEBOARD_FAB2(SCH_1):GND
 107    GND VSS<61> @BASEBOARD_FAB2_LIB.BASEBOARD_FAB2(SCH_1):GND
 109    GND VSS<60> @BASEBOARD_FAB2_LIB.BASEBOARD_FAB2(SCH_1):GND
 112    GND VSS<59> @BASEBOARD_FAB2_LIB.BASEBOARD_FAB2(SCH_1):GND
 114    GND VSS<58> @BASEBOARD_FAB2_LIB.BASEBOARD_FAB2(SCH_1):GND
 116    GND VSS<57> @BASEBOARD_FAB2_LIB.BASEBOARD_FAB2(SCH_1):GND
 118    GND VSS<56> @BASEBOARD_FAB2_LIB.BASEBOARD_FAB2(SCH_1):GND
 120    GND VSS<55> @BASEBOARD_FAB2_LIB.BASEBOARD_FAB2(SCH_1):GND
 123    GND VSS<54> @BASEBOARD_FAB2_LIB.BASEBOARD_FAB2(SCH_1):GND
 125    GND VSS<53> @BASEBOARD_FAB2_LIB.BASEBOARD_FAB2(SCH_1):GND
 127    GND VSS<52> @BASEBOARD_FAB2_LIB.BASEBOARD_FAB2(SCH_1):GND
 129    GND VSS<51> @BASEBOARD_FAB2_LIB.BASEBOARD_FAB2(SCH_1):GND
 131    GND VSS<50> @BASEBOARD_FAB2_LIB.BASEBOARD_FAB2(SCH_1):GND
 134    GND VSS<49> @BASEBOARD_FAB2_LIB.BASEBOARD_FAB2(SCH_1):GND
 136    GND VSS<48> @BASEBOARD_FAB2_LIB.BASEBOARD_FAB2(SCH_1):GND
 138    GND VSS<47> @BASEBOARD_FAB2_LIB.BASEBOARD_FAB2(SCH_1):GND
 147    GND VSS<46> @BASEBOARD_FAB2_LIB.BASEBOARD_FAB2(SCH_1):GND
 149    GND VSS<45> @BASEBOARD_FAB2_LIB.BASEBOARD_FAB2(SCH_1):GND
 151    GND VSS<44> @BASEBOARD_FAB2_LIB.BASEBOARD_FAB2(SCH_1):GND
 154    GND VSS<43> @BASEBOARD_FAB2_LIB.BASEBOARD_FAB2(SCH_1):GND
 156    GND VSS<42> @BASEBOARD_FAB2_LIB.BASEBOARD_FAB2(SCH_1):GND
 158    GND VSS<41> @BASEBOARD_FAB2_LIB.BASEBOARD_FAB2(SCH_1):GND
 160    GND VSS<40> @BASEBOARD_FAB2_LIB.BASEBOARD_FAB2(SCH_1):GND
 162    GND VSS<39> @BASEBOARD_FAB2_LIB.BASEBOARD_FAB2(SCH_1):GND
 165    GND VSS<38> @BASEBOARD_FAB2_LIB.BASEBOARD_FAB2(SCH_1):GND
 167    GND VSS<37> @BASEBOARD_FAB2_LIB.BASEBOARD_FAB2(SCH_1):GND
 169    GND VSS<36> @BASEBOARD_FAB2_LIB.BASEBOARD_FAB2(SCH_1):GND
 171    GND VSS<35> @BASEBOARD_FAB2_LIB.BASEBOARD_FAB2(SCH_1):GND
 173    GND VSS<34> @BASEBOARD_FAB2_LIB.BASEBOARD_FAB2(SCH_1):GND
 176    GND VSS<33> @BASEBOARD_FAB2_LIB.BASEBOARD_FAB2(SCH_1):GND
 178    GND VSS<32> @BASEBOARD_FAB2_LIB.BASEBOARD_FAB2(SCH_1):GND
 180    GND VSS<31> @BASEBOARD_FAB2_LIB.BASEBOARD_FAB2(SCH_1):GND
 182    GND VSS<30> @BASEBOARD_FAB2_LIB.BASEBOARD_FAB2(SCH_1):GND
 184    GND VSS<29> @BASEBOARD_FAB2_LIB.BASEBOARD_FAB2(SCH_1):GND
 187    GND VSS<28> @BASEBOARD_FAB2_LIB.BASEBOARD_FAB2(SCH_1):GND
 189    GND VSS<27> @BASEBOARD_FAB2_LIB.BASEBOARD_FAB2(SCH_1):GND
 191    GND VSS<26> @BASEBOARD_FAB2_LIB.BASEBOARD_FAB2(SCH_1):GND
 193    GND VSS<25> @BASEBOARD_FAB2_LIB.BASEBOARD_FAB2(SCH_1):GND
 195    GND VSS<24> @BASEBOARD_FAB2_LIB.BASEBOARD_FAB2(SCH_1):GND
 198    GND VSS<23> @BASEBOARD_FAB2_LIB.BASEBOARD_FAB2(SCH_1):GND
 200    GND VSS<22> @BASEBOARD_FAB2_LIB.BASEBOARD_FAB2(SCH_1):GND
 202    GND VSS<21> @BASEBOARD_FAB2_LIB.BASEBOARD_FAB2(SCH_1):GND
 239    GND VSS<20> @BASEBOARD_FAB2_LIB.BASEBOARD_FAB2(SCH_1):GND
 241    GND VSS<19> @BASEBOARD_FAB2_LIB.BASEBOARD_FAB2(SCH_1):GND
 243    GND VSS<18> @BASEBOARD_FAB2_LIB.BASEBOARD_FAB2(SCH_1):GND
 246    GND VSS<17> @BASEBOARD_FAB2_LIB.BASEBOARD_FAB2(SCH_1):GND
 248    GND VSS<16> @BASEBOARD_FAB2_LIB.BASEBOARD_FAB2(SCH_1):GND
 250    GND VSS<15> @BASEBOARD_FAB2_LIB.BASEBOARD_FAB2(SCH_1):GND
 252    GND VSS<14> @BASEBOARD_FAB2_LIB.BASEBOARD_FAB2(SCH_1):GND
 254    GND VSS<13> @BASEBOARD_FAB2_LIB.BASEBOARD_FAB2(SCH_1):GND
 257    GND VSS<12> @BASEBOARD_FAB2_LIB.BASEBOARD_FAB2(SCH_1):GND
 259    GND VSS<11> @BASEBOARD_FAB2_LIB.BASEBOARD_FAB2(SCH_1):GND
 261    GND VSS<10> @BASEBOARD_FAB2_LIB.BASEBOARD_FAB2(SCH_1):GND
 263    GND VSS<9> @BASEBOARD_FAB2_LIB.BASEBOARD_FAB2(SCH_1):GND
 265    GND VSS<8> @BASEBOARD_FAB2_LIB.BASEBOARD_FAB2(SCH_1):GND
 268    GND VSS<7> @BASEBOARD_FAB2_LIB.BASEBOARD_FAB2(SCH_1):GND
 270    GND VSS<6> @BASEBOARD_FAB2_LIB.BASEBOARD_FAB2(SCH_1):GND
 272    GND VSS<5> @BASEBOARD_FAB2_LIB.BASEBOARD_FAB2(SCH_1):GND
 274    GND VSS<4> @BASEBOARD_FAB2_LIB.BASEBOARD_FAB2(SCH_1):GND
 276    GND VSS<3> @BASEBOARD_FAB2_LIB.BASEBOARD_FAB2(SCH_1):GND
 279    GND VSS<2> @BASEBOARD_FAB2_LIB.BASEBOARD_FAB2(SCH_1):GND
 281    GND VSS<1> @BASEBOARD_FAB2_LIB.BASEBOARD_FAB2(SCH_1):GND
 283    GND VSS<0> @BASEBOARD_FAB2_LIB.BASEBOARD_FAB2(SCH_1):GND

SCONN288_H44441004_PIP-SCONN,HA  I66  J4B1
 152 M_D_DQS_DN<0>  DQS0N @BASEBOARD_FAB2_LIB.BASEBOARD_FAB2(SCH_1):M_D_DQS_DN(0)
 153 M_D_DQS_DP<0>  DQS0P @BASEBOARD_FAB2_LIB.BASEBOARD_FAB2(SCH_1):M_D_DQS_DP(0)
  19 M_D_DQS_DN<10> DQS10N @BASEBOARD_FAB2_LIB.BASEBOARD_FAB2(SCH_1):M_D_DQS_DN(10)
  18 M_D_DQS_DP<10> DQS10P @BASEBOARD_FAB2_LIB.BASEBOARD_FAB2(SCH_1):M_D_DQS_DP(10)
  30 M_D_DQS_DN<11> DQS11N @BASEBOARD_FAB2_LIB.BASEBOARD_FAB2(SCH_1):M_D_DQS_DN(11)
  29 M_D_DQS_DP<11> DQS11P @BASEBOARD_FAB2_LIB.BASEBOARD_FAB2(SCH_1):M_D_DQS_DP(11)
  41 M_D_DQS_DN<12> DQS12N @BASEBOARD_FAB2_LIB.BASEBOARD_FAB2(SCH_1):M_D_DQS_DN(12)
  40 M_D_DQS_DP<12> DQS12P @BASEBOARD_FAB2_LIB.BASEBOARD_FAB2(SCH_1):M_D_DQS_DP(12)
 100 M_D_DQS_DN<13> DQS13N @BASEBOARD_FAB2_LIB.BASEBOARD_FAB2(SCH_1):M_D_DQS_DN(13)
  99 M_D_DQS_DP<13> DQS13P @BASEBOARD_FAB2_LIB.BASEBOARD_FAB2(SCH_1):M_D_DQS_DP(13)
 111 M_D_DQS_DN<14> DQS14N @BASEBOARD_FAB2_LIB.BASEBOARD_FAB2(SCH_1):M_D_DQS_DN(14)
 110 M_D_DQS_DP<14> DQS14P @BASEBOARD_FAB2_LIB.BASEBOARD_FAB2(SCH_1):M_D_DQS_DP(14)
 122 M_D_DQS_DN<15> DQS15N @BASEBOARD_FAB2_LIB.BASEBOARD_FAB2(SCH_1):M_D_DQS_DN(15)
 121 M_D_DQS_DP<15> DQS15P @BASEBOARD_FAB2_LIB.BASEBOARD_FAB2(SCH_1):M_D_DQS_DP(15)
 133 M_D_DQS_DN<16> DQS16N @BASEBOARD_FAB2_LIB.BASEBOARD_FAB2(SCH_1):M_D_DQS_DN(16)
 132 M_D_DQS_DP<16> DQS16P @BASEBOARD_FAB2_LIB.BASEBOARD_FAB2(SCH_1):M_D_DQS_DP(16)
  52 M_D_DQS_DN<17> DQS17N @BASEBOARD_FAB2_LIB.BASEBOARD_FAB2(SCH_1):M_D_DQS_DN(17)
  51 M_D_DQS_DP<17> DQS17P @BASEBOARD_FAB2_LIB.BASEBOARD_FAB2(SCH_1):M_D_DQS_DP(17)
 163 M_D_DQS_DN<1>  DQS1N @BASEBOARD_FAB2_LIB.BASEBOARD_FAB2(SCH_1):M_D_DQS_DN(1)
 164 M_D_DQS_DP<1>  DQS1P @BASEBOARD_FAB2_LIB.BASEBOARD_FAB2(SCH_1):M_D_DQS_DP(1)
 174 M_D_DQS_DN<2>  DQS2N @BASEBOARD_FAB2_LIB.BASEBOARD_FAB2(SCH_1):M_D_DQS_DN(2)
 175 M_D_DQS_DP<2>  DQS2P @BASEBOARD_FAB2_LIB.BASEBOARD_FAB2(SCH_1):M_D_DQS_DP(2)
 185 M_D_DQS_DN<3>  DQS3N @BASEBOARD_FAB2_LIB.BASEBOARD_FAB2(SCH_1):M_D_DQS_DN(3)
 186 M_D_DQS_DP<3>  DQS3P @BASEBOARD_FAB2_LIB.BASEBOARD_FAB2(SCH_1):M_D_DQS_DP(3)
 244 M_D_DQS_DN<4>  DQS4N @BASEBOARD_FAB2_LIB.BASEBOARD_FAB2(SCH_1):M_D_DQS_DN(4)
 245 M_D_DQS_DP<4>  DQS4P @BASEBOARD_FAB2_LIB.BASEBOARD_FAB2(SCH_1):M_D_DQS_DP(4)
 255 M_D_DQS_DN<5>  DQS5N @BASEBOARD_FAB2_LIB.BASEBOARD_FAB2(SCH_1):M_D_DQS_DN(5)
 256 M_D_DQS_DP<5>  DQS5P @BASEBOARD_FAB2_LIB.BASEBOARD_FAB2(SCH_1):M_D_DQS_DP(5)
 266 M_D_DQS_DN<6>  DQS6N @BASEBOARD_FAB2_LIB.BASEBOARD_FAB2(SCH_1):M_D_DQS_DN(6)
 267 M_D_DQS_DP<6>  DQS6P @BASEBOARD_FAB2_LIB.BASEBOARD_FAB2(SCH_1):M_D_DQS_DP(6)
 277 M_D_DQS_DN<7>  DQS7N @BASEBOARD_FAB2_LIB.BASEBOARD_FAB2(SCH_1):M_D_DQS_DN(7)
 278 M_D_DQS_DP<7>  DQS7P @BASEBOARD_FAB2_LIB.BASEBOARD_FAB2(SCH_1):M_D_DQS_DP(7)
 196 M_D_DQS_DN<8>  DQS8N @BASEBOARD_FAB2_LIB.BASEBOARD_FAB2(SCH_1):M_D_DQS_DN(8)
 197 M_D_DQS_DP<8>  DQS8P @BASEBOARD_FAB2_LIB.BASEBOARD_FAB2(SCH_1):M_D_DQS_DP(8)
   8 M_D_DQS_DN<9>  DQS9N @BASEBOARD_FAB2_LIB.BASEBOARD_FAB2(SCH_1):M_D_DQS_DN(9)
   7 M_D_DQS_DP<9>  DQS9P @BASEBOARD_FAB2_LIB.BASEBOARD_FAB2(SCH_1):M_D_DQS_DP(9)

SCONN288_H44441004_PIP-SCONN,HA  I111  J4B1
  79 M_D_MA<0>     A0 @BASEBOARD_FAB2_LIB.BASEBOARD_FAB2(SCH_1):M_D_MA(0)
  72 M_D_MA<1>     A1 @BASEBOARD_FAB2_LIB.BASEBOARD_FAB2(SCH_1):M_D_MA(1)
 225 M_D_MA<10>    A10 @BASEBOARD_FAB2_LIB.BASEBOARD_FAB2(SCH_1):M_D_MA(10)
 210 M_D_MA<11>    A11 @BASEBOARD_FAB2_LIB.BASEBOARD_FAB2(SCH_1):M_D_MA(11)
  65 M_D_MA<12>    A12 @BASEBOARD_FAB2_LIB.BASEBOARD_FAB2(SCH_1):M_D_MA(12)
 232 M_D_MA<13>    A13 @BASEBOARD_FAB2_LIB.BASEBOARD_FAB2(SCH_1):M_D_MA(13)
 228 M_D_MA<14> A14_WE_N @BASEBOARD_FAB2_LIB.BASEBOARD_FAB2(SCH_1):M_D_MA(14)
  86 M_D_MA<15> A15_CAS_N @BASEBOARD_FAB2_LIB.BASEBOARD_FAB2(SCH_1):M_D_MA(15)
  82 M_D_MA<16> A16_RAS_N @BASEBOARD_FAB2_LIB.BASEBOARD_FAB2(SCH_1):M_D_MA(16)
 234 M_D_MA<17>    A17 @BASEBOARD_FAB2_LIB.BASEBOARD_FAB2(SCH_1):M_D_MA(17)
 216 M_D_MA<2>     A2 @BASEBOARD_FAB2_LIB.BASEBOARD_FAB2(SCH_1):M_D_MA(2)
  71 M_D_MA<3>     A3 @BASEBOARD_FAB2_LIB.BASEBOARD_FAB2(SCH_1):M_D_MA(3)
 214 M_D_MA<4>     A4 @BASEBOARD_FAB2_LIB.BASEBOARD_FAB2(SCH_1):M_D_MA(4)
 213 M_D_MA<5>     A5 @BASEBOARD_FAB2_LIB.BASEBOARD_FAB2(SCH_1):M_D_MA(5)
  69 M_D_MA<6>     A6 @BASEBOARD_FAB2_LIB.BASEBOARD_FAB2(SCH_1):M_D_MA(6)
 211 M_D_MA<7>     A7 @BASEBOARD_FAB2_LIB.BASEBOARD_FAB2(SCH_1):M_D_MA(7)
  68 M_D_MA<8>     A8 @BASEBOARD_FAB2_LIB.BASEBOARD_FAB2(SCH_1):M_D_MA(8)
  66 M_D_MA<9>     A9 @BASEBOARD_FAB2_LIB.BASEBOARD_FAB2(SCH_1):M_D_MA(9)
  62 M_D_ACT_N  ACT_N @BASEBOARD_FAB2_LIB.BASEBOARD_FAB2(SCH_1):M_D_ACT_N
 208 M_D_ALERT_N ALERT_N @BASEBOARD_FAB2_LIB.BASEBOARD_FAB2(SCH_1):M_D_ALERT_N
 224 M_D_BA<1>  BA<1> @BASEBOARD_FAB2_LIB.BASEBOARD_FAB2(SCH_1):M_D_BA(1)
  81 M_D_BA<0>  BA<0> @BASEBOARD_FAB2_LIB.BASEBOARD_FAB2(SCH_1):M_D_BA(0)
 207 M_D_BG<1>  BG<1> @BASEBOARD_FAB2_LIB.BASEBOARD_FAB2(SCH_1):M_D_BG(1)
  63 M_D_BG<0>  BG<0> @BASEBOARD_FAB2_LIB.BASEBOARD_FAB2(SCH_1):M_D_BG(0)
 235 M_D_C<2>   C<2> @BASEBOARD_FAB2_LIB.BASEBOARD_FAB2(SCH_1):M_D_C(2)
 199 M_D_ECC<6>  CB<7> @BASEBOARD_FAB2_LIB.BASEBOARD_FAB2(SCH_1):M_D_ECC(6)
  54 M_D_ECC<7>  CB<6> @BASEBOARD_FAB2_LIB.BASEBOARD_FAB2(SCH_1):M_D_ECC(7)
 192 M_D_ECC<4>  CB<5> @BASEBOARD_FAB2_LIB.BASEBOARD_FAB2(SCH_1):M_D_ECC(4)
  47 M_D_ECC<5>  CB<4> @BASEBOARD_FAB2_LIB.BASEBOARD_FAB2(SCH_1):M_D_ECC(5)
 201 M_D_ECC<2>  CB<3> @BASEBOARD_FAB2_LIB.BASEBOARD_FAB2(SCH_1):M_D_ECC(2)
  56 M_D_ECC<3>  CB<2> @BASEBOARD_FAB2_LIB.BASEBOARD_FAB2(SCH_1):M_D_ECC(3)
 194 M_D_ECC<0>  CB<1> @BASEBOARD_FAB2_LIB.BASEBOARD_FAB2(SCH_1):M_D_ECC(0)
  49 M_D_ECC<1>  CB<0> @BASEBOARD_FAB2_LIB.BASEBOARD_FAB2(SCH_1):M_D_ECC(1)
  75 M_D_CLK_DN<0>   CK0N @BASEBOARD_FAB2_LIB.BASEBOARD_FAB2(SCH_1):M_D_CLK_DN(0)
  74 M_D_CLK_DP<0>   CK0P @BASEBOARD_FAB2_LIB.BASEBOARD_FAB2(SCH_1):M_D_CLK_DP(0)
 219 M_D_CLK_DN<1>   CK1N @BASEBOARD_FAB2_LIB.BASEBOARD_FAB2(SCH_1):M_D_CLK_DN(1)
 218 M_D_CLK_DP<1>   CK1P @BASEBOARD_FAB2_LIB.BASEBOARD_FAB2(SCH_1):M_D_CLK_DP(1)
 203 M_D_CKE<1> CKE<1> @BASEBOARD_FAB2_LIB.BASEBOARD_FAB2(SCH_1):M_D_CKE(1)
  60 M_D_CKE<0> CKE<0> @BASEBOARD_FAB2_LIB.BASEBOARD_FAB2(SCH_1):M_D_CKE(0)
 280 M_D_DQ<62> DQ<63> @BASEBOARD_FAB2_LIB.BASEBOARD_FAB2(SCH_1):M_D_DQ(62)
 135 M_D_DQ<63> DQ<62> @BASEBOARD_FAB2_LIB.BASEBOARD_FAB2(SCH_1):M_D_DQ(63)
 273 M_D_DQ<60> DQ<61> @BASEBOARD_FAB2_LIB.BASEBOARD_FAB2(SCH_1):M_D_DQ(60)
 128 M_D_DQ<61> DQ<60> @BASEBOARD_FAB2_LIB.BASEBOARD_FAB2(SCH_1):M_D_DQ(61)
 282 M_D_DQ<58> DQ<59> @BASEBOARD_FAB2_LIB.BASEBOARD_FAB2(SCH_1):M_D_DQ(58)
 137 M_D_DQ<59> DQ<58> @BASEBOARD_FAB2_LIB.BASEBOARD_FAB2(SCH_1):M_D_DQ(59)
 275 M_D_DQ<56> DQ<57> @BASEBOARD_FAB2_LIB.BASEBOARD_FAB2(SCH_1):M_D_DQ(56)
 130 M_D_DQ<57> DQ<56> @BASEBOARD_FAB2_LIB.BASEBOARD_FAB2(SCH_1):M_D_DQ(57)
 269 M_D_DQ<54> DQ<55> @BASEBOARD_FAB2_LIB.BASEBOARD_FAB2(SCH_1):M_D_DQ(54)
 124 M_D_DQ<55> DQ<54> @BASEBOARD_FAB2_LIB.BASEBOARD_FAB2(SCH_1):M_D_DQ(55)
 262 M_D_DQ<52> DQ<53> @BASEBOARD_FAB2_LIB.BASEBOARD_FAB2(SCH_1):M_D_DQ(52)
 117 M_D_DQ<53> DQ<52> @BASEBOARD_FAB2_LIB.BASEBOARD_FAB2(SCH_1):M_D_DQ(53)
 271 M_D_DQ<50> DQ<51> @BASEBOARD_FAB2_LIB.BASEBOARD_FAB2(SCH_1):M_D_DQ(50)
 126 M_D_DQ<51> DQ<50> @BASEBOARD_FAB2_LIB.BASEBOARD_FAB2(SCH_1):M_D_DQ(51)
 264 M_D_DQ<48> DQ<49> @BASEBOARD_FAB2_LIB.BASEBOARD_FAB2(SCH_1):M_D_DQ(48)
 119 M_D_DQ<49> DQ<48> @BASEBOARD_FAB2_LIB.BASEBOARD_FAB2(SCH_1):M_D_DQ(49)
 258 M_D_DQ<46> DQ<47> @BASEBOARD_FAB2_LIB.BASEBOARD_FAB2(SCH_1):M_D_DQ(46)
 113 M_D_DQ<47> DQ<46> @BASEBOARD_FAB2_LIB.BASEBOARD_FAB2(SCH_1):M_D_DQ(47)
 251 M_D_DQ<44> DQ<45> @BASEBOARD_FAB2_LIB.BASEBOARD_FAB2(SCH_1):M_D_DQ(44)
 106 M_D_DQ<45> DQ<44> @BASEBOARD_FAB2_LIB.BASEBOARD_FAB2(SCH_1):M_D_DQ(45)
 260 M_D_DQ<42> DQ<43> @BASEBOARD_FAB2_LIB.BASEBOARD_FAB2(SCH_1):M_D_DQ(42)
 115 M_D_DQ<43> DQ<42> @BASEBOARD_FAB2_LIB.BASEBOARD_FAB2(SCH_1):M_D_DQ(43)
 253 M_D_DQ<40> DQ<41> @BASEBOARD_FAB2_LIB.BASEBOARD_FAB2(SCH_1):M_D_DQ(40)
 108 M_D_DQ<41> DQ<40> @BASEBOARD_FAB2_LIB.BASEBOARD_FAB2(SCH_1):M_D_DQ(41)
 247 M_D_DQ<38> DQ<39> @BASEBOARD_FAB2_LIB.BASEBOARD_FAB2(SCH_1):M_D_DQ(38)
 102 M_D_DQ<39> DQ<38> @BASEBOARD_FAB2_LIB.BASEBOARD_FAB2(SCH_1):M_D_DQ(39)
 240 M_D_DQ<36> DQ<37> @BASEBOARD_FAB2_LIB.BASEBOARD_FAB2(SCH_1):M_D_DQ(36)
  95 M_D_DQ<37> DQ<36> @BASEBOARD_FAB2_LIB.BASEBOARD_FAB2(SCH_1):M_D_DQ(37)
 249 M_D_DQ<34> DQ<35> @BASEBOARD_FAB2_LIB.BASEBOARD_FAB2(SCH_1):M_D_DQ(34)
 104 M_D_DQ<35> DQ<34> @BASEBOARD_FAB2_LIB.BASEBOARD_FAB2(SCH_1):M_D_DQ(35)
 242 M_D_DQ<32> DQ<33> @BASEBOARD_FAB2_LIB.BASEBOARD_FAB2(SCH_1):M_D_DQ(32)
  97 M_D_DQ<33> DQ<32> @BASEBOARD_FAB2_LIB.BASEBOARD_FAB2(SCH_1):M_D_DQ(33)
 188 M_D_DQ<30> DQ<31> @BASEBOARD_FAB2_LIB.BASEBOARD_FAB2(SCH_1):M_D_DQ(30)
  43 M_D_DQ<31> DQ<30> @BASEBOARD_FAB2_LIB.BASEBOARD_FAB2(SCH_1):M_D_DQ(31)
 181 M_D_DQ<28> DQ<29> @BASEBOARD_FAB2_LIB.BASEBOARD_FAB2(SCH_1):M_D_DQ(28)
  36 M_D_DQ<29> DQ<28> @BASEBOARD_FAB2_LIB.BASEBOARD_FAB2(SCH_1):M_D_DQ(29)
 190 M_D_DQ<26> DQ<27> @BASEBOARD_FAB2_LIB.BASEBOARD_FAB2(SCH_1):M_D_DQ(26)
  45 M_D_DQ<27> DQ<26> @BASEBOARD_FAB2_LIB.BASEBOARD_FAB2(SCH_1):M_D_DQ(27)
 183 M_D_DQ<24> DQ<25> @BASEBOARD_FAB2_LIB.BASEBOARD_FAB2(SCH_1):M_D_DQ(24)
  38 M_D_DQ<25> DQ<24> @BASEBOARD_FAB2_LIB.BASEBOARD_FAB2(SCH_1):M_D_DQ(25)
 177 M_D_DQ<22> DQ<23> @BASEBOARD_FAB2_LIB.BASEBOARD_FAB2(SCH_1):M_D_DQ(22)
  32 M_D_DQ<23> DQ<22> @BASEBOARD_FAB2_LIB.BASEBOARD_FAB2(SCH_1):M_D_DQ(23)
 170 M_D_DQ<20> DQ<21> @BASEBOARD_FAB2_LIB.BASEBOARD_FAB2(SCH_1):M_D_DQ(20)
  25 M_D_DQ<21> DQ<20> @BASEBOARD_FAB2_LIB.BASEBOARD_FAB2(SCH_1):M_D_DQ(21)
 179 M_D_DQ<18> DQ<19> @BASEBOARD_FAB2_LIB.BASEBOARD_FAB2(SCH_1):M_D_DQ(18)
  34 M_D_DQ<19> DQ<18> @BASEBOARD_FAB2_LIB.BASEBOARD_FAB2(SCH_1):M_D_DQ(19)
 172 M_D_DQ<16> DQ<17> @BASEBOARD_FAB2_LIB.BASEBOARD_FAB2(SCH_1):M_D_DQ(16)
  27 M_D_DQ<17> DQ<16> @BASEBOARD_FAB2_LIB.BASEBOARD_FAB2(SCH_1):M_D_DQ(17)
 166 M_D_DQ<14> DQ<15> @BASEBOARD_FAB2_LIB.BASEBOARD_FAB2(SCH_1):M_D_DQ(14)
  21 M_D_DQ<15> DQ<14> @BASEBOARD_FAB2_LIB.BASEBOARD_FAB2(SCH_1):M_D_DQ(15)
 159 M_D_DQ<12> DQ<13> @BASEBOARD_FAB2_LIB.BASEBOARD_FAB2(SCH_1):M_D_DQ(12)
  14 M_D_DQ<13> DQ<12> @BASEBOARD_FAB2_LIB.BASEBOARD_FAB2(SCH_1):M_D_DQ(13)
 168 M_D_DQ<10> DQ<11> @BASEBOARD_FAB2_LIB.BASEBOARD_FAB2(SCH_1):M_D_DQ(10)
  23 M_D_DQ<11> DQ<10> @BASEBOARD_FAB2_LIB.BASEBOARD_FAB2(SCH_1):M_D_DQ(11)
 161 M_D_DQ<8>  DQ<9> @BASEBOARD_FAB2_LIB.BASEBOARD_FAB2(SCH_1):M_D_DQ(8)
  16 M_D_DQ<9>  DQ<8> @BASEBOARD_FAB2_LIB.BASEBOARD_FAB2(SCH_1):M_D_DQ(9)
 155 M_D_DQ<6>  DQ<7> @BASEBOARD_FAB2_LIB.BASEBOARD_FAB2(SCH_1):M_D_DQ(6)
  10 M_D_DQ<7>  DQ<6> @BASEBOARD_FAB2_LIB.BASEBOARD_FAB2(SCH_1):M_D_DQ(7)
 148 M_D_DQ<4>  DQ<5> @BASEBOARD_FAB2_LIB.BASEBOARD_FAB2(SCH_1):M_D_DQ(4)
   3 M_D_DQ<5>  DQ<4> @BASEBOARD_FAB2_LIB.BASEBOARD_FAB2(SCH_1):M_D_DQ(5)
 157 M_D_DQ<2>  DQ<3> @BASEBOARD_FAB2_LIB.BASEBOARD_FAB2(SCH_1):M_D_DQ(2)
  12 M_D_DQ<3>  DQ<2> @BASEBOARD_FAB2_LIB.BASEBOARD_FAB2(SCH_1):M_D_DQ(3)
 150 M_D_DQ<0>  DQ<1> @BASEBOARD_FAB2_LIB.BASEBOARD_FAB2(SCH_1):M_D_DQ(0)
   5 M_D_DQ<1>  DQ<0> @BASEBOARD_FAB2_LIB.BASEBOARD_FAB2(SCH_1):M_D_DQ(1)
  78 FM_DIMM_EVENT_COD_N EVENT_N @BASEBOARD_FAB2_LIB.BASEBOARD_FAB2(SCH_1):FM_DIMM_EVENT_COD_N
  91 M_D_ODT<1> ODT<1> @BASEBOARD_FAB2_LIB.BASEBOARD_FAB2(SCH_1):M_D_ODT(1)
  87 M_D_ODT<0> ODT<0> @BASEBOARD_FAB2_LIB.BASEBOARD_FAB2(SCH_1):M_D_ODT(0)
 222 M_D_PAR    PAR @BASEBOARD_FAB2_LIB.BASEBOARD_FAB2(SCH_1):M_D_PAR
  58 M_DEF_RST_N RESET_N @BASEBOARD_FAB2_LIB.BASEBOARD_FAB2(SCH_1):M_DEF_RST_N
 144 TP_CH_D_DIMM_D0_RFU_2 RFU<2> @BASEBOARD_FAB2_LIB.BASEBOARD_FAB2(SCH_1):TP_CH_D_DIMM_D0_RFU_2
 227 TP_CH_D_DIMM_D0_RFU_1 RFU<1> @BASEBOARD_FAB2_LIB.BASEBOARD_FAB2(SCH_1):TP_CH_D_DIMM_D0_RFU_1
 205 TP_CH_D_DIMM_D0_RFU_0 RFU<0> @BASEBOARD_FAB2_LIB.BASEBOARD_FAB2(SCH_1):TP_CH_D_DIMM_D0_RFU_0
  84 M_D_CS_N<0>   S0_N @BASEBOARD_FAB2_LIB.BASEBOARD_FAB2(SCH_1):M_D_CS_N(0)
  89 M_D_CS_N<1>   S1_N @BASEBOARD_FAB2_LIB.BASEBOARD_FAB2(SCH_1):M_D_CS_N(1)
  93 M_D_CS_N<2> S2_N_C<0> @BASEBOARD_FAB2_LIB.BASEBOARD_FAB2(SCH_1):M_D_CS_N(2)
 237 M_D_CS_N<3> S3_N_C<1> @BASEBOARD_FAB2_LIB.BASEBOARD_FAB2(SCH_1):M_D_CS_N(3)
 238    GND  SA<2> @BASEBOARD_FAB2_LIB.BASEBOARD_FAB2(SCH_1):GND
 140    GND  SA<1> @BASEBOARD_FAB2_LIB.BASEBOARD_FAB2(SCH_1):GND
 139    GND  SA<0> @BASEBOARD_FAB2_LIB.BASEBOARD_FAB2(SCH_1):GND
 230 FM_ADR_COMPLETE_DEF_N SAVE_N_NC @BASEBOARD_FAB2_LIB.BASEBOARD_FAB2(SCH_1):FM_ADR_COMPLETE_DEF_N
 141 SMB_DDR_DEF_VPP_SCL    SCL @BASEBOARD_FAB2_LIB.BASEBOARD_FAB2(SCH_1):SMB_DDR_DEF_VPP_SCL
 285 SMB_DDR_DEF_VPP_SDA    SDA @BASEBOARD_FAB2_LIB.BASEBOARD_FAB2(SCH_1):SMB_DDR_DEF_VPP_SDA
 284 PVPP_DEF VDDSPD @BASEBOARD_FAB2_LIB.BASEBOARD_FAB2(SCH_1):PVPP_DEF
 146 M_D_VREF VREFCA @BASEBOARD_FAB2_LIB.BASEBOARD_FAB2(SCH_1):M_D_VREF

SCONN288_H44441004_PIP-SCONN,HA  I169  J4B1
   1 P12V_NVDIMM_DEF 12V<1> @BASEBOARD_FAB2_LIB.BASEBOARD_FAB2(SCH_1):P12V_NVDIMM_DEF
 145 P12V_NVDIMM_DEF 12V<0> @BASEBOARD_FAB2_LIB.BASEBOARD_FAB2(SCH_1):P12V_NVDIMM_DEF
  59 PVDDQ_DEF VDD<25> @BASEBOARD_FAB2_LIB.BASEBOARD_FAB2(SCH_1):PVDDQ_DEF
  61 PVDDQ_DEF VDD<24> @BASEBOARD_FAB2_LIB.BASEBOARD_FAB2(SCH_1):PVDDQ_DEF
  64 PVDDQ_DEF VDD<23> @BASEBOARD_FAB2_LIB.BASEBOARD_FAB2(SCH_1):PVDDQ_DEF
  67 PVDDQ_DEF VDD<22> @BASEBOARD_FAB2_LIB.BASEBOARD_FAB2(SCH_1):PVDDQ_DEF
  70 PVDDQ_DEF VDD<21> @BASEBOARD_FAB2_LIB.BASEBOARD_FAB2(SCH_1):PVDDQ_DEF
  73 PVDDQ_DEF VDD<20> @BASEBOARD_FAB2_LIB.BASEBOARD_FAB2(SCH_1):PVDDQ_DEF
  76 PVDDQ_DEF VDD<19> @BASEBOARD_FAB2_LIB.BASEBOARD_FAB2(SCH_1):PVDDQ_DEF
  80 PVDDQ_DEF VDD<18> @BASEBOARD_FAB2_LIB.BASEBOARD_FAB2(SCH_1):PVDDQ_DEF
  83 PVDDQ_DEF VDD<17> @BASEBOARD_FAB2_LIB.BASEBOARD_FAB2(SCH_1):PVDDQ_DEF
  85 PVDDQ_DEF VDD<16> @BASEBOARD_FAB2_LIB.BASEBOARD_FAB2(SCH_1):PVDDQ_DEF
  88 PVDDQ_DEF VDD<15> @BASEBOARD_FAB2_LIB.BASEBOARD_FAB2(SCH_1):PVDDQ_DEF
  90 PVDDQ_DEF VDD<14> @BASEBOARD_FAB2_LIB.BASEBOARD_FAB2(SCH_1):PVDDQ_DEF
  92 PVDDQ_DEF VDD<13> @BASEBOARD_FAB2_LIB.BASEBOARD_FAB2(SCH_1):PVDDQ_DEF
 204 PVDDQ_DEF VDD<12> @BASEBOARD_FAB2_LIB.BASEBOARD_FAB2(SCH_1):PVDDQ_DEF
 206 PVDDQ_DEF VDD<11> @BASEBOARD_FAB2_LIB.BASEBOARD_FAB2(SCH_1):PVDDQ_DEF
 209 PVDDQ_DEF VDD<10> @BASEBOARD_FAB2_LIB.BASEBOARD_FAB2(SCH_1):PVDDQ_DEF
 212 PVDDQ_DEF VDD<9> @BASEBOARD_FAB2_LIB.BASEBOARD_FAB2(SCH_1):PVDDQ_DEF
 215 PVDDQ_DEF VDD<8> @BASEBOARD_FAB2_LIB.BASEBOARD_FAB2(SCH_1):PVDDQ_DEF
 217 PVDDQ_DEF VDD<7> @BASEBOARD_FAB2_LIB.BASEBOARD_FAB2(SCH_1):PVDDQ_DEF
 220 PVDDQ_DEF VDD<6> @BASEBOARD_FAB2_LIB.BASEBOARD_FAB2(SCH_1):PVDDQ_DEF
 223 PVDDQ_DEF VDD<5> @BASEBOARD_FAB2_LIB.BASEBOARD_FAB2(SCH_1):PVDDQ_DEF
 226 PVDDQ_DEF VDD<4> @BASEBOARD_FAB2_LIB.BASEBOARD_FAB2(SCH_1):PVDDQ_DEF
 229 PVDDQ_DEF VDD<3> @BASEBOARD_FAB2_LIB.BASEBOARD_FAB2(SCH_1):PVDDQ_DEF
 231 PVDDQ_DEF VDD<2> @BASEBOARD_FAB2_LIB.BASEBOARD_FAB2(SCH_1):PVDDQ_DEF
 233 PVDDQ_DEF VDD<1> @BASEBOARD_FAB2_LIB.BASEBOARD_FAB2(SCH_1):PVDDQ_DEF
 236 PVDDQ_DEF VDD<0> @BASEBOARD_FAB2_LIB.BASEBOARD_FAB2(SCH_1):PVDDQ_DEF
 142 PVPP_DEF VPP<4> @BASEBOARD_FAB2_LIB.BASEBOARD_FAB2(SCH_1):PVPP_DEF
 143 PVPP_DEF VPP<3> @BASEBOARD_FAB2_LIB.BASEBOARD_FAB2(SCH_1):PVPP_DEF
 288 PVPP_DEF VPP<2> @BASEBOARD_FAB2_LIB.BASEBOARD_FAB2(SCH_1):PVPP_DEF
 286 PVPP_DEF VPP<1> @BASEBOARD_FAB2_LIB.BASEBOARD_FAB2(SCH_1):PVPP_DEF
 287 PVPP_DEF VPP<0> @BASEBOARD_FAB2_LIB.BASEBOARD_FAB2(SCH_1):PVPP_DEF
  77 PVTT_DEF VTT<1> @BASEBOARD_FAB2_LIB.BASEBOARD_FAB2(SCH_1):PVTT_DEF
 221 PVTT_DEF VTT<0> @BASEBOARD_FAB2_LIB.BASEBOARD_FAB2(SCH_1):PVTT_DEF

CAP_A_0402V-0.01UF,25V,10%,X7RA  I179  C4B12
   1 M_D_VREF      A @BASEBOARD_FAB2_LIB.BASEBOARD_FAB2(SCH_1):M_D_VREF
   2    GND      B @BASEBOARD_FAB2_LIB.BASEBOARD_FAB2(SCH_1):GND


DRAWING: @BASEBOARD_FAB2_LIB.BASEBOARD_FAB2(SCH_1):PAGE50 

SCONN288_H44441003_PIP-SCONN,HA  I44  J6M1
   2    GND VSS<93> @BASEBOARD_FAB2_LIB.BASEBOARD_FAB2(SCH_1):GND
   4    GND VSS<92> @BASEBOARD_FAB2_LIB.BASEBOARD_FAB2(SCH_1):GND
   6    GND VSS<91> @BASEBOARD_FAB2_LIB.BASEBOARD_FAB2(SCH_1):GND
   9    GND VSS<90> @BASEBOARD_FAB2_LIB.BASEBOARD_FAB2(SCH_1):GND
  11    GND VSS<89> @BASEBOARD_FAB2_LIB.BASEBOARD_FAB2(SCH_1):GND
  13    GND VSS<88> @BASEBOARD_FAB2_LIB.BASEBOARD_FAB2(SCH_1):GND
  15    GND VSS<87> @BASEBOARD_FAB2_LIB.BASEBOARD_FAB2(SCH_1):GND
  17    GND VSS<86> @BASEBOARD_FAB2_LIB.BASEBOARD_FAB2(SCH_1):GND
  20    GND VSS<85> @BASEBOARD_FAB2_LIB.BASEBOARD_FAB2(SCH_1):GND
  22    GND VSS<84> @BASEBOARD_FAB2_LIB.BASEBOARD_FAB2(SCH_1):GND
  24    GND VSS<83> @BASEBOARD_FAB2_LIB.BASEBOARD_FAB2(SCH_1):GND
  26    GND VSS<82> @BASEBOARD_FAB2_LIB.BASEBOARD_FAB2(SCH_1):GND
  28    GND VSS<81> @BASEBOARD_FAB2_LIB.BASEBOARD_FAB2(SCH_1):GND
  31    GND VSS<80> @BASEBOARD_FAB2_LIB.BASEBOARD_FAB2(SCH_1):GND
  33    GND VSS<79> @BASEBOARD_FAB2_LIB.BASEBOARD_FAB2(SCH_1):GND
  35    GND VSS<78> @BASEBOARD_FAB2_LIB.BASEBOARD_FAB2(SCH_1):GND
  37    GND VSS<77> @BASEBOARD_FAB2_LIB.BASEBOARD_FAB2(SCH_1):GND
  39    GND VSS<76> @BASEBOARD_FAB2_LIB.BASEBOARD_FAB2(SCH_1):GND
  42    GND VSS<75> @BASEBOARD_FAB2_LIB.BASEBOARD_FAB2(SCH_1):GND
  44    GND VSS<74> @BASEBOARD_FAB2_LIB.BASEBOARD_FAB2(SCH_1):GND
  46    GND VSS<73> @BASEBOARD_FAB2_LIB.BASEBOARD_FAB2(SCH_1):GND
  48    GND VSS<72> @BASEBOARD_FAB2_LIB.BASEBOARD_FAB2(SCH_1):GND
  50    GND VSS<71> @BASEBOARD_FAB2_LIB.BASEBOARD_FAB2(SCH_1):GND
  53    GND VSS<70> @BASEBOARD_FAB2_LIB.BASEBOARD_FAB2(SCH_1):GND
  55    GND VSS<69> @BASEBOARD_FAB2_LIB.BASEBOARD_FAB2(SCH_1):GND
  57    GND VSS<68> @BASEBOARD_FAB2_LIB.BASEBOARD_FAB2(SCH_1):GND
  94    GND VSS<67> @BASEBOARD_FAB2_LIB.BASEBOARD_FAB2(SCH_1):GND
  96    GND VSS<66> @BASEBOARD_FAB2_LIB.BASEBOARD_FAB2(SCH_1):GND
  98    GND VSS<65> @BASEBOARD_FAB2_LIB.BASEBOARD_FAB2(SCH_1):GND
 101    GND VSS<64> @BASEBOARD_FAB2_LIB.BASEBOARD_FAB2(SCH_1):GND
 103    GND VSS<63> @BASEBOARD_FAB2_LIB.BASEBOARD_FAB2(SCH_1):GND
 105    GND VSS<62> @BASEBOARD_FAB2_LIB.BASEBOARD_FAB2(SCH_1):GND
 107    GND VSS<61> @BASEBOARD_FAB2_LIB.BASEBOARD_FAB2(SCH_1):GND
 109    GND VSS<60> @BASEBOARD_FAB2_LIB.BASEBOARD_FAB2(SCH_1):GND
 112    GND VSS<59> @BASEBOARD_FAB2_LIB.BASEBOARD_FAB2(SCH_1):GND
 114    GND VSS<58> @BASEBOARD_FAB2_LIB.BASEBOARD_FAB2(SCH_1):GND
 116    GND VSS<57> @BASEBOARD_FAB2_LIB.BASEBOARD_FAB2(SCH_1):GND
 118    GND VSS<56> @BASEBOARD_FAB2_LIB.BASEBOARD_FAB2(SCH_1):GND
 120    GND VSS<55> @BASEBOARD_FAB2_LIB.BASEBOARD_FAB2(SCH_1):GND
 123    GND VSS<54> @BASEBOARD_FAB2_LIB.BASEBOARD_FAB2(SCH_1):GND
 125    GND VSS<53> @BASEBOARD_FAB2_LIB.BASEBOARD_FAB2(SCH_1):GND
 127    GND VSS<52> @BASEBOARD_FAB2_LIB.BASEBOARD_FAB2(SCH_1):GND
 129    GND VSS<51> @BASEBOARD_FAB2_LIB.BASEBOARD_FAB2(SCH_1):GND
 131    GND VSS<50> @BASEBOARD_FAB2_LIB.BASEBOARD_FAB2(SCH_1):GND
 134    GND VSS<49> @BASEBOARD_FAB2_LIB.BASEBOARD_FAB2(SCH_1):GND
 136    GND VSS<48> @BASEBOARD_FAB2_LIB.BASEBOARD_FAB2(SCH_1):GND
 138    GND VSS<47> @BASEBOARD_FAB2_LIB.BASEBOARD_FAB2(SCH_1):GND
 147    GND VSS<46> @BASEBOARD_FAB2_LIB.BASEBOARD_FAB2(SCH_1):GND
 149    GND VSS<45> @BASEBOARD_FAB2_LIB.BASEBOARD_FAB2(SCH_1):GND
 151    GND VSS<44> @BASEBOARD_FAB2_LIB.BASEBOARD_FAB2(SCH_1):GND
 154    GND VSS<43> @BASEBOARD_FAB2_LIB.BASEBOARD_FAB2(SCH_1):GND
 156    GND VSS<42> @BASEBOARD_FAB2_LIB.BASEBOARD_FAB2(SCH_1):GND
 158    GND VSS<41> @BASEBOARD_FAB2_LIB.BASEBOARD_FAB2(SCH_1):GND
 160    GND VSS<40> @BASEBOARD_FAB2_LIB.BASEBOARD_FAB2(SCH_1):GND
 162    GND VSS<39> @BASEBOARD_FAB2_LIB.BASEBOARD_FAB2(SCH_1):GND
 165    GND VSS<38> @BASEBOARD_FAB2_LIB.BASEBOARD_FAB2(SCH_1):GND
 167    GND VSS<37> @BASEBOARD_FAB2_LIB.BASEBOARD_FAB2(SCH_1):GND
 169    GND VSS<36> @BASEBOARD_FAB2_LIB.BASEBOARD_FAB2(SCH_1):GND
 171    GND VSS<35> @BASEBOARD_FAB2_LIB.BASEBOARD_FAB2(SCH_1):GND
 173    GND VSS<34> @BASEBOARD_FAB2_LIB.BASEBOARD_FAB2(SCH_1):GND
 176    GND VSS<33> @BASEBOARD_FAB2_LIB.BASEBOARD_FAB2(SCH_1):GND
 178    GND VSS<32> @BASEBOARD_FAB2_LIB.BASEBOARD_FAB2(SCH_1):GND
 180    GND VSS<31> @BASEBOARD_FAB2_LIB.BASEBOARD_FAB2(SCH_1):GND
 182    GND VSS<30> @BASEBOARD_FAB2_LIB.BASEBOARD_FAB2(SCH_1):GND
 184    GND VSS<29> @BASEBOARD_FAB2_LIB.BASEBOARD_FAB2(SCH_1):GND
 187    GND VSS<28> @BASEBOARD_FAB2_LIB.BASEBOARD_FAB2(SCH_1):GND
 189    GND VSS<27> @BASEBOARD_FAB2_LIB.BASEBOARD_FAB2(SCH_1):GND
 191    GND VSS<26> @BASEBOARD_FAB2_LIB.BASEBOARD_FAB2(SCH_1):GND
 193    GND VSS<25> @BASEBOARD_FAB2_LIB.BASEBOARD_FAB2(SCH_1):GND
 195    GND VSS<24> @BASEBOARD_FAB2_LIB.BASEBOARD_FAB2(SCH_1):GND
 198    GND VSS<23> @BASEBOARD_FAB2_LIB.BASEBOARD_FAB2(SCH_1):GND
 200    GND VSS<22> @BASEBOARD_FAB2_LIB.BASEBOARD_FAB2(SCH_1):GND
 202    GND VSS<21> @BASEBOARD_FAB2_LIB.BASEBOARD_FAB2(SCH_1):GND
 239    GND VSS<20> @BASEBOARD_FAB2_LIB.BASEBOARD_FAB2(SCH_1):GND
 241    GND VSS<19> @BASEBOARD_FAB2_LIB.BASEBOARD_FAB2(SCH_1):GND
 243    GND VSS<18> @BASEBOARD_FAB2_LIB.BASEBOARD_FAB2(SCH_1):GND
 246    GND VSS<17> @BASEBOARD_FAB2_LIB.BASEBOARD_FAB2(SCH_1):GND
 248    GND VSS<16> @BASEBOARD_FAB2_LIB.BASEBOARD_FAB2(SCH_1):GND
 250    GND VSS<15> @BASEBOARD_FAB2_LIB.BASEBOARD_FAB2(SCH_1):GND
 252    GND VSS<14> @BASEBOARD_FAB2_LIB.BASEBOARD_FAB2(SCH_1):GND
 254    GND VSS<13> @BASEBOARD_FAB2_LIB.BASEBOARD_FAB2(SCH_1):GND
 257    GND VSS<12> @BASEBOARD_FAB2_LIB.BASEBOARD_FAB2(SCH_1):GND
 259    GND VSS<11> @BASEBOARD_FAB2_LIB.BASEBOARD_FAB2(SCH_1):GND
 261    GND VSS<10> @BASEBOARD_FAB2_LIB.BASEBOARD_FAB2(SCH_1):GND
 263    GND VSS<9> @BASEBOARD_FAB2_LIB.BASEBOARD_FAB2(SCH_1):GND
 265    GND VSS<8> @BASEBOARD_FAB2_LIB.BASEBOARD_FAB2(SCH_1):GND
 268    GND VSS<7> @BASEBOARD_FAB2_LIB.BASEBOARD_FAB2(SCH_1):GND
 270    GND VSS<6> @BASEBOARD_FAB2_LIB.BASEBOARD_FAB2(SCH_1):GND
 272    GND VSS<5> @BASEBOARD_FAB2_LIB.BASEBOARD_FAB2(SCH_1):GND
 274    GND VSS<4> @BASEBOARD_FAB2_LIB.BASEBOARD_FAB2(SCH_1):GND
 276    GND VSS<3> @BASEBOARD_FAB2_LIB.BASEBOARD_FAB2(SCH_1):GND
 279    GND VSS<2> @BASEBOARD_FAB2_LIB.BASEBOARD_FAB2(SCH_1):GND
 281    GND VSS<1> @BASEBOARD_FAB2_LIB.BASEBOARD_FAB2(SCH_1):GND
 283    GND VSS<0> @BASEBOARD_FAB2_LIB.BASEBOARD_FAB2(SCH_1):GND

SCONN288_H44441003_PIP-SCONN,HA  I46  J6M1
 152 M_D_DQS_DN<0>  DQS0N @BASEBOARD_FAB2_LIB.BASEBOARD_FAB2(SCH_1):M_D_DQS_DN(0)
 153 M_D_DQS_DP<0>  DQS0P @BASEBOARD_FAB2_LIB.BASEBOARD_FAB2(SCH_1):M_D_DQS_DP(0)
  19 M_D_DQS_DN<10> DQS10N @BASEBOARD_FAB2_LIB.BASEBOARD_FAB2(SCH_1):M_D_DQS_DN(10)
  18 M_D_DQS_DP<10> DQS10P @BASEBOARD_FAB2_LIB.BASEBOARD_FAB2(SCH_1):M_D_DQS_DP(10)
  30 M_D_DQS_DN<11> DQS11N @BASEBOARD_FAB2_LIB.BASEBOARD_FAB2(SCH_1):M_D_DQS_DN(11)
  29 M_D_DQS_DP<11> DQS11P @BASEBOARD_FAB2_LIB.BASEBOARD_FAB2(SCH_1):M_D_DQS_DP(11)
  41 M_D_DQS_DN<12> DQS12N @BASEBOARD_FAB2_LIB.BASEBOARD_FAB2(SCH_1):M_D_DQS_DN(12)
  40 M_D_DQS_DP<12> DQS12P @BASEBOARD_FAB2_LIB.BASEBOARD_FAB2(SCH_1):M_D_DQS_DP(12)
 100 M_D_DQS_DN<13> DQS13N @BASEBOARD_FAB2_LIB.BASEBOARD_FAB2(SCH_1):M_D_DQS_DN(13)
  99 M_D_DQS_DP<13> DQS13P @BASEBOARD_FAB2_LIB.BASEBOARD_FAB2(SCH_1):M_D_DQS_DP(13)
 111 M_D_DQS_DN<14> DQS14N @BASEBOARD_FAB2_LIB.BASEBOARD_FAB2(SCH_1):M_D_DQS_DN(14)
 110 M_D_DQS_DP<14> DQS14P @BASEBOARD_FAB2_LIB.BASEBOARD_FAB2(SCH_1):M_D_DQS_DP(14)
 122 M_D_DQS_DN<15> DQS15N @BASEBOARD_FAB2_LIB.BASEBOARD_FAB2(SCH_1):M_D_DQS_DN(15)
 121 M_D_DQS_DP<15> DQS15P @BASEBOARD_FAB2_LIB.BASEBOARD_FAB2(SCH_1):M_D_DQS_DP(15)
 133 M_D_DQS_DN<16> DQS16N @BASEBOARD_FAB2_LIB.BASEBOARD_FAB2(SCH_1):M_D_DQS_DN(16)
 132 M_D_DQS_DP<16> DQS16P @BASEBOARD_FAB2_LIB.BASEBOARD_FAB2(SCH_1):M_D_DQS_DP(16)
  52 M_D_DQS_DN<17> DQS17N @BASEBOARD_FAB2_LIB.BASEBOARD_FAB2(SCH_1):M_D_DQS_DN(17)
  51 M_D_DQS_DP<17> DQS17P @BASEBOARD_FAB2_LIB.BASEBOARD_FAB2(SCH_1):M_D_DQS_DP(17)
 163 M_D_DQS_DN<1>  DQS1N @BASEBOARD_FAB2_LIB.BASEBOARD_FAB2(SCH_1):M_D_DQS_DN(1)
 164 M_D_DQS_DP<1>  DQS1P @BASEBOARD_FAB2_LIB.BASEBOARD_FAB2(SCH_1):M_D_DQS_DP(1)
 174 M_D_DQS_DN<2>  DQS2N @BASEBOARD_FAB2_LIB.BASEBOARD_FAB2(SCH_1):M_D_DQS_DN(2)
 175 M_D_DQS_DP<2>  DQS2P @BASEBOARD_FAB2_LIB.BASEBOARD_FAB2(SCH_1):M_D_DQS_DP(2)
 185 M_D_DQS_DN<3>  DQS3N @BASEBOARD_FAB2_LIB.BASEBOARD_FAB2(SCH_1):M_D_DQS_DN(3)
 186 M_D_DQS_DP<3>  DQS3P @BASEBOARD_FAB2_LIB.BASEBOARD_FAB2(SCH_1):M_D_DQS_DP(3)
 244 M_D_DQS_DN<4>  DQS4N @BASEBOARD_FAB2_LIB.BASEBOARD_FAB2(SCH_1):M_D_DQS_DN(4)
 245 M_D_DQS_DP<4>  DQS4P @BASEBOARD_FAB2_LIB.BASEBOARD_FAB2(SCH_1):M_D_DQS_DP(4)
 255 M_D_DQS_DN<5>  DQS5N @BASEBOARD_FAB2_LIB.BASEBOARD_FAB2(SCH_1):M_D_DQS_DN(5)
 256 M_D_DQS_DP<5>  DQS5P @BASEBOARD_FAB2_LIB.BASEBOARD_FAB2(SCH_1):M_D_DQS_DP(5)
 266 M_D_DQS_DN<6>  DQS6N @BASEBOARD_FAB2_LIB.BASEBOARD_FAB2(SCH_1):M_D_DQS_DN(6)
 267 M_D_DQS_DP<6>  DQS6P @BASEBOARD_FAB2_LIB.BASEBOARD_FAB2(SCH_1):M_D_DQS_DP(6)
 277 M_D_DQS_DN<7>  DQS7N @BASEBOARD_FAB2_LIB.BASEBOARD_FAB2(SCH_1):M_D_DQS_DN(7)
 278 M_D_DQS_DP<7>  DQS7P @BASEBOARD_FAB2_LIB.BASEBOARD_FAB2(SCH_1):M_D_DQS_DP(7)
 196 M_D_DQS_DN<8>  DQS8N @BASEBOARD_FAB2_LIB.BASEBOARD_FAB2(SCH_1):M_D_DQS_DN(8)
 197 M_D_DQS_DP<8>  DQS8P @BASEBOARD_FAB2_LIB.BASEBOARD_FAB2(SCH_1):M_D_DQS_DP(8)
   8 M_D_DQS_DN<9>  DQS9N @BASEBOARD_FAB2_LIB.BASEBOARD_FAB2(SCH_1):M_D_DQS_DN(9)
   7 M_D_DQS_DP<9>  DQS9P @BASEBOARD_FAB2_LIB.BASEBOARD_FAB2(SCH_1):M_D_DQS_DP(9)

SCONN288_H44441003_PIP-SCONN,HA  I50  J6M1
   1 P12V_NVDIMM_DEF 12V<1> @BASEBOARD_FAB2_LIB.BASEBOARD_FAB2(SCH_1):P12V_NVDIMM_DEF
 145 P12V_NVDIMM_DEF 12V<0> @BASEBOARD_FAB2_LIB.BASEBOARD_FAB2(SCH_1):P12V_NVDIMM_DEF
  59 PVDDQ_DEF VDD<25> @BASEBOARD_FAB2_LIB.BASEBOARD_FAB2(SCH_1):PVDDQ_DEF
  61 PVDDQ_DEF VDD<24> @BASEBOARD_FAB2_LIB.BASEBOARD_FAB2(SCH_1):PVDDQ_DEF
  64 PVDDQ_DEF VDD<23> @BASEBOARD_FAB2_LIB.BASEBOARD_FAB2(SCH_1):PVDDQ_DEF
  67 PVDDQ_DEF VDD<22> @BASEBOARD_FAB2_LIB.BASEBOARD_FAB2(SCH_1):PVDDQ_DEF
  70 PVDDQ_DEF VDD<21> @BASEBOARD_FAB2_LIB.BASEBOARD_FAB2(SCH_1):PVDDQ_DEF
  73 PVDDQ_DEF VDD<20> @BASEBOARD_FAB2_LIB.BASEBOARD_FAB2(SCH_1):PVDDQ_DEF
  76 PVDDQ_DEF VDD<19> @BASEBOARD_FAB2_LIB.BASEBOARD_FAB2(SCH_1):PVDDQ_DEF
  80 PVDDQ_DEF VDD<18> @BASEBOARD_FAB2_LIB.BASEBOARD_FAB2(SCH_1):PVDDQ_DEF
  83 PVDDQ_DEF VDD<17> @BASEBOARD_FAB2_LIB.BASEBOARD_FAB2(SCH_1):PVDDQ_DEF
  85 PVDDQ_DEF VDD<16> @BASEBOARD_FAB2_LIB.BASEBOARD_FAB2(SCH_1):PVDDQ_DEF
  88 PVDDQ_DEF VDD<15> @BASEBOARD_FAB2_LIB.BASEBOARD_FAB2(SCH_1):PVDDQ_DEF
  90 PVDDQ_DEF VDD<14> @BASEBOARD_FAB2_LIB.BASEBOARD_FAB2(SCH_1):PVDDQ_DEF
  92 PVDDQ_DEF VDD<13> @BASEBOARD_FAB2_LIB.BASEBOARD_FAB2(SCH_1):PVDDQ_DEF
 204 PVDDQ_DEF VDD<12> @BASEBOARD_FAB2_LIB.BASEBOARD_FAB2(SCH_1):PVDDQ_DEF
 206 PVDDQ_DEF VDD<11> @BASEBOARD_FAB2_LIB.BASEBOARD_FAB2(SCH_1):PVDDQ_DEF
 209 PVDDQ_DEF VDD<10> @BASEBOARD_FAB2_LIB.BASEBOARD_FAB2(SCH_1):PVDDQ_DEF
 212 PVDDQ_DEF VDD<9> @BASEBOARD_FAB2_LIB.BASEBOARD_FAB2(SCH_1):PVDDQ_DEF
 215 PVDDQ_DEF VDD<8> @BASEBOARD_FAB2_LIB.BASEBOARD_FAB2(SCH_1):PVDDQ_DEF
 217 PVDDQ_DEF VDD<7> @BASEBOARD_FAB2_LIB.BASEBOARD_FAB2(SCH_1):PVDDQ_DEF
 220 PVDDQ_DEF VDD<6> @BASEBOARD_FAB2_LIB.BASEBOARD_FAB2(SCH_1):PVDDQ_DEF
 223 PVDDQ_DEF VDD<5> @BASEBOARD_FAB2_LIB.BASEBOARD_FAB2(SCH_1):PVDDQ_DEF
 226 PVDDQ_DEF VDD<4> @BASEBOARD_FAB2_LIB.BASEBOARD_FAB2(SCH_1):PVDDQ_DEF
 229 PVDDQ_DEF VDD<3> @BASEBOARD_FAB2_LIB.BASEBOARD_FAB2(SCH_1):PVDDQ_DEF
 231 PVDDQ_DEF VDD<2> @BASEBOARD_FAB2_LIB.BASEBOARD_FAB2(SCH_1):PVDDQ_DEF
 233 PVDDQ_DEF VDD<1> @BASEBOARD_FAB2_LIB.BASEBOARD_FAB2(SCH_1):PVDDQ_DEF
 236 PVDDQ_DEF VDD<0> @BASEBOARD_FAB2_LIB.BASEBOARD_FAB2(SCH_1):PVDDQ_DEF
 142 PVPP_DEF VPP<4> @BASEBOARD_FAB2_LIB.BASEBOARD_FAB2(SCH_1):PVPP_DEF
 143 PVPP_DEF VPP<3> @BASEBOARD_FAB2_LIB.BASEBOARD_FAB2(SCH_1):PVPP_DEF
 288 PVPP_DEF VPP<2> @BASEBOARD_FAB2_LIB.BASEBOARD_FAB2(SCH_1):PVPP_DEF
 286 PVPP_DEF VPP<1> @BASEBOARD_FAB2_LIB.BASEBOARD_FAB2(SCH_1):PVPP_DEF
 287 PVPP_DEF VPP<0> @BASEBOARD_FAB2_LIB.BASEBOARD_FAB2(SCH_1):PVPP_DEF
  77 PVTT_DEF VTT<1> @BASEBOARD_FAB2_LIB.BASEBOARD_FAB2(SCH_1):PVTT_DEF
 221 PVTT_DEF VTT<0> @BASEBOARD_FAB2_LIB.BASEBOARD_FAB2(SCH_1):PVTT_DEF

SCONN288_H44441003_PIP-SCONN,HA  I158  J6M1
  79 M_D_MA<0>     A0 @BASEBOARD_FAB2_LIB.BASEBOARD_FAB2(SCH_1):M_D_MA(0)
  72 M_D_MA<1>     A1 @BASEBOARD_FAB2_LIB.BASEBOARD_FAB2(SCH_1):M_D_MA(1)
 225 M_D_MA<10>    A10 @BASEBOARD_FAB2_LIB.BASEBOARD_FAB2(SCH_1):M_D_MA(10)
 210 M_D_MA<11>    A11 @BASEBOARD_FAB2_LIB.BASEBOARD_FAB2(SCH_1):M_D_MA(11)
  65 M_D_MA<12>    A12 @BASEBOARD_FAB2_LIB.BASEBOARD_FAB2(SCH_1):M_D_MA(12)
 232 M_D_MA<13>    A13 @BASEBOARD_FAB2_LIB.BASEBOARD_FAB2(SCH_1):M_D_MA(13)
 228 M_D_MA<14> A14_WE_N @BASEBOARD_FAB2_LIB.BASEBOARD_FAB2(SCH_1):M_D_MA(14)
  86 M_D_MA<15> A15_CAS_N @BASEBOARD_FAB2_LIB.BASEBOARD_FAB2(SCH_1):M_D_MA(15)
  82 M_D_MA<16> A16_RAS_N @BASEBOARD_FAB2_LIB.BASEBOARD_FAB2(SCH_1):M_D_MA(16)
 234 M_D_MA<17>    A17 @BASEBOARD_FAB2_LIB.BASEBOARD_FAB2(SCH_1):M_D_MA(17)
 216 M_D_MA<2>     A2 @BASEBOARD_FAB2_LIB.BASEBOARD_FAB2(SCH_1):M_D_MA(2)
  71 M_D_MA<3>     A3 @BASEBOARD_FAB2_LIB.BASEBOARD_FAB2(SCH_1):M_D_MA(3)
 214 M_D_MA<4>     A4 @BASEBOARD_FAB2_LIB.BASEBOARD_FAB2(SCH_1):M_D_MA(4)
 213 M_D_MA<5>     A5 @BASEBOARD_FAB2_LIB.BASEBOARD_FAB2(SCH_1):M_D_MA(5)
  69 M_D_MA<6>     A6 @BASEBOARD_FAB2_LIB.BASEBOARD_FAB2(SCH_1):M_D_MA(6)
 211 M_D_MA<7>     A7 @BASEBOARD_FAB2_LIB.BASEBOARD_FAB2(SCH_1):M_D_MA(7)
  68 M_D_MA<8>     A8 @BASEBOARD_FAB2_LIB.BASEBOARD_FAB2(SCH_1):M_D_MA(8)
  66 M_D_MA<9>     A9 @BASEBOARD_FAB2_LIB.BASEBOARD_FAB2(SCH_1):M_D_MA(9)
  62 M_D_ACT_N  ACT_N @BASEBOARD_FAB2_LIB.BASEBOARD_FAB2(SCH_1):M_D_ACT_N
 208 M_D_ALERT_N ALERT_N @BASEBOARD_FAB2_LIB.BASEBOARD_FAB2(SCH_1):M_D_ALERT_N
 224 M_D_BA<1>  BA<1> @BASEBOARD_FAB2_LIB.BASEBOARD_FAB2(SCH_1):M_D_BA(1)
  81 M_D_BA<0>  BA<0> @BASEBOARD_FAB2_LIB.BASEBOARD_FAB2(SCH_1):M_D_BA(0)
 207 M_D_BG<1>  BG<1> @BASEBOARD_FAB2_LIB.BASEBOARD_FAB2(SCH_1):M_D_BG(1)
  63 M_D_BG<0>  BG<0> @BASEBOARD_FAB2_LIB.BASEBOARD_FAB2(SCH_1):M_D_BG(0)
 235 M_D_C<2>   C<2> @BASEBOARD_FAB2_LIB.BASEBOARD_FAB2(SCH_1):M_D_C(2)
 199 M_D_ECC<7>  CB<7> @BASEBOARD_FAB2_LIB.BASEBOARD_FAB2(SCH_1):M_D_ECC(7)
  54 M_D_ECC<6>  CB<6> @BASEBOARD_FAB2_LIB.BASEBOARD_FAB2(SCH_1):M_D_ECC(6)
 192 M_D_ECC<5>  CB<5> @BASEBOARD_FAB2_LIB.BASEBOARD_FAB2(SCH_1):M_D_ECC(5)
  47 M_D_ECC<4>  CB<4> @BASEBOARD_FAB2_LIB.BASEBOARD_FAB2(SCH_1):M_D_ECC(4)
 201 M_D_ECC<3>  CB<3> @BASEBOARD_FAB2_LIB.BASEBOARD_FAB2(SCH_1):M_D_ECC(3)
  56 M_D_ECC<2>  CB<2> @BASEBOARD_FAB2_LIB.BASEBOARD_FAB2(SCH_1):M_D_ECC(2)
 194 M_D_ECC<1>  CB<1> @BASEBOARD_FAB2_LIB.BASEBOARD_FAB2(SCH_1):M_D_ECC(1)
  49 M_D_ECC<0>  CB<0> @BASEBOARD_FAB2_LIB.BASEBOARD_FAB2(SCH_1):M_D_ECC(0)
  75 M_D_CLK_DN<2>   CK0N @BASEBOARD_FAB2_LIB.BASEBOARD_FAB2(SCH_1):M_D_CLK_DN(2)
  74 M_D_CLK_DP<2>   CK0P @BASEBOARD_FAB2_LIB.BASEBOARD_FAB2(SCH_1):M_D_CLK_DP(2)
 219 M_D_CLK_DN<3>   CK1N @BASEBOARD_FAB2_LIB.BASEBOARD_FAB2(SCH_1):M_D_CLK_DN(3)
 218 M_D_CLK_DP<3>   CK1P @BASEBOARD_FAB2_LIB.BASEBOARD_FAB2(SCH_1):M_D_CLK_DP(3)
 203 M_D_CKE<3> CKE<1> @BASEBOARD_FAB2_LIB.BASEBOARD_FAB2(SCH_1):M_D_CKE(3)
  60 M_D_CKE<2> CKE<0> @BASEBOARD_FAB2_LIB.BASEBOARD_FAB2(SCH_1):M_D_CKE(2)
 280 M_D_DQ<63> DQ<63> @BASEBOARD_FAB2_LIB.BASEBOARD_FAB2(SCH_1):M_D_DQ(63)
 135 M_D_DQ<62> DQ<62> @BASEBOARD_FAB2_LIB.BASEBOARD_FAB2(SCH_1):M_D_DQ(62)
 273 M_D_DQ<61> DQ<61> @BASEBOARD_FAB2_LIB.BASEBOARD_FAB2(SCH_1):M_D_DQ(61)
 128 M_D_DQ<60> DQ<60> @BASEBOARD_FAB2_LIB.BASEBOARD_FAB2(SCH_1):M_D_DQ(60)
 282 M_D_DQ<59> DQ<59> @BASEBOARD_FAB2_LIB.BASEBOARD_FAB2(SCH_1):M_D_DQ(59)
 137 M_D_DQ<58> DQ<58> @BASEBOARD_FAB2_LIB.BASEBOARD_FAB2(SCH_1):M_D_DQ(58)
 275 M_D_DQ<57> DQ<57> @BASEBOARD_FAB2_LIB.BASEBOARD_FAB2(SCH_1):M_D_DQ(57)
 130 M_D_DQ<56> DQ<56> @BASEBOARD_FAB2_LIB.BASEBOARD_FAB2(SCH_1):M_D_DQ(56)
 269 M_D_DQ<55> DQ<55> @BASEBOARD_FAB2_LIB.BASEBOARD_FAB2(SCH_1):M_D_DQ(55)
 124 M_D_DQ<54> DQ<54> @BASEBOARD_FAB2_LIB.BASEBOARD_FAB2(SCH_1):M_D_DQ(54)
 262 M_D_DQ<53> DQ<53> @BASEBOARD_FAB2_LIB.BASEBOARD_FAB2(SCH_1):M_D_DQ(53)
 117 M_D_DQ<52> DQ<52> @BASEBOARD_FAB2_LIB.BASEBOARD_FAB2(SCH_1):M_D_DQ(52)
 271 M_D_DQ<51> DQ<51> @BASEBOARD_FAB2_LIB.BASEBOARD_FAB2(SCH_1):M_D_DQ(51)
 126 M_D_DQ<50> DQ<50> @BASEBOARD_FAB2_LIB.BASEBOARD_FAB2(SCH_1):M_D_DQ(50)
 264 M_D_DQ<49> DQ<49> @BASEBOARD_FAB2_LIB.BASEBOARD_FAB2(SCH_1):M_D_DQ(49)
 119 M_D_DQ<48> DQ<48> @BASEBOARD_FAB2_LIB.BASEBOARD_FAB2(SCH_1):M_D_DQ(48)
 258 M_D_DQ<47> DQ<47> @BASEBOARD_FAB2_LIB.BASEBOARD_FAB2(SCH_1):M_D_DQ(47)
 113 M_D_DQ<46> DQ<46> @BASEBOARD_FAB2_LIB.BASEBOARD_FAB2(SCH_1):M_D_DQ(46)
 251 M_D_DQ<45> DQ<45> @BASEBOARD_FAB2_LIB.BASEBOARD_FAB2(SCH_1):M_D_DQ(45)
 106 M_D_DQ<44> DQ<44> @BASEBOARD_FAB2_LIB.BASEBOARD_FAB2(SCH_1):M_D_DQ(44)
 260 M_D_DQ<43> DQ<43> @BASEBOARD_FAB2_LIB.BASEBOARD_FAB2(SCH_1):M_D_DQ(43)
 115 M_D_DQ<42> DQ<42> @BASEBOARD_FAB2_LIB.BASEBOARD_FAB2(SCH_1):M_D_DQ(42)
 253 M_D_DQ<41> DQ<41> @BASEBOARD_FAB2_LIB.BASEBOARD_FAB2(SCH_1):M_D_DQ(41)
 108 M_D_DQ<40> DQ<40> @BASEBOARD_FAB2_LIB.BASEBOARD_FAB2(SCH_1):M_D_DQ(40)
 247 M_D_DQ<39> DQ<39> @BASEBOARD_FAB2_LIB.BASEBOARD_FAB2(SCH_1):M_D_DQ(39)
 102 M_D_DQ<38> DQ<38> @BASEBOARD_FAB2_LIB.BASEBOARD_FAB2(SCH_1):M_D_DQ(38)
 240 M_D_DQ<37> DQ<37> @BASEBOARD_FAB2_LIB.BASEBOARD_FAB2(SCH_1):M_D_DQ(37)
  95 M_D_DQ<36> DQ<36> @BASEBOARD_FAB2_LIB.BASEBOARD_FAB2(SCH_1):M_D_DQ(36)
 249 M_D_DQ<35> DQ<35> @BASEBOARD_FAB2_LIB.BASEBOARD_FAB2(SCH_1):M_D_DQ(35)
 104 M_D_DQ<34> DQ<34> @BASEBOARD_FAB2_LIB.BASEBOARD_FAB2(SCH_1):M_D_DQ(34)
 242 M_D_DQ<33> DQ<33> @BASEBOARD_FAB2_LIB.BASEBOARD_FAB2(SCH_1):M_D_DQ(33)
  97 M_D_DQ<32> DQ<32> @BASEBOARD_FAB2_LIB.BASEBOARD_FAB2(SCH_1):M_D_DQ(32)
 188 M_D_DQ<31> DQ<31> @BASEBOARD_FAB2_LIB.BASEBOARD_FAB2(SCH_1):M_D_DQ(31)
  43 M_D_DQ<30> DQ<30> @BASEBOARD_FAB2_LIB.BASEBOARD_FAB2(SCH_1):M_D_DQ(30)
 181 M_D_DQ<29> DQ<29> @BASEBOARD_FAB2_LIB.BASEBOARD_FAB2(SCH_1):M_D_DQ(29)
  36 M_D_DQ<28> DQ<28> @BASEBOARD_FAB2_LIB.BASEBOARD_FAB2(SCH_1):M_D_DQ(28)
 190 M_D_DQ<27> DQ<27> @BASEBOARD_FAB2_LIB.BASEBOARD_FAB2(SCH_1):M_D_DQ(27)
  45 M_D_DQ<26> DQ<26> @BASEBOARD_FAB2_LIB.BASEBOARD_FAB2(SCH_1):M_D_DQ(26)
 183 M_D_DQ<25> DQ<25> @BASEBOARD_FAB2_LIB.BASEBOARD_FAB2(SCH_1):M_D_DQ(25)
  38 M_D_DQ<24> DQ<24> @BASEBOARD_FAB2_LIB.BASEBOARD_FAB2(SCH_1):M_D_DQ(24)
 177 M_D_DQ<23> DQ<23> @BASEBOARD_FAB2_LIB.BASEBOARD_FAB2(SCH_1):M_D_DQ(23)
  32 M_D_DQ<22> DQ<22> @BASEBOARD_FAB2_LIB.BASEBOARD_FAB2(SCH_1):M_D_DQ(22)
 170 M_D_DQ<21> DQ<21> @BASEBOARD_FAB2_LIB.BASEBOARD_FAB2(SCH_1):M_D_DQ(21)
  25 M_D_DQ<20> DQ<20> @BASEBOARD_FAB2_LIB.BASEBOARD_FAB2(SCH_1):M_D_DQ(20)
 179 M_D_DQ<19> DQ<19> @BASEBOARD_FAB2_LIB.BASEBOARD_FAB2(SCH_1):M_D_DQ(19)
  34 M_D_DQ<18> DQ<18> @BASEBOARD_FAB2_LIB.BASEBOARD_FAB2(SCH_1):M_D_DQ(18)
 172 M_D_DQ<17> DQ<17> @BASEBOARD_FAB2_LIB.BASEBOARD_FAB2(SCH_1):M_D_DQ(17)
  27 M_D_DQ<16> DQ<16> @BASEBOARD_FAB2_LIB.BASEBOARD_FAB2(SCH_1):M_D_DQ(16)
 166 M_D_DQ<15> DQ<15> @BASEBOARD_FAB2_LIB.BASEBOARD_FAB2(SCH_1):M_D_DQ(15)
  21 M_D_DQ<14> DQ<14> @BASEBOARD_FAB2_LIB.BASEBOARD_FAB2(SCH_1):M_D_DQ(14)
 159 M_D_DQ<13> DQ<13> @BASEBOARD_FAB2_LIB.BASEBOARD_FAB2(SCH_1):M_D_DQ(13)
  14 M_D_DQ<12> DQ<12> @BASEBOARD_FAB2_LIB.BASEBOARD_FAB2(SCH_1):M_D_DQ(12)
 168 M_D_DQ<11> DQ<11> @BASEBOARD_FAB2_LIB.BASEBOARD_FAB2(SCH_1):M_D_DQ(11)
  23 M_D_DQ<10> DQ<10> @BASEBOARD_FAB2_LIB.BASEBOARD_FAB2(SCH_1):M_D_DQ(10)
 161 M_D_DQ<9>  DQ<9> @BASEBOARD_FAB2_LIB.BASEBOARD_FAB2(SCH_1):M_D_DQ(9)
  16 M_D_DQ<8>  DQ<8> @BASEBOARD_FAB2_LIB.BASEBOARD_FAB2(SCH_1):M_D_DQ(8)
 155 M_D_DQ<7>  DQ<7> @BASEBOARD_FAB2_LIB.BASEBOARD_FAB2(SCH_1):M_D_DQ(7)
  10 M_D_DQ<6>  DQ<6> @BASEBOARD_FAB2_LIB.BASEBOARD_FAB2(SCH_1):M_D_DQ(6)
 148 M_D_DQ<5>  DQ<5> @BASEBOARD_FAB2_LIB.BASEBOARD_FAB2(SCH_1):M_D_DQ(5)
   3 M_D_DQ<4>  DQ<4> @BASEBOARD_FAB2_LIB.BASEBOARD_FAB2(SCH_1):M_D_DQ(4)
 157 M_D_DQ<3>  DQ<3> @BASEBOARD_FAB2_LIB.BASEBOARD_FAB2(SCH_1):M_D_DQ(3)
  12 M_D_DQ<2>  DQ<2> @BASEBOARD_FAB2_LIB.BASEBOARD_FAB2(SCH_1):M_D_DQ(2)
 150 M_D_DQ<1>  DQ<1> @BASEBOARD_FAB2_LIB.BASEBOARD_FAB2(SCH_1):M_D_DQ(1)
   5 M_D_DQ<0>  DQ<0> @BASEBOARD_FAB2_LIB.BASEBOARD_FAB2(SCH_1):M_D_DQ(0)
  78 FM_DIMM_EVENT_COD_N EVENT_N @BASEBOARD_FAB2_LIB.BASEBOARD_FAB2(SCH_1):FM_DIMM_EVENT_COD_N
  91 M_D_ODT<3> ODT<1> @BASEBOARD_FAB2_LIB.BASEBOARD_FAB2(SCH_1):M_D_ODT(3)
  87 M_D_ODT<2> ODT<0> @BASEBOARD_FAB2_LIB.BASEBOARD_FAB2(SCH_1):M_D_ODT(2)
 222 M_D_PAR    PAR @BASEBOARD_FAB2_LIB.BASEBOARD_FAB2(SCH_1):M_D_PAR
  58 M_DEF_RST_N RESET_N @BASEBOARD_FAB2_LIB.BASEBOARD_FAB2(SCH_1):M_DEF_RST_N
 144 TP_CH_D_DIMM_D1_RFU_2 RFU<2> @BASEBOARD_FAB2_LIB.BASEBOARD_FAB2(SCH_1):TP_CH_D_DIMM_D1_RFU_2
 227 TP_CH_D_DIMM_D1_RFU_1 RFU<1> @BASEBOARD_FAB2_LIB.BASEBOARD_FAB2(SCH_1):TP_CH_D_DIMM_D1_RFU_1
 205 TP_CH_D_DIMM_D1_RFU_0 RFU<0> @BASEBOARD_FAB2_LIB.BASEBOARD_FAB2(SCH_1):TP_CH_D_DIMM_D1_RFU_0
  84 M_D_CS_N<4>   S0_N @BASEBOARD_FAB2_LIB.BASEBOARD_FAB2(SCH_1):M_D_CS_N(4)
  89 M_D_CS_N<5>   S1_N @BASEBOARD_FAB2_LIB.BASEBOARD_FAB2(SCH_1):M_D_CS_N(5)
  93 M_D_CS_N<6> S2_N_C<0> @BASEBOARD_FAB2_LIB.BASEBOARD_FAB2(SCH_1):M_D_CS_N(6)
 237 M_D_CS_N<7> S3_N_C<1> @BASEBOARD_FAB2_LIB.BASEBOARD_FAB2(SCH_1):M_D_CS_N(7)
 238    GND  SA<2> @BASEBOARD_FAB2_LIB.BASEBOARD_FAB2(SCH_1):GND
 140    GND  SA<1> @BASEBOARD_FAB2_LIB.BASEBOARD_FAB2(SCH_1):GND
 139 PVPP_DEF  SA<0> @BASEBOARD_FAB2_LIB.BASEBOARD_FAB2(SCH_1):PVPP_DEF
 230 FM_ADR_COMPLETE_DEF_N SAVE_N_NC @BASEBOARD_FAB2_LIB.BASEBOARD_FAB2(SCH_1):FM_ADR_COMPLETE_DEF_N
 141 SMB_DDR_DEF_VPP_SCL    SCL @BASEBOARD_FAB2_LIB.BASEBOARD_FAB2(SCH_1):SMB_DDR_DEF_VPP_SCL
 285 SMB_DDR_DEF_VPP_SDA    SDA @BASEBOARD_FAB2_LIB.BASEBOARD_FAB2(SCH_1):SMB_DDR_DEF_VPP_SDA
 284 PVPP_DEF VDDSPD @BASEBOARD_FAB2_LIB.BASEBOARD_FAB2(SCH_1):PVPP_DEF
 146 M_D_VREF VREFCA @BASEBOARD_FAB2_LIB.BASEBOARD_FAB2(SCH_1):M_D_VREF

CAP_A_0402V-0.01UF,25V,10%,X7RA  I177  C6M1
   1 M_D_VREF      A @BASEBOARD_FAB2_LIB.BASEBOARD_FAB2(SCH_1):M_D_VREF
   2    GND      B @BASEBOARD_FAB2_LIB.BASEBOARD_FAB2(SCH_1):GND


DRAWING: @BASEBOARD_FAB2_LIB.BASEBOARD_FAB2(SCH_1):PAGE51 

SCONN288_H44441004_PIP-SCONN,HA  I43  J4A2
   2    GND VSS<93> @BASEBOARD_FAB2_LIB.BASEBOARD_FAB2(SCH_1):GND
   4    GND VSS<92> @BASEBOARD_FAB2_LIB.BASEBOARD_FAB2(SCH_1):GND
   6    GND VSS<91> @BASEBOARD_FAB2_LIB.BASEBOARD_FAB2(SCH_1):GND
   9    GND VSS<90> @BASEBOARD_FAB2_LIB.BASEBOARD_FAB2(SCH_1):GND
  11    GND VSS<89> @BASEBOARD_FAB2_LIB.BASEBOARD_FAB2(SCH_1):GND
  13    GND VSS<88> @BASEBOARD_FAB2_LIB.BASEBOARD_FAB2(SCH_1):GND
  15    GND VSS<87> @BASEBOARD_FAB2_LIB.BASEBOARD_FAB2(SCH_1):GND
  17    GND VSS<86> @BASEBOARD_FAB2_LIB.BASEBOARD_FAB2(SCH_1):GND
  20    GND VSS<85> @BASEBOARD_FAB2_LIB.BASEBOARD_FAB2(SCH_1):GND
  22    GND VSS<84> @BASEBOARD_FAB2_LIB.BASEBOARD_FAB2(SCH_1):GND
  24    GND VSS<83> @BASEBOARD_FAB2_LIB.BASEBOARD_FAB2(SCH_1):GND
  26    GND VSS<82> @BASEBOARD_FAB2_LIB.BASEBOARD_FAB2(SCH_1):GND
  28    GND VSS<81> @BASEBOARD_FAB2_LIB.BASEBOARD_FAB2(SCH_1):GND
  31    GND VSS<80> @BASEBOARD_FAB2_LIB.BASEBOARD_FAB2(SCH_1):GND
  33    GND VSS<79> @BASEBOARD_FAB2_LIB.BASEBOARD_FAB2(SCH_1):GND
  35    GND VSS<78> @BASEBOARD_FAB2_LIB.BASEBOARD_FAB2(SCH_1):GND
  37    GND VSS<77> @BASEBOARD_FAB2_LIB.BASEBOARD_FAB2(SCH_1):GND
  39    GND VSS<76> @BASEBOARD_FAB2_LIB.BASEBOARD_FAB2(SCH_1):GND
  42    GND VSS<75> @BASEBOARD_FAB2_LIB.BASEBOARD_FAB2(SCH_1):GND
  44    GND VSS<74> @BASEBOARD_FAB2_LIB.BASEBOARD_FAB2(SCH_1):GND
  46    GND VSS<73> @BASEBOARD_FAB2_LIB.BASEBOARD_FAB2(SCH_1):GND
  48    GND VSS<72> @BASEBOARD_FAB2_LIB.BASEBOARD_FAB2(SCH_1):GND
  50    GND VSS<71> @BASEBOARD_FAB2_LIB.BASEBOARD_FAB2(SCH_1):GND
  53    GND VSS<70> @BASEBOARD_FAB2_LIB.BASEBOARD_FAB2(SCH_1):GND
  55    GND VSS<69> @BASEBOARD_FAB2_LIB.BASEBOARD_FAB2(SCH_1):GND
  57    GND VSS<68> @BASEBOARD_FAB2_LIB.BASEBOARD_FAB2(SCH_1):GND
  94    GND VSS<67> @BASEBOARD_FAB2_LIB.BASEBOARD_FAB2(SCH_1):GND
  96    GND VSS<66> @BASEBOARD_FAB2_LIB.BASEBOARD_FAB2(SCH_1):GND
  98    GND VSS<65> @BASEBOARD_FAB2_LIB.BASEBOARD_FAB2(SCH_1):GND
 101    GND VSS<64> @BASEBOARD_FAB2_LIB.BASEBOARD_FAB2(SCH_1):GND
 103    GND VSS<63> @BASEBOARD_FAB2_LIB.BASEBOARD_FAB2(SCH_1):GND
 105    GND VSS<62> @BASEBOARD_FAB2_LIB.BASEBOARD_FAB2(SCH_1):GND
 107    GND VSS<61> @BASEBOARD_FAB2_LIB.BASEBOARD_FAB2(SCH_1):GND
 109    GND VSS<60> @BASEBOARD_FAB2_LIB.BASEBOARD_FAB2(SCH_1):GND
 112    GND VSS<59> @BASEBOARD_FAB2_LIB.BASEBOARD_FAB2(SCH_1):GND
 114    GND VSS<58> @BASEBOARD_FAB2_LIB.BASEBOARD_FAB2(SCH_1):GND
 116    GND VSS<57> @BASEBOARD_FAB2_LIB.BASEBOARD_FAB2(SCH_1):GND
 118    GND VSS<56> @BASEBOARD_FAB2_LIB.BASEBOARD_FAB2(SCH_1):GND
 120    GND VSS<55> @BASEBOARD_FAB2_LIB.BASEBOARD_FAB2(SCH_1):GND
 123    GND VSS<54> @BASEBOARD_FAB2_LIB.BASEBOARD_FAB2(SCH_1):GND
 125    GND VSS<53> @BASEBOARD_FAB2_LIB.BASEBOARD_FAB2(SCH_1):GND
 127    GND VSS<52> @BASEBOARD_FAB2_LIB.BASEBOARD_FAB2(SCH_1):GND
 129    GND VSS<51> @BASEBOARD_FAB2_LIB.BASEBOARD_FAB2(SCH_1):GND
 131    GND VSS<50> @BASEBOARD_FAB2_LIB.BASEBOARD_FAB2(SCH_1):GND
 134    GND VSS<49> @BASEBOARD_FAB2_LIB.BASEBOARD_FAB2(SCH_1):GND
 136    GND VSS<48> @BASEBOARD_FAB2_LIB.BASEBOARD_FAB2(SCH_1):GND
 138    GND VSS<47> @BASEBOARD_FAB2_LIB.BASEBOARD_FAB2(SCH_1):GND
 147    GND VSS<46> @BASEBOARD_FAB2_LIB.BASEBOARD_FAB2(SCH_1):GND
 149    GND VSS<45> @BASEBOARD_FAB2_LIB.BASEBOARD_FAB2(SCH_1):GND
 151    GND VSS<44> @BASEBOARD_FAB2_LIB.BASEBOARD_FAB2(SCH_1):GND
 154    GND VSS<43> @BASEBOARD_FAB2_LIB.BASEBOARD_FAB2(SCH_1):GND
 156    GND VSS<42> @BASEBOARD_FAB2_LIB.BASEBOARD_FAB2(SCH_1):GND
 158    GND VSS<41> @BASEBOARD_FAB2_LIB.BASEBOARD_FAB2(SCH_1):GND
 160    GND VSS<40> @BASEBOARD_FAB2_LIB.BASEBOARD_FAB2(SCH_1):GND
 162    GND VSS<39> @BASEBOARD_FAB2_LIB.BASEBOARD_FAB2(SCH_1):GND
 165    GND VSS<38> @BASEBOARD_FAB2_LIB.BASEBOARD_FAB2(SCH_1):GND
 167    GND VSS<37> @BASEBOARD_FAB2_LIB.BASEBOARD_FAB2(SCH_1):GND
 169    GND VSS<36> @BASEBOARD_FAB2_LIB.BASEBOARD_FAB2(SCH_1):GND
 171    GND VSS<35> @BASEBOARD_FAB2_LIB.BASEBOARD_FAB2(SCH_1):GND
 173    GND VSS<34> @BASEBOARD_FAB2_LIB.BASEBOARD_FAB2(SCH_1):GND
 176    GND VSS<33> @BASEBOARD_FAB2_LIB.BASEBOARD_FAB2(SCH_1):GND
 178    GND VSS<32> @BASEBOARD_FAB2_LIB.BASEBOARD_FAB2(SCH_1):GND
 180    GND VSS<31> @BASEBOARD_FAB2_LIB.BASEBOARD_FAB2(SCH_1):GND
 182    GND VSS<30> @BASEBOARD_FAB2_LIB.BASEBOARD_FAB2(SCH_1):GND
 184    GND VSS<29> @BASEBOARD_FAB2_LIB.BASEBOARD_FAB2(SCH_1):GND
 187    GND VSS<28> @BASEBOARD_FAB2_LIB.BASEBOARD_FAB2(SCH_1):GND
 189    GND VSS<27> @BASEBOARD_FAB2_LIB.BASEBOARD_FAB2(SCH_1):GND
 191    GND VSS<26> @BASEBOARD_FAB2_LIB.BASEBOARD_FAB2(SCH_1):GND
 193    GND VSS<25> @BASEBOARD_FAB2_LIB.BASEBOARD_FAB2(SCH_1):GND
 195    GND VSS<24> @BASEBOARD_FAB2_LIB.BASEBOARD_FAB2(SCH_1):GND
 198    GND VSS<23> @BASEBOARD_FAB2_LIB.BASEBOARD_FAB2(SCH_1):GND
 200    GND VSS<22> @BASEBOARD_FAB2_LIB.BASEBOARD_FAB2(SCH_1):GND
 202    GND VSS<21> @BASEBOARD_FAB2_LIB.BASEBOARD_FAB2(SCH_1):GND
 239    GND VSS<20> @BASEBOARD_FAB2_LIB.BASEBOARD_FAB2(SCH_1):GND
 241    GND VSS<19> @BASEBOARD_FAB2_LIB.BASEBOARD_FAB2(SCH_1):GND
 243    GND VSS<18> @BASEBOARD_FAB2_LIB.BASEBOARD_FAB2(SCH_1):GND
 246    GND VSS<17> @BASEBOARD_FAB2_LIB.BASEBOARD_FAB2(SCH_1):GND
 248    GND VSS<16> @BASEBOARD_FAB2_LIB.BASEBOARD_FAB2(SCH_1):GND
 250    GND VSS<15> @BASEBOARD_FAB2_LIB.BASEBOARD_FAB2(SCH_1):GND
 252    GND VSS<14> @BASEBOARD_FAB2_LIB.BASEBOARD_FAB2(SCH_1):GND
 254    GND VSS<13> @BASEBOARD_FAB2_LIB.BASEBOARD_FAB2(SCH_1):GND
 257    GND VSS<12> @BASEBOARD_FAB2_LIB.BASEBOARD_FAB2(SCH_1):GND
 259    GND VSS<11> @BASEBOARD_FAB2_LIB.BASEBOARD_FAB2(SCH_1):GND
 261    GND VSS<10> @BASEBOARD_FAB2_LIB.BASEBOARD_FAB2(SCH_1):GND
 263    GND VSS<9> @BASEBOARD_FAB2_LIB.BASEBOARD_FAB2(SCH_1):GND
 265    GND VSS<8> @BASEBOARD_FAB2_LIB.BASEBOARD_FAB2(SCH_1):GND
 268    GND VSS<7> @BASEBOARD_FAB2_LIB.BASEBOARD_FAB2(SCH_1):GND
 270    GND VSS<6> @BASEBOARD_FAB2_LIB.BASEBOARD_FAB2(SCH_1):GND
 272    GND VSS<5> @BASEBOARD_FAB2_LIB.BASEBOARD_FAB2(SCH_1):GND
 274    GND VSS<4> @BASEBOARD_FAB2_LIB.BASEBOARD_FAB2(SCH_1):GND
 276    GND VSS<3> @BASEBOARD_FAB2_LIB.BASEBOARD_FAB2(SCH_1):GND
 279    GND VSS<2> @BASEBOARD_FAB2_LIB.BASEBOARD_FAB2(SCH_1):GND
 281    GND VSS<1> @BASEBOARD_FAB2_LIB.BASEBOARD_FAB2(SCH_1):GND
 283    GND VSS<0> @BASEBOARD_FAB2_LIB.BASEBOARD_FAB2(SCH_1):GND

SCONN288_H44441004_PIP-SCONN,HA  I66  J4A2
 152 M_E_DQS_DN<0>  DQS0N @BASEBOARD_FAB2_LIB.BASEBOARD_FAB2(SCH_1):M_E_DQS_DN(0)
 153 M_E_DQS_DP<0>  DQS0P @BASEBOARD_FAB2_LIB.BASEBOARD_FAB2(SCH_1):M_E_DQS_DP(0)
  19 M_E_DQS_DN<10> DQS10N @BASEBOARD_FAB2_LIB.BASEBOARD_FAB2(SCH_1):M_E_DQS_DN(10)
  18 M_E_DQS_DP<10> DQS10P @BASEBOARD_FAB2_LIB.BASEBOARD_FAB2(SCH_1):M_E_DQS_DP(10)
  30 M_E_DQS_DN<11> DQS11N @BASEBOARD_FAB2_LIB.BASEBOARD_FAB2(SCH_1):M_E_DQS_DN(11)
  29 M_E_DQS_DP<11> DQS11P @BASEBOARD_FAB2_LIB.BASEBOARD_FAB2(SCH_1):M_E_DQS_DP(11)
  41 M_E_DQS_DN<12> DQS12N @BASEBOARD_FAB2_LIB.BASEBOARD_FAB2(SCH_1):M_E_DQS_DN(12)
  40 M_E_DQS_DP<12> DQS12P @BASEBOARD_FAB2_LIB.BASEBOARD_FAB2(SCH_1):M_E_DQS_DP(12)
 100 M_E_DQS_DN<13> DQS13N @BASEBOARD_FAB2_LIB.BASEBOARD_FAB2(SCH_1):M_E_DQS_DN(13)
  99 M_E_DQS_DP<13> DQS13P @BASEBOARD_FAB2_LIB.BASEBOARD_FAB2(SCH_1):M_E_DQS_DP(13)
 111 M_E_DQS_DN<14> DQS14N @BASEBOARD_FAB2_LIB.BASEBOARD_FAB2(SCH_1):M_E_DQS_DN(14)
 110 M_E_DQS_DP<14> DQS14P @BASEBOARD_FAB2_LIB.BASEBOARD_FAB2(SCH_1):M_E_DQS_DP(14)
 122 M_E_DQS_DN<15> DQS15N @BASEBOARD_FAB2_LIB.BASEBOARD_FAB2(SCH_1):M_E_DQS_DN(15)
 121 M_E_DQS_DP<15> DQS15P @BASEBOARD_FAB2_LIB.BASEBOARD_FAB2(SCH_1):M_E_DQS_DP(15)
 133 M_E_DQS_DN<16> DQS16N @BASEBOARD_FAB2_LIB.BASEBOARD_FAB2(SCH_1):M_E_DQS_DN(16)
 132 M_E_DQS_DP<16> DQS16P @BASEBOARD_FAB2_LIB.BASEBOARD_FAB2(SCH_1):M_E_DQS_DP(16)
  52 M_E_DQS_DN<17> DQS17N @BASEBOARD_FAB2_LIB.BASEBOARD_FAB2(SCH_1):M_E_DQS_DN(17)
  51 M_E_DQS_DP<17> DQS17P @BASEBOARD_FAB2_LIB.BASEBOARD_FAB2(SCH_1):M_E_DQS_DP(17)
 163 M_E_DQS_DN<1>  DQS1N @BASEBOARD_FAB2_LIB.BASEBOARD_FAB2(SCH_1):M_E_DQS_DN(1)
 164 M_E_DQS_DP<1>  DQS1P @BASEBOARD_FAB2_LIB.BASEBOARD_FAB2(SCH_1):M_E_DQS_DP(1)
 174 M_E_DQS_DN<2>  DQS2N @BASEBOARD_FAB2_LIB.BASEBOARD_FAB2(SCH_1):M_E_DQS_DN(2)
 175 M_E_DQS_DP<2>  DQS2P @BASEBOARD_FAB2_LIB.BASEBOARD_FAB2(SCH_1):M_E_DQS_DP(2)
 185 M_E_DQS_DN<3>  DQS3N @BASEBOARD_FAB2_LIB.BASEBOARD_FAB2(SCH_1):M_E_DQS_DN(3)
 186 M_E_DQS_DP<3>  DQS3P @BASEBOARD_FAB2_LIB.BASEBOARD_FAB2(SCH_1):M_E_DQS_DP(3)
 244 M_E_DQS_DN<4>  DQS4N @BASEBOARD_FAB2_LIB.BASEBOARD_FAB2(SCH_1):M_E_DQS_DN(4)
 245 M_E_DQS_DP<4>  DQS4P @BASEBOARD_FAB2_LIB.BASEBOARD_FAB2(SCH_1):M_E_DQS_DP(4)
 255 M_E_DQS_DN<5>  DQS5N @BASEBOARD_FAB2_LIB.BASEBOARD_FAB2(SCH_1):M_E_DQS_DN(5)
 256 M_E_DQS_DP<5>  DQS5P @BASEBOARD_FAB2_LIB.BASEBOARD_FAB2(SCH_1):M_E_DQS_DP(5)
 266 M_E_DQS_DN<6>  DQS6N @BASEBOARD_FAB2_LIB.BASEBOARD_FAB2(SCH_1):M_E_DQS_DN(6)
 267 M_E_DQS_DP<6>  DQS6P @BASEBOARD_FAB2_LIB.BASEBOARD_FAB2(SCH_1):M_E_DQS_DP(6)
 277 M_E_DQS_DN<7>  DQS7N @BASEBOARD_FAB2_LIB.BASEBOARD_FAB2(SCH_1):M_E_DQS_DN(7)
 278 M_E_DQS_DP<7>  DQS7P @BASEBOARD_FAB2_LIB.BASEBOARD_FAB2(SCH_1):M_E_DQS_DP(7)
 196 M_E_DQS_DN<8>  DQS8N @BASEBOARD_FAB2_LIB.BASEBOARD_FAB2(SCH_1):M_E_DQS_DN(8)
 197 M_E_DQS_DP<8>  DQS8P @BASEBOARD_FAB2_LIB.BASEBOARD_FAB2(SCH_1):M_E_DQS_DP(8)
   8 M_E_DQS_DN<9>  DQS9N @BASEBOARD_FAB2_LIB.BASEBOARD_FAB2(SCH_1):M_E_DQS_DN(9)
   7 M_E_DQS_DP<9>  DQS9P @BASEBOARD_FAB2_LIB.BASEBOARD_FAB2(SCH_1):M_E_DQS_DP(9)

SCONN288_H44441004_PIP-SCONN,HA  I111  J4A2
  79 M_E_MA<0>     A0 @BASEBOARD_FAB2_LIB.BASEBOARD_FAB2(SCH_1):M_E_MA(0)
  72 M_E_MA<1>     A1 @BASEBOARD_FAB2_LIB.BASEBOARD_FAB2(SCH_1):M_E_MA(1)
 225 M_E_MA<10>    A10 @BASEBOARD_FAB2_LIB.BASEBOARD_FAB2(SCH_1):M_E_MA(10)
 210 M_E_MA<11>    A11 @BASEBOARD_FAB2_LIB.BASEBOARD_FAB2(SCH_1):M_E_MA(11)
  65 M_E_MA<12>    A12 @BASEBOARD_FAB2_LIB.BASEBOARD_FAB2(SCH_1):M_E_MA(12)
 232 M_E_MA<13>    A13 @BASEBOARD_FAB2_LIB.BASEBOARD_FAB2(SCH_1):M_E_MA(13)
 228 M_E_MA<14> A14_WE_N @BASEBOARD_FAB2_LIB.BASEBOARD_FAB2(SCH_1):M_E_MA(14)
  86 M_E_MA<15> A15_CAS_N @BASEBOARD_FAB2_LIB.BASEBOARD_FAB2(SCH_1):M_E_MA(15)
  82 M_E_MA<16> A16_RAS_N @BASEBOARD_FAB2_LIB.BASEBOARD_FAB2(SCH_1):M_E_MA(16)
 234 M_E_MA<17>    A17 @BASEBOARD_FAB2_LIB.BASEBOARD_FAB2(SCH_1):M_E_MA(17)
 216 M_E_MA<2>     A2 @BASEBOARD_FAB2_LIB.BASEBOARD_FAB2(SCH_1):M_E_MA(2)
  71 M_E_MA<3>     A3 @BASEBOARD_FAB2_LIB.BASEBOARD_FAB2(SCH_1):M_E_MA(3)
 214 M_E_MA<4>     A4 @BASEBOARD_FAB2_LIB.BASEBOARD_FAB2(SCH_1):M_E_MA(4)
 213 M_E_MA<5>     A5 @BASEBOARD_FAB2_LIB.BASEBOARD_FAB2(SCH_1):M_E_MA(5)
  69 M_E_MA<6>     A6 @BASEBOARD_FAB2_LIB.BASEBOARD_FAB2(SCH_1):M_E_MA(6)
 211 M_E_MA<7>     A7 @BASEBOARD_FAB2_LIB.BASEBOARD_FAB2(SCH_1):M_E_MA(7)
  68 M_E_MA<8>     A8 @BASEBOARD_FAB2_LIB.BASEBOARD_FAB2(SCH_1):M_E_MA(8)
  66 M_E_MA<9>     A9 @BASEBOARD_FAB2_LIB.BASEBOARD_FAB2(SCH_1):M_E_MA(9)
  62 M_E_ACT_N  ACT_N @BASEBOARD_FAB2_LIB.BASEBOARD_FAB2(SCH_1):M_E_ACT_N
 208 M_E_ALERT_N ALERT_N @BASEBOARD_FAB2_LIB.BASEBOARD_FAB2(SCH_1):M_E_ALERT_N
 224 M_E_BA<1>  BA<1> @BASEBOARD_FAB2_LIB.BASEBOARD_FAB2(SCH_1):M_E_BA(1)
  81 M_E_BA<0>  BA<0> @BASEBOARD_FAB2_LIB.BASEBOARD_FAB2(SCH_1):M_E_BA(0)
 207 M_E_BG<1>  BG<1> @BASEBOARD_FAB2_LIB.BASEBOARD_FAB2(SCH_1):M_E_BG(1)
  63 M_E_BG<0>  BG<0> @BASEBOARD_FAB2_LIB.BASEBOARD_FAB2(SCH_1):M_E_BG(0)
 235 M_E_C<2>   C<2> @BASEBOARD_FAB2_LIB.BASEBOARD_FAB2(SCH_1):M_E_C(2)
 199 M_E_ECC<6>  CB<7> @BASEBOARD_FAB2_LIB.BASEBOARD_FAB2(SCH_1):M_E_ECC(6)
  54 M_E_ECC<7>  CB<6> @BASEBOARD_FAB2_LIB.BASEBOARD_FAB2(SCH_1):M_E_ECC(7)
 192 M_E_ECC<4>  CB<5> @BASEBOARD_FAB2_LIB.BASEBOARD_FAB2(SCH_1):M_E_ECC(4)
  47 M_E_ECC<5>  CB<4> @BASEBOARD_FAB2_LIB.BASEBOARD_FAB2(SCH_1):M_E_ECC(5)
 201 M_E_ECC<2>  CB<3> @BASEBOARD_FAB2_LIB.BASEBOARD_FAB2(SCH_1):M_E_ECC(2)
  56 M_E_ECC<3>  CB<2> @BASEBOARD_FAB2_LIB.BASEBOARD_FAB2(SCH_1):M_E_ECC(3)
 194 M_E_ECC<0>  CB<1> @BASEBOARD_FAB2_LIB.BASEBOARD_FAB2(SCH_1):M_E_ECC(0)
  49 M_E_ECC<1>  CB<0> @BASEBOARD_FAB2_LIB.BASEBOARD_FAB2(SCH_1):M_E_ECC(1)
  75 M_E_CLK_DN<0>   CK0N @BASEBOARD_FAB2_LIB.BASEBOARD_FAB2(SCH_1):M_E_CLK_DN(0)
  74 M_E_CLK_DP<0>   CK0P @BASEBOARD_FAB2_LIB.BASEBOARD_FAB2(SCH_1):M_E_CLK_DP(0)
 219 M_E_CLK_DN<1>   CK1N @BASEBOARD_FAB2_LIB.BASEBOARD_FAB2(SCH_1):M_E_CLK_DN(1)
 218 M_E_CLK_DP<1>   CK1P @BASEBOARD_FAB2_LIB.BASEBOARD_FAB2(SCH_1):M_E_CLK_DP(1)
 203 M_E_CKE<1> CKE<1> @BASEBOARD_FAB2_LIB.BASEBOARD_FAB2(SCH_1):M_E_CKE(1)
  60 M_E_CKE<0> CKE<0> @BASEBOARD_FAB2_LIB.BASEBOARD_FAB2(SCH_1):M_E_CKE(0)
 280 M_E_DQ<62> DQ<63> @BASEBOARD_FAB2_LIB.BASEBOARD_FAB2(SCH_1):M_E_DQ(62)
 135 M_E_DQ<63> DQ<62> @BASEBOARD_FAB2_LIB.BASEBOARD_FAB2(SCH_1):M_E_DQ(63)
 273 M_E_DQ<60> DQ<61> @BASEBOARD_FAB2_LIB.BASEBOARD_FAB2(SCH_1):M_E_DQ(60)
 128 M_E_DQ<61> DQ<60> @BASEBOARD_FAB2_LIB.BASEBOARD_FAB2(SCH_1):M_E_DQ(61)
 282 M_E_DQ<58> DQ<59> @BASEBOARD_FAB2_LIB.BASEBOARD_FAB2(SCH_1):M_E_DQ(58)
 137 M_E_DQ<59> DQ<58> @BASEBOARD_FAB2_LIB.BASEBOARD_FAB2(SCH_1):M_E_DQ(59)
 275 M_E_DQ<56> DQ<57> @BASEBOARD_FAB2_LIB.BASEBOARD_FAB2(SCH_1):M_E_DQ(56)
 130 M_E_DQ<57> DQ<56> @BASEBOARD_FAB2_LIB.BASEBOARD_FAB2(SCH_1):M_E_DQ(57)
 269 M_E_DQ<54> DQ<55> @BASEBOARD_FAB2_LIB.BASEBOARD_FAB2(SCH_1):M_E_DQ(54)
 124 M_E_DQ<55> DQ<54> @BASEBOARD_FAB2_LIB.BASEBOARD_FAB2(SCH_1):M_E_DQ(55)
 262 M_E_DQ<52> DQ<53> @BASEBOARD_FAB2_LIB.BASEBOARD_FAB2(SCH_1):M_E_DQ(52)
 117 M_E_DQ<53> DQ<52> @BASEBOARD_FAB2_LIB.BASEBOARD_FAB2(SCH_1):M_E_DQ(53)
 271 M_E_DQ<50> DQ<51> @BASEBOARD_FAB2_LIB.BASEBOARD_FAB2(SCH_1):M_E_DQ(50)
 126 M_E_DQ<51> DQ<50> @BASEBOARD_FAB2_LIB.BASEBOARD_FAB2(SCH_1):M_E_DQ(51)
 264 M_E_DQ<48> DQ<49> @BASEBOARD_FAB2_LIB.BASEBOARD_FAB2(SCH_1):M_E_DQ(48)
 119 M_E_DQ<49> DQ<48> @BASEBOARD_FAB2_LIB.BASEBOARD_FAB2(SCH_1):M_E_DQ(49)
 258 M_E_DQ<46> DQ<47> @BASEBOARD_FAB2_LIB.BASEBOARD_FAB2(SCH_1):M_E_DQ(46)
 113 M_E_DQ<47> DQ<46> @BASEBOARD_FAB2_LIB.BASEBOARD_FAB2(SCH_1):M_E_DQ(47)
 251 M_E_DQ<44> DQ<45> @BASEBOARD_FAB2_LIB.BASEBOARD_FAB2(SCH_1):M_E_DQ(44)
 106 M_E_DQ<45> DQ<44> @BASEBOARD_FAB2_LIB.BASEBOARD_FAB2(SCH_1):M_E_DQ(45)
 260 M_E_DQ<42> DQ<43> @BASEBOARD_FAB2_LIB.BASEBOARD_FAB2(SCH_1):M_E_DQ(42)
 115 M_E_DQ<43> DQ<42> @BASEBOARD_FAB2_LIB.BASEBOARD_FAB2(SCH_1):M_E_DQ(43)
 253 M_E_DQ<40> DQ<41> @BASEBOARD_FAB2_LIB.BASEBOARD_FAB2(SCH_1):M_E_DQ(40)
 108 M_E_DQ<41> DQ<40> @BASEBOARD_FAB2_LIB.BASEBOARD_FAB2(SCH_1):M_E_DQ(41)
 247 M_E_DQ<38> DQ<39> @BASEBOARD_FAB2_LIB.BASEBOARD_FAB2(SCH_1):M_E_DQ(38)
 102 M_E_DQ<39> DQ<38> @BASEBOARD_FAB2_LIB.BASEBOARD_FAB2(SCH_1):M_E_DQ(39)
 240 M_E_DQ<36> DQ<37> @BASEBOARD_FAB2_LIB.BASEBOARD_FAB2(SCH_1):M_E_DQ(36)
  95 M_E_DQ<37> DQ<36> @BASEBOARD_FAB2_LIB.BASEBOARD_FAB2(SCH_1):M_E_DQ(37)
 249 M_E_DQ<34> DQ<35> @BASEBOARD_FAB2_LIB.BASEBOARD_FAB2(SCH_1):M_E_DQ(34)
 104 M_E_DQ<35> DQ<34> @BASEBOARD_FAB2_LIB.BASEBOARD_FAB2(SCH_1):M_E_DQ(35)
 242 M_E_DQ<32> DQ<33> @BASEBOARD_FAB2_LIB.BASEBOARD_FAB2(SCH_1):M_E_DQ(32)
  97 M_E_DQ<33> DQ<32> @BASEBOARD_FAB2_LIB.BASEBOARD_FAB2(SCH_1):M_E_DQ(33)
 188 M_E_DQ<30> DQ<31> @BASEBOARD_FAB2_LIB.BASEBOARD_FAB2(SCH_1):M_E_DQ(30)
  43 M_E_DQ<31> DQ<30> @BASEBOARD_FAB2_LIB.BASEBOARD_FAB2(SCH_1):M_E_DQ(31)
 181 M_E_DQ<28> DQ<29> @BASEBOARD_FAB2_LIB.BASEBOARD_FAB2(SCH_1):M_E_DQ(28)
  36 M_E_DQ<29> DQ<28> @BASEBOARD_FAB2_LIB.BASEBOARD_FAB2(SCH_1):M_E_DQ(29)
 190 M_E_DQ<26> DQ<27> @BASEBOARD_FAB2_LIB.BASEBOARD_FAB2(SCH_1):M_E_DQ(26)
  45 M_E_DQ<27> DQ<26> @BASEBOARD_FAB2_LIB.BASEBOARD_FAB2(SCH_1):M_E_DQ(27)
 183 M_E_DQ<24> DQ<25> @BASEBOARD_FAB2_LIB.BASEBOARD_FAB2(SCH_1):M_E_DQ(24)
  38 M_E_DQ<25> DQ<24> @BASEBOARD_FAB2_LIB.BASEBOARD_FAB2(SCH_1):M_E_DQ(25)
 177 M_E_DQ<22> DQ<23> @BASEBOARD_FAB2_LIB.BASEBOARD_FAB2(SCH_1):M_E_DQ(22)
  32 M_E_DQ<23> DQ<22> @BASEBOARD_FAB2_LIB.BASEBOARD_FAB2(SCH_1):M_E_DQ(23)
 170 M_E_DQ<20> DQ<21> @BASEBOARD_FAB2_LIB.BASEBOARD_FAB2(SCH_1):M_E_DQ(20)
  25 M_E_DQ<21> DQ<20> @BASEBOARD_FAB2_LIB.BASEBOARD_FAB2(SCH_1):M_E_DQ(21)
 179 M_E_DQ<18> DQ<19> @BASEBOARD_FAB2_LIB.BASEBOARD_FAB2(SCH_1):M_E_DQ(18)
  34 M_E_DQ<19> DQ<18> @BASEBOARD_FAB2_LIB.BASEBOARD_FAB2(SCH_1):M_E_DQ(19)
 172 M_E_DQ<16> DQ<17> @BASEBOARD_FAB2_LIB.BASEBOARD_FAB2(SCH_1):M_E_DQ(16)
  27 M_E_DQ<17> DQ<16> @BASEBOARD_FAB2_LIB.BASEBOARD_FAB2(SCH_1):M_E_DQ(17)
 166 M_E_DQ<14> DQ<15> @BASEBOARD_FAB2_LIB.BASEBOARD_FAB2(SCH_1):M_E_DQ(14)
  21 M_E_DQ<15> DQ<14> @BASEBOARD_FAB2_LIB.BASEBOARD_FAB2(SCH_1):M_E_DQ(15)
 159 M_E_DQ<12> DQ<13> @BASEBOARD_FAB2_LIB.BASEBOARD_FAB2(SCH_1):M_E_DQ(12)
  14 M_E_DQ<13> DQ<12> @BASEBOARD_FAB2_LIB.BASEBOARD_FAB2(SCH_1):M_E_DQ(13)
 168 M_E_DQ<10> DQ<11> @BASEBOARD_FAB2_LIB.BASEBOARD_FAB2(SCH_1):M_E_DQ(10)
  23 M_E_DQ<11> DQ<10> @BASEBOARD_FAB2_LIB.BASEBOARD_FAB2(SCH_1):M_E_DQ(11)
 161 M_E_DQ<8>  DQ<9> @BASEBOARD_FAB2_LIB.BASEBOARD_FAB2(SCH_1):M_E_DQ(8)
  16 M_E_DQ<9>  DQ<8> @BASEBOARD_FAB2_LIB.BASEBOARD_FAB2(SCH_1):M_E_DQ(9)
 155 M_E_DQ<6>  DQ<7> @BASEBOARD_FAB2_LIB.BASEBOARD_FAB2(SCH_1):M_E_DQ(6)
  10 M_E_DQ<7>  DQ<6> @BASEBOARD_FAB2_LIB.BASEBOARD_FAB2(SCH_1):M_E_DQ(7)
 148 M_E_DQ<4>  DQ<5> @BASEBOARD_FAB2_LIB.BASEBOARD_FAB2(SCH_1):M_E_DQ(4)
   3 M_E_DQ<5>  DQ<4> @BASEBOARD_FAB2_LIB.BASEBOARD_FAB2(SCH_1):M_E_DQ(5)
 157 M_E_DQ<2>  DQ<3> @BASEBOARD_FAB2_LIB.BASEBOARD_FAB2(SCH_1):M_E_DQ(2)
  12 M_E_DQ<3>  DQ<2> @BASEBOARD_FAB2_LIB.BASEBOARD_FAB2(SCH_1):M_E_DQ(3)
 150 M_E_DQ<0>  DQ<1> @BASEBOARD_FAB2_LIB.BASEBOARD_FAB2(SCH_1):M_E_DQ(0)
   5 M_E_DQ<1>  DQ<0> @BASEBOARD_FAB2_LIB.BASEBOARD_FAB2(SCH_1):M_E_DQ(1)
  78 FM_DIMM_EVENT_COD_N EVENT_N @BASEBOARD_FAB2_LIB.BASEBOARD_FAB2(SCH_1):FM_DIMM_EVENT_COD_N
  91 M_E_ODT<1> ODT<1> @BASEBOARD_FAB2_LIB.BASEBOARD_FAB2(SCH_1):M_E_ODT(1)
  87 M_E_ODT<0> ODT<0> @BASEBOARD_FAB2_LIB.BASEBOARD_FAB2(SCH_1):M_E_ODT(0)
 222 M_E_PAR    PAR @BASEBOARD_FAB2_LIB.BASEBOARD_FAB2(SCH_1):M_E_PAR
  58 M_DEF_RST_N RESET_N @BASEBOARD_FAB2_LIB.BASEBOARD_FAB2(SCH_1):M_DEF_RST_N
 144 TP_CH_E_DIMM_E0_RFU_2 RFU<2> @BASEBOARD_FAB2_LIB.BASEBOARD_FAB2(SCH_1):TP_CH_E_DIMM_E0_RFU_2
 227 TP_CH_E_DIMM_E0_RFU_1 RFU<1> @BASEBOARD_FAB2_LIB.BASEBOARD_FAB2(SCH_1):TP_CH_E_DIMM_E0_RFU_1
 205 TP_CH_E_DIMM_E0_RFU_0 RFU<0> @BASEBOARD_FAB2_LIB.BASEBOARD_FAB2(SCH_1):TP_CH_E_DIMM_E0_RFU_0
  84 M_E_CS_N<0>   S0_N @BASEBOARD_FAB2_LIB.BASEBOARD_FAB2(SCH_1):M_E_CS_N(0)
  89 M_E_CS_N<1>   S1_N @BASEBOARD_FAB2_LIB.BASEBOARD_FAB2(SCH_1):M_E_CS_N(1)
  93 M_E_CS_N<2> S2_N_C<0> @BASEBOARD_FAB2_LIB.BASEBOARD_FAB2(SCH_1):M_E_CS_N(2)
 237 M_E_CS_N<3> S3_N_C<1> @BASEBOARD_FAB2_LIB.BASEBOARD_FAB2(SCH_1):M_E_CS_N(3)
 238    GND  SA<2> @BASEBOARD_FAB2_LIB.BASEBOARD_FAB2(SCH_1):GND
 140 PVPP_DEF  SA<1> @BASEBOARD_FAB2_LIB.BASEBOARD_FAB2(SCH_1):PVPP_DEF
 139    GND  SA<0> @BASEBOARD_FAB2_LIB.BASEBOARD_FAB2(SCH_1):GND
 230 FM_ADR_COMPLETE_DEF_N SAVE_N_NC @BASEBOARD_FAB2_LIB.BASEBOARD_FAB2(SCH_1):FM_ADR_COMPLETE_DEF_N
 141 SMB_DDR_DEF_VPP_SCL    SCL @BASEBOARD_FAB2_LIB.BASEBOARD_FAB2(SCH_1):SMB_DDR_DEF_VPP_SCL
 285 SMB_DDR_DEF_VPP_SDA    SDA @BASEBOARD_FAB2_LIB.BASEBOARD_FAB2(SCH_1):SMB_DDR_DEF_VPP_SDA
 284 PVPP_DEF VDDSPD @BASEBOARD_FAB2_LIB.BASEBOARD_FAB2(SCH_1):PVPP_DEF
 146 M_E_VREF VREFCA @BASEBOARD_FAB2_LIB.BASEBOARD_FAB2(SCH_1):M_E_VREF

SCONN288_H44441004_PIP-SCONN,HA  I167  J4A2
   1 P12V_NVDIMM_DEF 12V<1> @BASEBOARD_FAB2_LIB.BASEBOARD_FAB2(SCH_1):P12V_NVDIMM_DEF
 145 P12V_NVDIMM_DEF 12V<0> @BASEBOARD_FAB2_LIB.BASEBOARD_FAB2(SCH_1):P12V_NVDIMM_DEF
  59 PVDDQ_DEF VDD<25> @BASEBOARD_FAB2_LIB.BASEBOARD_FAB2(SCH_1):PVDDQ_DEF
  61 PVDDQ_DEF VDD<24> @BASEBOARD_FAB2_LIB.BASEBOARD_FAB2(SCH_1):PVDDQ_DEF
  64 PVDDQ_DEF VDD<23> @BASEBOARD_FAB2_LIB.BASEBOARD_FAB2(SCH_1):PVDDQ_DEF
  67 PVDDQ_DEF VDD<22> @BASEBOARD_FAB2_LIB.BASEBOARD_FAB2(SCH_1):PVDDQ_DEF
  70 PVDDQ_DEF VDD<21> @BASEBOARD_FAB2_LIB.BASEBOARD_FAB2(SCH_1):PVDDQ_DEF
  73 PVDDQ_DEF VDD<20> @BASEBOARD_FAB2_LIB.BASEBOARD_FAB2(SCH_1):PVDDQ_DEF
  76 PVDDQ_DEF VDD<19> @BASEBOARD_FAB2_LIB.BASEBOARD_FAB2(SCH_1):PVDDQ_DEF
  80 PVDDQ_DEF VDD<18> @BASEBOARD_FAB2_LIB.BASEBOARD_FAB2(SCH_1):PVDDQ_DEF
  83 PVDDQ_DEF VDD<17> @BASEBOARD_FAB2_LIB.BASEBOARD_FAB2(SCH_1):PVDDQ_DEF
  85 PVDDQ_DEF VDD<16> @BASEBOARD_FAB2_LIB.BASEBOARD_FAB2(SCH_1):PVDDQ_DEF
  88 PVDDQ_DEF VDD<15> @BASEBOARD_FAB2_LIB.BASEBOARD_FAB2(SCH_1):PVDDQ_DEF
  90 PVDDQ_DEF VDD<14> @BASEBOARD_FAB2_LIB.BASEBOARD_FAB2(SCH_1):PVDDQ_DEF
  92 PVDDQ_DEF VDD<13> @BASEBOARD_FAB2_LIB.BASEBOARD_FAB2(SCH_1):PVDDQ_DEF
 204 PVDDQ_DEF VDD<12> @BASEBOARD_FAB2_LIB.BASEBOARD_FAB2(SCH_1):PVDDQ_DEF
 206 PVDDQ_DEF VDD<11> @BASEBOARD_FAB2_LIB.BASEBOARD_FAB2(SCH_1):PVDDQ_DEF
 209 PVDDQ_DEF VDD<10> @BASEBOARD_FAB2_LIB.BASEBOARD_FAB2(SCH_1):PVDDQ_DEF
 212 PVDDQ_DEF VDD<9> @BASEBOARD_FAB2_LIB.BASEBOARD_FAB2(SCH_1):PVDDQ_DEF
 215 PVDDQ_DEF VDD<8> @BASEBOARD_FAB2_LIB.BASEBOARD_FAB2(SCH_1):PVDDQ_DEF
 217 PVDDQ_DEF VDD<7> @BASEBOARD_FAB2_LIB.BASEBOARD_FAB2(SCH_1):PVDDQ_DEF
 220 PVDDQ_DEF VDD<6> @BASEBOARD_FAB2_LIB.BASEBOARD_FAB2(SCH_1):PVDDQ_DEF
 223 PVDDQ_DEF VDD<5> @BASEBOARD_FAB2_LIB.BASEBOARD_FAB2(SCH_1):PVDDQ_DEF
 226 PVDDQ_DEF VDD<4> @BASEBOARD_FAB2_LIB.BASEBOARD_FAB2(SCH_1):PVDDQ_DEF
 229 PVDDQ_DEF VDD<3> @BASEBOARD_FAB2_LIB.BASEBOARD_FAB2(SCH_1):PVDDQ_DEF
 231 PVDDQ_DEF VDD<2> @BASEBOARD_FAB2_LIB.BASEBOARD_FAB2(SCH_1):PVDDQ_DEF
 233 PVDDQ_DEF VDD<1> @BASEBOARD_FAB2_LIB.BASEBOARD_FAB2(SCH_1):PVDDQ_DEF
 236 PVDDQ_DEF VDD<0> @BASEBOARD_FAB2_LIB.BASEBOARD_FAB2(SCH_1):PVDDQ_DEF
 142 PVPP_DEF VPP<4> @BASEBOARD_FAB2_LIB.BASEBOARD_FAB2(SCH_1):PVPP_DEF
 143 PVPP_DEF VPP<3> @BASEBOARD_FAB2_LIB.BASEBOARD_FAB2(SCH_1):PVPP_DEF
 288 PVPP_DEF VPP<2> @BASEBOARD_FAB2_LIB.BASEBOARD_FAB2(SCH_1):PVPP_DEF
 286 PVPP_DEF VPP<1> @BASEBOARD_FAB2_LIB.BASEBOARD_FAB2(SCH_1):PVPP_DEF
 287 PVPP_DEF VPP<0> @BASEBOARD_FAB2_LIB.BASEBOARD_FAB2(SCH_1):PVPP_DEF
  77 PVTT_DEF VTT<1> @BASEBOARD_FAB2_LIB.BASEBOARD_FAB2(SCH_1):PVTT_DEF
 221 PVTT_DEF VTT<0> @BASEBOARD_FAB2_LIB.BASEBOARD_FAB2(SCH_1):PVTT_DEF

CAP_A_0402V-0.01UF,25V,10%,X7RA  I175  C6L6
   1 M_E_VREF      A @BASEBOARD_FAB2_LIB.BASEBOARD_FAB2(SCH_1):M_E_VREF
   2    GND      B @BASEBOARD_FAB2_LIB.BASEBOARD_FAB2(SCH_1):GND


DRAWING: @BASEBOARD_FAB2_LIB.BASEBOARD_FAB2(SCH_1):PAGE52 

CAP_A_0402V-0.01UF,25V,10%,X7RA  I3  C4A18
   1 M_E_VREF      A @BASEBOARD_FAB2_LIB.BASEBOARD_FAB2(SCH_1):M_E_VREF
   2    GND      B @BASEBOARD_FAB2_LIB.BASEBOARD_FAB2(SCH_1):GND

SCONN288_H44441003_PIP-SCONN,HA  I12  J6L2
  79 M_E_MA<0>     A0 @BASEBOARD_FAB2_LIB.BASEBOARD_FAB2(SCH_1):M_E_MA(0)
  72 M_E_MA<1>     A1 @BASEBOARD_FAB2_LIB.BASEBOARD_FAB2(SCH_1):M_E_MA(1)
 225 M_E_MA<10>    A10 @BASEBOARD_FAB2_LIB.BASEBOARD_FAB2(SCH_1):M_E_MA(10)
 210 M_E_MA<11>    A11 @BASEBOARD_FAB2_LIB.BASEBOARD_FAB2(SCH_1):M_E_MA(11)
  65 M_E_MA<12>    A12 @BASEBOARD_FAB2_LIB.BASEBOARD_FAB2(SCH_1):M_E_MA(12)
 232 M_E_MA<13>    A13 @BASEBOARD_FAB2_LIB.BASEBOARD_FAB2(SCH_1):M_E_MA(13)
 228 M_E_MA<14> A14_WE_N @BASEBOARD_FAB2_LIB.BASEBOARD_FAB2(SCH_1):M_E_MA(14)
  86 M_E_MA<15> A15_CAS_N @BASEBOARD_FAB2_LIB.BASEBOARD_FAB2(SCH_1):M_E_MA(15)
  82 M_E_MA<16> A16_RAS_N @BASEBOARD_FAB2_LIB.BASEBOARD_FAB2(SCH_1):M_E_MA(16)
 234 M_E_MA<17>    A17 @BASEBOARD_FAB2_LIB.BASEBOARD_FAB2(SCH_1):M_E_MA(17)
 216 M_E_MA<2>     A2 @BASEBOARD_FAB2_LIB.BASEBOARD_FAB2(SCH_1):M_E_MA(2)
  71 M_E_MA<3>     A3 @BASEBOARD_FAB2_LIB.BASEBOARD_FAB2(SCH_1):M_E_MA(3)
 214 M_E_MA<4>     A4 @BASEBOARD_FAB2_LIB.BASEBOARD_FAB2(SCH_1):M_E_MA(4)
 213 M_E_MA<5>     A5 @BASEBOARD_FAB2_LIB.BASEBOARD_FAB2(SCH_1):M_E_MA(5)
  69 M_E_MA<6>     A6 @BASEBOARD_FAB2_LIB.BASEBOARD_FAB2(SCH_1):M_E_MA(6)
 211 M_E_MA<7>     A7 @BASEBOARD_FAB2_LIB.BASEBOARD_FAB2(SCH_1):M_E_MA(7)
  68 M_E_MA<8>     A8 @BASEBOARD_FAB2_LIB.BASEBOARD_FAB2(SCH_1):M_E_MA(8)
  66 M_E_MA<9>     A9 @BASEBOARD_FAB2_LIB.BASEBOARD_FAB2(SCH_1):M_E_MA(9)
  62 M_E_ACT_N  ACT_N @BASEBOARD_FAB2_LIB.BASEBOARD_FAB2(SCH_1):M_E_ACT_N
 208 M_E_ALERT_N ALERT_N @BASEBOARD_FAB2_LIB.BASEBOARD_FAB2(SCH_1):M_E_ALERT_N
 224 M_E_BA<1>  BA<1> @BASEBOARD_FAB2_LIB.BASEBOARD_FAB2(SCH_1):M_E_BA(1)
  81 M_E_BA<0>  BA<0> @BASEBOARD_FAB2_LIB.BASEBOARD_FAB2(SCH_1):M_E_BA(0)
 207 M_E_BG<1>  BG<1> @BASEBOARD_FAB2_LIB.BASEBOARD_FAB2(SCH_1):M_E_BG(1)
  63 M_E_BG<0>  BG<0> @BASEBOARD_FAB2_LIB.BASEBOARD_FAB2(SCH_1):M_E_BG(0)
 235 M_E_C<2>   C<2> @BASEBOARD_FAB2_LIB.BASEBOARD_FAB2(SCH_1):M_E_C(2)
 199 M_E_ECC<7>  CB<7> @BASEBOARD_FAB2_LIB.BASEBOARD_FAB2(SCH_1):M_E_ECC(7)
  54 M_E_ECC<6>  CB<6> @BASEBOARD_FAB2_LIB.BASEBOARD_FAB2(SCH_1):M_E_ECC(6)
 192 M_E_ECC<5>  CB<5> @BASEBOARD_FAB2_LIB.BASEBOARD_FAB2(SCH_1):M_E_ECC(5)
  47 M_E_ECC<4>  CB<4> @BASEBOARD_FAB2_LIB.BASEBOARD_FAB2(SCH_1):M_E_ECC(4)
 201 M_E_ECC<3>  CB<3> @BASEBOARD_FAB2_LIB.BASEBOARD_FAB2(SCH_1):M_E_ECC(3)
  56 M_E_ECC<2>  CB<2> @BASEBOARD_FAB2_LIB.BASEBOARD_FAB2(SCH_1):M_E_ECC(2)
 194 M_E_ECC<1>  CB<1> @BASEBOARD_FAB2_LIB.BASEBOARD_FAB2(SCH_1):M_E_ECC(1)
  49 M_E_ECC<0>  CB<0> @BASEBOARD_FAB2_LIB.BASEBOARD_FAB2(SCH_1):M_E_ECC(0)
  75 M_E_CLK_DN<2>   CK0N @BASEBOARD_FAB2_LIB.BASEBOARD_FAB2(SCH_1):M_E_CLK_DN(2)
  74 M_E_CLK_DP<2>   CK0P @BASEBOARD_FAB2_LIB.BASEBOARD_FAB2(SCH_1):M_E_CLK_DP(2)
 219 M_E_CLK_DN<3>   CK1N @BASEBOARD_FAB2_LIB.BASEBOARD_FAB2(SCH_1):M_E_CLK_DN(3)
 218 M_E_CLK_DP<3>   CK1P @BASEBOARD_FAB2_LIB.BASEBOARD_FAB2(SCH_1):M_E_CLK_DP(3)
 203 M_E_CKE<3> CKE<1> @BASEBOARD_FAB2_LIB.BASEBOARD_FAB2(SCH_1):M_E_CKE(3)
  60 M_E_CKE<2> CKE<0> @BASEBOARD_FAB2_LIB.BASEBOARD_FAB2(SCH_1):M_E_CKE(2)
 280 M_E_DQ<63> DQ<63> @BASEBOARD_FAB2_LIB.BASEBOARD_FAB2(SCH_1):M_E_DQ(63)
 135 M_E_DQ<62> DQ<62> @BASEBOARD_FAB2_LIB.BASEBOARD_FAB2(SCH_1):M_E_DQ(62)
 273 M_E_DQ<61> DQ<61> @BASEBOARD_FAB2_LIB.BASEBOARD_FAB2(SCH_1):M_E_DQ(61)
 128 M_E_DQ<60> DQ<60> @BASEBOARD_FAB2_LIB.BASEBOARD_FAB2(SCH_1):M_E_DQ(60)
 282 M_E_DQ<59> DQ<59> @BASEBOARD_FAB2_LIB.BASEBOARD_FAB2(SCH_1):M_E_DQ(59)
 137 M_E_DQ<58> DQ<58> @BASEBOARD_FAB2_LIB.BASEBOARD_FAB2(SCH_1):M_E_DQ(58)
 275 M_E_DQ<57> DQ<57> @BASEBOARD_FAB2_LIB.BASEBOARD_FAB2(SCH_1):M_E_DQ(57)
 130 M_E_DQ<56> DQ<56> @BASEBOARD_FAB2_LIB.BASEBOARD_FAB2(SCH_1):M_E_DQ(56)
 269 M_E_DQ<55> DQ<55> @BASEBOARD_FAB2_LIB.BASEBOARD_FAB2(SCH_1):M_E_DQ(55)
 124 M_E_DQ<54> DQ<54> @BASEBOARD_FAB2_LIB.BASEBOARD_FAB2(SCH_1):M_E_DQ(54)
 262 M_E_DQ<53> DQ<53> @BASEBOARD_FAB2_LIB.BASEBOARD_FAB2(SCH_1):M_E_DQ(53)
 117 M_E_DQ<52> DQ<52> @BASEBOARD_FAB2_LIB.BASEBOARD_FAB2(SCH_1):M_E_DQ(52)
 271 M_E_DQ<51> DQ<51> @BASEBOARD_FAB2_LIB.BASEBOARD_FAB2(SCH_1):M_E_DQ(51)
 126 M_E_DQ<50> DQ<50> @BASEBOARD_FAB2_LIB.BASEBOARD_FAB2(SCH_1):M_E_DQ(50)
 264 M_E_DQ<49> DQ<49> @BASEBOARD_FAB2_LIB.BASEBOARD_FAB2(SCH_1):M_E_DQ(49)
 119 M_E_DQ<48> DQ<48> @BASEBOARD_FAB2_LIB.BASEBOARD_FAB2(SCH_1):M_E_DQ(48)
 258 M_E_DQ<47> DQ<47> @BASEBOARD_FAB2_LIB.BASEBOARD_FAB2(SCH_1):M_E_DQ(47)
 113 M_E_DQ<46> DQ<46> @BASEBOARD_FAB2_LIB.BASEBOARD_FAB2(SCH_1):M_E_DQ(46)
 251 M_E_DQ<45> DQ<45> @BASEBOARD_FAB2_LIB.BASEBOARD_FAB2(SCH_1):M_E_DQ(45)
 106 M_E_DQ<44> DQ<44> @BASEBOARD_FAB2_LIB.BASEBOARD_FAB2(SCH_1):M_E_DQ(44)
 260 M_E_DQ<43> DQ<43> @BASEBOARD_FAB2_LIB.BASEBOARD_FAB2(SCH_1):M_E_DQ(43)
 115 M_E_DQ<42> DQ<42> @BASEBOARD_FAB2_LIB.BASEBOARD_FAB2(SCH_1):M_E_DQ(42)
 253 M_E_DQ<41> DQ<41> @BASEBOARD_FAB2_LIB.BASEBOARD_FAB2(SCH_1):M_E_DQ(41)
 108 M_E_DQ<40> DQ<40> @BASEBOARD_FAB2_LIB.BASEBOARD_FAB2(SCH_1):M_E_DQ(40)
 247 M_E_DQ<39> DQ<39> @BASEBOARD_FAB2_LIB.BASEBOARD_FAB2(SCH_1):M_E_DQ(39)
 102 M_E_DQ<38> DQ<38> @BASEBOARD_FAB2_LIB.BASEBOARD_FAB2(SCH_1):M_E_DQ(38)
 240 M_E_DQ<37> DQ<37> @BASEBOARD_FAB2_LIB.BASEBOARD_FAB2(SCH_1):M_E_DQ(37)
  95 M_E_DQ<36> DQ<36> @BASEBOARD_FAB2_LIB.BASEBOARD_FAB2(SCH_1):M_E_DQ(36)
 249 M_E_DQ<35> DQ<35> @BASEBOARD_FAB2_LIB.BASEBOARD_FAB2(SCH_1):M_E_DQ(35)
 104 M_E_DQ<34> DQ<34> @BASEBOARD_FAB2_LIB.BASEBOARD_FAB2(SCH_1):M_E_DQ(34)
 242 M_E_DQ<33> DQ<33> @BASEBOARD_FAB2_LIB.BASEBOARD_FAB2(SCH_1):M_E_DQ(33)
  97 M_E_DQ<32> DQ<32> @BASEBOARD_FAB2_LIB.BASEBOARD_FAB2(SCH_1):M_E_DQ(32)
 188 M_E_DQ<31> DQ<31> @BASEBOARD_FAB2_LIB.BASEBOARD_FAB2(SCH_1):M_E_DQ(31)
  43 M_E_DQ<30> DQ<30> @BASEBOARD_FAB2_LIB.BASEBOARD_FAB2(SCH_1):M_E_DQ(30)
 181 M_E_DQ<29> DQ<29> @BASEBOARD_FAB2_LIB.BASEBOARD_FAB2(SCH_1):M_E_DQ(29)
  36 M_E_DQ<28> DQ<28> @BASEBOARD_FAB2_LIB.BASEBOARD_FAB2(SCH_1):M_E_DQ(28)
 190 M_E_DQ<27> DQ<27> @BASEBOARD_FAB2_LIB.BASEBOARD_FAB2(SCH_1):M_E_DQ(27)
  45 M_E_DQ<26> DQ<26> @BASEBOARD_FAB2_LIB.BASEBOARD_FAB2(SCH_1):M_E_DQ(26)
 183 M_E_DQ<25> DQ<25> @BASEBOARD_FAB2_LIB.BASEBOARD_FAB2(SCH_1):M_E_DQ(25)
  38 M_E_DQ<24> DQ<24> @BASEBOARD_FAB2_LIB.BASEBOARD_FAB2(SCH_1):M_E_DQ(24)
 177 M_E_DQ<23> DQ<23> @BASEBOARD_FAB2_LIB.BASEBOARD_FAB2(SCH_1):M_E_DQ(23)
  32 M_E_DQ<22> DQ<22> @BASEBOARD_FAB2_LIB.BASEBOARD_FAB2(SCH_1):M_E_DQ(22)
 170 M_E_DQ<21> DQ<21> @BASEBOARD_FAB2_LIB.BASEBOARD_FAB2(SCH_1):M_E_DQ(21)
  25 M_E_DQ<20> DQ<20> @BASEBOARD_FAB2_LIB.BASEBOARD_FAB2(SCH_1):M_E_DQ(20)
 179 M_E_DQ<19> DQ<19> @BASEBOARD_FAB2_LIB.BASEBOARD_FAB2(SCH_1):M_E_DQ(19)
  34 M_E_DQ<18> DQ<18> @BASEBOARD_FAB2_LIB.BASEBOARD_FAB2(SCH_1):M_E_DQ(18)
 172 M_E_DQ<17> DQ<17> @BASEBOARD_FAB2_LIB.BASEBOARD_FAB2(SCH_1):M_E_DQ(17)
  27 M_E_DQ<16> DQ<16> @BASEBOARD_FAB2_LIB.BASEBOARD_FAB2(SCH_1):M_E_DQ(16)
 166 M_E_DQ<15> DQ<15> @BASEBOARD_FAB2_LIB.BASEBOARD_FAB2(SCH_1):M_E_DQ(15)
  21 M_E_DQ<14> DQ<14> @BASEBOARD_FAB2_LIB.BASEBOARD_FAB2(SCH_1):M_E_DQ(14)
 159 M_E_DQ<13> DQ<13> @BASEBOARD_FAB2_LIB.BASEBOARD_FAB2(SCH_1):M_E_DQ(13)
  14 M_E_DQ<12> DQ<12> @BASEBOARD_FAB2_LIB.BASEBOARD_FAB2(SCH_1):M_E_DQ(12)
 168 M_E_DQ<11> DQ<11> @BASEBOARD_FAB2_LIB.BASEBOARD_FAB2(SCH_1):M_E_DQ(11)
  23 M_E_DQ<10> DQ<10> @BASEBOARD_FAB2_LIB.BASEBOARD_FAB2(SCH_1):M_E_DQ(10)
 161 M_E_DQ<9>  DQ<9> @BASEBOARD_FAB2_LIB.BASEBOARD_FAB2(SCH_1):M_E_DQ(9)
  16 M_E_DQ<8>  DQ<8> @BASEBOARD_FAB2_LIB.BASEBOARD_FAB2(SCH_1):M_E_DQ(8)
 155 M_E_DQ<7>  DQ<7> @BASEBOARD_FAB2_LIB.BASEBOARD_FAB2(SCH_1):M_E_DQ(7)
  10 M_E_DQ<6>  DQ<6> @BASEBOARD_FAB2_LIB.BASEBOARD_FAB2(SCH_1):M_E_DQ(6)
 148 M_E_DQ<5>  DQ<5> @BASEBOARD_FAB2_LIB.BASEBOARD_FAB2(SCH_1):M_E_DQ(5)
   3 M_E_DQ<4>  DQ<4> @BASEBOARD_FAB2_LIB.BASEBOARD_FAB2(SCH_1):M_E_DQ(4)
 157 M_E_DQ<3>  DQ<3> @BASEBOARD_FAB2_LIB.BASEBOARD_FAB2(SCH_1):M_E_DQ(3)
  12 M_E_DQ<2>  DQ<2> @BASEBOARD_FAB2_LIB.BASEBOARD_FAB2(SCH_1):M_E_DQ(2)
 150 M_E_DQ<1>  DQ<1> @BASEBOARD_FAB2_LIB.BASEBOARD_FAB2(SCH_1):M_E_DQ(1)
   5 M_E_DQ<0>  DQ<0> @BASEBOARD_FAB2_LIB.BASEBOARD_FAB2(SCH_1):M_E_DQ(0)
  78 FM_DIMM_EVENT_COD_N EVENT_N @BASEBOARD_FAB2_LIB.BASEBOARD_FAB2(SCH_1):FM_DIMM_EVENT_COD_N
  91 M_E_ODT<3> ODT<1> @BASEBOARD_FAB2_LIB.BASEBOARD_FAB2(SCH_1):M_E_ODT(3)
  87 M_E_ODT<2> ODT<0> @BASEBOARD_FAB2_LIB.BASEBOARD_FAB2(SCH_1):M_E_ODT(2)
 222 M_E_PAR    PAR @BASEBOARD_FAB2_LIB.BASEBOARD_FAB2(SCH_1):M_E_PAR
  58 M_DEF_RST_N RESET_N @BASEBOARD_FAB2_LIB.BASEBOARD_FAB2(SCH_1):M_DEF_RST_N
 144 TP_CH_E_DIMM_E1_RFU_2 RFU<2> @BASEBOARD_FAB2_LIB.BASEBOARD_FAB2(SCH_1):TP_CH_E_DIMM_E1_RFU_2
 227 TP_CH_E_DIMM_E1_RFU_1 RFU<1> @BASEBOARD_FAB2_LIB.BASEBOARD_FAB2(SCH_1):TP_CH_E_DIMM_E1_RFU_1
 205 TP_CH_E_DIMM_E1_RFU_0 RFU<0> @BASEBOARD_FAB2_LIB.BASEBOARD_FAB2(SCH_1):TP_CH_E_DIMM_E1_RFU_0
  84 M_E_CS_N<4>   S0_N @BASEBOARD_FAB2_LIB.BASEBOARD_FAB2(SCH_1):M_E_CS_N(4)
  89 M_E_CS_N<5>   S1_N @BASEBOARD_FAB2_LIB.BASEBOARD_FAB2(SCH_1):M_E_CS_N(5)
  93 M_E_CS_N<6> S2_N_C<0> @BASEBOARD_FAB2_LIB.BASEBOARD_FAB2(SCH_1):M_E_CS_N(6)
 237 M_E_CS_N<7> S3_N_C<1> @BASEBOARD_FAB2_LIB.BASEBOARD_FAB2(SCH_1):M_E_CS_N(7)
 238    GND  SA<2> @BASEBOARD_FAB2_LIB.BASEBOARD_FAB2(SCH_1):GND
 140 PVPP_DEF  SA<1> @BASEBOARD_FAB2_LIB.BASEBOARD_FAB2(SCH_1):PVPP_DEF
 139 PVPP_DEF  SA<0> @BASEBOARD_FAB2_LIB.BASEBOARD_FAB2(SCH_1):PVPP_DEF
 230 FM_ADR_COMPLETE_DEF_N SAVE_N_NC @BASEBOARD_FAB2_LIB.BASEBOARD_FAB2(SCH_1):FM_ADR_COMPLETE_DEF_N
 141 SMB_DDR_DEF_VPP_SCL    SCL @BASEBOARD_FAB2_LIB.BASEBOARD_FAB2(SCH_1):SMB_DDR_DEF_VPP_SCL
 285 SMB_DDR_DEF_VPP_SDA    SDA @BASEBOARD_FAB2_LIB.BASEBOARD_FAB2(SCH_1):SMB_DDR_DEF_VPP_SDA
 284 PVPP_DEF VDDSPD @BASEBOARD_FAB2_LIB.BASEBOARD_FAB2(SCH_1):PVPP_DEF
 146 M_E_VREF VREFCA @BASEBOARD_FAB2_LIB.BASEBOARD_FAB2(SCH_1):M_E_VREF

SCONN288_H44441003_PIP-SCONN,HA  I55  J6L2
   1 P12V_NVDIMM_DEF 12V<1> @BASEBOARD_FAB2_LIB.BASEBOARD_FAB2(SCH_1):P12V_NVDIMM_DEF
 145 P12V_NVDIMM_DEF 12V<0> @BASEBOARD_FAB2_LIB.BASEBOARD_FAB2(SCH_1):P12V_NVDIMM_DEF
  59 PVDDQ_DEF VDD<25> @BASEBOARD_FAB2_LIB.BASEBOARD_FAB2(SCH_1):PVDDQ_DEF
  61 PVDDQ_DEF VDD<24> @BASEBOARD_FAB2_LIB.BASEBOARD_FAB2(SCH_1):PVDDQ_DEF
  64 PVDDQ_DEF VDD<23> @BASEBOARD_FAB2_LIB.BASEBOARD_FAB2(SCH_1):PVDDQ_DEF
  67 PVDDQ_DEF VDD<22> @BASEBOARD_FAB2_LIB.BASEBOARD_FAB2(SCH_1):PVDDQ_DEF
  70 PVDDQ_DEF VDD<21> @BASEBOARD_FAB2_LIB.BASEBOARD_FAB2(SCH_1):PVDDQ_DEF
  73 PVDDQ_DEF VDD<20> @BASEBOARD_FAB2_LIB.BASEBOARD_FAB2(SCH_1):PVDDQ_DEF
  76 PVDDQ_DEF VDD<19> @BASEBOARD_FAB2_LIB.BASEBOARD_FAB2(SCH_1):PVDDQ_DEF
  80 PVDDQ_DEF VDD<18> @BASEBOARD_FAB2_LIB.BASEBOARD_FAB2(SCH_1):PVDDQ_DEF
  83 PVDDQ_DEF VDD<17> @BASEBOARD_FAB2_LIB.BASEBOARD_FAB2(SCH_1):PVDDQ_DEF
  85 PVDDQ_DEF VDD<16> @BASEBOARD_FAB2_LIB.BASEBOARD_FAB2(SCH_1):PVDDQ_DEF
  88 PVDDQ_DEF VDD<15> @BASEBOARD_FAB2_LIB.BASEBOARD_FAB2(SCH_1):PVDDQ_DEF
  90 PVDDQ_DEF VDD<14> @BASEBOARD_FAB2_LIB.BASEBOARD_FAB2(SCH_1):PVDDQ_DEF
  92 PVDDQ_DEF VDD<13> @BASEBOARD_FAB2_LIB.BASEBOARD_FAB2(SCH_1):PVDDQ_DEF
 204 PVDDQ_DEF VDD<12> @BASEBOARD_FAB2_LIB.BASEBOARD_FAB2(SCH_1):PVDDQ_DEF
 206 PVDDQ_DEF VDD<11> @BASEBOARD_FAB2_LIB.BASEBOARD_FAB2(SCH_1):PVDDQ_DEF
 209 PVDDQ_DEF VDD<10> @BASEBOARD_FAB2_LIB.BASEBOARD_FAB2(SCH_1):PVDDQ_DEF
 212 PVDDQ_DEF VDD<9> @BASEBOARD_FAB2_LIB.BASEBOARD_FAB2(SCH_1):PVDDQ_DEF
 215 PVDDQ_DEF VDD<8> @BASEBOARD_FAB2_LIB.BASEBOARD_FAB2(SCH_1):PVDDQ_DEF
 217 PVDDQ_DEF VDD<7> @BASEBOARD_FAB2_LIB.BASEBOARD_FAB2(SCH_1):PVDDQ_DEF
 220 PVDDQ_DEF VDD<6> @BASEBOARD_FAB2_LIB.BASEBOARD_FAB2(SCH_1):PVDDQ_DEF
 223 PVDDQ_DEF VDD<5> @BASEBOARD_FAB2_LIB.BASEBOARD_FAB2(SCH_1):PVDDQ_DEF
 226 PVDDQ_DEF VDD<4> @BASEBOARD_FAB2_LIB.BASEBOARD_FAB2(SCH_1):PVDDQ_DEF
 229 PVDDQ_DEF VDD<3> @BASEBOARD_FAB2_LIB.BASEBOARD_FAB2(SCH_1):PVDDQ_DEF
 231 PVDDQ_DEF VDD<2> @BASEBOARD_FAB2_LIB.BASEBOARD_FAB2(SCH_1):PVDDQ_DEF
 233 PVDDQ_DEF VDD<1> @BASEBOARD_FAB2_LIB.BASEBOARD_FAB2(SCH_1):PVDDQ_DEF
 236 PVDDQ_DEF VDD<0> @BASEBOARD_FAB2_LIB.BASEBOARD_FAB2(SCH_1):PVDDQ_DEF
 142 PVPP_DEF VPP<4> @BASEBOARD_FAB2_LIB.BASEBOARD_FAB2(SCH_1):PVPP_DEF
 143 PVPP_DEF VPP<3> @BASEBOARD_FAB2_LIB.BASEBOARD_FAB2(SCH_1):PVPP_DEF
 288 PVPP_DEF VPP<2> @BASEBOARD_FAB2_LIB.BASEBOARD_FAB2(SCH_1):PVPP_DEF
 286 PVPP_DEF VPP<1> @BASEBOARD_FAB2_LIB.BASEBOARD_FAB2(SCH_1):PVPP_DEF
 287 PVPP_DEF VPP<0> @BASEBOARD_FAB2_LIB.BASEBOARD_FAB2(SCH_1):PVPP_DEF
  77 PVTT_DEF VTT<1> @BASEBOARD_FAB2_LIB.BASEBOARD_FAB2(SCH_1):PVTT_DEF
 221 PVTT_DEF VTT<0> @BASEBOARD_FAB2_LIB.BASEBOARD_FAB2(SCH_1):PVTT_DEF

SCONN288_H44441003_PIP-SCONN,HA  I100  J6L2
 152 M_E_DQS_DN<0>  DQS0N @BASEBOARD_FAB2_LIB.BASEBOARD_FAB2(SCH_1):M_E_DQS_DN(0)
 153 M_E_DQS_DP<0>  DQS0P @BASEBOARD_FAB2_LIB.BASEBOARD_FAB2(SCH_1):M_E_DQS_DP(0)
  19 M_E_DQS_DN<10> DQS10N @BASEBOARD_FAB2_LIB.BASEBOARD_FAB2(SCH_1):M_E_DQS_DN(10)
  18 M_E_DQS_DP<10> DQS10P @BASEBOARD_FAB2_LIB.BASEBOARD_FAB2(SCH_1):M_E_DQS_DP(10)
  30 M_E_DQS_DN<11> DQS11N @BASEBOARD_FAB2_LIB.BASEBOARD_FAB2(SCH_1):M_E_DQS_DN(11)
  29 M_E_DQS_DP<11> DQS11P @BASEBOARD_FAB2_LIB.BASEBOARD_FAB2(SCH_1):M_E_DQS_DP(11)
  41 M_E_DQS_DN<12> DQS12N @BASEBOARD_FAB2_LIB.BASEBOARD_FAB2(SCH_1):M_E_DQS_DN(12)
  40 M_E_DQS_DP<12> DQS12P @BASEBOARD_FAB2_LIB.BASEBOARD_FAB2(SCH_1):M_E_DQS_DP(12)
 100 M_E_DQS_DN<13> DQS13N @BASEBOARD_FAB2_LIB.BASEBOARD_FAB2(SCH_1):M_E_DQS_DN(13)
  99 M_E_DQS_DP<13> DQS13P @BASEBOARD_FAB2_LIB.BASEBOARD_FAB2(SCH_1):M_E_DQS_DP(13)
 111 M_E_DQS_DN<14> DQS14N @BASEBOARD_FAB2_LIB.BASEBOARD_FAB2(SCH_1):M_E_DQS_DN(14)
 110 M_E_DQS_DP<14> DQS14P @BASEBOARD_FAB2_LIB.BASEBOARD_FAB2(SCH_1):M_E_DQS_DP(14)
 122 M_E_DQS_DN<15> DQS15N @BASEBOARD_FAB2_LIB.BASEBOARD_FAB2(SCH_1):M_E_DQS_DN(15)
 121 M_E_DQS_DP<15> DQS15P @BASEBOARD_FAB2_LIB.BASEBOARD_FAB2(SCH_1):M_E_DQS_DP(15)
 133 M_E_DQS_DN<16> DQS16N @BASEBOARD_FAB2_LIB.BASEBOARD_FAB2(SCH_1):M_E_DQS_DN(16)
 132 M_E_DQS_DP<16> DQS16P @BASEBOARD_FAB2_LIB.BASEBOARD_FAB2(SCH_1):M_E_DQS_DP(16)
  52 M_E_DQS_DN<17> DQS17N @BASEBOARD_FAB2_LIB.BASEBOARD_FAB2(SCH_1):M_E_DQS_DN(17)
  51 M_E_DQS_DP<17> DQS17P @BASEBOARD_FAB2_LIB.BASEBOARD_FAB2(SCH_1):M_E_DQS_DP(17)
 163 M_E_DQS_DN<1>  DQS1N @BASEBOARD_FAB2_LIB.BASEBOARD_FAB2(SCH_1):M_E_DQS_DN(1)
 164 M_E_DQS_DP<1>  DQS1P @BASEBOARD_FAB2_LIB.BASEBOARD_FAB2(SCH_1):M_E_DQS_DP(1)
 174 M_E_DQS_DN<2>  DQS2N @BASEBOARD_FAB2_LIB.BASEBOARD_FAB2(SCH_1):M_E_DQS_DN(2)
 175 M_E_DQS_DP<2>  DQS2P @BASEBOARD_FAB2_LIB.BASEBOARD_FAB2(SCH_1):M_E_DQS_DP(2)
 185 M_E_DQS_DN<3>  DQS3N @BASEBOARD_FAB2_LIB.BASEBOARD_FAB2(SCH_1):M_E_DQS_DN(3)
 186 M_E_DQS_DP<3>  DQS3P @BASEBOARD_FAB2_LIB.BASEBOARD_FAB2(SCH_1):M_E_DQS_DP(3)
 244 M_E_DQS_DN<4>  DQS4N @BASEBOARD_FAB2_LIB.BASEBOARD_FAB2(SCH_1):M_E_DQS_DN(4)
 245 M_E_DQS_DP<4>  DQS4P @BASEBOARD_FAB2_LIB.BASEBOARD_FAB2(SCH_1):M_E_DQS_DP(4)
 255 M_E_DQS_DN<5>  DQS5N @BASEBOARD_FAB2_LIB.BASEBOARD_FAB2(SCH_1):M_E_DQS_DN(5)
 256 M_E_DQS_DP<5>  DQS5P @BASEBOARD_FAB2_LIB.BASEBOARD_FAB2(SCH_1):M_E_DQS_DP(5)
 266 M_E_DQS_DN<6>  DQS6N @BASEBOARD_FAB2_LIB.BASEBOARD_FAB2(SCH_1):M_E_DQS_DN(6)
 267 M_E_DQS_DP<6>  DQS6P @BASEBOARD_FAB2_LIB.BASEBOARD_FAB2(SCH_1):M_E_DQS_DP(6)
 277 M_E_DQS_DN<7>  DQS7N @BASEBOARD_FAB2_LIB.BASEBOARD_FAB2(SCH_1):M_E_DQS_DN(7)
 278 M_E_DQS_DP<7>  DQS7P @BASEBOARD_FAB2_LIB.BASEBOARD_FAB2(SCH_1):M_E_DQS_DP(7)
 196 M_E_DQS_DN<8>  DQS8N @BASEBOARD_FAB2_LIB.BASEBOARD_FAB2(SCH_1):M_E_DQS_DN(8)
 197 M_E_DQS_DP<8>  DQS8P @BASEBOARD_FAB2_LIB.BASEBOARD_FAB2(SCH_1):M_E_DQS_DP(8)
   8 M_E_DQS_DN<9>  DQS9N @BASEBOARD_FAB2_LIB.BASEBOARD_FAB2(SCH_1):M_E_DQS_DN(9)
   7 M_E_DQS_DP<9>  DQS9P @BASEBOARD_FAB2_LIB.BASEBOARD_FAB2(SCH_1):M_E_DQS_DP(9)

SCONN288_H44441003_PIP-SCONN,HA  I138  J6L2
   2    GND VSS<93> @BASEBOARD_FAB2_LIB.BASEBOARD_FAB2(SCH_1):GND
   4    GND VSS<92> @BASEBOARD_FAB2_LIB.BASEBOARD_FAB2(SCH_1):GND
   6    GND VSS<91> @BASEBOARD_FAB2_LIB.BASEBOARD_FAB2(SCH_1):GND
   9    GND VSS<90> @BASEBOARD_FAB2_LIB.BASEBOARD_FAB2(SCH_1):GND
  11    GND VSS<89> @BASEBOARD_FAB2_LIB.BASEBOARD_FAB2(SCH_1):GND
  13    GND VSS<88> @BASEBOARD_FAB2_LIB.BASEBOARD_FAB2(SCH_1):GND
  15    GND VSS<87> @BASEBOARD_FAB2_LIB.BASEBOARD_FAB2(SCH_1):GND
  17    GND VSS<86> @BASEBOARD_FAB2_LIB.BASEBOARD_FAB2(SCH_1):GND
  20    GND VSS<85> @BASEBOARD_FAB2_LIB.BASEBOARD_FAB2(SCH_1):GND
  22    GND VSS<84> @BASEBOARD_FAB2_LIB.BASEBOARD_FAB2(SCH_1):GND
  24    GND VSS<83> @BASEBOARD_FAB2_LIB.BASEBOARD_FAB2(SCH_1):GND
  26    GND VSS<82> @BASEBOARD_FAB2_LIB.BASEBOARD_FAB2(SCH_1):GND
  28    GND VSS<81> @BASEBOARD_FAB2_LIB.BASEBOARD_FAB2(SCH_1):GND
  31    GND VSS<80> @BASEBOARD_FAB2_LIB.BASEBOARD_FAB2(SCH_1):GND
  33    GND VSS<79> @BASEBOARD_FAB2_LIB.BASEBOARD_FAB2(SCH_1):GND
  35    GND VSS<78> @BASEBOARD_FAB2_LIB.BASEBOARD_FAB2(SCH_1):GND
  37    GND VSS<77> @BASEBOARD_FAB2_LIB.BASEBOARD_FAB2(SCH_1):GND
  39    GND VSS<76> @BASEBOARD_FAB2_LIB.BASEBOARD_FAB2(SCH_1):GND
  42    GND VSS<75> @BASEBOARD_FAB2_LIB.BASEBOARD_FAB2(SCH_1):GND
  44    GND VSS<74> @BASEBOARD_FAB2_LIB.BASEBOARD_FAB2(SCH_1):GND
  46    GND VSS<73> @BASEBOARD_FAB2_LIB.BASEBOARD_FAB2(SCH_1):GND
  48    GND VSS<72> @BASEBOARD_FAB2_LIB.BASEBOARD_FAB2(SCH_1):GND
  50    GND VSS<71> @BASEBOARD_FAB2_LIB.BASEBOARD_FAB2(SCH_1):GND
  53    GND VSS<70> @BASEBOARD_FAB2_LIB.BASEBOARD_FAB2(SCH_1):GND
  55    GND VSS<69> @BASEBOARD_FAB2_LIB.BASEBOARD_FAB2(SCH_1):GND
  57    GND VSS<68> @BASEBOARD_FAB2_LIB.BASEBOARD_FAB2(SCH_1):GND
  94    GND VSS<67> @BASEBOARD_FAB2_LIB.BASEBOARD_FAB2(SCH_1):GND
  96    GND VSS<66> @BASEBOARD_FAB2_LIB.BASEBOARD_FAB2(SCH_1):GND
  98    GND VSS<65> @BASEBOARD_FAB2_LIB.BASEBOARD_FAB2(SCH_1):GND
 101    GND VSS<64> @BASEBOARD_FAB2_LIB.BASEBOARD_FAB2(SCH_1):GND
 103    GND VSS<63> @BASEBOARD_FAB2_LIB.BASEBOARD_FAB2(SCH_1):GND
 105    GND VSS<62> @BASEBOARD_FAB2_LIB.BASEBOARD_FAB2(SCH_1):GND
 107    GND VSS<61> @BASEBOARD_FAB2_LIB.BASEBOARD_FAB2(SCH_1):GND
 109    GND VSS<60> @BASEBOARD_FAB2_LIB.BASEBOARD_FAB2(SCH_1):GND
 112    GND VSS<59> @BASEBOARD_FAB2_LIB.BASEBOARD_FAB2(SCH_1):GND
 114    GND VSS<58> @BASEBOARD_FAB2_LIB.BASEBOARD_FAB2(SCH_1):GND
 116    GND VSS<57> @BASEBOARD_FAB2_LIB.BASEBOARD_FAB2(SCH_1):GND
 118    GND VSS<56> @BASEBOARD_FAB2_LIB.BASEBOARD_FAB2(SCH_1):GND
 120    GND VSS<55> @BASEBOARD_FAB2_LIB.BASEBOARD_FAB2(SCH_1):GND
 123    GND VSS<54> @BASEBOARD_FAB2_LIB.BASEBOARD_FAB2(SCH_1):GND
 125    GND VSS<53> @BASEBOARD_FAB2_LIB.BASEBOARD_FAB2(SCH_1):GND
 127    GND VSS<52> @BASEBOARD_FAB2_LIB.BASEBOARD_FAB2(SCH_1):GND
 129    GND VSS<51> @BASEBOARD_FAB2_LIB.BASEBOARD_FAB2(SCH_1):GND
 131    GND VSS<50> @BASEBOARD_FAB2_LIB.BASEBOARD_FAB2(SCH_1):GND
 134    GND VSS<49> @BASEBOARD_FAB2_LIB.BASEBOARD_FAB2(SCH_1):GND
 136    GND VSS<48> @BASEBOARD_FAB2_LIB.BASEBOARD_FAB2(SCH_1):GND
 138    GND VSS<47> @BASEBOARD_FAB2_LIB.BASEBOARD_FAB2(SCH_1):GND
 147    GND VSS<46> @BASEBOARD_FAB2_LIB.BASEBOARD_FAB2(SCH_1):GND
 149    GND VSS<45> @BASEBOARD_FAB2_LIB.BASEBOARD_FAB2(SCH_1):GND
 151    GND VSS<44> @BASEBOARD_FAB2_LIB.BASEBOARD_FAB2(SCH_1):GND
 154    GND VSS<43> @BASEBOARD_FAB2_LIB.BASEBOARD_FAB2(SCH_1):GND
 156    GND VSS<42> @BASEBOARD_FAB2_LIB.BASEBOARD_FAB2(SCH_1):GND
 158    GND VSS<41> @BASEBOARD_FAB2_LIB.BASEBOARD_FAB2(SCH_1):GND
 160    GND VSS<40> @BASEBOARD_FAB2_LIB.BASEBOARD_FAB2(SCH_1):GND
 162    GND VSS<39> @BASEBOARD_FAB2_LIB.BASEBOARD_FAB2(SCH_1):GND
 165    GND VSS<38> @BASEBOARD_FAB2_LIB.BASEBOARD_FAB2(SCH_1):GND
 167    GND VSS<37> @BASEBOARD_FAB2_LIB.BASEBOARD_FAB2(SCH_1):GND
 169    GND VSS<36> @BASEBOARD_FAB2_LIB.BASEBOARD_FAB2(SCH_1):GND
 171    GND VSS<35> @BASEBOARD_FAB2_LIB.BASEBOARD_FAB2(SCH_1):GND
 173    GND VSS<34> @BASEBOARD_FAB2_LIB.BASEBOARD_FAB2(SCH_1):GND
 176    GND VSS<33> @BASEBOARD_FAB2_LIB.BASEBOARD_FAB2(SCH_1):GND
 178    GND VSS<32> @BASEBOARD_FAB2_LIB.BASEBOARD_FAB2(SCH_1):GND
 180    GND VSS<31> @BASEBOARD_FAB2_LIB.BASEBOARD_FAB2(SCH_1):GND
 182    GND VSS<30> @BASEBOARD_FAB2_LIB.BASEBOARD_FAB2(SCH_1):GND
 184    GND VSS<29> @BASEBOARD_FAB2_LIB.BASEBOARD_FAB2(SCH_1):GND
 187    GND VSS<28> @BASEBOARD_FAB2_LIB.BASEBOARD_FAB2(SCH_1):GND
 189    GND VSS<27> @BASEBOARD_FAB2_LIB.BASEBOARD_FAB2(SCH_1):GND
 191    GND VSS<26> @BASEBOARD_FAB2_LIB.BASEBOARD_FAB2(SCH_1):GND
 193    GND VSS<25> @BASEBOARD_FAB2_LIB.BASEBOARD_FAB2(SCH_1):GND
 195    GND VSS<24> @BASEBOARD_FAB2_LIB.BASEBOARD_FAB2(SCH_1):GND
 198    GND VSS<23> @BASEBOARD_FAB2_LIB.BASEBOARD_FAB2(SCH_1):GND
 200    GND VSS<22> @BASEBOARD_FAB2_LIB.BASEBOARD_FAB2(SCH_1):GND
 202    GND VSS<21> @BASEBOARD_FAB2_LIB.BASEBOARD_FAB2(SCH_1):GND
 239    GND VSS<20> @BASEBOARD_FAB2_LIB.BASEBOARD_FAB2(SCH_1):GND
 241    GND VSS<19> @BASEBOARD_FAB2_LIB.BASEBOARD_FAB2(SCH_1):GND
 243    GND VSS<18> @BASEBOARD_FAB2_LIB.BASEBOARD_FAB2(SCH_1):GND
 246    GND VSS<17> @BASEBOARD_FAB2_LIB.BASEBOARD_FAB2(SCH_1):GND
 248    GND VSS<16> @BASEBOARD_FAB2_LIB.BASEBOARD_FAB2(SCH_1):GND
 250    GND VSS<15> @BASEBOARD_FAB2_LIB.BASEBOARD_FAB2(SCH_1):GND
 252    GND VSS<14> @BASEBOARD_FAB2_LIB.BASEBOARD_FAB2(SCH_1):GND
 254    GND VSS<13> @BASEBOARD_FAB2_LIB.BASEBOARD_FAB2(SCH_1):GND
 257    GND VSS<12> @BASEBOARD_FAB2_LIB.BASEBOARD_FAB2(SCH_1):GND
 259    GND VSS<11> @BASEBOARD_FAB2_LIB.BASEBOARD_FAB2(SCH_1):GND
 261    GND VSS<10> @BASEBOARD_FAB2_LIB.BASEBOARD_FAB2(SCH_1):GND
 263    GND VSS<9> @BASEBOARD_FAB2_LIB.BASEBOARD_FAB2(SCH_1):GND
 265    GND VSS<8> @BASEBOARD_FAB2_LIB.BASEBOARD_FAB2(SCH_1):GND
 268    GND VSS<7> @BASEBOARD_FAB2_LIB.BASEBOARD_FAB2(SCH_1):GND
 270    GND VSS<6> @BASEBOARD_FAB2_LIB.BASEBOARD_FAB2(SCH_1):GND
 272    GND VSS<5> @BASEBOARD_FAB2_LIB.BASEBOARD_FAB2(SCH_1):GND
 274    GND VSS<4> @BASEBOARD_FAB2_LIB.BASEBOARD_FAB2(SCH_1):GND
 276    GND VSS<3> @BASEBOARD_FAB2_LIB.BASEBOARD_FAB2(SCH_1):GND
 279    GND VSS<2> @BASEBOARD_FAB2_LIB.BASEBOARD_FAB2(SCH_1):GND
 281    GND VSS<1> @BASEBOARD_FAB2_LIB.BASEBOARD_FAB2(SCH_1):GND
 283    GND VSS<0> @BASEBOARD_FAB2_LIB.BASEBOARD_FAB2(SCH_1):GND


DRAWING: @BASEBOARD_FAB2_LIB.BASEBOARD_FAB2(SCH_1):PAGE53 

SCONN288_H44441004_PIP-SCONN,HA  I43  J4A1
   2    GND VSS<93> @BASEBOARD_FAB2_LIB.BASEBOARD_FAB2(SCH_1):GND
   4    GND VSS<92> @BASEBOARD_FAB2_LIB.BASEBOARD_FAB2(SCH_1):GND
   6    GND VSS<91> @BASEBOARD_FAB2_LIB.BASEBOARD_FAB2(SCH_1):GND
   9    GND VSS<90> @BASEBOARD_FAB2_LIB.BASEBOARD_FAB2(SCH_1):GND
  11    GND VSS<89> @BASEBOARD_FAB2_LIB.BASEBOARD_FAB2(SCH_1):GND
  13    GND VSS<88> @BASEBOARD_FAB2_LIB.BASEBOARD_FAB2(SCH_1):GND
  15    GND VSS<87> @BASEBOARD_FAB2_LIB.BASEBOARD_FAB2(SCH_1):GND
  17    GND VSS<86> @BASEBOARD_FAB2_LIB.BASEBOARD_FAB2(SCH_1):GND
  20    GND VSS<85> @BASEBOARD_FAB2_LIB.BASEBOARD_FAB2(SCH_1):GND
  22    GND VSS<84> @BASEBOARD_FAB2_LIB.BASEBOARD_FAB2(SCH_1):GND
  24    GND VSS<83> @BASEBOARD_FAB2_LIB.BASEBOARD_FAB2(SCH_1):GND
  26    GND VSS<82> @BASEBOARD_FAB2_LIB.BASEBOARD_FAB2(SCH_1):GND
  28    GND VSS<81> @BASEBOARD_FAB2_LIB.BASEBOARD_FAB2(SCH_1):GND
  31    GND VSS<80> @BASEBOARD_FAB2_LIB.BASEBOARD_FAB2(SCH_1):GND
  33    GND VSS<79> @BASEBOARD_FAB2_LIB.BASEBOARD_FAB2(SCH_1):GND
  35    GND VSS<78> @BASEBOARD_FAB2_LIB.BASEBOARD_FAB2(SCH_1):GND
  37    GND VSS<77> @BASEBOARD_FAB2_LIB.BASEBOARD_FAB2(SCH_1):GND
  39    GND VSS<76> @BASEBOARD_FAB2_LIB.BASEBOARD_FAB2(SCH_1):GND
  42    GND VSS<75> @BASEBOARD_FAB2_LIB.BASEBOARD_FAB2(SCH_1):GND
  44    GND VSS<74> @BASEBOARD_FAB2_LIB.BASEBOARD_FAB2(SCH_1):GND
  46    GND VSS<73> @BASEBOARD_FAB2_LIB.BASEBOARD_FAB2(SCH_1):GND
  48    GND VSS<72> @BASEBOARD_FAB2_LIB.BASEBOARD_FAB2(SCH_1):GND
  50    GND VSS<71> @BASEBOARD_FAB2_LIB.BASEBOARD_FAB2(SCH_1):GND
  53    GND VSS<70> @BASEBOARD_FAB2_LIB.BASEBOARD_FAB2(SCH_1):GND
  55    GND VSS<69> @BASEBOARD_FAB2_LIB.BASEBOARD_FAB2(SCH_1):GND
  57    GND VSS<68> @BASEBOARD_FAB2_LIB.BASEBOARD_FAB2(SCH_1):GND
  94    GND VSS<67> @BASEBOARD_FAB2_LIB.BASEBOARD_FAB2(SCH_1):GND
  96    GND VSS<66> @BASEBOARD_FAB2_LIB.BASEBOARD_FAB2(SCH_1):GND
  98    GND VSS<65> @BASEBOARD_FAB2_LIB.BASEBOARD_FAB2(SCH_1):GND
 101    GND VSS<64> @BASEBOARD_FAB2_LIB.BASEBOARD_FAB2(SCH_1):GND
 103    GND VSS<63> @BASEBOARD_FAB2_LIB.BASEBOARD_FAB2(SCH_1):GND
 105    GND VSS<62> @BASEBOARD_FAB2_LIB.BASEBOARD_FAB2(SCH_1):GND
 107    GND VSS<61> @BASEBOARD_FAB2_LIB.BASEBOARD_FAB2(SCH_1):GND
 109    GND VSS<60> @BASEBOARD_FAB2_LIB.BASEBOARD_FAB2(SCH_1):GND
 112    GND VSS<59> @BASEBOARD_FAB2_LIB.BASEBOARD_FAB2(SCH_1):GND
 114    GND VSS<58> @BASEBOARD_FAB2_LIB.BASEBOARD_FAB2(SCH_1):GND
 116    GND VSS<57> @BASEBOARD_FAB2_LIB.BASEBOARD_FAB2(SCH_1):GND
 118    GND VSS<56> @BASEBOARD_FAB2_LIB.BASEBOARD_FAB2(SCH_1):GND
 120    GND VSS<55> @BASEBOARD_FAB2_LIB.BASEBOARD_FAB2(SCH_1):GND
 123    GND VSS<54> @BASEBOARD_FAB2_LIB.BASEBOARD_FAB2(SCH_1):GND
 125    GND VSS<53> @BASEBOARD_FAB2_LIB.BASEBOARD_FAB2(SCH_1):GND
 127    GND VSS<52> @BASEBOARD_FAB2_LIB.BASEBOARD_FAB2(SCH_1):GND
 129    GND VSS<51> @BASEBOARD_FAB2_LIB.BASEBOARD_FAB2(SCH_1):GND
 131    GND VSS<50> @BASEBOARD_FAB2_LIB.BASEBOARD_FAB2(SCH_1):GND
 134    GND VSS<49> @BASEBOARD_FAB2_LIB.BASEBOARD_FAB2(SCH_1):GND
 136    GND VSS<48> @BASEBOARD_FAB2_LIB.BASEBOARD_FAB2(SCH_1):GND
 138    GND VSS<47> @BASEBOARD_FAB2_LIB.BASEBOARD_FAB2(SCH_1):GND
 147    GND VSS<46> @BASEBOARD_FAB2_LIB.BASEBOARD_FAB2(SCH_1):GND
 149    GND VSS<45> @BASEBOARD_FAB2_LIB.BASEBOARD_FAB2(SCH_1):GND
 151    GND VSS<44> @BASEBOARD_FAB2_LIB.BASEBOARD_FAB2(SCH_1):GND
 154    GND VSS<43> @BASEBOARD_FAB2_LIB.BASEBOARD_FAB2(SCH_1):GND
 156    GND VSS<42> @BASEBOARD_FAB2_LIB.BASEBOARD_FAB2(SCH_1):GND
 158    GND VSS<41> @BASEBOARD_FAB2_LIB.BASEBOARD_FAB2(SCH_1):GND
 160    GND VSS<40> @BASEBOARD_FAB2_LIB.BASEBOARD_FAB2(SCH_1):GND
 162    GND VSS<39> @BASEBOARD_FAB2_LIB.BASEBOARD_FAB2(SCH_1):GND
 165    GND VSS<38> @BASEBOARD_FAB2_LIB.BASEBOARD_FAB2(SCH_1):GND
 167    GND VSS<37> @BASEBOARD_FAB2_LIB.BASEBOARD_FAB2(SCH_1):GND
 169    GND VSS<36> @BASEBOARD_FAB2_LIB.BASEBOARD_FAB2(SCH_1):GND
 171    GND VSS<35> @BASEBOARD_FAB2_LIB.BASEBOARD_FAB2(SCH_1):GND
 173    GND VSS<34> @BASEBOARD_FAB2_LIB.BASEBOARD_FAB2(SCH_1):GND
 176    GND VSS<33> @BASEBOARD_FAB2_LIB.BASEBOARD_FAB2(SCH_1):GND
 178    GND VSS<32> @BASEBOARD_FAB2_LIB.BASEBOARD_FAB2(SCH_1):GND
 180    GND VSS<31> @BASEBOARD_FAB2_LIB.BASEBOARD_FAB2(SCH_1):GND
 182    GND VSS<30> @BASEBOARD_FAB2_LIB.BASEBOARD_FAB2(SCH_1):GND
 184    GND VSS<29> @BASEBOARD_FAB2_LIB.BASEBOARD_FAB2(SCH_1):GND
 187    GND VSS<28> @BASEBOARD_FAB2_LIB.BASEBOARD_FAB2(SCH_1):GND
 189    GND VSS<27> @BASEBOARD_FAB2_LIB.BASEBOARD_FAB2(SCH_1):GND
 191    GND VSS<26> @BASEBOARD_FAB2_LIB.BASEBOARD_FAB2(SCH_1):GND
 193    GND VSS<25> @BASEBOARD_FAB2_LIB.BASEBOARD_FAB2(SCH_1):GND
 195    GND VSS<24> @BASEBOARD_FAB2_LIB.BASEBOARD_FAB2(SCH_1):GND
 198    GND VSS<23> @BASEBOARD_FAB2_LIB.BASEBOARD_FAB2(SCH_1):GND
 200    GND VSS<22> @BASEBOARD_FAB2_LIB.BASEBOARD_FAB2(SCH_1):GND
 202    GND VSS<21> @BASEBOARD_FAB2_LIB.BASEBOARD_FAB2(SCH_1):GND
 239    GND VSS<20> @BASEBOARD_FAB2_LIB.BASEBOARD_FAB2(SCH_1):GND
 241    GND VSS<19> @BASEBOARD_FAB2_LIB.BASEBOARD_FAB2(SCH_1):GND
 243    GND VSS<18> @BASEBOARD_FAB2_LIB.BASEBOARD_FAB2(SCH_1):GND
 246    GND VSS<17> @BASEBOARD_FAB2_LIB.BASEBOARD_FAB2(SCH_1):GND
 248    GND VSS<16> @BASEBOARD_FAB2_LIB.BASEBOARD_FAB2(SCH_1):GND
 250    GND VSS<15> @BASEBOARD_FAB2_LIB.BASEBOARD_FAB2(SCH_1):GND
 252    GND VSS<14> @BASEBOARD_FAB2_LIB.BASEBOARD_FAB2(SCH_1):GND
 254    GND VSS<13> @BASEBOARD_FAB2_LIB.BASEBOARD_FAB2(SCH_1):GND
 257    GND VSS<12> @BASEBOARD_FAB2_LIB.BASEBOARD_FAB2(SCH_1):GND
 259    GND VSS<11> @BASEBOARD_FAB2_LIB.BASEBOARD_FAB2(SCH_1):GND
 261    GND VSS<10> @BASEBOARD_FAB2_LIB.BASEBOARD_FAB2(SCH_1):GND
 263    GND VSS<9> @BASEBOARD_FAB2_LIB.BASEBOARD_FAB2(SCH_1):GND
 265    GND VSS<8> @BASEBOARD_FAB2_LIB.BASEBOARD_FAB2(SCH_1):GND
 268    GND VSS<7> @BASEBOARD_FAB2_LIB.BASEBOARD_FAB2(SCH_1):GND
 270    GND VSS<6> @BASEBOARD_FAB2_LIB.BASEBOARD_FAB2(SCH_1):GND
 272    GND VSS<5> @BASEBOARD_FAB2_LIB.BASEBOARD_FAB2(SCH_1):GND
 274    GND VSS<4> @BASEBOARD_FAB2_LIB.BASEBOARD_FAB2(SCH_1):GND
 276    GND VSS<3> @BASEBOARD_FAB2_LIB.BASEBOARD_FAB2(SCH_1):GND
 279    GND VSS<2> @BASEBOARD_FAB2_LIB.BASEBOARD_FAB2(SCH_1):GND
 281    GND VSS<1> @BASEBOARD_FAB2_LIB.BASEBOARD_FAB2(SCH_1):GND
 283    GND VSS<0> @BASEBOARD_FAB2_LIB.BASEBOARD_FAB2(SCH_1):GND

SCONN288_H44441004_PIP-SCONN,HA  I66  J4A1
 152 M_F_DQS_DN<0>  DQS0N @BASEBOARD_FAB2_LIB.BASEBOARD_FAB2(SCH_1):M_F_DQS_DN(0)
 153 M_F_DQS_DP<0>  DQS0P @BASEBOARD_FAB2_LIB.BASEBOARD_FAB2(SCH_1):M_F_DQS_DP(0)
  19 M_F_DQS_DN<10> DQS10N @BASEBOARD_FAB2_LIB.BASEBOARD_FAB2(SCH_1):M_F_DQS_DN(10)
  18 M_F_DQS_DP<10> DQS10P @BASEBOARD_FAB2_LIB.BASEBOARD_FAB2(SCH_1):M_F_DQS_DP(10)
  30 M_F_DQS_DN<11> DQS11N @BASEBOARD_FAB2_LIB.BASEBOARD_FAB2(SCH_1):M_F_DQS_DN(11)
  29 M_F_DQS_DP<11> DQS11P @BASEBOARD_FAB2_LIB.BASEBOARD_FAB2(SCH_1):M_F_DQS_DP(11)
  41 M_F_DQS_DN<12> DQS12N @BASEBOARD_FAB2_LIB.BASEBOARD_FAB2(SCH_1):M_F_DQS_DN(12)
  40 M_F_DQS_DP<12> DQS12P @BASEBOARD_FAB2_LIB.BASEBOARD_FAB2(SCH_1):M_F_DQS_DP(12)
 100 M_F_DQS_DN<13> DQS13N @BASEBOARD_FAB2_LIB.BASEBOARD_FAB2(SCH_1):M_F_DQS_DN(13)
  99 M_F_DQS_DP<13> DQS13P @BASEBOARD_FAB2_LIB.BASEBOARD_FAB2(SCH_1):M_F_DQS_DP(13)
 111 M_F_DQS_DN<14> DQS14N @BASEBOARD_FAB2_LIB.BASEBOARD_FAB2(SCH_1):M_F_DQS_DN(14)
 110 M_F_DQS_DP<14> DQS14P @BASEBOARD_FAB2_LIB.BASEBOARD_FAB2(SCH_1):M_F_DQS_DP(14)
 122 M_F_DQS_DN<15> DQS15N @BASEBOARD_FAB2_LIB.BASEBOARD_FAB2(SCH_1):M_F_DQS_DN(15)
 121 M_F_DQS_DP<15> DQS15P @BASEBOARD_FAB2_LIB.BASEBOARD_FAB2(SCH_1):M_F_DQS_DP(15)
 133 M_F_DQS_DN<16> DQS16N @BASEBOARD_FAB2_LIB.BASEBOARD_FAB2(SCH_1):M_F_DQS_DN(16)
 132 M_F_DQS_DP<16> DQS16P @BASEBOARD_FAB2_LIB.BASEBOARD_FAB2(SCH_1):M_F_DQS_DP(16)
  52 M_F_DQS_DN<17> DQS17N @BASEBOARD_FAB2_LIB.BASEBOARD_FAB2(SCH_1):M_F_DQS_DN(17)
  51 M_F_DQS_DP<17> DQS17P @BASEBOARD_FAB2_LIB.BASEBOARD_FAB2(SCH_1):M_F_DQS_DP(17)
 163 M_F_DQS_DN<1>  DQS1N @BASEBOARD_FAB2_LIB.BASEBOARD_FAB2(SCH_1):M_F_DQS_DN(1)
 164 M_F_DQS_DP<1>  DQS1P @BASEBOARD_FAB2_LIB.BASEBOARD_FAB2(SCH_1):M_F_DQS_DP(1)
 174 M_F_DQS_DN<2>  DQS2N @BASEBOARD_FAB2_LIB.BASEBOARD_FAB2(SCH_1):M_F_DQS_DN(2)
 175 M_F_DQS_DP<2>  DQS2P @BASEBOARD_FAB2_LIB.BASEBOARD_FAB2(SCH_1):M_F_DQS_DP(2)
 185 M_F_DQS_DN<3>  DQS3N @BASEBOARD_FAB2_LIB.BASEBOARD_FAB2(SCH_1):M_F_DQS_DN(3)
 186 M_F_DQS_DP<3>  DQS3P @BASEBOARD_FAB2_LIB.BASEBOARD_FAB2(SCH_1):M_F_DQS_DP(3)
 244 M_F_DQS_DN<4>  DQS4N @BASEBOARD_FAB2_LIB.BASEBOARD_FAB2(SCH_1):M_F_DQS_DN(4)
 245 M_F_DQS_DP<4>  DQS4P @BASEBOARD_FAB2_LIB.BASEBOARD_FAB2(SCH_1):M_F_DQS_DP(4)
 255 M_F_DQS_DN<5>  DQS5N @BASEBOARD_FAB2_LIB.BASEBOARD_FAB2(SCH_1):M_F_DQS_DN(5)
 256 M_F_DQS_DP<5>  DQS5P @BASEBOARD_FAB2_LIB.BASEBOARD_FAB2(SCH_1):M_F_DQS_DP(5)
 266 M_F_DQS_DN<6>  DQS6N @BASEBOARD_FAB2_LIB.BASEBOARD_FAB2(SCH_1):M_F_DQS_DN(6)
 267 M_F_DQS_DP<6>  DQS6P @BASEBOARD_FAB2_LIB.BASEBOARD_FAB2(SCH_1):M_F_DQS_DP(6)
 277 M_F_DQS_DN<7>  DQS7N @BASEBOARD_FAB2_LIB.BASEBOARD_FAB2(SCH_1):M_F_DQS_DN(7)
 278 M_F_DQS_DP<7>  DQS7P @BASEBOARD_FAB2_LIB.BASEBOARD_FAB2(SCH_1):M_F_DQS_DP(7)
 196 M_F_DQS_DN<8>  DQS8N @BASEBOARD_FAB2_LIB.BASEBOARD_FAB2(SCH_1):M_F_DQS_DN(8)
 197 M_F_DQS_DP<8>  DQS8P @BASEBOARD_FAB2_LIB.BASEBOARD_FAB2(SCH_1):M_F_DQS_DP(8)
   8 M_F_DQS_DN<9>  DQS9N @BASEBOARD_FAB2_LIB.BASEBOARD_FAB2(SCH_1):M_F_DQS_DN(9)
   7 M_F_DQS_DP<9>  DQS9P @BASEBOARD_FAB2_LIB.BASEBOARD_FAB2(SCH_1):M_F_DQS_DP(9)

SCONN288_H44441004_PIP-SCONN,HA  I111  J4A1
  79 M_F_MA<0>     A0 @BASEBOARD_FAB2_LIB.BASEBOARD_FAB2(SCH_1):M_F_MA(0)
  72 M_F_MA<1>     A1 @BASEBOARD_FAB2_LIB.BASEBOARD_FAB2(SCH_1):M_F_MA(1)
 225 M_F_MA<10>    A10 @BASEBOARD_FAB2_LIB.BASEBOARD_FAB2(SCH_1):M_F_MA(10)
 210 M_F_MA<11>    A11 @BASEBOARD_FAB2_LIB.BASEBOARD_FAB2(SCH_1):M_F_MA(11)
  65 M_F_MA<12>    A12 @BASEBOARD_FAB2_LIB.BASEBOARD_FAB2(SCH_1):M_F_MA(12)
 232 M_F_MA<13>    A13 @BASEBOARD_FAB2_LIB.BASEBOARD_FAB2(SCH_1):M_F_MA(13)
 228 M_F_MA<14> A14_WE_N @BASEBOARD_FAB2_LIB.BASEBOARD_FAB2(SCH_1):M_F_MA(14)
  86 M_F_MA<15> A15_CAS_N @BASEBOARD_FAB2_LIB.BASEBOARD_FAB2(SCH_1):M_F_MA(15)
  82 M_F_MA<16> A16_RAS_N @BASEBOARD_FAB2_LIB.BASEBOARD_FAB2(SCH_1):M_F_MA(16)
 234 M_F_MA<17>    A17 @BASEBOARD_FAB2_LIB.BASEBOARD_FAB2(SCH_1):M_F_MA(17)
 216 M_F_MA<2>     A2 @BASEBOARD_FAB2_LIB.BASEBOARD_FAB2(SCH_1):M_F_MA(2)
  71 M_F_MA<3>     A3 @BASEBOARD_FAB2_LIB.BASEBOARD_FAB2(SCH_1):M_F_MA(3)
 214 M_F_MA<4>     A4 @BASEBOARD_FAB2_LIB.BASEBOARD_FAB2(SCH_1):M_F_MA(4)
 213 M_F_MA<5>     A5 @BASEBOARD_FAB2_LIB.BASEBOARD_FAB2(SCH_1):M_F_MA(5)
  69 M_F_MA<6>     A6 @BASEBOARD_FAB2_LIB.BASEBOARD_FAB2(SCH_1):M_F_MA(6)
 211 M_F_MA<7>     A7 @BASEBOARD_FAB2_LIB.BASEBOARD_FAB2(SCH_1):M_F_MA(7)
  68 M_F_MA<8>     A8 @BASEBOARD_FAB2_LIB.BASEBOARD_FAB2(SCH_1):M_F_MA(8)
  66 M_F_MA<9>     A9 @BASEBOARD_FAB2_LIB.BASEBOARD_FAB2(SCH_1):M_F_MA(9)
  62 M_F_ACT_N  ACT_N @BASEBOARD_FAB2_LIB.BASEBOARD_FAB2(SCH_1):M_F_ACT_N
 208 M_F_ALERT_N ALERT_N @BASEBOARD_FAB2_LIB.BASEBOARD_FAB2(SCH_1):M_F_ALERT_N
 224 M_F_BA<1>  BA<1> @BASEBOARD_FAB2_LIB.BASEBOARD_FAB2(SCH_1):M_F_BA(1)
  81 M_F_BA<0>  BA<0> @BASEBOARD_FAB2_LIB.BASEBOARD_FAB2(SCH_1):M_F_BA(0)
 207 M_F_BG<1>  BG<1> @BASEBOARD_FAB2_LIB.BASEBOARD_FAB2(SCH_1):M_F_BG(1)
  63 M_F_BG<0>  BG<0> @BASEBOARD_FAB2_LIB.BASEBOARD_FAB2(SCH_1):M_F_BG(0)
 235 M_F_C<2>   C<2> @BASEBOARD_FAB2_LIB.BASEBOARD_FAB2(SCH_1):M_F_C(2)
 199 M_F_ECC<6>  CB<7> @BASEBOARD_FAB2_LIB.BASEBOARD_FAB2(SCH_1):M_F_ECC(6)
  54 M_F_ECC<7>  CB<6> @BASEBOARD_FAB2_LIB.BASEBOARD_FAB2(SCH_1):M_F_ECC(7)
 192 M_F_ECC<4>  CB<5> @BASEBOARD_FAB2_LIB.BASEBOARD_FAB2(SCH_1):M_F_ECC(4)
  47 M_F_ECC<5>  CB<4> @BASEBOARD_FAB2_LIB.BASEBOARD_FAB2(SCH_1):M_F_ECC(5)
 201 M_F_ECC<2>  CB<3> @BASEBOARD_FAB2_LIB.BASEBOARD_FAB2(SCH_1):M_F_ECC(2)
  56 M_F_ECC<3>  CB<2> @BASEBOARD_FAB2_LIB.BASEBOARD_FAB2(SCH_1):M_F_ECC(3)
 194 M_F_ECC<0>  CB<1> @BASEBOARD_FAB2_LIB.BASEBOARD_FAB2(SCH_1):M_F_ECC(0)
  49 M_F_ECC<1>  CB<0> @BASEBOARD_FAB2_LIB.BASEBOARD_FAB2(SCH_1):M_F_ECC(1)
  75 M_F_CLK_DN<0>   CK0N @BASEBOARD_FAB2_LIB.BASEBOARD_FAB2(SCH_1):M_F_CLK_DN(0)
  74 M_F_CLK_DP<0>   CK0P @BASEBOARD_FAB2_LIB.BASEBOARD_FAB2(SCH_1):M_F_CLK_DP(0)
 219 M_F_CLK_DN<1>   CK1N @BASEBOARD_FAB2_LIB.BASEBOARD_FAB2(SCH_1):M_F_CLK_DN(1)
 218 M_F_CLK_DP<1>   CK1P @BASEBOARD_FAB2_LIB.BASEBOARD_FAB2(SCH_1):M_F_CLK_DP(1)
 203 M_F_CKE<1> CKE<1> @BASEBOARD_FAB2_LIB.BASEBOARD_FAB2(SCH_1):M_F_CKE(1)
  60 M_F_CKE<0> CKE<0> @BASEBOARD_FAB2_LIB.BASEBOARD_FAB2(SCH_1):M_F_CKE(0)
 280 M_F_DQ<62> DQ<63> @BASEBOARD_FAB2_LIB.BASEBOARD_FAB2(SCH_1):M_F_DQ(62)
 135 M_F_DQ<63> DQ<62> @BASEBOARD_FAB2_LIB.BASEBOARD_FAB2(SCH_1):M_F_DQ(63)
 273 M_F_DQ<60> DQ<61> @BASEBOARD_FAB2_LIB.BASEBOARD_FAB2(SCH_1):M_F_DQ(60)
 128 M_F_DQ<61> DQ<60> @BASEBOARD_FAB2_LIB.BASEBOARD_FAB2(SCH_1):M_F_DQ(61)
 282 M_F_DQ<58> DQ<59> @BASEBOARD_FAB2_LIB.BASEBOARD_FAB2(SCH_1):M_F_DQ(58)
 137 M_F_DQ<59> DQ<58> @BASEBOARD_FAB2_LIB.BASEBOARD_FAB2(SCH_1):M_F_DQ(59)
 275 M_F_DQ<56> DQ<57> @BASEBOARD_FAB2_LIB.BASEBOARD_FAB2(SCH_1):M_F_DQ(56)
 130 M_F_DQ<57> DQ<56> @BASEBOARD_FAB2_LIB.BASEBOARD_FAB2(SCH_1):M_F_DQ(57)
 269 M_F_DQ<54> DQ<55> @BASEBOARD_FAB2_LIB.BASEBOARD_FAB2(SCH_1):M_F_DQ(54)
 124 M_F_DQ<55> DQ<54> @BASEBOARD_FAB2_LIB.BASEBOARD_FAB2(SCH_1):M_F_DQ(55)
 262 M_F_DQ<52> DQ<53> @BASEBOARD_FAB2_LIB.BASEBOARD_FAB2(SCH_1):M_F_DQ(52)
 117 M_F_DQ<53> DQ<52> @BASEBOARD_FAB2_LIB.BASEBOARD_FAB2(SCH_1):M_F_DQ(53)
 271 M_F_DQ<50> DQ<51> @BASEBOARD_FAB2_LIB.BASEBOARD_FAB2(SCH_1):M_F_DQ(50)
 126 M_F_DQ<51> DQ<50> @BASEBOARD_FAB2_LIB.BASEBOARD_FAB2(SCH_1):M_F_DQ(51)
 264 M_F_DQ<48> DQ<49> @BASEBOARD_FAB2_LIB.BASEBOARD_FAB2(SCH_1):M_F_DQ(48)
 119 M_F_DQ<49> DQ<48> @BASEBOARD_FAB2_LIB.BASEBOARD_FAB2(SCH_1):M_F_DQ(49)
 258 M_F_DQ<46> DQ<47> @BASEBOARD_FAB2_LIB.BASEBOARD_FAB2(SCH_1):M_F_DQ(46)
 113 M_F_DQ<47> DQ<46> @BASEBOARD_FAB2_LIB.BASEBOARD_FAB2(SCH_1):M_F_DQ(47)
 251 M_F_DQ<44> DQ<45> @BASEBOARD_FAB2_LIB.BASEBOARD_FAB2(SCH_1):M_F_DQ(44)
 106 M_F_DQ<45> DQ<44> @BASEBOARD_FAB2_LIB.BASEBOARD_FAB2(SCH_1):M_F_DQ(45)
 260 M_F_DQ<42> DQ<43> @BASEBOARD_FAB2_LIB.BASEBOARD_FAB2(SCH_1):M_F_DQ(42)
 115 M_F_DQ<43> DQ<42> @BASEBOARD_FAB2_LIB.BASEBOARD_FAB2(SCH_1):M_F_DQ(43)
 253 M_F_DQ<40> DQ<41> @BASEBOARD_FAB2_LIB.BASEBOARD_FAB2(SCH_1):M_F_DQ(40)
 108 M_F_DQ<41> DQ<40> @BASEBOARD_FAB2_LIB.BASEBOARD_FAB2(SCH_1):M_F_DQ(41)
 247 M_F_DQ<38> DQ<39> @BASEBOARD_FAB2_LIB.BASEBOARD_FAB2(SCH_1):M_F_DQ(38)
 102 M_F_DQ<39> DQ<38> @BASEBOARD_FAB2_LIB.BASEBOARD_FAB2(SCH_1):M_F_DQ(39)
 240 M_F_DQ<36> DQ<37> @BASEBOARD_FAB2_LIB.BASEBOARD_FAB2(SCH_1):M_F_DQ(36)
  95 M_F_DQ<37> DQ<36> @BASEBOARD_FAB2_LIB.BASEBOARD_FAB2(SCH_1):M_F_DQ(37)
 249 M_F_DQ<34> DQ<35> @BASEBOARD_FAB2_LIB.BASEBOARD_FAB2(SCH_1):M_F_DQ(34)
 104 M_F_DQ<35> DQ<34> @BASEBOARD_FAB2_LIB.BASEBOARD_FAB2(SCH_1):M_F_DQ(35)
 242 M_F_DQ<32> DQ<33> @BASEBOARD_FAB2_LIB.BASEBOARD_FAB2(SCH_1):M_F_DQ(32)
  97 M_F_DQ<33> DQ<32> @BASEBOARD_FAB2_LIB.BASEBOARD_FAB2(SCH_1):M_F_DQ(33)
 188 M_F_DQ<30> DQ<31> @BASEBOARD_FAB2_LIB.BASEBOARD_FAB2(SCH_1):M_F_DQ(30)
  43 M_F_DQ<31> DQ<30> @BASEBOARD_FAB2_LIB.BASEBOARD_FAB2(SCH_1):M_F_DQ(31)
 181 M_F_DQ<28> DQ<29> @BASEBOARD_FAB2_LIB.BASEBOARD_FAB2(SCH_1):M_F_DQ(28)
  36 M_F_DQ<29> DQ<28> @BASEBOARD_FAB2_LIB.BASEBOARD_FAB2(SCH_1):M_F_DQ(29)
 190 M_F_DQ<26> DQ<27> @BASEBOARD_FAB2_LIB.BASEBOARD_FAB2(SCH_1):M_F_DQ(26)
  45 M_F_DQ<27> DQ<26> @BASEBOARD_FAB2_LIB.BASEBOARD_FAB2(SCH_1):M_F_DQ(27)
 183 M_F_DQ<24> DQ<25> @BASEBOARD_FAB2_LIB.BASEBOARD_FAB2(SCH_1):M_F_DQ(24)
  38 M_F_DQ<25> DQ<24> @BASEBOARD_FAB2_LIB.BASEBOARD_FAB2(SCH_1):M_F_DQ(25)
 177 M_F_DQ<22> DQ<23> @BASEBOARD_FAB2_LIB.BASEBOARD_FAB2(SCH_1):M_F_DQ(22)
  32 M_F_DQ<23> DQ<22> @BASEBOARD_FAB2_LIB.BASEBOARD_FAB2(SCH_1):M_F_DQ(23)
 170 M_F_DQ<20> DQ<21> @BASEBOARD_FAB2_LIB.BASEBOARD_FAB2(SCH_1):M_F_DQ(20)
  25 M_F_DQ<21> DQ<20> @BASEBOARD_FAB2_LIB.BASEBOARD_FAB2(SCH_1):M_F_DQ(21)
 179 M_F_DQ<18> DQ<19> @BASEBOARD_FAB2_LIB.BASEBOARD_FAB2(SCH_1):M_F_DQ(18)
  34 M_F_DQ<19> DQ<18> @BASEBOARD_FAB2_LIB.BASEBOARD_FAB2(SCH_1):M_F_DQ(19)
 172 M_F_DQ<16> DQ<17> @BASEBOARD_FAB2_LIB.BASEBOARD_FAB2(SCH_1):M_F_DQ(16)
  27 M_F_DQ<17> DQ<16> @BASEBOARD_FAB2_LIB.BASEBOARD_FAB2(SCH_1):M_F_DQ(17)
 166 M_F_DQ<14> DQ<15> @BASEBOARD_FAB2_LIB.BASEBOARD_FAB2(SCH_1):M_F_DQ(14)
  21 M_F_DQ<15> DQ<14> @BASEBOARD_FAB2_LIB.BASEBOARD_FAB2(SCH_1):M_F_DQ(15)
 159 M_F_DQ<12> DQ<13> @BASEBOARD_FAB2_LIB.BASEBOARD_FAB2(SCH_1):M_F_DQ(12)
  14 M_F_DQ<13> DQ<12> @BASEBOARD_FAB2_LIB.BASEBOARD_FAB2(SCH_1):M_F_DQ(13)
 168 M_F_DQ<10> DQ<11> @BASEBOARD_FAB2_LIB.BASEBOARD_FAB2(SCH_1):M_F_DQ(10)
  23 M_F_DQ<11> DQ<10> @BASEBOARD_FAB2_LIB.BASEBOARD_FAB2(SCH_1):M_F_DQ(11)
 161 M_F_DQ<8>  DQ<9> @BASEBOARD_FAB2_LIB.BASEBOARD_FAB2(SCH_1):M_F_DQ(8)
  16 M_F_DQ<9>  DQ<8> @BASEBOARD_FAB2_LIB.BASEBOARD_FAB2(SCH_1):M_F_DQ(9)
 155 M_F_DQ<6>  DQ<7> @BASEBOARD_FAB2_LIB.BASEBOARD_FAB2(SCH_1):M_F_DQ(6)
  10 M_F_DQ<7>  DQ<6> @BASEBOARD_FAB2_LIB.BASEBOARD_FAB2(SCH_1):M_F_DQ(7)
 148 M_F_DQ<4>  DQ<5> @BASEBOARD_FAB2_LIB.BASEBOARD_FAB2(SCH_1):M_F_DQ(4)
   3 M_F_DQ<5>  DQ<4> @BASEBOARD_FAB2_LIB.BASEBOARD_FAB2(SCH_1):M_F_DQ(5)
 157 M_F_DQ<2>  DQ<3> @BASEBOARD_FAB2_LIB.BASEBOARD_FAB2(SCH_1):M_F_DQ(2)
  12 M_F_DQ<3>  DQ<2> @BASEBOARD_FAB2_LIB.BASEBOARD_FAB2(SCH_1):M_F_DQ(3)
 150 M_F_DQ<0>  DQ<1> @BASEBOARD_FAB2_LIB.BASEBOARD_FAB2(SCH_1):M_F_DQ(0)
   5 M_F_DQ<1>  DQ<0> @BASEBOARD_FAB2_LIB.BASEBOARD_FAB2(SCH_1):M_F_DQ(1)
  78 FM_DIMM_EVENT_COD_N EVENT_N @BASEBOARD_FAB2_LIB.BASEBOARD_FAB2(SCH_1):FM_DIMM_EVENT_COD_N
  91 M_F_ODT<1> ODT<1> @BASEBOARD_FAB2_LIB.BASEBOARD_FAB2(SCH_1):M_F_ODT(1)
  87 M_F_ODT<0> ODT<0> @BASEBOARD_FAB2_LIB.BASEBOARD_FAB2(SCH_1):M_F_ODT(0)
 222 M_F_PAR    PAR @BASEBOARD_FAB2_LIB.BASEBOARD_FAB2(SCH_1):M_F_PAR
  58 M_DEF_RST_N RESET_N @BASEBOARD_FAB2_LIB.BASEBOARD_FAB2(SCH_1):M_DEF_RST_N
 144 TP_CH_F_DIMM_F0_RFU_2 RFU<2> @BASEBOARD_FAB2_LIB.BASEBOARD_FAB2(SCH_1):TP_CH_F_DIMM_F0_RFU_2
 227 TP_CH_F_DIMM_F0_RFU_1 RFU<1> @BASEBOARD_FAB2_LIB.BASEBOARD_FAB2(SCH_1):TP_CH_F_DIMM_F0_RFU_1
 205 TP_CH_F_DIMM_F0_RFU_0 RFU<0> @BASEBOARD_FAB2_LIB.BASEBOARD_FAB2(SCH_1):TP_CH_F_DIMM_F0_RFU_0
  84 M_F_CS_N<0>   S0_N @BASEBOARD_FAB2_LIB.BASEBOARD_FAB2(SCH_1):M_F_CS_N(0)
  89 M_F_CS_N<1>   S1_N @BASEBOARD_FAB2_LIB.BASEBOARD_FAB2(SCH_1):M_F_CS_N(1)
  93 M_F_CS_N<2> S2_N_C<0> @BASEBOARD_FAB2_LIB.BASEBOARD_FAB2(SCH_1):M_F_CS_N(2)
 237 M_F_CS_N<3> S3_N_C<1> @BASEBOARD_FAB2_LIB.BASEBOARD_FAB2(SCH_1):M_F_CS_N(3)
 238 PVPP_DEF  SA<2> @BASEBOARD_FAB2_LIB.BASEBOARD_FAB2(SCH_1):PVPP_DEF
 140    GND  SA<1> @BASEBOARD_FAB2_LIB.BASEBOARD_FAB2(SCH_1):GND
 139    GND  SA<0> @BASEBOARD_FAB2_LIB.BASEBOARD_FAB2(SCH_1):GND
 230 FM_ADR_COMPLETE_DEF_N SAVE_N_NC @BASEBOARD_FAB2_LIB.BASEBOARD_FAB2(SCH_1):FM_ADR_COMPLETE_DEF_N
 141 SMB_DDR_DEF_VPP_SCL    SCL @BASEBOARD_FAB2_LIB.BASEBOARD_FAB2(SCH_1):SMB_DDR_DEF_VPP_SCL
 285 SMB_DDR_DEF_VPP_SDA    SDA @BASEBOARD_FAB2_LIB.BASEBOARD_FAB2(SCH_1):SMB_DDR_DEF_VPP_SDA
 284 PVPP_DEF VDDSPD @BASEBOARD_FAB2_LIB.BASEBOARD_FAB2(SCH_1):PVPP_DEF
 146 M_F_VREF VREFCA @BASEBOARD_FAB2_LIB.BASEBOARD_FAB2(SCH_1):M_F_VREF

SCONN288_H44441004_PIP-SCONN,HA  I171  J4A1
   1 P12V_NVDIMM_DEF 12V<1> @BASEBOARD_FAB2_LIB.BASEBOARD_FAB2(SCH_1):P12V_NVDIMM_DEF
 145 P12V_NVDIMM_DEF 12V<0> @BASEBOARD_FAB2_LIB.BASEBOARD_FAB2(SCH_1):P12V_NVDIMM_DEF
  59 PVDDQ_DEF VDD<25> @BASEBOARD_FAB2_LIB.BASEBOARD_FAB2(SCH_1):PVDDQ_DEF
  61 PVDDQ_DEF VDD<24> @BASEBOARD_FAB2_LIB.BASEBOARD_FAB2(SCH_1):PVDDQ_DEF
  64 PVDDQ_DEF VDD<23> @BASEBOARD_FAB2_LIB.BASEBOARD_FAB2(SCH_1):PVDDQ_DEF
  67 PVDDQ_DEF VDD<22> @BASEBOARD_FAB2_LIB.BASEBOARD_FAB2(SCH_1):PVDDQ_DEF
  70 PVDDQ_DEF VDD<21> @BASEBOARD_FAB2_LIB.BASEBOARD_FAB2(SCH_1):PVDDQ_DEF
  73 PVDDQ_DEF VDD<20> @BASEBOARD_FAB2_LIB.BASEBOARD_FAB2(SCH_1):PVDDQ_DEF
  76 PVDDQ_DEF VDD<19> @BASEBOARD_FAB2_LIB.BASEBOARD_FAB2(SCH_1):PVDDQ_DEF
  80 PVDDQ_DEF VDD<18> @BASEBOARD_FAB2_LIB.BASEBOARD_FAB2(SCH_1):PVDDQ_DEF
  83 PVDDQ_DEF VDD<17> @BASEBOARD_FAB2_LIB.BASEBOARD_FAB2(SCH_1):PVDDQ_DEF
  85 PVDDQ_DEF VDD<16> @BASEBOARD_FAB2_LIB.BASEBOARD_FAB2(SCH_1):PVDDQ_DEF
  88 PVDDQ_DEF VDD<15> @BASEBOARD_FAB2_LIB.BASEBOARD_FAB2(SCH_1):PVDDQ_DEF
  90 PVDDQ_DEF VDD<14> @BASEBOARD_FAB2_LIB.BASEBOARD_FAB2(SCH_1):PVDDQ_DEF
  92 PVDDQ_DEF VDD<13> @BASEBOARD_FAB2_LIB.BASEBOARD_FAB2(SCH_1):PVDDQ_DEF
 204 PVDDQ_DEF VDD<12> @BASEBOARD_FAB2_LIB.BASEBOARD_FAB2(SCH_1):PVDDQ_DEF
 206 PVDDQ_DEF VDD<11> @BASEBOARD_FAB2_LIB.BASEBOARD_FAB2(SCH_1):PVDDQ_DEF
 209 PVDDQ_DEF VDD<10> @BASEBOARD_FAB2_LIB.BASEBOARD_FAB2(SCH_1):PVDDQ_DEF
 212 PVDDQ_DEF VDD<9> @BASEBOARD_FAB2_LIB.BASEBOARD_FAB2(SCH_1):PVDDQ_DEF
 215 PVDDQ_DEF VDD<8> @BASEBOARD_FAB2_LIB.BASEBOARD_FAB2(SCH_1):PVDDQ_DEF
 217 PVDDQ_DEF VDD<7> @BASEBOARD_FAB2_LIB.BASEBOARD_FAB2(SCH_1):PVDDQ_DEF
 220 PVDDQ_DEF VDD<6> @BASEBOARD_FAB2_LIB.BASEBOARD_FAB2(SCH_1):PVDDQ_DEF
 223 PVDDQ_DEF VDD<5> @BASEBOARD_FAB2_LIB.BASEBOARD_FAB2(SCH_1):PVDDQ_DEF
 226 PVDDQ_DEF VDD<4> @BASEBOARD_FAB2_LIB.BASEBOARD_FAB2(SCH_1):PVDDQ_DEF
 229 PVDDQ_DEF VDD<3> @BASEBOARD_FAB2_LIB.BASEBOARD_FAB2(SCH_1):PVDDQ_DEF
 231 PVDDQ_DEF VDD<2> @BASEBOARD_FAB2_LIB.BASEBOARD_FAB2(SCH_1):PVDDQ_DEF
 233 PVDDQ_DEF VDD<1> @BASEBOARD_FAB2_LIB.BASEBOARD_FAB2(SCH_1):PVDDQ_DEF
 236 PVDDQ_DEF VDD<0> @BASEBOARD_FAB2_LIB.BASEBOARD_FAB2(SCH_1):PVDDQ_DEF
 142 PVPP_DEF VPP<4> @BASEBOARD_FAB2_LIB.BASEBOARD_FAB2(SCH_1):PVPP_DEF
 143 PVPP_DEF VPP<3> @BASEBOARD_FAB2_LIB.BASEBOARD_FAB2(SCH_1):PVPP_DEF
 288 PVPP_DEF VPP<2> @BASEBOARD_FAB2_LIB.BASEBOARD_FAB2(SCH_1):PVPP_DEF
 286 PVPP_DEF VPP<1> @BASEBOARD_FAB2_LIB.BASEBOARD_FAB2(SCH_1):PVPP_DEF
 287 PVPP_DEF VPP<0> @BASEBOARD_FAB2_LIB.BASEBOARD_FAB2(SCH_1):PVPP_DEF
  77 PVTT_DEF VTT<1> @BASEBOARD_FAB2_LIB.BASEBOARD_FAB2(SCH_1):PVTT_DEF
 221 PVTT_DEF VTT<0> @BASEBOARD_FAB2_LIB.BASEBOARD_FAB2(SCH_1):PVTT_DEF

CAP_A_0402V-0.01UF,25V,10%,X7RA  I178  C6L1
   1 M_F_VREF      A @BASEBOARD_FAB2_LIB.BASEBOARD_FAB2(SCH_1):M_F_VREF
   2    GND      B @BASEBOARD_FAB2_LIB.BASEBOARD_FAB2(SCH_1):GND


DRAWING: @BASEBOARD_FAB2_LIB.BASEBOARD_FAB2(SCH_1):PAGE54 

SCONN288_H44441003_PIP-SCONN,HA  I43  J6L1
   2    GND VSS<93> @BASEBOARD_FAB2_LIB.BASEBOARD_FAB2(SCH_1):GND
   4    GND VSS<92> @BASEBOARD_FAB2_LIB.BASEBOARD_FAB2(SCH_1):GND
   6    GND VSS<91> @BASEBOARD_FAB2_LIB.BASEBOARD_FAB2(SCH_1):GND
   9    GND VSS<90> @BASEBOARD_FAB2_LIB.BASEBOARD_FAB2(SCH_1):GND
  11    GND VSS<89> @BASEBOARD_FAB2_LIB.BASEBOARD_FAB2(SCH_1):GND
  13    GND VSS<88> @BASEBOARD_FAB2_LIB.BASEBOARD_FAB2(SCH_1):GND
  15    GND VSS<87> @BASEBOARD_FAB2_LIB.BASEBOARD_FAB2(SCH_1):GND
  17    GND VSS<86> @BASEBOARD_FAB2_LIB.BASEBOARD_FAB2(SCH_1):GND
  20    GND VSS<85> @BASEBOARD_FAB2_LIB.BASEBOARD_FAB2(SCH_1):GND
  22    GND VSS<84> @BASEBOARD_FAB2_LIB.BASEBOARD_FAB2(SCH_1):GND
  24    GND VSS<83> @BASEBOARD_FAB2_LIB.BASEBOARD_FAB2(SCH_1):GND
  26    GND VSS<82> @BASEBOARD_FAB2_LIB.BASEBOARD_FAB2(SCH_1):GND
  28    GND VSS<81> @BASEBOARD_FAB2_LIB.BASEBOARD_FAB2(SCH_1):GND
  31    GND VSS<80> @BASEBOARD_FAB2_LIB.BASEBOARD_FAB2(SCH_1):GND
  33    GND VSS<79> @BASEBOARD_FAB2_LIB.BASEBOARD_FAB2(SCH_1):GND
  35    GND VSS<78> @BASEBOARD_FAB2_LIB.BASEBOARD_FAB2(SCH_1):GND
  37    GND VSS<77> @BASEBOARD_FAB2_LIB.BASEBOARD_FAB2(SCH_1):GND
  39    GND VSS<76> @BASEBOARD_FAB2_LIB.BASEBOARD_FAB2(SCH_1):GND
  42    GND VSS<75> @BASEBOARD_FAB2_LIB.BASEBOARD_FAB2(SCH_1):GND
  44    GND VSS<74> @BASEBOARD_FAB2_LIB.BASEBOARD_FAB2(SCH_1):GND
  46    GND VSS<73> @BASEBOARD_FAB2_LIB.BASEBOARD_FAB2(SCH_1):GND
  48    GND VSS<72> @BASEBOARD_FAB2_LIB.BASEBOARD_FAB2(SCH_1):GND
  50    GND VSS<71> @BASEBOARD_FAB2_LIB.BASEBOARD_FAB2(SCH_1):GND
  53    GND VSS<70> @BASEBOARD_FAB2_LIB.BASEBOARD_FAB2(SCH_1):GND
  55    GND VSS<69> @BASEBOARD_FAB2_LIB.BASEBOARD_FAB2(SCH_1):GND
  57    GND VSS<68> @BASEBOARD_FAB2_LIB.BASEBOARD_FAB2(SCH_1):GND
  94    GND VSS<67> @BASEBOARD_FAB2_LIB.BASEBOARD_FAB2(SCH_1):GND
  96    GND VSS<66> @BASEBOARD_FAB2_LIB.BASEBOARD_FAB2(SCH_1):GND
  98    GND VSS<65> @BASEBOARD_FAB2_LIB.BASEBOARD_FAB2(SCH_1):GND
 101    GND VSS<64> @BASEBOARD_FAB2_LIB.BASEBOARD_FAB2(SCH_1):GND
 103    GND VSS<63> @BASEBOARD_FAB2_LIB.BASEBOARD_FAB2(SCH_1):GND
 105    GND VSS<62> @BASEBOARD_FAB2_LIB.BASEBOARD_FAB2(SCH_1):GND
 107    GND VSS<61> @BASEBOARD_FAB2_LIB.BASEBOARD_FAB2(SCH_1):GND
 109    GND VSS<60> @BASEBOARD_FAB2_LIB.BASEBOARD_FAB2(SCH_1):GND
 112    GND VSS<59> @BASEBOARD_FAB2_LIB.BASEBOARD_FAB2(SCH_1):GND
 114    GND VSS<58> @BASEBOARD_FAB2_LIB.BASEBOARD_FAB2(SCH_1):GND
 116    GND VSS<57> @BASEBOARD_FAB2_LIB.BASEBOARD_FAB2(SCH_1):GND
 118    GND VSS<56> @BASEBOARD_FAB2_LIB.BASEBOARD_FAB2(SCH_1):GND
 120    GND VSS<55> @BASEBOARD_FAB2_LIB.BASEBOARD_FAB2(SCH_1):GND
 123    GND VSS<54> @BASEBOARD_FAB2_LIB.BASEBOARD_FAB2(SCH_1):GND
 125    GND VSS<53> @BASEBOARD_FAB2_LIB.BASEBOARD_FAB2(SCH_1):GND
 127    GND VSS<52> @BASEBOARD_FAB2_LIB.BASEBOARD_FAB2(SCH_1):GND
 129    GND VSS<51> @BASEBOARD_FAB2_LIB.BASEBOARD_FAB2(SCH_1):GND
 131    GND VSS<50> @BASEBOARD_FAB2_LIB.BASEBOARD_FAB2(SCH_1):GND
 134    GND VSS<49> @BASEBOARD_FAB2_LIB.BASEBOARD_FAB2(SCH_1):GND
 136    GND VSS<48> @BASEBOARD_FAB2_LIB.BASEBOARD_FAB2(SCH_1):GND
 138    GND VSS<47> @BASEBOARD_FAB2_LIB.BASEBOARD_FAB2(SCH_1):GND
 147    GND VSS<46> @BASEBOARD_FAB2_LIB.BASEBOARD_FAB2(SCH_1):GND
 149    GND VSS<45> @BASEBOARD_FAB2_LIB.BASEBOARD_FAB2(SCH_1):GND
 151    GND VSS<44> @BASEBOARD_FAB2_LIB.BASEBOARD_FAB2(SCH_1):GND
 154    GND VSS<43> @BASEBOARD_FAB2_LIB.BASEBOARD_FAB2(SCH_1):GND
 156    GND VSS<42> @BASEBOARD_FAB2_LIB.BASEBOARD_FAB2(SCH_1):GND
 158    GND VSS<41> @BASEBOARD_FAB2_LIB.BASEBOARD_FAB2(SCH_1):GND
 160    GND VSS<40> @BASEBOARD_FAB2_LIB.BASEBOARD_FAB2(SCH_1):GND
 162    GND VSS<39> @BASEBOARD_FAB2_LIB.BASEBOARD_FAB2(SCH_1):GND
 165    GND VSS<38> @BASEBOARD_FAB2_LIB.BASEBOARD_FAB2(SCH_1):GND
 167    GND VSS<37> @BASEBOARD_FAB2_LIB.BASEBOARD_FAB2(SCH_1):GND
 169    GND VSS<36> @BASEBOARD_FAB2_LIB.BASEBOARD_FAB2(SCH_1):GND
 171    GND VSS<35> @BASEBOARD_FAB2_LIB.BASEBOARD_FAB2(SCH_1):GND
 173    GND VSS<34> @BASEBOARD_FAB2_LIB.BASEBOARD_FAB2(SCH_1):GND
 176    GND VSS<33> @BASEBOARD_FAB2_LIB.BASEBOARD_FAB2(SCH_1):GND
 178    GND VSS<32> @BASEBOARD_FAB2_LIB.BASEBOARD_FAB2(SCH_1):GND
 180    GND VSS<31> @BASEBOARD_FAB2_LIB.BASEBOARD_FAB2(SCH_1):GND
 182    GND VSS<30> @BASEBOARD_FAB2_LIB.BASEBOARD_FAB2(SCH_1):GND
 184    GND VSS<29> @BASEBOARD_FAB2_LIB.BASEBOARD_FAB2(SCH_1):GND
 187    GND VSS<28> @BASEBOARD_FAB2_LIB.BASEBOARD_FAB2(SCH_1):GND
 189    GND VSS<27> @BASEBOARD_FAB2_LIB.BASEBOARD_FAB2(SCH_1):GND
 191    GND VSS<26> @BASEBOARD_FAB2_LIB.BASEBOARD_FAB2(SCH_1):GND
 193    GND VSS<25> @BASEBOARD_FAB2_LIB.BASEBOARD_FAB2(SCH_1):GND
 195    GND VSS<24> @BASEBOARD_FAB2_LIB.BASEBOARD_FAB2(SCH_1):GND
 198    GND VSS<23> @BASEBOARD_FAB2_LIB.BASEBOARD_FAB2(SCH_1):GND
 200    GND VSS<22> @BASEBOARD_FAB2_LIB.BASEBOARD_FAB2(SCH_1):GND
 202    GND VSS<21> @BASEBOARD_FAB2_LIB.BASEBOARD_FAB2(SCH_1):GND
 239    GND VSS<20> @BASEBOARD_FAB2_LIB.BASEBOARD_FAB2(SCH_1):GND
 241    GND VSS<19> @BASEBOARD_FAB2_LIB.BASEBOARD_FAB2(SCH_1):GND
 243    GND VSS<18> @BASEBOARD_FAB2_LIB.BASEBOARD_FAB2(SCH_1):GND
 246    GND VSS<17> @BASEBOARD_FAB2_LIB.BASEBOARD_FAB2(SCH_1):GND
 248    GND VSS<16> @BASEBOARD_FAB2_LIB.BASEBOARD_FAB2(SCH_1):GND
 250    GND VSS<15> @BASEBOARD_FAB2_LIB.BASEBOARD_FAB2(SCH_1):GND
 252    GND VSS<14> @BASEBOARD_FAB2_LIB.BASEBOARD_FAB2(SCH_1):GND
 254    GND VSS<13> @BASEBOARD_FAB2_LIB.BASEBOARD_FAB2(SCH_1):GND
 257    GND VSS<12> @BASEBOARD_FAB2_LIB.BASEBOARD_FAB2(SCH_1):GND
 259    GND VSS<11> @BASEBOARD_FAB2_LIB.BASEBOARD_FAB2(SCH_1):GND
 261    GND VSS<10> @BASEBOARD_FAB2_LIB.BASEBOARD_FAB2(SCH_1):GND
 263    GND VSS<9> @BASEBOARD_FAB2_LIB.BASEBOARD_FAB2(SCH_1):GND
 265    GND VSS<8> @BASEBOARD_FAB2_LIB.BASEBOARD_FAB2(SCH_1):GND
 268    GND VSS<7> @BASEBOARD_FAB2_LIB.BASEBOARD_FAB2(SCH_1):GND
 270    GND VSS<6> @BASEBOARD_FAB2_LIB.BASEBOARD_FAB2(SCH_1):GND
 272    GND VSS<5> @BASEBOARD_FAB2_LIB.BASEBOARD_FAB2(SCH_1):GND
 274    GND VSS<4> @BASEBOARD_FAB2_LIB.BASEBOARD_FAB2(SCH_1):GND
 276    GND VSS<3> @BASEBOARD_FAB2_LIB.BASEBOARD_FAB2(SCH_1):GND
 279    GND VSS<2> @BASEBOARD_FAB2_LIB.BASEBOARD_FAB2(SCH_1):GND
 281    GND VSS<1> @BASEBOARD_FAB2_LIB.BASEBOARD_FAB2(SCH_1):GND
 283    GND VSS<0> @BASEBOARD_FAB2_LIB.BASEBOARD_FAB2(SCH_1):GND

SCONN288_H44441003_PIP-SCONN,HA  I66  J6L1
 152 M_F_DQS_DN<0>  DQS0N @BASEBOARD_FAB2_LIB.BASEBOARD_FAB2(SCH_1):M_F_DQS_DN(0)
 153 M_F_DQS_DP<0>  DQS0P @BASEBOARD_FAB2_LIB.BASEBOARD_FAB2(SCH_1):M_F_DQS_DP(0)
  19 M_F_DQS_DN<10> DQS10N @BASEBOARD_FAB2_LIB.BASEBOARD_FAB2(SCH_1):M_F_DQS_DN(10)
  18 M_F_DQS_DP<10> DQS10P @BASEBOARD_FAB2_LIB.BASEBOARD_FAB2(SCH_1):M_F_DQS_DP(10)
  30 M_F_DQS_DN<11> DQS11N @BASEBOARD_FAB2_LIB.BASEBOARD_FAB2(SCH_1):M_F_DQS_DN(11)
  29 M_F_DQS_DP<11> DQS11P @BASEBOARD_FAB2_LIB.BASEBOARD_FAB2(SCH_1):M_F_DQS_DP(11)
  41 M_F_DQS_DN<12> DQS12N @BASEBOARD_FAB2_LIB.BASEBOARD_FAB2(SCH_1):M_F_DQS_DN(12)
  40 M_F_DQS_DP<12> DQS12P @BASEBOARD_FAB2_LIB.BASEBOARD_FAB2(SCH_1):M_F_DQS_DP(12)
 100 M_F_DQS_DN<13> DQS13N @BASEBOARD_FAB2_LIB.BASEBOARD_FAB2(SCH_1):M_F_DQS_DN(13)
  99 M_F_DQS_DP<13> DQS13P @BASEBOARD_FAB2_LIB.BASEBOARD_FAB2(SCH_1):M_F_DQS_DP(13)
 111 M_F_DQS_DN<14> DQS14N @BASEBOARD_FAB2_LIB.BASEBOARD_FAB2(SCH_1):M_F_DQS_DN(14)
 110 M_F_DQS_DP<14> DQS14P @BASEBOARD_FAB2_LIB.BASEBOARD_FAB2(SCH_1):M_F_DQS_DP(14)
 122 M_F_DQS_DN<15> DQS15N @BASEBOARD_FAB2_LIB.BASEBOARD_FAB2(SCH_1):M_F_DQS_DN(15)
 121 M_F_DQS_DP<15> DQS15P @BASEBOARD_FAB2_LIB.BASEBOARD_FAB2(SCH_1):M_F_DQS_DP(15)
 133 M_F_DQS_DN<16> DQS16N @BASEBOARD_FAB2_LIB.BASEBOARD_FAB2(SCH_1):M_F_DQS_DN(16)
 132 M_F_DQS_DP<16> DQS16P @BASEBOARD_FAB2_LIB.BASEBOARD_FAB2(SCH_1):M_F_DQS_DP(16)
  52 M_F_DQS_DN<17> DQS17N @BASEBOARD_FAB2_LIB.BASEBOARD_FAB2(SCH_1):M_F_DQS_DN(17)
  51 M_F_DQS_DP<17> DQS17P @BASEBOARD_FAB2_LIB.BASEBOARD_FAB2(SCH_1):M_F_DQS_DP(17)
 163 M_F_DQS_DN<1>  DQS1N @BASEBOARD_FAB2_LIB.BASEBOARD_FAB2(SCH_1):M_F_DQS_DN(1)
 164 M_F_DQS_DP<1>  DQS1P @BASEBOARD_FAB2_LIB.BASEBOARD_FAB2(SCH_1):M_F_DQS_DP(1)
 174 M_F_DQS_DN<2>  DQS2N @BASEBOARD_FAB2_LIB.BASEBOARD_FAB2(SCH_1):M_F_DQS_DN(2)
 175 M_F_DQS_DP<2>  DQS2P @BASEBOARD_FAB2_LIB.BASEBOARD_FAB2(SCH_1):M_F_DQS_DP(2)
 185 M_F_DQS_DN<3>  DQS3N @BASEBOARD_FAB2_LIB.BASEBOARD_FAB2(SCH_1):M_F_DQS_DN(3)
 186 M_F_DQS_DP<3>  DQS3P @BASEBOARD_FAB2_LIB.BASEBOARD_FAB2(SCH_1):M_F_DQS_DP(3)
 244 M_F_DQS_DN<4>  DQS4N @BASEBOARD_FAB2_LIB.BASEBOARD_FAB2(SCH_1):M_F_DQS_DN(4)
 245 M_F_DQS_DP<4>  DQS4P @BASEBOARD_FAB2_LIB.BASEBOARD_FAB2(SCH_1):M_F_DQS_DP(4)
 255 M_F_DQS_DN<5>  DQS5N @BASEBOARD_FAB2_LIB.BASEBOARD_FAB2(SCH_1):M_F_DQS_DN(5)
 256 M_F_DQS_DP<5>  DQS5P @BASEBOARD_FAB2_LIB.BASEBOARD_FAB2(SCH_1):M_F_DQS_DP(5)
 266 M_F_DQS_DN<6>  DQS6N @BASEBOARD_FAB2_LIB.BASEBOARD_FAB2(SCH_1):M_F_DQS_DN(6)
 267 M_F_DQS_DP<6>  DQS6P @BASEBOARD_FAB2_LIB.BASEBOARD_FAB2(SCH_1):M_F_DQS_DP(6)
 277 M_F_DQS_DN<7>  DQS7N @BASEBOARD_FAB2_LIB.BASEBOARD_FAB2(SCH_1):M_F_DQS_DN(7)
 278 M_F_DQS_DP<7>  DQS7P @BASEBOARD_FAB2_LIB.BASEBOARD_FAB2(SCH_1):M_F_DQS_DP(7)
 196 M_F_DQS_DN<8>  DQS8N @BASEBOARD_FAB2_LIB.BASEBOARD_FAB2(SCH_1):M_F_DQS_DN(8)
 197 M_F_DQS_DP<8>  DQS8P @BASEBOARD_FAB2_LIB.BASEBOARD_FAB2(SCH_1):M_F_DQS_DP(8)
   8 M_F_DQS_DN<9>  DQS9N @BASEBOARD_FAB2_LIB.BASEBOARD_FAB2(SCH_1):M_F_DQS_DN(9)
   7 M_F_DQS_DP<9>  DQS9P @BASEBOARD_FAB2_LIB.BASEBOARD_FAB2(SCH_1):M_F_DQS_DP(9)

SCONN288_H44441003_PIP-SCONN,HA  I111  J6L1
  79 M_F_MA<0>     A0 @BASEBOARD_FAB2_LIB.BASEBOARD_FAB2(SCH_1):M_F_MA(0)
  72 M_F_MA<1>     A1 @BASEBOARD_FAB2_LIB.BASEBOARD_FAB2(SCH_1):M_F_MA(1)
 225 M_F_MA<10>    A10 @BASEBOARD_FAB2_LIB.BASEBOARD_FAB2(SCH_1):M_F_MA(10)
 210 M_F_MA<11>    A11 @BASEBOARD_FAB2_LIB.BASEBOARD_FAB2(SCH_1):M_F_MA(11)
  65 M_F_MA<12>    A12 @BASEBOARD_FAB2_LIB.BASEBOARD_FAB2(SCH_1):M_F_MA(12)
 232 M_F_MA<13>    A13 @BASEBOARD_FAB2_LIB.BASEBOARD_FAB2(SCH_1):M_F_MA(13)
 228 M_F_MA<14> A14_WE_N @BASEBOARD_FAB2_LIB.BASEBOARD_FAB2(SCH_1):M_F_MA(14)
  86 M_F_MA<15> A15_CAS_N @BASEBOARD_FAB2_LIB.BASEBOARD_FAB2(SCH_1):M_F_MA(15)
  82 M_F_MA<16> A16_RAS_N @BASEBOARD_FAB2_LIB.BASEBOARD_FAB2(SCH_1):M_F_MA(16)
 234 M_F_MA<17>    A17 @BASEBOARD_FAB2_LIB.BASEBOARD_FAB2(SCH_1):M_F_MA(17)
 216 M_F_MA<2>     A2 @BASEBOARD_FAB2_LIB.BASEBOARD_FAB2(SCH_1):M_F_MA(2)
  71 M_F_MA<3>     A3 @BASEBOARD_FAB2_LIB.BASEBOARD_FAB2(SCH_1):M_F_MA(3)
 214 M_F_MA<4>     A4 @BASEBOARD_FAB2_LIB.BASEBOARD_FAB2(SCH_1):M_F_MA(4)
 213 M_F_MA<5>     A5 @BASEBOARD_FAB2_LIB.BASEBOARD_FAB2(SCH_1):M_F_MA(5)
  69 M_F_MA<6>     A6 @BASEBOARD_FAB2_LIB.BASEBOARD_FAB2(SCH_1):M_F_MA(6)
 211 M_F_MA<7>     A7 @BASEBOARD_FAB2_LIB.BASEBOARD_FAB2(SCH_1):M_F_MA(7)
  68 M_F_MA<8>     A8 @BASEBOARD_FAB2_LIB.BASEBOARD_FAB2(SCH_1):M_F_MA(8)
  66 M_F_MA<9>     A9 @BASEBOARD_FAB2_LIB.BASEBOARD_FAB2(SCH_1):M_F_MA(9)
  62 M_F_ACT_N  ACT_N @BASEBOARD_FAB2_LIB.BASEBOARD_FAB2(SCH_1):M_F_ACT_N
 208 M_F_ALERT_N ALERT_N @BASEBOARD_FAB2_LIB.BASEBOARD_FAB2(SCH_1):M_F_ALERT_N
 224 M_F_BA<1>  BA<1> @BASEBOARD_FAB2_LIB.BASEBOARD_FAB2(SCH_1):M_F_BA(1)
  81 M_F_BA<0>  BA<0> @BASEBOARD_FAB2_LIB.BASEBOARD_FAB2(SCH_1):M_F_BA(0)
 207 M_F_BG<1>  BG<1> @BASEBOARD_FAB2_LIB.BASEBOARD_FAB2(SCH_1):M_F_BG(1)
  63 M_F_BG<0>  BG<0> @BASEBOARD_FAB2_LIB.BASEBOARD_FAB2(SCH_1):M_F_BG(0)
 235 M_F_C<2>   C<2> @BASEBOARD_FAB2_LIB.BASEBOARD_FAB2(SCH_1):M_F_C(2)
 199 M_F_ECC<7>  CB<7> @BASEBOARD_FAB2_LIB.BASEBOARD_FAB2(SCH_1):M_F_ECC(7)
  54 M_F_ECC<6>  CB<6> @BASEBOARD_FAB2_LIB.BASEBOARD_FAB2(SCH_1):M_F_ECC(6)
 192 M_F_ECC<5>  CB<5> @BASEBOARD_FAB2_LIB.BASEBOARD_FAB2(SCH_1):M_F_ECC(5)
  47 M_F_ECC<4>  CB<4> @BASEBOARD_FAB2_LIB.BASEBOARD_FAB2(SCH_1):M_F_ECC(4)
 201 M_F_ECC<3>  CB<3> @BASEBOARD_FAB2_LIB.BASEBOARD_FAB2(SCH_1):M_F_ECC(3)
  56 M_F_ECC<2>  CB<2> @BASEBOARD_FAB2_LIB.BASEBOARD_FAB2(SCH_1):M_F_ECC(2)
 194 M_F_ECC<1>  CB<1> @BASEBOARD_FAB2_LIB.BASEBOARD_FAB2(SCH_1):M_F_ECC(1)
  49 M_F_ECC<0>  CB<0> @BASEBOARD_FAB2_LIB.BASEBOARD_FAB2(SCH_1):M_F_ECC(0)
  75 M_F_CLK_DN<2>   CK0N @BASEBOARD_FAB2_LIB.BASEBOARD_FAB2(SCH_1):M_F_CLK_DN(2)
  74 M_F_CLK_DP<2>   CK0P @BASEBOARD_FAB2_LIB.BASEBOARD_FAB2(SCH_1):M_F_CLK_DP(2)
 219 M_F_CLK_DN<3>   CK1N @BASEBOARD_FAB2_LIB.BASEBOARD_FAB2(SCH_1):M_F_CLK_DN(3)
 218 M_F_CLK_DP<3>   CK1P @BASEBOARD_FAB2_LIB.BASEBOARD_FAB2(SCH_1):M_F_CLK_DP(3)
 203 M_F_CKE<3> CKE<1> @BASEBOARD_FAB2_LIB.BASEBOARD_FAB2(SCH_1):M_F_CKE(3)
  60 M_F_CKE<2> CKE<0> @BASEBOARD_FAB2_LIB.BASEBOARD_FAB2(SCH_1):M_F_CKE(2)
 280 M_F_DQ<63> DQ<63> @BASEBOARD_FAB2_LIB.BASEBOARD_FAB2(SCH_1):M_F_DQ(63)
 135 M_F_DQ<62> DQ<62> @BASEBOARD_FAB2_LIB.BASEBOARD_FAB2(SCH_1):M_F_DQ(62)
 273 M_F_DQ<61> DQ<61> @BASEBOARD_FAB2_LIB.BASEBOARD_FAB2(SCH_1):M_F_DQ(61)
 128 M_F_DQ<60> DQ<60> @BASEBOARD_FAB2_LIB.BASEBOARD_FAB2(SCH_1):M_F_DQ(60)
 282 M_F_DQ<59> DQ<59> @BASEBOARD_FAB2_LIB.BASEBOARD_FAB2(SCH_1):M_F_DQ(59)
 137 M_F_DQ<58> DQ<58> @BASEBOARD_FAB2_LIB.BASEBOARD_FAB2(SCH_1):M_F_DQ(58)
 275 M_F_DQ<57> DQ<57> @BASEBOARD_FAB2_LIB.BASEBOARD_FAB2(SCH_1):M_F_DQ(57)
 130 M_F_DQ<56> DQ<56> @BASEBOARD_FAB2_LIB.BASEBOARD_FAB2(SCH_1):M_F_DQ(56)
 269 M_F_DQ<55> DQ<55> @BASEBOARD_FAB2_LIB.BASEBOARD_FAB2(SCH_1):M_F_DQ(55)
 124 M_F_DQ<54> DQ<54> @BASEBOARD_FAB2_LIB.BASEBOARD_FAB2(SCH_1):M_F_DQ(54)
 262 M_F_DQ<53> DQ<53> @BASEBOARD_FAB2_LIB.BASEBOARD_FAB2(SCH_1):M_F_DQ(53)
 117 M_F_DQ<52> DQ<52> @BASEBOARD_FAB2_LIB.BASEBOARD_FAB2(SCH_1):M_F_DQ(52)
 271 M_F_DQ<51> DQ<51> @BASEBOARD_FAB2_LIB.BASEBOARD_FAB2(SCH_1):M_F_DQ(51)
 126 M_F_DQ<50> DQ<50> @BASEBOARD_FAB2_LIB.BASEBOARD_FAB2(SCH_1):M_F_DQ(50)
 264 M_F_DQ<49> DQ<49> @BASEBOARD_FAB2_LIB.BASEBOARD_FAB2(SCH_1):M_F_DQ(49)
 119 M_F_DQ<48> DQ<48> @BASEBOARD_FAB2_LIB.BASEBOARD_FAB2(SCH_1):M_F_DQ(48)
 258 M_F_DQ<47> DQ<47> @BASEBOARD_FAB2_LIB.BASEBOARD_FAB2(SCH_1):M_F_DQ(47)
 113 M_F_DQ<46> DQ<46> @BASEBOARD_FAB2_LIB.BASEBOARD_FAB2(SCH_1):M_F_DQ(46)
 251 M_F_DQ<45> DQ<45> @BASEBOARD_FAB2_LIB.BASEBOARD_FAB2(SCH_1):M_F_DQ(45)
 106 M_F_DQ<44> DQ<44> @BASEBOARD_FAB2_LIB.BASEBOARD_FAB2(SCH_1):M_F_DQ(44)
 260 M_F_DQ<43> DQ<43> @BASEBOARD_FAB2_LIB.BASEBOARD_FAB2(SCH_1):M_F_DQ(43)
 115 M_F_DQ<42> DQ<42> @BASEBOARD_FAB2_LIB.BASEBOARD_FAB2(SCH_1):M_F_DQ(42)
 253 M_F_DQ<41> DQ<41> @BASEBOARD_FAB2_LIB.BASEBOARD_FAB2(SCH_1):M_F_DQ(41)
 108 M_F_DQ<40> DQ<40> @BASEBOARD_FAB2_LIB.BASEBOARD_FAB2(SCH_1):M_F_DQ(40)
 247 M_F_DQ<39> DQ<39> @BASEBOARD_FAB2_LIB.BASEBOARD_FAB2(SCH_1):M_F_DQ(39)
 102 M_F_DQ<38> DQ<38> @BASEBOARD_FAB2_LIB.BASEBOARD_FAB2(SCH_1):M_F_DQ(38)
 240 M_F_DQ<37> DQ<37> @BASEBOARD_FAB2_LIB.BASEBOARD_FAB2(SCH_1):M_F_DQ(37)
  95 M_F_DQ<36> DQ<36> @BASEBOARD_FAB2_LIB.BASEBOARD_FAB2(SCH_1):M_F_DQ(36)
 249 M_F_DQ<35> DQ<35> @BASEBOARD_FAB2_LIB.BASEBOARD_FAB2(SCH_1):M_F_DQ(35)
 104 M_F_DQ<34> DQ<34> @BASEBOARD_FAB2_LIB.BASEBOARD_FAB2(SCH_1):M_F_DQ(34)
 242 M_F_DQ<33> DQ<33> @BASEBOARD_FAB2_LIB.BASEBOARD_FAB2(SCH_1):M_F_DQ(33)
  97 M_F_DQ<32> DQ<32> @BASEBOARD_FAB2_LIB.BASEBOARD_FAB2(SCH_1):M_F_DQ(32)
 188 M_F_DQ<31> DQ<31> @BASEBOARD_FAB2_LIB.BASEBOARD_FAB2(SCH_1):M_F_DQ(31)
  43 M_F_DQ<30> DQ<30> @BASEBOARD_FAB2_LIB.BASEBOARD_FAB2(SCH_1):M_F_DQ(30)
 181 M_F_DQ<29> DQ<29> @BASEBOARD_FAB2_LIB.BASEBOARD_FAB2(SCH_1):M_F_DQ(29)
  36 M_F_DQ<28> DQ<28> @BASEBOARD_FAB2_LIB.BASEBOARD_FAB2(SCH_1):M_F_DQ(28)
 190 M_F_DQ<27> DQ<27> @BASEBOARD_FAB2_LIB.BASEBOARD_FAB2(SCH_1):M_F_DQ(27)
  45 M_F_DQ<26> DQ<26> @BASEBOARD_FAB2_LIB.BASEBOARD_FAB2(SCH_1):M_F_DQ(26)
 183 M_F_DQ<25> DQ<25> @BASEBOARD_FAB2_LIB.BASEBOARD_FAB2(SCH_1):M_F_DQ(25)
  38 M_F_DQ<24> DQ<24> @BASEBOARD_FAB2_LIB.BASEBOARD_FAB2(SCH_1):M_F_DQ(24)
 177 M_F_DQ<23> DQ<23> @BASEBOARD_FAB2_LIB.BASEBOARD_FAB2(SCH_1):M_F_DQ(23)
  32 M_F_DQ<22> DQ<22> @BASEBOARD_FAB2_LIB.BASEBOARD_FAB2(SCH_1):M_F_DQ(22)
 170 M_F_DQ<21> DQ<21> @BASEBOARD_FAB2_LIB.BASEBOARD_FAB2(SCH_1):M_F_DQ(21)
  25 M_F_DQ<20> DQ<20> @BASEBOARD_FAB2_LIB.BASEBOARD_FAB2(SCH_1):M_F_DQ(20)
 179 M_F_DQ<19> DQ<19> @BASEBOARD_FAB2_LIB.BASEBOARD_FAB2(SCH_1):M_F_DQ(19)
  34 M_F_DQ<18> DQ<18> @BASEBOARD_FAB2_LIB.BASEBOARD_FAB2(SCH_1):M_F_DQ(18)
 172 M_F_DQ<17> DQ<17> @BASEBOARD_FAB2_LIB.BASEBOARD_FAB2(SCH_1):M_F_DQ(17)
  27 M_F_DQ<16> DQ<16> @BASEBOARD_FAB2_LIB.BASEBOARD_FAB2(SCH_1):M_F_DQ(16)
 166 M_F_DQ<15> DQ<15> @BASEBOARD_FAB2_LIB.BASEBOARD_FAB2(SCH_1):M_F_DQ(15)
  21 M_F_DQ<14> DQ<14> @BASEBOARD_FAB2_LIB.BASEBOARD_FAB2(SCH_1):M_F_DQ(14)
 159 M_F_DQ<13> DQ<13> @BASEBOARD_FAB2_LIB.BASEBOARD_FAB2(SCH_1):M_F_DQ(13)
  14 M_F_DQ<12> DQ<12> @BASEBOARD_FAB2_LIB.BASEBOARD_FAB2(SCH_1):M_F_DQ(12)
 168 M_F_DQ<11> DQ<11> @BASEBOARD_FAB2_LIB.BASEBOARD_FAB2(SCH_1):M_F_DQ(11)
  23 M_F_DQ<10> DQ<10> @BASEBOARD_FAB2_LIB.BASEBOARD_FAB2(SCH_1):M_F_DQ(10)
 161 M_F_DQ<9>  DQ<9> @BASEBOARD_FAB2_LIB.BASEBOARD_FAB2(SCH_1):M_F_DQ(9)
  16 M_F_DQ<8>  DQ<8> @BASEBOARD_FAB2_LIB.BASEBOARD_FAB2(SCH_1):M_F_DQ(8)
 155 M_F_DQ<7>  DQ<7> @BASEBOARD_FAB2_LIB.BASEBOARD_FAB2(SCH_1):M_F_DQ(7)
  10 M_F_DQ<6>  DQ<6> @BASEBOARD_FAB2_LIB.BASEBOARD_FAB2(SCH_1):M_F_DQ(6)
 148 M_F_DQ<5>  DQ<5> @BASEBOARD_FAB2_LIB.BASEBOARD_FAB2(SCH_1):M_F_DQ(5)
   3 M_F_DQ<4>  DQ<4> @BASEBOARD_FAB2_LIB.BASEBOARD_FAB2(SCH_1):M_F_DQ(4)
 157 M_F_DQ<3>  DQ<3> @BASEBOARD_FAB2_LIB.BASEBOARD_FAB2(SCH_1):M_F_DQ(3)
  12 M_F_DQ<2>  DQ<2> @BASEBOARD_FAB2_LIB.BASEBOARD_FAB2(SCH_1):M_F_DQ(2)
 150 M_F_DQ<1>  DQ<1> @BASEBOARD_FAB2_LIB.BASEBOARD_FAB2(SCH_1):M_F_DQ(1)
   5 M_F_DQ<0>  DQ<0> @BASEBOARD_FAB2_LIB.BASEBOARD_FAB2(SCH_1):M_F_DQ(0)
  78 FM_DIMM_EVENT_COD_N EVENT_N @BASEBOARD_FAB2_LIB.BASEBOARD_FAB2(SCH_1):FM_DIMM_EVENT_COD_N
  91 M_F_ODT<3> ODT<1> @BASEBOARD_FAB2_LIB.BASEBOARD_FAB2(SCH_1):M_F_ODT(3)
  87 M_F_ODT<2> ODT<0> @BASEBOARD_FAB2_LIB.BASEBOARD_FAB2(SCH_1):M_F_ODT(2)
 222 M_F_PAR    PAR @BASEBOARD_FAB2_LIB.BASEBOARD_FAB2(SCH_1):M_F_PAR
  58 M_DEF_RST_N RESET_N @BASEBOARD_FAB2_LIB.BASEBOARD_FAB2(SCH_1):M_DEF_RST_N
 144 TP_CH_F_DIMM_F1_RFU_2 RFU<2> @BASEBOARD_FAB2_LIB.BASEBOARD_FAB2(SCH_1):TP_CH_F_DIMM_F1_RFU_2
 227 TP_CH_F_DIMM_F1_RFU_1 RFU<1> @BASEBOARD_FAB2_LIB.BASEBOARD_FAB2(SCH_1):TP_CH_F_DIMM_F1_RFU_1
 205 TP_CH_F_DIMM_F1_RFU_0 RFU<0> @BASEBOARD_FAB2_LIB.BASEBOARD_FAB2(SCH_1):TP_CH_F_DIMM_F1_RFU_0
  84 M_F_CS_N<4>   S0_N @BASEBOARD_FAB2_LIB.BASEBOARD_FAB2(SCH_1):M_F_CS_N(4)
  89 M_F_CS_N<5>   S1_N @BASEBOARD_FAB2_LIB.BASEBOARD_FAB2(SCH_1):M_F_CS_N(5)
  93 M_F_CS_N<6> S2_N_C<0> @BASEBOARD_FAB2_LIB.BASEBOARD_FAB2(SCH_1):M_F_CS_N(6)
 237 M_F_CS_N<7> S3_N_C<1> @BASEBOARD_FAB2_LIB.BASEBOARD_FAB2(SCH_1):M_F_CS_N(7)
 238 PVPP_DEF  SA<2> @BASEBOARD_FAB2_LIB.BASEBOARD_FAB2(SCH_1):PVPP_DEF
 140    GND  SA<1> @BASEBOARD_FAB2_LIB.BASEBOARD_FAB2(SCH_1):GND
 139 PVPP_DEF  SA<0> @BASEBOARD_FAB2_LIB.BASEBOARD_FAB2(SCH_1):PVPP_DEF
 230 FM_ADR_COMPLETE_DEF_N SAVE_N_NC @BASEBOARD_FAB2_LIB.BASEBOARD_FAB2(SCH_1):FM_ADR_COMPLETE_DEF_N
 141 SMB_DDR_DEF_VPP_SCL    SCL @BASEBOARD_FAB2_LIB.BASEBOARD_FAB2(SCH_1):SMB_DDR_DEF_VPP_SCL
 285 SMB_DDR_DEF_VPP_SDA    SDA @BASEBOARD_FAB2_LIB.BASEBOARD_FAB2(SCH_1):SMB_DDR_DEF_VPP_SDA
 284 PVPP_DEF VDDSPD @BASEBOARD_FAB2_LIB.BASEBOARD_FAB2(SCH_1):PVPP_DEF
 146 M_F_VREF VREFCA @BASEBOARD_FAB2_LIB.BASEBOARD_FAB2(SCH_1):M_F_VREF

SCONN288_H44441003_PIP-SCONN,HA  I170  J6L1
   1 P12V_NVDIMM_DEF 12V<1> @BASEBOARD_FAB2_LIB.BASEBOARD_FAB2(SCH_1):P12V_NVDIMM_DEF
 145 P12V_NVDIMM_DEF 12V<0> @BASEBOARD_FAB2_LIB.BASEBOARD_FAB2(SCH_1):P12V_NVDIMM_DEF
  59 PVDDQ_DEF VDD<25> @BASEBOARD_FAB2_LIB.BASEBOARD_FAB2(SCH_1):PVDDQ_DEF
  61 PVDDQ_DEF VDD<24> @BASEBOARD_FAB2_LIB.BASEBOARD_FAB2(SCH_1):PVDDQ_DEF
  64 PVDDQ_DEF VDD<23> @BASEBOARD_FAB2_LIB.BASEBOARD_FAB2(SCH_1):PVDDQ_DEF
  67 PVDDQ_DEF VDD<22> @BASEBOARD_FAB2_LIB.BASEBOARD_FAB2(SCH_1):PVDDQ_DEF
  70 PVDDQ_DEF VDD<21> @BASEBOARD_FAB2_LIB.BASEBOARD_FAB2(SCH_1):PVDDQ_DEF
  73 PVDDQ_DEF VDD<20> @BASEBOARD_FAB2_LIB.BASEBOARD_FAB2(SCH_1):PVDDQ_DEF
  76 PVDDQ_DEF VDD<19> @BASEBOARD_FAB2_LIB.BASEBOARD_FAB2(SCH_1):PVDDQ_DEF
  80 PVDDQ_DEF VDD<18> @BASEBOARD_FAB2_LIB.BASEBOARD_FAB2(SCH_1):PVDDQ_DEF
  83 PVDDQ_DEF VDD<17> @BASEBOARD_FAB2_LIB.BASEBOARD_FAB2(SCH_1):PVDDQ_DEF
  85 PVDDQ_DEF VDD<16> @BASEBOARD_FAB2_LIB.BASEBOARD_FAB2(SCH_1):PVDDQ_DEF
  88 PVDDQ_DEF VDD<15> @BASEBOARD_FAB2_LIB.BASEBOARD_FAB2(SCH_1):PVDDQ_DEF
  90 PVDDQ_DEF VDD<14> @BASEBOARD_FAB2_LIB.BASEBOARD_FAB2(SCH_1):PVDDQ_DEF
  92 PVDDQ_DEF VDD<13> @BASEBOARD_FAB2_LIB.BASEBOARD_FAB2(SCH_1):PVDDQ_DEF
 204 PVDDQ_DEF VDD<12> @BASEBOARD_FAB2_LIB.BASEBOARD_FAB2(SCH_1):PVDDQ_DEF
 206 PVDDQ_DEF VDD<11> @BASEBOARD_FAB2_LIB.BASEBOARD_FAB2(SCH_1):PVDDQ_DEF
 209 PVDDQ_DEF VDD<10> @BASEBOARD_FAB2_LIB.BASEBOARD_FAB2(SCH_1):PVDDQ_DEF
 212 PVDDQ_DEF VDD<9> @BASEBOARD_FAB2_LIB.BASEBOARD_FAB2(SCH_1):PVDDQ_DEF
 215 PVDDQ_DEF VDD<8> @BASEBOARD_FAB2_LIB.BASEBOARD_FAB2(SCH_1):PVDDQ_DEF
 217 PVDDQ_DEF VDD<7> @BASEBOARD_FAB2_LIB.BASEBOARD_FAB2(SCH_1):PVDDQ_DEF
 220 PVDDQ_DEF VDD<6> @BASEBOARD_FAB2_LIB.BASEBOARD_FAB2(SCH_1):PVDDQ_DEF
 223 PVDDQ_DEF VDD<5> @BASEBOARD_FAB2_LIB.BASEBOARD_FAB2(SCH_1):PVDDQ_DEF
 226 PVDDQ_DEF VDD<4> @BASEBOARD_FAB2_LIB.BASEBOARD_FAB2(SCH_1):PVDDQ_DEF
 229 PVDDQ_DEF VDD<3> @BASEBOARD_FAB2_LIB.BASEBOARD_FAB2(SCH_1):PVDDQ_DEF
 231 PVDDQ_DEF VDD<2> @BASEBOARD_FAB2_LIB.BASEBOARD_FAB2(SCH_1):PVDDQ_DEF
 233 PVDDQ_DEF VDD<1> @BASEBOARD_FAB2_LIB.BASEBOARD_FAB2(SCH_1):PVDDQ_DEF
 236 PVDDQ_DEF VDD<0> @BASEBOARD_FAB2_LIB.BASEBOARD_FAB2(SCH_1):PVDDQ_DEF
 142 PVPP_DEF VPP<4> @BASEBOARD_FAB2_LIB.BASEBOARD_FAB2(SCH_1):PVPP_DEF
 143 PVPP_DEF VPP<3> @BASEBOARD_FAB2_LIB.BASEBOARD_FAB2(SCH_1):PVPP_DEF
 288 PVPP_DEF VPP<2> @BASEBOARD_FAB2_LIB.BASEBOARD_FAB2(SCH_1):PVPP_DEF
 286 PVPP_DEF VPP<1> @BASEBOARD_FAB2_LIB.BASEBOARD_FAB2(SCH_1):PVPP_DEF
 287 PVPP_DEF VPP<0> @BASEBOARD_FAB2_LIB.BASEBOARD_FAB2(SCH_1):PVPP_DEF
  77 PVTT_DEF VTT<1> @BASEBOARD_FAB2_LIB.BASEBOARD_FAB2(SCH_1):PVTT_DEF
 221 PVTT_DEF VTT<0> @BASEBOARD_FAB2_LIB.BASEBOARD_FAB2(SCH_1):PVTT_DEF

CAP_A_0402V-0.01UF,25V,10%,X7RA  I179  C4A5
   1 M_F_VREF      A @BASEBOARD_FAB2_LIB.BASEBOARD_FAB2(SCH_1):M_F_VREF
   2    GND      B @BASEBOARD_FAB2_LIB.BASEBOARD_FAB2(SCH_1):GND


DRAWING: @BASEBOARD_FAB2_LIB.BASEBOARD_FAB2(SCH_1):PAGE55 

RES_0402-49.9,1%,1/16W,CHIP,G2A  I4  R9N1
   1 PVCCIO_CPU1      A @BASEBOARD_FAB2_LIB.BASEBOARD_FAB2(SCH_1):PVCCIO_CPU1
   2 SVID_ALERT1_CPU1_R_N      B @BASEBOARD_FAB2_LIB.BASEBOARD_FAB2(SCH_1):SVID_ALERT1_CPU1_R_N

RES_0402-100.0,1%,1/16W,CHIP,GA  I7  R9N2
   1 PVCCIO_CPU1      A @BASEBOARD_FAB2_LIB.BASEBOARD_FAB2(SCH_1):PVCCIO_CPU1
   2 SVID_DIO1_CPU1_R      B @BASEBOARD_FAB2_LIB.BASEBOARD_FAB2(SCH_1):SVID_DIO1_CPU1_R

RES_0402-49.9,1%,1/16W,CHIP,G2A  I19  R3B2
   1 SVID_ALERT0_CPU1_R_N      A @BASEBOARD_FAB2_LIB.BASEBOARD_FAB2(SCH_1):SVID_ALERT0_CPU1_R_N
   2 PVCCIO_CPU1      B @BASEBOARD_FAB2_LIB.BASEBOARD_FAB2(SCH_1):PVCCIO_CPU1

RES_0402-100.0,1%,1/16W,CHIP,GA  I21  R3B4
   1 SVID_DIO0_CPU1_R      A @BASEBOARD_FAB2_LIB.BASEBOARD_FAB2(SCH_1):SVID_DIO0_CPU1_R
   2 PVCCIO_CPU1      B @BASEBOARD_FAB2_LIB.BASEBOARD_FAB2(SCH_1):PVCCIO_CPU1

RES_0402-0.0,5%,1/16W,CHIP,G21A  I24  R1C2
   1 SVID_DIO1_CPU1      A @BASEBOARD_FAB2_LIB.BASEBOARD_FAB2(SCH_1):SVID_DIO1_CPU1
   2 SVID_DIO1_CPU1_R      B @BASEBOARD_FAB2_LIB.BASEBOARD_FAB2(SCH_1):SVID_DIO1_CPU1_R

RES_0402-0.0,5%,1/16W,CHIP,G21A  I25  R1C3
   1 SVID_CLK1_CPU1      A @BASEBOARD_FAB2_LIB.BASEBOARD_FAB2(SCH_1):SVID_CLK1_CPU1
   2 SVID_CLK1_CPU1_R      B @BASEBOARD_FAB2_LIB.BASEBOARD_FAB2(SCH_1):SVID_CLK1_CPU1_R

RES_0402-221,1.0%,1/16W,CHIP,GA  I26  R1C1
   1 SVID_ALERT1_CPU1_N      A @BASEBOARD_FAB2_LIB.BASEBOARD_FAB2(SCH_1):SVID_ALERT1_CPU1_N
   2 SVID_ALERT1_CPU1_R_N      B @BASEBOARD_FAB2_LIB.BASEBOARD_FAB2(SCH_1):SVID_ALERT1_CPU1_R_N

RES_0402-221,1.0%,1/16W,CHIP,GA  I27  R3B1
   1 SVID_ALERT0_CPU1_N      A @BASEBOARD_FAB2_LIB.BASEBOARD_FAB2(SCH_1):SVID_ALERT0_CPU1_N
   2 SVID_ALERT0_CPU1_R_N      B @BASEBOARD_FAB2_LIB.BASEBOARD_FAB2(SCH_1):SVID_ALERT0_CPU1_R_N

RES_0402-0.0,5%,1/16W,CHIP,G21A  I28  R3B5
   1 SVID_CLK0_CPU1      A @BASEBOARD_FAB2_LIB.BASEBOARD_FAB2(SCH_1):SVID_CLK0_CPU1
   2 SVID_CLK0_CPU1_R      B @BASEBOARD_FAB2_LIB.BASEBOARD_FAB2(SCH_1):SVID_CLK0_CPU1_R

RES_0402-0.0,5%,1/16W,CHIP,G21A  I29  R3B3
   1 SVID_DIO0_CPU1      A @BASEBOARD_FAB2_LIB.BASEBOARD_FAB2(SCH_1):SVID_DIO0_CPU1
   2 SVID_DIO0_CPU1_R      B @BASEBOARD_FAB2_LIB.BASEBOARD_FAB2(SCH_1):SVID_DIO0_CPU1_R

RES_0402-100.0,1%,1/16W,CHIP,GA  I115  R7P19
   1 A_CPU1_GHJ_RCOMP2      A @BASEBOARD_FAB2_LIB.BASEBOARD_FAB2(SCH_1):A_CPU1_GHJ_RCOMP2
   2    GND      B @BASEBOARD_FAB2_LIB.BASEBOARD_FAB2(SCH_1):GND

RES_0402-90.9,1%,1/16W,CHIP,G2A  I116  R3D1
   1 A_CPU1_KLM_RCOMP0      A @BASEBOARD_FAB2_LIB.BASEBOARD_FAB2(SCH_1):A_CPU1_KLM_RCOMP0
   2    GND      B @BASEBOARD_FAB2_LIB.BASEBOARD_FAB2(SCH_1):GND

RES_0402-90.9,1%,1/16W,CHIP,G2A  I117  R3D2
   1 A_CPU1_KLM_RCOMP1      A @BASEBOARD_FAB2_LIB.BASEBOARD_FAB2(SCH_1):A_CPU1_KLM_RCOMP1
   2    GND      B @BASEBOARD_FAB2_LIB.BASEBOARD_FAB2(SCH_1):GND

RES_0402-100.0,1%,1/16W,CHIP,GA  I118  R3D3
   1 A_CPU1_KLM_RCOMP2      A @BASEBOARD_FAB2_LIB.BASEBOARD_FAB2(SCH_1):A_CPU1_KLM_RCOMP2
   2    GND      B @BASEBOARD_FAB2_LIB.BASEBOARD_FAB2(SCH_1):GND

RES_0402-90.9,1%,1/16W,CHIP,G2A  I119  R7P16
   1 A_CPU1_GHJ_RCOMP0      A @BASEBOARD_FAB2_LIB.BASEBOARD_FAB2(SCH_1):A_CPU1_GHJ_RCOMP0
   2    GND      B @BASEBOARD_FAB2_LIB.BASEBOARD_FAB2(SCH_1):GND

RES_0402-49.9,1%,1/16W,CHIP,G2A  I123  R7P8
   1 A_CPU1_PE3_RBIAS      A @BASEBOARD_FAB2_LIB.BASEBOARD_FAB2(SCH_1):A_CPU1_PE3_RBIAS
   2    GND      B @BASEBOARD_FAB2_LIB.BASEBOARD_FAB2(SCH_1):GND

RES_0402-49.9,1%,1/16W,CHIP,G2A  I124  R7P10
   1 A_CPU1_PE012_RBIAS      A @BASEBOARD_FAB2_LIB.BASEBOARD_FAB2(SCH_1):A_CPU1_PE012_RBIAS
   2    GND      B @BASEBOARD_FAB2_LIB.BASEBOARD_FAB2(SCH_1):GND

RES_0402-49.9,1%,1/16W,CHIP,G2A  I125  R3D19
   1 A_CPU1_UPI01_RBIAS      A @BASEBOARD_FAB2_LIB.BASEBOARD_FAB2(SCH_1):A_CPU1_UPI01_RBIAS
   2    GND      B @BASEBOARD_FAB2_LIB.BASEBOARD_FAB2(SCH_1):GND

RES_0402-49.9,1%,1/16W,CHIP,G2A  I126  R7P11
   1 A_CPU1_UPI2_RBIAS      A @BASEBOARD_FAB2_LIB.BASEBOARD_FAB2(SCH_1):A_CPU1_UPI2_RBIAS
   2    GND      B @BASEBOARD_FAB2_LIB.BASEBOARD_FAB2(SCH_1):GND

RES_0402-90.9,1%,1/16W,CHIP,G2A  I140  R7P17
   1 A_CPU1_GHJ_RCOMP1      A @BASEBOARD_FAB2_LIB.BASEBOARD_FAB2(SCH_1):A_CPU1_GHJ_RCOMP1
   2    GND      B @BASEBOARD_FAB2_LIB.BASEBOARD_FAB2(SCH_1):GND

SOCKET_P_MECH_A_RIGHT-P0,PLASTA  I152  XRU2
SOCKET_P_MECH_A_LEFT-P0,PLASTIA  I153  XLU2
RES_0402-49.9,1%,1/16W,CHIP,G2A  I155  R3D4
   1 A_CPU1_MCP01_RBIAS      A @BASEBOARD_FAB2_LIB.BASEBOARD_FAB2(SCH_1):A_CPU1_MCP01_RBIAS
   2    GND      B @BASEBOARD_FAB2_LIB.BASEBOARD_FAB2(SCH_1):GND

RES_0402-49.9,1%,1/16W,CHIP,G2A  I156  R7P26
   1 H_PMSYNC_CLK_24M_CPU1      A @BASEBOARD_FAB2_LIB.BASEBOARD_FAB2(SCH_1):H_PMSYNC_CLK_24M_CPU1
   2 H_PMSYNC_CLK_24M      B @BASEBOARD_FAB2_LIB.BASEBOARD_FAB2(SCH_1):H_PMSYNC_CLK_24M

RES_0402-1.8K,1%,1/16W,CHIP,G2A  I157  R8N1
   1 P3V3_STBY      A @BASEBOARD_FAB2_LIB.BASEBOARD_FAB2(SCH_1):P3V3_STBY
   2 FM_CPU1_PROC_ID1      B @BASEBOARD_FAB2_LIB.BASEBOARD_FAB2(SCH_1):FM_CPU1_PROC_ID1

RES_0402-1.8K,1%,1/16W,CHIP,G2A  I158  R8N4
   1 P3V3_STBY      A @BASEBOARD_FAB2_LIB.BASEBOARD_FAB2(SCH_1):P3V3_STBY
   2 FM_CPU1_PROC_ID0      B @BASEBOARD_FAB2_LIB.BASEBOARD_FAB2(SCH_1):FM_CPU1_PROC_ID0

RES_0402-10.0K,1%,1/16W,CHIP,GA  I159  R8N3
   1 P3V3_STBY      A @BASEBOARD_FAB2_LIB.BASEBOARD_FAB2(SCH_1):P3V3_STBY
   2 FM_CPU1_PKGID2      B @BASEBOARD_FAB2_LIB.BASEBOARD_FAB2(SCH_1):FM_CPU1_PKGID2

RES_0402-10.0K,1%,1/16W,CHIP,GA  I160  R8N5
   1 P3V3_STBY      A @BASEBOARD_FAB2_LIB.BASEBOARD_FAB2(SCH_1):P3V3_STBY
   2 FM_CPU1_PKGID1      B @BASEBOARD_FAB2_LIB.BASEBOARD_FAB2(SCH_1):FM_CPU1_PKGID1

RES_0402-10.0K,1%,1/16W,CHIP,GA  I161  R8N2
   1 P3V3_STBY      A @BASEBOARD_FAB2_LIB.BASEBOARD_FAB2(SCH_1):P3V3_STBY
   2 FM_CPU1_PKGID0      B @BASEBOARD_FAB2_LIB.BASEBOARD_FAB2(SCH_1):FM_CPU1_PKGID0

RES_0402-49.9,1%,1/16W,CHIP,G2A  I170  R7P25
   1 H_PM_SYNC_GTL_R2      A @BASEBOARD_FAB2_LIB.BASEBOARD_FAB2(SCH_1):H_PM_SYNC_GTL_R2
   2 H_PM_SYNC_GTL      B @BASEBOARD_FAB2_LIB.BASEBOARD_FAB2(SCH_1):H_PM_SYNC_GTL

SKX_EXT_B_BGA1-IC,TBD  I172  U2D1
AU24 CLK_100M_CPU1_BCLK0_DN BCLK0_DN @BASEBOARD_FAB2_LIB.BASEBOARD_FAB2(SCH_1):CLK_100M_CPU1_BCLK0_DN
AW24 CLK_100M_CPU1_BCLK0_DP BCLK0_DP @BASEBOARD_FAB2_LIB.BASEBOARD_FAB2(SCH_1):CLK_100M_CPU1_BCLK0_DP
CR26 CLK_100M_CPU1_BCLK1_DN BCLK1_DN @BASEBOARD_FAB2_LIB.BASEBOARD_FAB2(SCH_1):CLK_100M_CPU1_BCLK1_DN
CP27 CLK_100M_CPU1_BCLK1_DP BCLK1_DP @BASEBOARD_FAB2_LIB.BASEBOARD_FAB2(SCH_1):CLK_100M_CPU1_BCLK1_DP
CT25 CLK_100M_CPU1_BCLK2_DN BCLK2_DN @BASEBOARD_FAB2_LIB.BASEBOARD_FAB2(SCH_1):CLK_100M_CPU1_BCLK2_DN
CU26 CLK_100M_CPU1_BCLK2_DP BCLK2_DP @BASEBOARD_FAB2_LIB.BASEBOARD_FAB2(SCH_1):CLK_100M_CPU1_BCLK2_DP
BA20 PD_CPU1_BIST_ENABLE BIST_ENABLE @BASEBOARD_FAB2_LIB.BASEBOARD_FAB2(SCH_1):PD_CPU1_BIST_ENABLE
BD23 H_CPU1_BMCINIT BMCINIT @BASEBOARD_FAB2_LIB.BASEBOARD_FAB2(SCH_1):H_CPU1_BMCINIT
AC12 XDP_CPU_OBSFN_B1_MBP7_N BPM_N<7> @BASEBOARD_FAB2_LIB.BASEBOARD_FAB2(SCH_1):XDP_CPU_OBSFN_B1_MBP7_N
AE12 XDP_CPU_OBSFN_B0_MBP6_N BPM_N<6> @BASEBOARD_FAB2_LIB.BASEBOARD_FAB2(SCH_1):XDP_CPU_OBSFN_B0_MBP6_N
 Y11 TP_XDP_CPU1_OBSDATA_B3_MBP5_N BPM_N<5> @BASEBOARD_FAB2_LIB.BASEBOARD_FAB2(SCH_1):TP_XDP_CPU1_OBSDATA_B3_MBP5_N
AA12 TP_XDP_CPU1_OBSDATA_B2_MBP4_N BPM_N<4> @BASEBOARD_FAB2_LIB.BASEBOARD_FAB2(SCH_1):TP_XDP_CPU1_OBSDATA_B2_MBP4_N
AF11 TP_XDP_CPU1_OBSDATA_B1_MBP3_N BPM_N<3> @BASEBOARD_FAB2_LIB.BASEBOARD_FAB2(SCH_1):TP_XDP_CPU1_OBSDATA_B1_MBP3_N
AG10 TP_XDP_CPU1_OBSDATA_B0_MBP2_N BPM_N<2> @BASEBOARD_FAB2_LIB.BASEBOARD_FAB2(SCH_1):TP_XDP_CPU1_OBSDATA_B0_MBP2_N
AH11 XDP_CPU_MBP1_N BPM_N<1> @BASEBOARD_FAB2_LIB.BASEBOARD_FAB2(SCH_1):XDP_CPU_MBP1_N
AJ10 XDP_CPU_MBP0_N BPM_N<0> @BASEBOARD_FAB2_LIB.BASEBOARD_FAB2(SCH_1):XDP_CPU_MBP0_N
AL14 H_CPU1_CATERR_G_N CATERR_N @BASEBOARD_FAB2_LIB.BASEBOARD_FAB2(SCH_1):H_CPU1_CATERR_G_N
AN30 PWRGD_CPU1_DRAMPWROK_GHJ_G DDR012_DRAM_PWR_OK @BASEBOARD_FAB2_LIB.BASEBOARD_FAB2(SCH_1):PWRGD_CPU1_DRAMPWROK_GHJ_G
AC42 A_CPU1_GHJ_RCOMP2 DDR012_RCOMP<2> @BASEBOARD_FAB2_LIB.BASEBOARD_FAB2(SCH_1):A_CPU1_GHJ_RCOMP2
AB43 A_CPU1_GHJ_RCOMP1 DDR012_RCOMP<1> @BASEBOARD_FAB2_LIB.BASEBOARD_FAB2(SCH_1):A_CPU1_GHJ_RCOMP1
 Y43 A_CPU1_GHJ_RCOMP0 DDR012_RCOMP<0> @BASEBOARD_FAB2_LIB.BASEBOARD_FAB2(SCH_1):A_CPU1_GHJ_RCOMP0
 U64 M_GHJ_RST_N DDR012_RESET_N @BASEBOARD_FAB2_LIB.BASEBOARD_FAB2(SCH_1):M_GHJ_RST_N
AJ18 SMB_DDR_GHJ_SCL_G_R DDR012_SPDSCL @BASEBOARD_FAB2_LIB.BASEBOARD_FAB2(SCH_1):SMB_DDR_GHJ_SCL_G_R
AF17 SMB_DDR_GHJ_SDA_G_R DDR012_SPDSDA @BASEBOARD_FAB2_LIB.BASEBOARD_FAB2(SCH_1):SMB_DDR_GHJ_SDA_G_R
AJ64 M_G_CPU_VREF DDR0_CAVREF @BASEBOARD_FAB2_LIB.BASEBOARD_FAB2(SCH_1):M_G_CPU_VREF
AK63 M_H_CPU_VREF DDR1_CAVREF @BASEBOARD_FAB2_LIB.BASEBOARD_FAB2(SCH_1):M_H_CPU_VREF
AH63 M_J_CPU_VREF DDR2_CAVREF @BASEBOARD_FAB2_LIB.BASEBOARD_FAB2(SCH_1):M_J_CPU_VREF
CR28 PWRGD_CPU1_DRAMPWROK_KLM_G DDR345_DRAM_PWR_OK @BASEBOARD_FAB2_LIB.BASEBOARD_FAB2(SCH_1):PWRGD_CPU1_DRAMPWROK_KLM_G
DD49 A_CPU1_KLM_RCOMP2 DDR345_RCOMP<2> @BASEBOARD_FAB2_LIB.BASEBOARD_FAB2(SCH_1):A_CPU1_KLM_RCOMP2
DD47 A_CPU1_KLM_RCOMP1 DDR345_RCOMP<1> @BASEBOARD_FAB2_LIB.BASEBOARD_FAB2(SCH_1):A_CPU1_KLM_RCOMP1
DC48 A_CPU1_KLM_RCOMP0 DDR345_RCOMP<0> @BASEBOARD_FAB2_LIB.BASEBOARD_FAB2(SCH_1):A_CPU1_KLM_RCOMP0
DV63 M_KLM_RST_N DDR345_RESET_N @BASEBOARD_FAB2_LIB.BASEBOARD_FAB2(SCH_1):M_KLM_RST_N
AE18 SMB_DDR_KLM_SCL_G_R DDR345_SPDSCL @BASEBOARD_FAB2_LIB.BASEBOARD_FAB2(SCH_1):SMB_DDR_KLM_SCL_G_R
AD17 SMB_DDR_KLM_SDA_G_R DDR345_SPDSDA @BASEBOARD_FAB2_LIB.BASEBOARD_FAB2(SCH_1):SMB_DDR_KLM_SDA_G_R
CP61 M_K_CPU_VREF DDR3_CAVREF @BASEBOARD_FAB2_LIB.BASEBOARD_FAB2(SCH_1):M_K_CPU_VREF
CT61 M_L_CPU_VREF DDR4_CAVREF @BASEBOARD_FAB2_LIB.BASEBOARD_FAB2(SCH_1):M_L_CPU_VREF
CV61 M_M_CPU_VREF DDR5_CAVREF @BASEBOARD_FAB2_LIB.BASEBOARD_FAB2(SCH_1):M_M_CPU_VREF
AJ14 PU_CPU1_EAR_N  EAR_N @BASEBOARD_FAB2_LIB.BASEBOARD_FAB2(SCH_1):PU_CPU1_EAR_N
AL12 H_CPU1_ERR2_G_N ERROR_N<2> @BASEBOARD_FAB2_LIB.BASEBOARD_FAB2(SCH_1):H_CPU1_ERR2_G_N
AK11 H_CPU1_ERR1_G_N ERROR_N<1> @BASEBOARD_FAB2_LIB.BASEBOARD_FAB2(SCH_1):H_CPU1_ERR1_G_N
AJ12 H_CPU1_ERR0_G_N ERROR_N<0> @BASEBOARD_FAB2_LIB.BASEBOARD_FAB2(SCH_1):H_CPU1_ERR0_G_N
AV17 PU_CPU1_FRMAGENT FRMAGENT @BASEBOARD_FAB2_LIB.BASEBOARD_FAB2(SCH_1):PU_CPU1_FRMAGENT
AE20 PU_CPU1_LEGACY_SKT LEGACY_SKT @BASEBOARD_FAB2_LIB.BASEBOARD_FAB2(SCH_1):PU_CPU1_LEGACY_SKT
CT31 A_CPU1_MCP01_RBIAS MCP01_RBIAS<1> @BASEBOARD_FAB2_LIB.BASEBOARD_FAB2(SCH_1):A_CPU1_MCP01_RBIAS
CU32 A_CPU1_MCP01_RBIAS MCP01_RBIAS<0> @BASEBOARD_FAB2_LIB.BASEBOARD_FAB2(SCH_1):A_CPU1_MCP01_RBIAS
AH13 H_CPU1_MEMGHJ_MEMHOT_G_N MEM_HOT_C012_N @BASEBOARD_FAB2_LIB.BASEBOARD_FAB2(SCH_1):H_CPU1_MEMGHJ_MEMHOT_G_N
AF13 H_CPU1_MEMKLM_MEMHOT_G_N MEM_HOT_C345_N @BASEBOARD_FAB2_LIB.BASEBOARD_FAB2(SCH_1):H_CPU1_MEMKLM_MEMHOT_G_N
AN20 H_CPU1_MSMI_G_N MSMI_N @BASEBOARD_FAB2_LIB.BASEBOARD_FAB2(SCH_1):H_CPU1_MSMI_G_N
AP11 TP_CPU1_NMI    NMI @BASEBOARD_FAB2_LIB.BASEBOARD_FAB2(SCH_1):TP_CPU1_NMI
CL30 A_CPU1_PE012_RBIAS PE012_RBIAS<1> @BASEBOARD_FAB2_LIB.BASEBOARD_FAB2(SCH_1):A_CPU1_PE012_RBIAS
CN30 A_CPU1_PE012_RBIAS PE012_RBIAS<0> @BASEBOARD_FAB2_LIB.BASEBOARD_FAB2(SCH_1):A_CPU1_PE012_RBIAS
CR30 A_CPU1_PE3_RBIAS PE3_RBIAS<1> @BASEBOARD_FAB2_LIB.BASEBOARD_FAB2(SCH_1):A_CPU1_PE3_RBIAS
CP29 A_CPU1_PE3_RBIAS PE3_RBIAS<0> @BASEBOARD_FAB2_LIB.BASEBOARD_FAB2(SCH_1):A_CPU1_PE3_RBIAS
AU12 PECI_CPU_G   PECI @BASEBOARD_FAB2_LIB.BASEBOARD_FAB2(SCH_1):PECI_CPU_G
AM19 SMB_CPU1_PE_HP_GTL_SCL PE_HP_SCL @BASEBOARD_FAB2_LIB.BASEBOARD_FAB2(SCH_1):SMB_CPU1_PE_HP_GTL_SCL
AL18 SMB_CPU1_PE_HP_GTL_SDA PE_HP_SDA @BASEBOARD_FAB2_LIB.BASEBOARD_FAB2(SCH_1):SMB_CPU1_PE_HP_GTL_SDA
CW56 PD_PIROM_CPU1_ADDR2 PIROM_ADDR<2> @BASEBOARD_FAB2_LIB.BASEBOARD_FAB2(SCH_1):PD_PIROM_CPU1_ADDR2
CV57 PD_PIROM_CPU1_ADDR1 PIROM_ADDR<1> @BASEBOARD_FAB2_LIB.BASEBOARD_FAB2(SCH_1):PD_PIROM_CPU1_ADDR1
CU58 PU_PIROM_CPU1_ADDR0 PIROM_ADDR<0> @BASEBOARD_FAB2_LIB.BASEBOARD_FAB2(SCH_1):PU_PIROM_CPU1_ADDR0
DA72 FM_CPU1_PKGID2 PKGID<2> @BASEBOARD_FAB2_LIB.BASEBOARD_FAB2(SCH_1):FM_CPU1_PKGID2
CW72 FM_CPU1_PKGID1 PKGID<1> @BASEBOARD_FAB2_LIB.BASEBOARD_FAB2(SCH_1):FM_CPU1_PKGID1
DC72 FM_CPU1_PKGID0 PKGID<0> @BASEBOARD_FAB2_LIB.BASEBOARD_FAB2(SCH_1):FM_CPU1_PKGID0
AR14 H_PM_SYNC_GTL_R2 PMSYNC @BASEBOARD_FAB2_LIB.BASEBOARD_FAB2(SCH_1):H_PM_SYNC_GTL_R2
AT19 H_PMSYNC_CLK_24M_CPU1 PMSYNC_CLK @BASEBOARD_FAB2_LIB.BASEBOARD_FAB2(SCH_1):H_PMSYNC_CLK_24M_CPU1
AF15 H_CPU1_FAST_WAKE_N PM_FAST_WAKE_N @BASEBOARD_FAB2_LIB.BASEBOARD_FAB2(SCH_1):H_CPU1_FAST_WAKE_N
AG16 XDP_CPU_PRDY_N PRDY_N @BASEBOARD_FAB2_LIB.BASEBOARD_FAB2(SCH_1):XDP_CPU_PRDY_N
AR12 XDP_CPU_PREQ_N PREQ_N @BASEBOARD_FAB2_LIB.BASEBOARD_FAB2(SCH_1):XDP_CPU_PREQ_N
AB17 TP_CPU1_PROC_DIS_G_N PROCDIS_N @BASEBOARD_FAB2_LIB.BASEBOARD_FAB2(SCH_1):TP_CPU1_PROC_DIS_G_N
AC16 H_CPU1_PROCHOT_G_N PROCHOT_N @BASEBOARD_FAB2_LIB.BASEBOARD_FAB2(SCH_1):H_CPU1_PROCHOT_G_N
DB71 FM_CPU1_PROC_ID1 PROC_ID<1> @BASEBOARD_FAB2_LIB.BASEBOARD_FAB2(SCH_1):FM_CPU1_PROC_ID1
CY71 FM_CPU1_PROC_ID0 PROC_ID<0> @BASEBOARD_FAB2_LIB.BASEBOARD_FAB2(SCH_1):FM_CPU1_PROC_ID0
BC24 PWRGD_CPU1_G PWRGOOD @BASEBOARD_FAB2_LIB.BASEBOARD_FAB2(SCH_1):PWRGD_CPU1_G
AP21 RST_CPU1_G_N RESET_N @BASEBOARD_FAB2_LIB.BASEBOARD_FAB2(SCH_1):RST_CPU1_G_N
AR18 PU_CPU1_SAFE_MODE_BOOT SAFE_MODE_BOOT @BASEBOARD_FAB2_LIB.BASEBOARD_FAB2(SCH_1):PU_CPU1_SAFE_MODE_BOOT
AB13 FM_CPU1_SKTOCC_LVT3_N SKTOCC_N @BASEBOARD_FAB2_LIB.BASEBOARD_FAB2(SCH_1):FM_CPU1_SKTOCC_LVT3_N
CT59 SMB_PIROM_CPU1_SCL SMBCLK @BASEBOARD_FAB2_LIB.BASEBOARD_FAB2(SCH_1):SMB_PIROM_CPU1_SCL
CW58 SMB_PIROM_CPU1_SDA SMBDAT @BASEBOARD_FAB2_LIB.BASEBOARD_FAB2(SCH_1):SMB_PIROM_CPU1_SDA
CV59 FM_CPU1_SM_WP  SM_WP @BASEBOARD_FAB2_LIB.BASEBOARD_FAB2(SCH_1):FM_CPU1_SM_WP
AU20 TP_CPU1_SOCKET_ID_2 SOCKET_ID<2> @BASEBOARD_FAB2_LIB.BASEBOARD_FAB2(SCH_1):TP_CPU1_SOCKET_ID_2
AU16 PU_CPU1_SOCKET_ID_1 SOCKET_ID<1> @BASEBOARD_FAB2_LIB.BASEBOARD_FAB2(SCH_1):PU_CPU1_SOCKET_ID_1
AU22 PU_CPU1_SOCKET_ID_0 SOCKET_ID<0> @BASEBOARD_FAB2_LIB.BASEBOARD_FAB2(SCH_1):PU_CPU1_SOCKET_ID_0
DL44 SVID_ALERT1_CPU1_N SVIDALERT_N<1> @BASEBOARD_FAB2_LIB.BASEBOARD_FAB2(SCH_1):SVID_ALERT1_CPU1_N
DE44 SVID_ALERT0_CPU1_N SVIDALERT_N<0> @BASEBOARD_FAB2_LIB.BASEBOARD_FAB2(SCH_1):SVID_ALERT0_CPU1_N
DG44 SVID_CLK1_CPU1 SVIDCLK<1> @BASEBOARD_FAB2_LIB.BASEBOARD_FAB2(SCH_1):SVID_CLK1_CPU1
DC44 SVID_CLK0_CPU1 SVIDCLK<0> @BASEBOARD_FAB2_LIB.BASEBOARD_FAB2(SCH_1):SVID_CLK0_CPU1
DJ44 SVID_DIO1_CPU1 SVIDDATA<1> @BASEBOARD_FAB2_LIB.BASEBOARD_FAB2(SCH_1):SVID_DIO1_CPU1
DB45 SVID_DIO0_CPU1 SVIDDATA<0> @BASEBOARD_FAB2_LIB.BASEBOARD_FAB2(SCH_1):SVID_DIO0_CPU1
AA14 XDP_CPU_TCK0    TCK @BASEBOARD_FAB2_LIB.BASEBOARD_FAB2(SCH_1):XDP_CPU_TCK0
AC14 XDP_CPU1_TDI    TDI @BASEBOARD_FAB2_LIB.BASEBOARD_FAB2(SCH_1):XDP_CPU1_TDI
AE14 XDP_CPU1_TDO    TDO @BASEBOARD_FAB2_LIB.BASEBOARD_FAB2(SCH_1):XDP_CPU1_TDO
AY19 PD_CPU1_TEST12 TEST_12 @BASEBOARD_FAB2_LIB.BASEBOARD_FAB2(SCH_1):PD_CPU1_TEST12
DB51 PD_CPU1_TEST13 TEST_13 @BASEBOARD_FAB2_LIB.BASEBOARD_FAB2(SCH_1):PD_CPU1_TEST13
DC50 PD_CPU1_TEST14 TEST_14 @BASEBOARD_FAB2_LIB.BASEBOARD_FAB2(SCH_1):PD_CPU1_TEST14
AW14 PD_CPU1_KSFC_DIS TEST_15 @BASEBOARD_FAB2_LIB.BASEBOARD_FAB2(SCH_1):PD_CPU1_KSFC_DIS
AB15 H_CPU1_THERMTRIP_G_N THERMTRIP_N @BASEBOARD_FAB2_LIB.BASEBOARD_FAB2(SCH_1):H_CPU1_THERMTRIP_G_N
 W14 XDP_CPU_TMS    TMS @BASEBOARD_FAB2_LIB.BASEBOARD_FAB2(SCH_1):XDP_CPU_TMS
 Y13 XDP_CPU_TRST_N TRST_N @BASEBOARD_FAB2_LIB.BASEBOARD_FAB2(SCH_1):XDP_CPU_TRST_N
AM11 PU_CPU1_TSC_SYNC TSC_SYNC @BASEBOARD_FAB2_LIB.BASEBOARD_FAB2(SCH_1):PU_CPU1_TSC_SYNC
AW18 PU_CPU1_TXT_AGENT TXT_AGENT @BASEBOARD_FAB2_LIB.BASEBOARD_FAB2(SCH_1):PU_CPU1_TXT_AGENT
AV15 PD_CPU1_TXT_PLTEN TXT_PLTEN @BASEBOARD_FAB2_LIB.BASEBOARD_FAB2(SCH_1):PD_CPU1_TXT_PLTEN
AP29 A_CPU1_UPI01_RBIAS UPI01_RBIAS<1> @BASEBOARD_FAB2_LIB.BASEBOARD_FAB2(SCH_1):A_CPU1_UPI01_RBIAS
AT29 A_CPU1_UPI01_RBIAS UPI01_RBIAS<0> @BASEBOARD_FAB2_LIB.BASEBOARD_FAB2(SCH_1):A_CPU1_UPI01_RBIAS
CK29 A_CPU1_UPI2_RBIAS UPI2_RBIAS<1> @BASEBOARD_FAB2_LIB.BASEBOARD_FAB2(SCH_1):A_CPU1_UPI2_RBIAS
CL28 A_CPU1_UPI2_RBIAS UPI2_RBIAS<0> @BASEBOARD_FAB2_LIB.BASEBOARD_FAB2(SCH_1):A_CPU1_UPI2_RBIAS

RES_0402-4.75K,1%,1/16W,CHIP,GA  I181  R6P39
   1 P3V3_STBY      A @BASEBOARD_FAB2_LIB.BASEBOARD_FAB2(SCH_1):P3V3_STBY
   2 FM_CPU1_SKTOCC_LVT3_N      B @BASEBOARD_FAB2_LIB.BASEBOARD_FAB2(SCH_1):FM_CPU1_SKTOCC_LVT3_N


DRAWING: @BASEBOARD_FAB2_LIB.BASEBOARD_FAB2(SCH_1):PAGE56 

SKX_EXT_B_BGA1-IC,TBD  I169  U2D1
AV21 XDP_PRESENT_N DEBUG_EN_N @BASEBOARD_FAB2_LIB.BASEBOARD_FAB2(SCH_1):XDP_PRESENT_N
AW12 PD_CPU1_DMIMODE_OVERRIDE DMIMODE_OVERRIDE @BASEBOARD_FAB2_LIB.BASEBOARD_FAB2(SCH_1):PD_CPU1_DMIMODE_OVERRIDE
AU14 H_CPU1_FIVR_FAULT_G FIVR_FAULT @BASEBOARD_FAB2_LIB.BASEBOARD_FAB2(SCH_1):H_CPU1_FIVR_FAULT_G
AP17 XDP_CPU_PWR_DEBUG_N PWR_DEBUG_N @BASEBOARD_FAB2_LIB.BASEBOARD_FAB2(SCH_1):XDP_CPU_PWR_DEBUG_N
  A4 TP_CPU1_RSVD_304 RSVD<304> @BASEBOARD_FAB2_LIB.BASEBOARD_FAB2(SCH_1):TP_CPU1_RSVD_304
  A6 TP_CPU1_RSVD_303 RSVD<303> @BASEBOARD_FAB2_LIB.BASEBOARD_FAB2(SCH_1):TP_CPU1_RSVD_303
 A14 P1V8_MCP_CPU1 RSVD<302> @BASEBOARD_FAB2_LIB.BASEBOARD_FAB2(SCH_1):P1V8_MCP_CPU1
 A16 P1V8_MCP_CPU1 RSVD<301> @BASEBOARD_FAB2_LIB.BASEBOARD_FAB2(SCH_1):P1V8_MCP_CPU1
 A24 TP_CPU1_RSVD_300 RSVD<300> @BASEBOARD_FAB2_LIB.BASEBOARD_FAB2(SCH_1):TP_CPU1_RSVD_300
  B3 TP_CPU1_RSVD_299 RSVD<299> @BASEBOARD_FAB2_LIB.BASEBOARD_FAB2(SCH_1):TP_CPU1_RSVD_299
  B7 TP_CPU1_RSVD_298 RSVD<298> @BASEBOARD_FAB2_LIB.BASEBOARD_FAB2(SCH_1):TP_CPU1_RSVD_298
 B13 P1V8_MCP_CPU1 RSVD<296> @BASEBOARD_FAB2_LIB.BASEBOARD_FAB2(SCH_1):P1V8_MCP_CPU1
 B15 P1V8_MCP_CPU1 RSVD<295> @BASEBOARD_FAB2_LIB.BASEBOARD_FAB2(SCH_1):P1V8_MCP_CPU1
 B17 P1V8_MCP_CPU1 RSVD<294> @BASEBOARD_FAB2_LIB.BASEBOARD_FAB2(SCH_1):P1V8_MCP_CPU1
 B77 TP_CPU1_RSVD_293 RSVD<293> @BASEBOARD_FAB2_LIB.BASEBOARD_FAB2(SCH_1):TP_CPU1_RSVD_293
 B81 TP_CPU1_RSVD_292 RSVD<292> @BASEBOARD_FAB2_LIB.BASEBOARD_FAB2(SCH_1):TP_CPU1_RSVD_292
  C6 TP_CPU1_RSVD_291 RSVD<291> @BASEBOARD_FAB2_LIB.BASEBOARD_FAB2(SCH_1):TP_CPU1_RSVD_291
 C18 TP_CPU1_RSVD_290 RSVD<290> @BASEBOARD_FAB2_LIB.BASEBOARD_FAB2(SCH_1):TP_CPU1_RSVD_290
 C24 TP_CPU1_RSVD_289 RSVD<289> @BASEBOARD_FAB2_LIB.BASEBOARD_FAB2(SCH_1):TP_CPU1_RSVD_289
 C82 TP_CPU1_RSVD_288 RSVD<288> @BASEBOARD_FAB2_LIB.BASEBOARD_FAB2(SCH_1):TP_CPU1_RSVD_288
  D5 TP_CPU1_RSVD_287 RSVD<287> @BASEBOARD_FAB2_LIB.BASEBOARD_FAB2(SCH_1):TP_CPU1_RSVD_287
 D17 TP_CPU1_RSVD_286 RSVD<286> @BASEBOARD_FAB2_LIB.BASEBOARD_FAB2(SCH_1):TP_CPU1_RSVD_286
 D65 TP_CPU1_RSVD_285 RSVD<285> @BASEBOARD_FAB2_LIB.BASEBOARD_FAB2(SCH_1):TP_CPU1_RSVD_285
 D83 TP_CPU1_RSVD_284 RSVD<284> @BASEBOARD_FAB2_LIB.BASEBOARD_FAB2(SCH_1):TP_CPU1_RSVD_284
  E2 TP_CPU1_RSVD_283 RSVD<283> @BASEBOARD_FAB2_LIB.BASEBOARD_FAB2(SCH_1):TP_CPU1_RSVD_283
  E4 TP_CPU1_RSVD_282 RSVD<282> @BASEBOARD_FAB2_LIB.BASEBOARD_FAB2(SCH_1):TP_CPU1_RSVD_282
 E24 TP_CPU1_RSVD_281 RSVD<281> @BASEBOARD_FAB2_LIB.BASEBOARD_FAB2(SCH_1):TP_CPU1_RSVD_281
 E84 TP_CPU1_RSVD_280 RSVD<280> @BASEBOARD_FAB2_LIB.BASEBOARD_FAB2(SCH_1):TP_CPU1_RSVD_280
  F3 TP_CPU1_RSVD_279 RSVD<279> @BASEBOARD_FAB2_LIB.BASEBOARD_FAB2(SCH_1):TP_CPU1_RSVD_279
 F23 TP_CPU1_RSVD_278 RSVD<278> @BASEBOARD_FAB2_LIB.BASEBOARD_FAB2(SCH_1):TP_CPU1_RSVD_278
 F65 TP_CPU1_RSVD_277 RSVD<277> @BASEBOARD_FAB2_LIB.BASEBOARD_FAB2(SCH_1):TP_CPU1_RSVD_277
 F83 TP_CPU1_RSVD_276 RSVD<276> @BASEBOARD_FAB2_LIB.BASEBOARD_FAB2(SCH_1):TP_CPU1_RSVD_276
  G2 TP_CPU1_RSVD_275 RSVD<275> @BASEBOARD_FAB2_LIB.BASEBOARD_FAB2(SCH_1):TP_CPU1_RSVD_275
 G64 TP_CPU1_RSVD_274 RSVD<274> @BASEBOARD_FAB2_LIB.BASEBOARD_FAB2(SCH_1):TP_CPU1_RSVD_274
 G84 TP_CPU1_RSVD_273 RSVD<273> @BASEBOARD_FAB2_LIB.BASEBOARD_FAB2(SCH_1):TP_CPU1_RSVD_273
  H1 TP_CPU1_RSVD_272 RSVD<272> @BASEBOARD_FAB2_LIB.BASEBOARD_FAB2(SCH_1):TP_CPU1_RSVD_272
 H83 TP_CPU1_RSVD_271 RSVD<271> @BASEBOARD_FAB2_LIB.BASEBOARD_FAB2(SCH_1):TP_CPU1_RSVD_271
 H85 TP_CPU1_RSVD_270 RSVD<270> @BASEBOARD_FAB2_LIB.BASEBOARD_FAB2(SCH_1):TP_CPU1_RSVD_270
 J46 TP_CPU1_RSVD_269 RSVD<269> @BASEBOARD_FAB2_LIB.BASEBOARD_FAB2(SCH_1):TP_CPU1_RSVD_269
 J62 TP_CPU1_RSVD_268 RSVD<268> @BASEBOARD_FAB2_LIB.BASEBOARD_FAB2(SCH_1):TP_CPU1_RSVD_268
 K61 TP_CPU1_RSVD_267 RSVD<267> @BASEBOARD_FAB2_LIB.BASEBOARD_FAB2(SCH_1):TP_CPU1_RSVD_267
 M63 TP_CPU1_RSVD_266 RSVD<266> @BASEBOARD_FAB2_LIB.BASEBOARD_FAB2(SCH_1):TP_CPU1_RSVD_266
 P65 TP_CPU1_RSVD_265 RSVD<265> @BASEBOARD_FAB2_LIB.BASEBOARD_FAB2(SCH_1):TP_CPU1_RSVD_265
 R62 TP_CPU1_RSVD_264 RSVD<264> @BASEBOARD_FAB2_LIB.BASEBOARD_FAB2(SCH_1):TP_CPU1_RSVD_264
 R66 TP_CPU1_RSVD_263 RSVD<263> @BASEBOARD_FAB2_LIB.BASEBOARD_FAB2(SCH_1):TP_CPU1_RSVD_263
 T67 TP_CPU1_RSVD_262 RSVD<262> @BASEBOARD_FAB2_LIB.BASEBOARD_FAB2(SCH_1):TP_CPU1_RSVD_262
 U66 TP_CPU1_RSVD_261 RSVD<261> @BASEBOARD_FAB2_LIB.BASEBOARD_FAB2(SCH_1):TP_CPU1_RSVD_261
 V65 TP_CPU1_RSVD_260 RSVD<260> @BASEBOARD_FAB2_LIB.BASEBOARD_FAB2(SCH_1):TP_CPU1_RSVD_260
 V67 TP_CPU1_RSVD_259 RSVD<259> @BASEBOARD_FAB2_LIB.BASEBOARD_FAB2(SCH_1):TP_CPU1_RSVD_259
 W66 TP_CPU1_RSVD_258 RSVD<258> @BASEBOARD_FAB2_LIB.BASEBOARD_FAB2(SCH_1):TP_CPU1_RSVD_258
 Y23 FM_CPU1_RC_ERROR_N RSVD<257> @BASEBOARD_FAB2_LIB.BASEBOARD_FAB2(SCH_1):FM_CPU1_RC_ERROR_N
 Y65 TP_CPU1_RSVD_256 RSVD<256> @BASEBOARD_FAB2_LIB.BASEBOARD_FAB2(SCH_1):TP_CPU1_RSVD_256
AD47 TP_CPU1_RSVD_254 RSVD<254> @BASEBOARD_FAB2_LIB.BASEBOARD_FAB2(SCH_1):TP_CPU1_RSVD_254
AD49 TP_CPU1_RSVD_253 RSVD<253> @BASEBOARD_FAB2_LIB.BASEBOARD_FAB2(SCH_1):TP_CPU1_RSVD_253
AD51 TP_CPU1_RSVD_252 RSVD<252> @BASEBOARD_FAB2_LIB.BASEBOARD_FAB2(SCH_1):TP_CPU1_RSVD_252
AE46 TP_CPU1_RSVD_251 RSVD<251> @BASEBOARD_FAB2_LIB.BASEBOARD_FAB2(SCH_1):TP_CPU1_RSVD_251
AE48 TP_CPU1_RSVD_250 RSVD<250> @BASEBOARD_FAB2_LIB.BASEBOARD_FAB2(SCH_1):TP_CPU1_RSVD_250
AE50 TP_CPU1_RSVD_249 RSVD<249> @BASEBOARD_FAB2_LIB.BASEBOARD_FAB2(SCH_1):TP_CPU1_RSVD_249
AE52 TP_CPU1_RSVD_248 RSVD<248> @BASEBOARD_FAB2_LIB.BASEBOARD_FAB2(SCH_1):TP_CPU1_RSVD_248
AE72 TP_CPU1_RSVD_247 RSVD<247> @BASEBOARD_FAB2_LIB.BASEBOARD_FAB2(SCH_1):TP_CPU1_RSVD_247
AF19 TP_CPU1_RSVD_246 RSVD<246> @BASEBOARD_FAB2_LIB.BASEBOARD_FAB2(SCH_1):TP_CPU1_RSVD_246
AF47 TP_CPU1_RSVD_245 RSVD<245> @BASEBOARD_FAB2_LIB.BASEBOARD_FAB2(SCH_1):TP_CPU1_RSVD_245
AF49 TP_CPU1_RSVD_244 RSVD<244> @BASEBOARD_FAB2_LIB.BASEBOARD_FAB2(SCH_1):TP_CPU1_RSVD_244
AF51 TP_CPU1_RSVD_243 RSVD<243> @BASEBOARD_FAB2_LIB.BASEBOARD_FAB2(SCH_1):TP_CPU1_RSVD_243
AF53 TP_CPU1_RSVD_242 RSVD<242> @BASEBOARD_FAB2_LIB.BASEBOARD_FAB2(SCH_1):TP_CPU1_RSVD_242
AF71 TP_CPU1_RSVD_241 RSVD<241> @BASEBOARD_FAB2_LIB.BASEBOARD_FAB2(SCH_1):TP_CPU1_RSVD_241
AG20 TP_CPU1_RSVD_240 RSVD<240> @BASEBOARD_FAB2_LIB.BASEBOARD_FAB2(SCH_1):TP_CPU1_RSVD_240
AG48 TP_CPU1_RSVD_239 RSVD<239> @BASEBOARD_FAB2_LIB.BASEBOARD_FAB2(SCH_1):TP_CPU1_RSVD_239
AG50 TP_CPU1_RSVD_238 RSVD<238> @BASEBOARD_FAB2_LIB.BASEBOARD_FAB2(SCH_1):TP_CPU1_RSVD_238
AG52 TP_CPU1_RSVD_237 RSVD<237> @BASEBOARD_FAB2_LIB.BASEBOARD_FAB2(SCH_1):TP_CPU1_RSVD_237
AG54 TP_CPU1_RSVD_236 RSVD<236> @BASEBOARD_FAB2_LIB.BASEBOARD_FAB2(SCH_1):TP_CPU1_RSVD_236
AG56 TP_CPU1_RSVD_235 RSVD<235> @BASEBOARD_FAB2_LIB.BASEBOARD_FAB2(SCH_1):TP_CPU1_RSVD_235
AG72 TP_CPU1_RSVD_234 RSVD<234> @BASEBOARD_FAB2_LIB.BASEBOARD_FAB2(SCH_1):TP_CPU1_RSVD_234
AH15 TP_CPU1_RSVD_233 RSVD<233> @BASEBOARD_FAB2_LIB.BASEBOARD_FAB2(SCH_1):TP_CPU1_RSVD_233
AH19 TP_CPU1_RSVD_232 RSVD<232> @BASEBOARD_FAB2_LIB.BASEBOARD_FAB2(SCH_1):TP_CPU1_RSVD_232
AH55 TP_CPU1_RSVD_231 RSVD<231> @BASEBOARD_FAB2_LIB.BASEBOARD_FAB2(SCH_1):TP_CPU1_RSVD_231
AH57 TP_CPU1_RSVD_230 RSVD<230> @BASEBOARD_FAB2_LIB.BASEBOARD_FAB2(SCH_1):TP_CPU1_RSVD_230
AH71 TP_CPU1_RSVD_229 RSVD<229> @BASEBOARD_FAB2_LIB.BASEBOARD_FAB2(SCH_1):TP_CPU1_RSVD_229
AH73 TP_CPU1_RSVD_228 RSVD<228> @BASEBOARD_FAB2_LIB.BASEBOARD_FAB2(SCH_1):TP_CPU1_RSVD_228
AJ20 TP_CPU1_RSVD_227 RSVD<227> @BASEBOARD_FAB2_LIB.BASEBOARD_FAB2(SCH_1):TP_CPU1_RSVD_227
AJ56 TP_CPU1_RSVD_226 RSVD<226> @BASEBOARD_FAB2_LIB.BASEBOARD_FAB2(SCH_1):TP_CPU1_RSVD_226
AJ58 TP_CPU1_RSVD_225 RSVD<225> @BASEBOARD_FAB2_LIB.BASEBOARD_FAB2(SCH_1):TP_CPU1_RSVD_225
AJ60 TP_CPU1_RSVD_224 RSVD<224> @BASEBOARD_FAB2_LIB.BASEBOARD_FAB2(SCH_1):TP_CPU1_RSVD_224
AJ62 TP_CPU1_RSVD_223 RSVD<223> @BASEBOARD_FAB2_LIB.BASEBOARD_FAB2(SCH_1):TP_CPU1_RSVD_223
AJ70 TP_CPU1_RSVD_222 RSVD<222> @BASEBOARD_FAB2_LIB.BASEBOARD_FAB2(SCH_1):TP_CPU1_RSVD_222
AK21 VSENSE_P1V8MCP_CPU1_SKT_VSEN RSVD<221> @BASEBOARD_FAB2_LIB.BASEBOARD_FAB2(SCH_1):VSENSE_P1V8MCP_CPU1_SKT_VSEN
AK27 CLK_322M_OSC_CPU1_RC_DP RSVD<220> @BASEBOARD_FAB2_LIB.BASEBOARD_FAB2(SCH_1):CLK_322M_OSC_CPU1_RC_DP
AK57 TP_CPU1_RSVD_219 RSVD<219> @BASEBOARD_FAB2_LIB.BASEBOARD_FAB2(SCH_1):TP_CPU1_RSVD_219
AK59 TP_CPU1_RSVD_218 RSVD<218> @BASEBOARD_FAB2_LIB.BASEBOARD_FAB2(SCH_1):TP_CPU1_RSVD_218
AK61 TP_CPU1_RSVD_217 RSVD<217> @BASEBOARD_FAB2_LIB.BASEBOARD_FAB2(SCH_1):TP_CPU1_RSVD_217
AK69 TP_CPU1_RSVD_216 RSVD<216> @BASEBOARD_FAB2_LIB.BASEBOARD_FAB2(SCH_1):TP_CPU1_RSVD_216
AL20 VSENSE_P1V8MCP_CPU1_SKT_VRTN RSVD<215> @BASEBOARD_FAB2_LIB.BASEBOARD_FAB2(SCH_1):VSENSE_P1V8MCP_CPU1_SKT_VRTN
AL22 TP_CPU1_RSVD_214 RSVD<214> @BASEBOARD_FAB2_LIB.BASEBOARD_FAB2(SCH_1):TP_CPU1_RSVD_214
AL26 CLK_322M_OSC_CPU1_RC_DN RSVD<213> @BASEBOARD_FAB2_LIB.BASEBOARD_FAB2(SCH_1):CLK_322M_OSC_CPU1_RC_DN
AL58 TP_CPU1_RSVD_212 RSVD<212> @BASEBOARD_FAB2_LIB.BASEBOARD_FAB2(SCH_1):TP_CPU1_RSVD_212
AL60 TP_CPU1_RSVD_211 RSVD<211> @BASEBOARD_FAB2_LIB.BASEBOARD_FAB2(SCH_1):TP_CPU1_RSVD_211
AL62 TP_CPU1_RSVD_210 RSVD<210> @BASEBOARD_FAB2_LIB.BASEBOARD_FAB2(SCH_1):TP_CPU1_RSVD_210
AM21 PVCCMCP_CPU1 RSVD<209> @BASEBOARD_FAB2_LIB.BASEBOARD_FAB2(SCH_1):PVCCMCP_CPU1
AM23 TP_CPU1_RSVD_208 RSVD<208> @BASEBOARD_FAB2_LIB.BASEBOARD_FAB2(SCH_1):TP_CPU1_RSVD_208
AM25 PVCCMCP_CPU1 RSVD<207> @BASEBOARD_FAB2_LIB.BASEBOARD_FAB2(SCH_1):PVCCMCP_CPU1
AM27 CLK_100M_CPU1_RC_REFCLK0_DP RSVD<206> @BASEBOARD_FAB2_LIB.BASEBOARD_FAB2(SCH_1):CLK_100M_CPU1_RC_REFCLK0_DP
AM59 TP_CPU1_RSVD_205 RSVD<205> @BASEBOARD_FAB2_LIB.BASEBOARD_FAB2(SCH_1):TP_CPU1_RSVD_205
AM61 TP_CPU1_RSVD_204 RSVD<204> @BASEBOARD_FAB2_LIB.BASEBOARD_FAB2(SCH_1):TP_CPU1_RSVD_204
AN18 PVCCMCP_CPU1 RSVD<203> @BASEBOARD_FAB2_LIB.BASEBOARD_FAB2(SCH_1):PVCCMCP_CPU1
AN22 PVCCMCP_CPU1 RSVD<202> @BASEBOARD_FAB2_LIB.BASEBOARD_FAB2(SCH_1):PVCCMCP_CPU1
AN24 PVCCMCP_CPU1 RSVD<201> @BASEBOARD_FAB2_LIB.BASEBOARD_FAB2(SCH_1):PVCCMCP_CPU1
AN26 PVCCMCP_CPU1 RSVD<200> @BASEBOARD_FAB2_LIB.BASEBOARD_FAB2(SCH_1):PVCCMCP_CPU1
AN60 TP_CPU1_RSVD_199 RSVD<199> @BASEBOARD_FAB2_LIB.BASEBOARD_FAB2(SCH_1):TP_CPU1_RSVD_199
AN62 TP_CPU1_RSVD_198 RSVD<198> @BASEBOARD_FAB2_LIB.BASEBOARD_FAB2(SCH_1):TP_CPU1_RSVD_198
AP23 PVCCMCP_CPU1 RSVD<197> @BASEBOARD_FAB2_LIB.BASEBOARD_FAB2(SCH_1):PVCCMCP_CPU1
AP25 PVCCMCP_CPU1 RSVD<196> @BASEBOARD_FAB2_LIB.BASEBOARD_FAB2(SCH_1):PVCCMCP_CPU1
AP27 CLK_100M_CPU1_RC_REFCLK0_DN RSVD<195> @BASEBOARD_FAB2_LIB.BASEBOARD_FAB2(SCH_1):CLK_100M_CPU1_RC_REFCLK0_DN
AP61 TP_CPU1_RSVD_194 RSVD<194> @BASEBOARD_FAB2_LIB.BASEBOARD_FAB2(SCH_1):TP_CPU1_RSVD_194
AF45 PD_CPU1_RSVD_TEST_1 TEST_1 @BASEBOARD_FAB2_LIB.BASEBOARD_FAB2(SCH_1):PD_CPU1_RSVD_TEST_1
AY13 TP_CPU1_RSVD_TEST_11 TEST_11 @BASEBOARD_FAB2_LIB.BASEBOARD_FAB2(SCH_1):TP_CPU1_RSVD_TEST_11
AG46 PD_CPU1_RSVD_TEST_2 TEST_2 @BASEBOARD_FAB2_LIB.BASEBOARD_FAB2(SCH_1):PD_CPU1_RSVD_TEST_2
AM13 TP_CPU1_RSVD_TEST_3 TEST_3 @BASEBOARD_FAB2_LIB.BASEBOARD_FAB2(SCH_1):TP_CPU1_RSVD_TEST_3
AN12 TP_CPU1_RSVD_TEST_4 TEST_4 @BASEBOARD_FAB2_LIB.BASEBOARD_FAB2(SCH_1):TP_CPU1_RSVD_TEST_4
AN14 TP_CPU1_RSVD_TEST_5 TEST_5 @BASEBOARD_FAB2_LIB.BASEBOARD_FAB2(SCH_1):TP_CPU1_RSVD_TEST_5

RES_0402-49.9,1%,1/16W,CHIP,G2A  I173  R8P3
   1 PD_CPU1_RSVD_TEST_2      A @BASEBOARD_FAB2_LIB.BASEBOARD_FAB2(SCH_1):PD_CPU1_RSVD_TEST_2
   2    GND      B @BASEBOARD_FAB2_LIB.BASEBOARD_FAB2(SCH_1):GND

RES_0402-49.9,1%,1/16W,CHIP,G2A  I174  R8R1
   1 PD_CPU1_RSVD_TEST_1      A @BASEBOARD_FAB2_LIB.BASEBOARD_FAB2(SCH_1):PD_CPU1_RSVD_TEST_1
   2    GND      B @BASEBOARD_FAB2_LIB.BASEBOARD_FAB2(SCH_1):GND


DRAWING: @BASEBOARD_FAB2_LIB.BASEBOARD_FAB2(SCH_1):PAGE57 

SKX_EXT_B_BGA1-IC,TBD  I172  U2D1
 J60 M_G_ACT_N DDR0_ACT_N @BASEBOARD_FAB2_LIB.BASEBOARD_FAB2(SCH_1):M_G_ACT_N
 B61 M_G_ALERT_N DDR0_ALERT_N @BASEBOARD_FAB2_LIB.BASEBOARD_FAB2(SCH_1):M_G_ALERT_N
 G54 M_G_BA<1> DDR0_BA<1> @BASEBOARD_FAB2_LIB.BASEBOARD_FAB2(SCH_1):M_G_BA(1)
 C52 M_G_BA<0> DDR0_BA<0> @BASEBOARD_FAB2_LIB.BASEBOARD_FAB2(SCH_1):M_G_BA(0)
 F63 M_G_BG<1> DDR0_BG<1> @BASEBOARD_FAB2_LIB.BASEBOARD_FAB2(SCH_1):M_G_BG(1)
 D61 M_G_BG<0> DDR0_BG<0> @BASEBOARD_FAB2_LIB.BASEBOARD_FAB2(SCH_1):M_G_BG(0)
 G46 M_G_C<2> DDR0_CID<2> @BASEBOARD_FAB2_LIB.BASEBOARD_FAB2(SCH_1):M_G_C(2)
 D63 M_G_CKE<3> DDR0_CKE<3> @BASEBOARD_FAB2_LIB.BASEBOARD_FAB2(SCH_1):M_G_CKE(3)
 B63 M_G_CKE<2> DDR0_CKE<2> @BASEBOARD_FAB2_LIB.BASEBOARD_FAB2(SCH_1):M_G_CKE(2)
 C64 M_G_CKE<1> DDR0_CKE<1> @BASEBOARD_FAB2_LIB.BASEBOARD_FAB2(SCH_1):M_G_CKE(1)
 C62 M_G_CKE<0> DDR0_CKE<0> @BASEBOARD_FAB2_LIB.BASEBOARD_FAB2(SCH_1):M_G_CKE(0)
 C56 M_G_CLK_DN<3> DDR0_CLK_DN<3> @BASEBOARD_FAB2_LIB.BASEBOARD_FAB2(SCH_1):M_G_CLK_DN(3)
 J56 M_G_CLK_DN<2> DDR0_CLK_DN<2> @BASEBOARD_FAB2_LIB.BASEBOARD_FAB2(SCH_1):M_G_CLK_DN(2)
 C54 M_G_CLK_DN<1> DDR0_CLK_DN<1> @BASEBOARD_FAB2_LIB.BASEBOARD_FAB2(SCH_1):M_G_CLK_DN(1)
 F55 M_G_CLK_DN<0> DDR0_CLK_DN<0> @BASEBOARD_FAB2_LIB.BASEBOARD_FAB2(SCH_1):M_G_CLK_DN(0)
 B57 M_G_CLK_DP<3> DDR0_CLK_DP<3> @BASEBOARD_FAB2_LIB.BASEBOARD_FAB2(SCH_1):M_G_CLK_DP(3)
 G56 M_G_CLK_DP<2> DDR0_CLK_DP<2> @BASEBOARD_FAB2_LIB.BASEBOARD_FAB2(SCH_1):M_G_CLK_DP(2)
 B55 M_G_CLK_DP<1> DDR0_CLK_DP<1> @BASEBOARD_FAB2_LIB.BASEBOARD_FAB2(SCH_1):M_G_CLK_DP(1)
 D55 M_G_CLK_DP<0> DDR0_CLK_DP<0> @BASEBOARD_FAB2_LIB.BASEBOARD_FAB2(SCH_1):M_G_CLK_DP(0)
 K45 M_G_CS_N<7> DDR0_CS_N<7> @BASEBOARD_FAB2_LIB.BASEBOARD_FAB2(SCH_1):M_G_CS_N(7)
 F45 M_G_CS_N<6> DDR0_CS_N<6> @BASEBOARD_FAB2_LIB.BASEBOARD_FAB2(SCH_1):M_G_CS_N(6)
 D49 M_G_CS_N<5> DDR0_CS_N<5> @BASEBOARD_FAB2_LIB.BASEBOARD_FAB2(SCH_1):M_G_CS_N(5)
 B51 M_G_CS_N<4> DDR0_CS_N<4> @BASEBOARD_FAB2_LIB.BASEBOARD_FAB2(SCH_1):M_G_CS_N(4)
 F47 M_G_CS_N<3> DDR0_CS_N<3> @BASEBOARD_FAB2_LIB.BASEBOARD_FAB2(SCH_1):M_G_CS_N(3)
 D47 M_G_CS_N<2> DDR0_CS_N<2> @BASEBOARD_FAB2_LIB.BASEBOARD_FAB2(SCH_1):M_G_CS_N(2)
 F49 M_G_CS_N<1> DDR0_CS_N<1> @BASEBOARD_FAB2_LIB.BASEBOARD_FAB2(SCH_1):M_G_CS_N(1)
 G52 M_G_CS_N<0> DDR0_CS_N<0> @BASEBOARD_FAB2_LIB.BASEBOARD_FAB2(SCH_1):M_G_CS_N(0)
 K23 M_G_DQ<63> DDR0_DQ<63> @BASEBOARD_FAB2_LIB.BASEBOARD_FAB2(SCH_1):M_G_DQ(63)
 H23 M_G_DQ<62> DDR0_DQ<62> @BASEBOARD_FAB2_LIB.BASEBOARD_FAB2(SCH_1):M_G_DQ(62)
 N26 M_G_DQ<61> DDR0_DQ<61> @BASEBOARD_FAB2_LIB.BASEBOARD_FAB2(SCH_1):M_G_DQ(61)
 L26 M_G_DQ<60> DDR0_DQ<60> @BASEBOARD_FAB2_LIB.BASEBOARD_FAB2(SCH_1):M_G_DQ(60)
 T23 M_G_DQ<59> DDR0_DQ<59> @BASEBOARD_FAB2_LIB.BASEBOARD_FAB2(SCH_1):M_G_DQ(59)
 P23 M_G_DQ<58> DDR0_DQ<58> @BASEBOARD_FAB2_LIB.BASEBOARD_FAB2(SCH_1):M_G_DQ(58)
 P25 M_G_DQ<57> DDR0_DQ<57> @BASEBOARD_FAB2_LIB.BASEBOARD_FAB2(SCH_1):M_G_DQ(57)
 K25 M_G_DQ<56> DDR0_DQ<56> @BASEBOARD_FAB2_LIB.BASEBOARD_FAB2(SCH_1):M_G_DQ(56)
 P29 M_G_DQ<55> DDR0_DQ<55> @BASEBOARD_FAB2_LIB.BASEBOARD_FAB2(SCH_1):M_G_DQ(55)
 K29 M_G_DQ<54> DDR0_DQ<54> @BASEBOARD_FAB2_LIB.BASEBOARD_FAB2(SCH_1):M_G_DQ(54)
 N32 M_G_DQ<53> DDR0_DQ<53> @BASEBOARD_FAB2_LIB.BASEBOARD_FAB2(SCH_1):M_G_DQ(53)
 L32 M_G_DQ<52> DDR0_DQ<52> @BASEBOARD_FAB2_LIB.BASEBOARD_FAB2(SCH_1):M_G_DQ(52)
 N28 M_G_DQ<51> DDR0_DQ<51> @BASEBOARD_FAB2_LIB.BASEBOARD_FAB2(SCH_1):M_G_DQ(51)
 L28 M_G_DQ<50> DDR0_DQ<50> @BASEBOARD_FAB2_LIB.BASEBOARD_FAB2(SCH_1):M_G_DQ(50)
 P31 M_G_DQ<49> DDR0_DQ<49> @BASEBOARD_FAB2_LIB.BASEBOARD_FAB2(SCH_1):M_G_DQ(49)
 K31 M_G_DQ<48> DDR0_DQ<48> @BASEBOARD_FAB2_LIB.BASEBOARD_FAB2(SCH_1):M_G_DQ(48)
 P35 M_G_DQ<47> DDR0_DQ<47> @BASEBOARD_FAB2_LIB.BASEBOARD_FAB2(SCH_1):M_G_DQ(47)
 K35 M_G_DQ<46> DDR0_DQ<46> @BASEBOARD_FAB2_LIB.BASEBOARD_FAB2(SCH_1):M_G_DQ(46)
 N38 M_G_DQ<45> DDR0_DQ<45> @BASEBOARD_FAB2_LIB.BASEBOARD_FAB2(SCH_1):M_G_DQ(45)
 L38 M_G_DQ<44> DDR0_DQ<44> @BASEBOARD_FAB2_LIB.BASEBOARD_FAB2(SCH_1):M_G_DQ(44)
 N34 M_G_DQ<43> DDR0_DQ<43> @BASEBOARD_FAB2_LIB.BASEBOARD_FAB2(SCH_1):M_G_DQ(43)
 L34 M_G_DQ<42> DDR0_DQ<42> @BASEBOARD_FAB2_LIB.BASEBOARD_FAB2(SCH_1):M_G_DQ(42)
 P37 M_G_DQ<41> DDR0_DQ<41> @BASEBOARD_FAB2_LIB.BASEBOARD_FAB2(SCH_1):M_G_DQ(41)
 K37 M_G_DQ<40> DDR0_DQ<40> @BASEBOARD_FAB2_LIB.BASEBOARD_FAB2(SCH_1):M_G_DQ(40)
 F39 M_G_DQ<39> DDR0_DQ<39> @BASEBOARD_FAB2_LIB.BASEBOARD_FAB2(SCH_1):M_G_DQ(39)
 B39 M_G_DQ<38> DDR0_DQ<38> @BASEBOARD_FAB2_LIB.BASEBOARD_FAB2(SCH_1):M_G_DQ(38)
 F41 M_G_DQ<37> DDR0_DQ<37> @BASEBOARD_FAB2_LIB.BASEBOARD_FAB2(SCH_1):M_G_DQ(37)
 E42 M_G_DQ<36> DDR0_DQ<36> @BASEBOARD_FAB2_LIB.BASEBOARD_FAB2(SCH_1):M_G_DQ(36)
 E38 M_G_DQ<35> DDR0_DQ<35> @BASEBOARD_FAB2_LIB.BASEBOARD_FAB2(SCH_1):M_G_DQ(35)
 C38 M_G_DQ<34> DDR0_DQ<34> @BASEBOARD_FAB2_LIB.BASEBOARD_FAB2(SCH_1):M_G_DQ(34)
 B41 M_G_DQ<33> DDR0_DQ<33> @BASEBOARD_FAB2_LIB.BASEBOARD_FAB2(SCH_1):M_G_DQ(33)
 C42 M_G_DQ<32> DDR0_DQ<32> @BASEBOARD_FAB2_LIB.BASEBOARD_FAB2(SCH_1):M_G_DQ(32)
 R74 M_G_DQ<31> DDR0_DQ<31> @BASEBOARD_FAB2_LIB.BASEBOARD_FAB2(SCH_1):M_G_DQ(31)
 L74 M_G_DQ<30> DDR0_DQ<30> @BASEBOARD_FAB2_LIB.BASEBOARD_FAB2(SCH_1):M_G_DQ(30)
 P77 M_G_DQ<29> DDR0_DQ<29> @BASEBOARD_FAB2_LIB.BASEBOARD_FAB2(SCH_1):M_G_DQ(29)
 M77 M_G_DQ<28> DDR0_DQ<28> @BASEBOARD_FAB2_LIB.BASEBOARD_FAB2(SCH_1):M_G_DQ(28)
 P73 M_G_DQ<27> DDR0_DQ<27> @BASEBOARD_FAB2_LIB.BASEBOARD_FAB2(SCH_1):M_G_DQ(27)
 M73 M_G_DQ<26> DDR0_DQ<26> @BASEBOARD_FAB2_LIB.BASEBOARD_FAB2(SCH_1):M_G_DQ(26)
 R76 M_G_DQ<25> DDR0_DQ<25> @BASEBOARD_FAB2_LIB.BASEBOARD_FAB2(SCH_1):M_G_DQ(25)
 L76 M_G_DQ<24> DDR0_DQ<24> @BASEBOARD_FAB2_LIB.BASEBOARD_FAB2(SCH_1):M_G_DQ(24)
 N80 M_G_DQ<23> DDR0_DQ<23> @BASEBOARD_FAB2_LIB.BASEBOARD_FAB2(SCH_1):M_G_DQ(23)
 R82 M_G_DQ<22> DDR0_DQ<22> @BASEBOARD_FAB2_LIB.BASEBOARD_FAB2(SCH_1):M_G_DQ(22)
 V79 M_G_DQ<21> DDR0_DQ<21> @BASEBOARD_FAB2_LIB.BASEBOARD_FAB2(SCH_1):M_G_DQ(21)
 W80 M_G_DQ<20> DDR0_DQ<20> @BASEBOARD_FAB2_LIB.BASEBOARD_FAB2(SCH_1):M_G_DQ(20)
 M81 M_G_DQ<19> DDR0_DQ<19> @BASEBOARD_FAB2_LIB.BASEBOARD_FAB2(SCH_1):M_G_DQ(19)
 N82 M_G_DQ<18> DDR0_DQ<18> @BASEBOARD_FAB2_LIB.BASEBOARD_FAB2(SCH_1):M_G_DQ(18)
 T79 M_G_DQ<17> DDR0_DQ<17> @BASEBOARD_FAB2_LIB.BASEBOARD_FAB2(SCH_1):M_G_DQ(17)
 V81 M_G_DQ<16> DDR0_DQ<16> @BASEBOARD_FAB2_LIB.BASEBOARD_FAB2(SCH_1):M_G_DQ(16)
 N84 M_G_DQ<15> DDR0_DQ<15> @BASEBOARD_FAB2_LIB.BASEBOARD_FAB2(SCH_1):M_G_DQ(15)
 N86 M_G_DQ<14> DDR0_DQ<14> @BASEBOARD_FAB2_LIB.BASEBOARD_FAB2(SCH_1):M_G_DQ(14)
AA84 M_G_DQ<13> DDR0_DQ<13> @BASEBOARD_FAB2_LIB.BASEBOARD_FAB2(SCH_1):M_G_DQ(13)
AA86 M_G_DQ<12> DDR0_DQ<12> @BASEBOARD_FAB2_LIB.BASEBOARD_FAB2(SCH_1):M_G_DQ(12)
 L84 M_G_DQ<11> DDR0_DQ<11> @BASEBOARD_FAB2_LIB.BASEBOARD_FAB2(SCH_1):M_G_DQ(11)
 L86 M_G_DQ<10> DDR0_DQ<10> @BASEBOARD_FAB2_LIB.BASEBOARD_FAB2(SCH_1):M_G_DQ(10)
 W84 M_G_DQ<9> DDR0_DQ<9> @BASEBOARD_FAB2_LIB.BASEBOARD_FAB2(SCH_1):M_G_DQ(9)
 W86 M_G_DQ<8> DDR0_DQ<8> @BASEBOARD_FAB2_LIB.BASEBOARD_FAB2(SCH_1):M_G_DQ(8)
AG84 M_G_DQ<7> DDR0_DQ<7> @BASEBOARD_FAB2_LIB.BASEBOARD_FAB2(SCH_1):M_G_DQ(7)
AG86 M_G_DQ<6> DDR0_DQ<6> @BASEBOARD_FAB2_LIB.BASEBOARD_FAB2(SCH_1):M_G_DQ(6)
AR84 M_G_DQ<5> DDR0_DQ<5> @BASEBOARD_FAB2_LIB.BASEBOARD_FAB2(SCH_1):M_G_DQ(5)
AR86 M_G_DQ<4> DDR0_DQ<4> @BASEBOARD_FAB2_LIB.BASEBOARD_FAB2(SCH_1):M_G_DQ(4)
AE84 M_G_DQ<3> DDR0_DQ<3> @BASEBOARD_FAB2_LIB.BASEBOARD_FAB2(SCH_1):M_G_DQ(3)
AE86 M_G_DQ<2> DDR0_DQ<2> @BASEBOARD_FAB2_LIB.BASEBOARD_FAB2(SCH_1):M_G_DQ(2)
AN84 M_G_DQ<1> DDR0_DQ<1> @BASEBOARD_FAB2_LIB.BASEBOARD_FAB2(SCH_1):M_G_DQ(1)
AN86 M_G_DQ<0> DDR0_DQ<0> @BASEBOARD_FAB2_LIB.BASEBOARD_FAB2(SCH_1):M_G_DQ(0)
AB67 M_G_DQS_DN<17> DDR0_DQS_DN<17> @BASEBOARD_FAB2_LIB.BASEBOARD_FAB2(SCH_1):M_G_DQS_DN(17)
 J24 M_G_DQS_DN<16> DDR0_DQS_DN<16> @BASEBOARD_FAB2_LIB.BASEBOARD_FAB2(SCH_1):M_G_DQS_DN(16)
 J30 M_G_DQS_DN<15> DDR0_DQS_DN<15> @BASEBOARD_FAB2_LIB.BASEBOARD_FAB2(SCH_1):M_G_DQS_DN(15)
 J36 M_G_DQS_DN<14> DDR0_DQS_DN<14> @BASEBOARD_FAB2_LIB.BASEBOARD_FAB2(SCH_1):M_G_DQS_DN(14)
 A40 M_G_DQS_DN<13> DDR0_DQS_DN<13> @BASEBOARD_FAB2_LIB.BASEBOARD_FAB2(SCH_1):M_G_DQS_DN(13)
 K75 M_G_DQS_DN<12> DDR0_DQS_DN<12> @BASEBOARD_FAB2_LIB.BASEBOARD_FAB2(SCH_1):M_G_DQS_DN(12)
 U82 M_G_DQS_DN<11> DDR0_DQS_DN<11> @BASEBOARD_FAB2_LIB.BASEBOARD_FAB2(SCH_1):M_G_DQS_DN(11)
 U84 M_G_DQS_DN<10> DDR0_DQS_DN<10> @BASEBOARD_FAB2_LIB.BASEBOARD_FAB2(SCH_1):M_G_DQS_DN(10)
AL84 M_G_DQS_DN<9> DDR0_DQS_DN<9> @BASEBOARD_FAB2_LIB.BASEBOARD_FAB2(SCH_1):M_G_DQS_DN(9)
AH67 M_G_DQS_DN<8> DDR0_DQS_DN<8> @BASEBOARD_FAB2_LIB.BASEBOARD_FAB2(SCH_1):M_G_DQS_DN(8)
 N24 M_G_DQS_DN<7> DDR0_DQS_DN<7> @BASEBOARD_FAB2_LIB.BASEBOARD_FAB2(SCH_1):M_G_DQS_DN(7)
 R30 M_G_DQS_DN<6> DDR0_DQS_DN<6> @BASEBOARD_FAB2_LIB.BASEBOARD_FAB2(SCH_1):M_G_DQS_DN(6)
 R36 M_G_DQS_DN<5> DDR0_DQS_DN<5> @BASEBOARD_FAB2_LIB.BASEBOARD_FAB2(SCH_1):M_G_DQS_DN(5)
 G40 M_G_DQS_DN<4> DDR0_DQS_DN<4> @BASEBOARD_FAB2_LIB.BASEBOARD_FAB2(SCH_1):M_G_DQS_DN(4)
 T75 M_G_DQS_DN<3> DDR0_DQS_DN<3> @BASEBOARD_FAB2_LIB.BASEBOARD_FAB2(SCH_1):M_G_DQS_DN(3)
 P79 M_G_DQS_DN<2> DDR0_DQS_DN<2> @BASEBOARD_FAB2_LIB.BASEBOARD_FAB2(SCH_1):M_G_DQS_DN(2)
 R84 M_G_DQS_DN<1> DDR0_DQS_DN<1> @BASEBOARD_FAB2_LIB.BASEBOARD_FAB2(SCH_1):M_G_DQS_DN(1)
AJ84 M_G_DQS_DN<0> DDR0_DQS_DN<0> @BASEBOARD_FAB2_LIB.BASEBOARD_FAB2(SCH_1):M_G_DQS_DN(0)
AD67 M_G_DQS_DP<17> DDR0_DQS_DP<17> @BASEBOARD_FAB2_LIB.BASEBOARD_FAB2(SCH_1):M_G_DQS_DP(17)
 L24 M_G_DQS_DP<16> DDR0_DQS_DP<16> @BASEBOARD_FAB2_LIB.BASEBOARD_FAB2(SCH_1):M_G_DQS_DP(16)
 L30 M_G_DQS_DP<15> DDR0_DQS_DP<15> @BASEBOARD_FAB2_LIB.BASEBOARD_FAB2(SCH_1):M_G_DQS_DP(15)
 L36 M_G_DQS_DP<14> DDR0_DQS_DP<14> @BASEBOARD_FAB2_LIB.BASEBOARD_FAB2(SCH_1):M_G_DQS_DP(14)
 C40 M_G_DQS_DP<13> DDR0_DQS_DP<13> @BASEBOARD_FAB2_LIB.BASEBOARD_FAB2(SCH_1):M_G_DQS_DP(13)
 M75 M_G_DQS_DP<12> DDR0_DQS_DP<12> @BASEBOARD_FAB2_LIB.BASEBOARD_FAB2(SCH_1):M_G_DQS_DP(12)
 T81 M_G_DQS_DP<11> DDR0_DQS_DP<11> @BASEBOARD_FAB2_LIB.BASEBOARD_FAB2(SCH_1):M_G_DQS_DP(11)
 V85 M_G_DQS_DP<10> DDR0_DQS_DP<10> @BASEBOARD_FAB2_LIB.BASEBOARD_FAB2(SCH_1):M_G_DQS_DP(10)
AM85 M_G_DQS_DP<9> DDR0_DQS_DP<9> @BASEBOARD_FAB2_LIB.BASEBOARD_FAB2(SCH_1):M_G_DQS_DP(9)
AF67 M_G_DQS_DP<8> DDR0_DQS_DP<8> @BASEBOARD_FAB2_LIB.BASEBOARD_FAB2(SCH_1):M_G_DQS_DP(8)
 R24 M_G_DQS_DP<7> DDR0_DQS_DP<7> @BASEBOARD_FAB2_LIB.BASEBOARD_FAB2(SCH_1):M_G_DQS_DP(7)
 N30 M_G_DQS_DP<6> DDR0_DQS_DP<6> @BASEBOARD_FAB2_LIB.BASEBOARD_FAB2(SCH_1):M_G_DQS_DP(6)
 N36 M_G_DQS_DP<5> DDR0_DQS_DP<5> @BASEBOARD_FAB2_LIB.BASEBOARD_FAB2(SCH_1):M_G_DQS_DP(5)
 E40 M_G_DQS_DP<4> DDR0_DQS_DP<4> @BASEBOARD_FAB2_LIB.BASEBOARD_FAB2(SCH_1):M_G_DQS_DP(4)
 P75 M_G_DQS_DP<3> DDR0_DQS_DP<3> @BASEBOARD_FAB2_LIB.BASEBOARD_FAB2(SCH_1):M_G_DQS_DP(3)
 R80 M_G_DQS_DP<2> DDR0_DQS_DP<2> @BASEBOARD_FAB2_LIB.BASEBOARD_FAB2(SCH_1):M_G_DQS_DP(2)
 P85 M_G_DQS_DP<1> DDR0_DQS_DP<1> @BASEBOARD_FAB2_LIB.BASEBOARD_FAB2(SCH_1):M_G_DQS_DP(1)
AH85 M_G_DQS_DP<0> DDR0_DQS_DP<0> @BASEBOARD_FAB2_LIB.BASEBOARD_FAB2(SCH_1):M_G_DQS_DP(0)
AG66 M_G_ECC<7> DDR0_ECC<7> @BASEBOARD_FAB2_LIB.BASEBOARD_FAB2(SCH_1):M_G_ECC(7)
AC66 M_G_ECC<6> DDR0_ECC<6> @BASEBOARD_FAB2_LIB.BASEBOARD_FAB2(SCH_1):M_G_ECC(6)
AF69 M_G_ECC<5> DDR0_ECC<5> @BASEBOARD_FAB2_LIB.BASEBOARD_FAB2(SCH_1):M_G_ECC(5)
AD69 M_G_ECC<4> DDR0_ECC<4> @BASEBOARD_FAB2_LIB.BASEBOARD_FAB2(SCH_1):M_G_ECC(4)
AF65 M_G_ECC<3> DDR0_ECC<3> @BASEBOARD_FAB2_LIB.BASEBOARD_FAB2(SCH_1):M_G_ECC(3)
AD65 M_G_ECC<2> DDR0_ECC<2> @BASEBOARD_FAB2_LIB.BASEBOARD_FAB2(SCH_1):M_G_ECC(2)
AG68 M_G_ECC<1> DDR0_ECC<1> @BASEBOARD_FAB2_LIB.BASEBOARD_FAB2(SCH_1):M_G_ECC(1)
AC68 M_G_ECC<0> DDR0_ECC<0> @BASEBOARD_FAB2_LIB.BASEBOARD_FAB2(SCH_1):M_G_ECC(0)
 K47 M_G_MA<17> DDR0_MA<17> @BASEBOARD_FAB2_LIB.BASEBOARD_FAB2(SCH_1):M_G_MA(17)
 D51 M_G_MA<16> DDR0_MA<16> @BASEBOARD_FAB2_LIB.BASEBOARD_FAB2(SCH_1):M_G_MA(16)
 K49 M_G_MA<15> DDR0_MA<15> @BASEBOARD_FAB2_LIB.BASEBOARD_FAB2(SCH_1):M_G_MA(15)
 F51 M_G_MA<14> DDR0_MA<14> @BASEBOARD_FAB2_LIB.BASEBOARD_FAB2(SCH_1):M_G_MA(14)
 J48 M_G_MA<13> DDR0_MA<13> @BASEBOARD_FAB2_LIB.BASEBOARD_FAB2(SCH_1):M_G_MA(13)
 J64 M_G_MA<12> DDR0_MA<12> @BASEBOARD_FAB2_LIB.BASEBOARD_FAB2(SCH_1):M_G_MA(12)
 G62 M_G_MA<11> DDR0_MA<11> @BASEBOARD_FAB2_LIB.BASEBOARD_FAB2(SCH_1):M_G_MA(11)
 J54 M_G_MA<10> DDR0_MA<10> @BASEBOARD_FAB2_LIB.BASEBOARD_FAB2(SCH_1):M_G_MA(10)
 F61 M_G_MA<9> DDR0_MA<9> @BASEBOARD_FAB2_LIB.BASEBOARD_FAB2(SCH_1):M_G_MA(9)
 C60 M_G_MA<8> DDR0_MA<8> @BASEBOARD_FAB2_LIB.BASEBOARD_FAB2(SCH_1):M_G_MA(8)
 G60 M_G_MA<7> DDR0_MA<7> @BASEBOARD_FAB2_LIB.BASEBOARD_FAB2(SCH_1):M_G_MA(7)
 D59 M_G_MA<6> DDR0_MA<6> @BASEBOARD_FAB2_LIB.BASEBOARD_FAB2(SCH_1):M_G_MA(6)
 F59 M_G_MA<5> DDR0_MA<5> @BASEBOARD_FAB2_LIB.BASEBOARD_FAB2(SCH_1):M_G_MA(5)
 G58 M_G_MA<4> DDR0_MA<4> @BASEBOARD_FAB2_LIB.BASEBOARD_FAB2(SCH_1):M_G_MA(4)
 C58 M_G_MA<3> DDR0_MA<3> @BASEBOARD_FAB2_LIB.BASEBOARD_FAB2(SCH_1):M_G_MA(3)
 D57 M_G_MA<2> DDR0_MA<2> @BASEBOARD_FAB2_LIB.BASEBOARD_FAB2(SCH_1):M_G_MA(2)
 F57 M_G_MA<1> DDR0_MA<1> @BASEBOARD_FAB2_LIB.BASEBOARD_FAB2(SCH_1):M_G_MA(1)
 F53 M_G_MA<0> DDR0_MA<0> @BASEBOARD_FAB2_LIB.BASEBOARD_FAB2(SCH_1):M_G_MA(0)
 G48 M_G_ODT<3> DDR0_ODT<3> @BASEBOARD_FAB2_LIB.BASEBOARD_FAB2(SCH_1):M_G_ODT(3)
 G50 M_G_ODT<2> DDR0_ODT<2> @BASEBOARD_FAB2_LIB.BASEBOARD_FAB2(SCH_1):M_G_ODT(2)
 C48 M_G_ODT<1> DDR0_ODT<1> @BASEBOARD_FAB2_LIB.BASEBOARD_FAB2(SCH_1):M_G_ODT(1)
 C50 M_G_ODT<0> DDR0_ODT<0> @BASEBOARD_FAB2_LIB.BASEBOARD_FAB2(SCH_1):M_G_ODT(0)
 D53 M_G_PAR DDR0_PAR @BASEBOARD_FAB2_LIB.BASEBOARD_FAB2(SCH_1):M_G_PAR


DRAWING: @BASEBOARD_FAB2_LIB.BASEBOARD_FAB2(SCH_1):PAGE58 

SKX_EXT_B_BGA1-IC,TBD  I172  U2D1
 T63 M_H_ACT_N DDR1_ACT_N @BASEBOARD_FAB2_LIB.BASEBOARD_FAB2(SCH_1):M_H_ACT_N
 W62 M_H_ALERT_N DDR1_ALERT_N @BASEBOARD_FAB2_LIB.BASEBOARD_FAB2(SCH_1):M_H_ALERT_N
 K55 M_H_BA<1> DDR1_BA<1> @BASEBOARD_FAB2_LIB.BASEBOARD_FAB2(SCH_1):M_H_BA(1)
 T53 M_H_BA<0> DDR1_BA<0> @BASEBOARD_FAB2_LIB.BASEBOARD_FAB2(SCH_1):M_H_BA(0)
 N60 M_H_BG<1> DDR1_BG<1> @BASEBOARD_FAB2_LIB.BASEBOARD_FAB2(SCH_1):M_H_BG(1)
 M61 M_H_BG<0> DDR1_BG<0> @BASEBOARD_FAB2_LIB.BASEBOARD_FAB2(SCH_1):M_H_BG(0)
 M47 M_H_C<2> DDR1_CID<2> @BASEBOARD_FAB2_LIB.BASEBOARD_FAB2(SCH_1):M_H_C(2)
 L64 M_H_CKE<3> DDR1_CKE<3> @BASEBOARD_FAB2_LIB.BASEBOARD_FAB2(SCH_1):M_H_CKE(3)
 K63 M_H_CKE<2> DDR1_CKE<2> @BASEBOARD_FAB2_LIB.BASEBOARD_FAB2(SCH_1):M_H_CKE(2)
 R64 M_H_CKE<1> DDR1_CKE<1> @BASEBOARD_FAB2_LIB.BASEBOARD_FAB2(SCH_1):M_H_CKE(1)
 N62 M_H_CKE<0> DDR1_CKE<0> @BASEBOARD_FAB2_LIB.BASEBOARD_FAB2(SCH_1):M_H_CKE(0)
 R56 M_H_CLK_DN<3> DDR1_CLK_DN<3> @BASEBOARD_FAB2_LIB.BASEBOARD_FAB2(SCH_1):M_H_CLK_DN(3)
 N56 M_H_CLK_DN<2> DDR1_CLK_DN<2> @BASEBOARD_FAB2_LIB.BASEBOARD_FAB2(SCH_1):M_H_CLK_DN(2)
 R54 M_H_CLK_DN<1> DDR1_CLK_DN<1> @BASEBOARD_FAB2_LIB.BASEBOARD_FAB2(SCH_1):M_H_CLK_DN(1)
 M53 M_H_CLK_DN<0> DDR1_CLK_DN<0> @BASEBOARD_FAB2_LIB.BASEBOARD_FAB2(SCH_1):M_H_CLK_DN(0)
 T57 M_H_CLK_DP<3> DDR1_CLK_DP<3> @BASEBOARD_FAB2_LIB.BASEBOARD_FAB2(SCH_1):M_H_CLK_DP(3)
 M57 M_H_CLK_DP<2> DDR1_CLK_DP<2> @BASEBOARD_FAB2_LIB.BASEBOARD_FAB2(SCH_1):M_H_CLK_DP(2)
 T55 M_H_CLK_DP<1> DDR1_CLK_DP<1> @BASEBOARD_FAB2_LIB.BASEBOARD_FAB2(SCH_1):M_H_CLK_DP(1)
 N54 M_H_CLK_DP<0> DDR1_CLK_DP<0> @BASEBOARD_FAB2_LIB.BASEBOARD_FAB2(SCH_1):M_H_CLK_DP(0)
 R46 M_H_CS_N<7> DDR1_CS_N<7> @BASEBOARD_FAB2_LIB.BASEBOARD_FAB2(SCH_1):M_H_CS_N(7)
 M45 M_H_CS_N<6> DDR1_CS_N<6> @BASEBOARD_FAB2_LIB.BASEBOARD_FAB2(SCH_1):M_H_CS_N(6)
 T49 M_H_CS_N<5> DDR1_CS_N<5> @BASEBOARD_FAB2_LIB.BASEBOARD_FAB2(SCH_1):M_H_CS_N(5)
 J50 M_H_CS_N<4> DDR1_CS_N<4> @BASEBOARD_FAB2_LIB.BASEBOARD_FAB2(SCH_1):M_H_CS_N(4)
 V47 M_H_CS_N<3> DDR1_CS_N<3> @BASEBOARD_FAB2_LIB.BASEBOARD_FAB2(SCH_1):M_H_CS_N(3)
 N46 M_H_CS_N<2> DDR1_CS_N<2> @BASEBOARD_FAB2_LIB.BASEBOARD_FAB2(SCH_1):M_H_CS_N(2)
 R50 M_H_CS_N<1> DDR1_CS_N<1> @BASEBOARD_FAB2_LIB.BASEBOARD_FAB2(SCH_1):M_H_CS_N(1)
 K51 M_H_CS_N<0> DDR1_CS_N<0> @BASEBOARD_FAB2_LIB.BASEBOARD_FAB2(SCH_1):M_H_CS_N(0)
AA26 M_H_DQ<63> DDR1_DQ<63> @BASEBOARD_FAB2_LIB.BASEBOARD_FAB2(SCH_1):M_H_DQ(63)
 U26 M_H_DQ<62> DDR1_DQ<62> @BASEBOARD_FAB2_LIB.BASEBOARD_FAB2(SCH_1):M_H_DQ(62)
 Y29 M_H_DQ<61> DDR1_DQ<61> @BASEBOARD_FAB2_LIB.BASEBOARD_FAB2(SCH_1):M_H_DQ(61)
 V29 M_H_DQ<60> DDR1_DQ<60> @BASEBOARD_FAB2_LIB.BASEBOARD_FAB2(SCH_1):M_H_DQ(60)
 Y25 M_H_DQ<59> DDR1_DQ<59> @BASEBOARD_FAB2_LIB.BASEBOARD_FAB2(SCH_1):M_H_DQ(59)
 V25 M_H_DQ<58> DDR1_DQ<58> @BASEBOARD_FAB2_LIB.BASEBOARD_FAB2(SCH_1):M_H_DQ(58)
AA28 M_H_DQ<57> DDR1_DQ<57> @BASEBOARD_FAB2_LIB.BASEBOARD_FAB2(SCH_1):M_H_DQ(57)
 U28 M_H_DQ<56> DDR1_DQ<56> @BASEBOARD_FAB2_LIB.BASEBOARD_FAB2(SCH_1):M_H_DQ(56)
 F27 M_H_DQ<55> DDR1_DQ<55> @BASEBOARD_FAB2_LIB.BASEBOARD_FAB2(SCH_1):M_H_DQ(55)
 B27 M_H_DQ<54> DDR1_DQ<54> @BASEBOARD_FAB2_LIB.BASEBOARD_FAB2(SCH_1):M_H_DQ(54)
 F29 M_H_DQ<53> DDR1_DQ<53> @BASEBOARD_FAB2_LIB.BASEBOARD_FAB2(SCH_1):M_H_DQ(53)
 E30 M_H_DQ<52> DDR1_DQ<52> @BASEBOARD_FAB2_LIB.BASEBOARD_FAB2(SCH_1):M_H_DQ(52)
 E26 M_H_DQ<51> DDR1_DQ<51> @BASEBOARD_FAB2_LIB.BASEBOARD_FAB2(SCH_1):M_H_DQ(51)
 C26 M_H_DQ<50> DDR1_DQ<50> @BASEBOARD_FAB2_LIB.BASEBOARD_FAB2(SCH_1):M_H_DQ(50)
 B29 M_H_DQ<49> DDR1_DQ<49> @BASEBOARD_FAB2_LIB.BASEBOARD_FAB2(SCH_1):M_H_DQ(49)
 C30 M_H_DQ<48> DDR1_DQ<48> @BASEBOARD_FAB2_LIB.BASEBOARD_FAB2(SCH_1):M_H_DQ(48)
 F33 M_H_DQ<47> DDR1_DQ<47> @BASEBOARD_FAB2_LIB.BASEBOARD_FAB2(SCH_1):M_H_DQ(47)
 B33 M_H_DQ<46> DDR1_DQ<46> @BASEBOARD_FAB2_LIB.BASEBOARD_FAB2(SCH_1):M_H_DQ(46)
 F35 M_H_DQ<45> DDR1_DQ<45> @BASEBOARD_FAB2_LIB.BASEBOARD_FAB2(SCH_1):M_H_DQ(45)
 E36 M_H_DQ<44> DDR1_DQ<44> @BASEBOARD_FAB2_LIB.BASEBOARD_FAB2(SCH_1):M_H_DQ(44)
 E32 M_H_DQ<43> DDR1_DQ<43> @BASEBOARD_FAB2_LIB.BASEBOARD_FAB2(SCH_1):M_H_DQ(43)
 C32 M_H_DQ<42> DDR1_DQ<42> @BASEBOARD_FAB2_LIB.BASEBOARD_FAB2(SCH_1):M_H_DQ(42)
 B35 M_H_DQ<41> DDR1_DQ<41> @BASEBOARD_FAB2_LIB.BASEBOARD_FAB2(SCH_1):M_H_DQ(41)
 C36 M_H_DQ<40> DDR1_DQ<40> @BASEBOARD_FAB2_LIB.BASEBOARD_FAB2(SCH_1):M_H_DQ(40)
 P41 M_H_DQ<39> DDR1_DQ<39> @BASEBOARD_FAB2_LIB.BASEBOARD_FAB2(SCH_1):M_H_DQ(39)
 K41 M_H_DQ<38> DDR1_DQ<38> @BASEBOARD_FAB2_LIB.BASEBOARD_FAB2(SCH_1):M_H_DQ(38)
 T43 M_H_DQ<37> DDR1_DQ<37> @BASEBOARD_FAB2_LIB.BASEBOARD_FAB2(SCH_1):M_H_DQ(37)
 P43 M_H_DQ<36> DDR1_DQ<36> @BASEBOARD_FAB2_LIB.BASEBOARD_FAB2(SCH_1):M_H_DQ(36)
 N40 M_H_DQ<35> DDR1_DQ<35> @BASEBOARD_FAB2_LIB.BASEBOARD_FAB2(SCH_1):M_H_DQ(35)
 L40 M_H_DQ<34> DDR1_DQ<34> @BASEBOARD_FAB2_LIB.BASEBOARD_FAB2(SCH_1):M_H_DQ(34)
 H43 M_H_DQ<33> DDR1_DQ<33> @BASEBOARD_FAB2_LIB.BASEBOARD_FAB2(SCH_1):M_H_DQ(33)
 K43 M_H_DQ<32> DDR1_DQ<32> @BASEBOARD_FAB2_LIB.BASEBOARD_FAB2(SCH_1):M_H_DQ(32)
 G72 M_H_DQ<31> DDR1_DQ<31> @BASEBOARD_FAB2_LIB.BASEBOARD_FAB2(SCH_1):M_H_DQ(31)
 C72 M_H_DQ<30> DDR1_DQ<30> @BASEBOARD_FAB2_LIB.BASEBOARD_FAB2(SCH_1):M_H_DQ(30)
 G74 M_H_DQ<29> DDR1_DQ<29> @BASEBOARD_FAB2_LIB.BASEBOARD_FAB2(SCH_1):M_H_DQ(29)
 F75 M_H_DQ<28> DDR1_DQ<28> @BASEBOARD_FAB2_LIB.BASEBOARD_FAB2(SCH_1):M_H_DQ(28)
 F71 M_H_DQ<27> DDR1_DQ<27> @BASEBOARD_FAB2_LIB.BASEBOARD_FAB2(SCH_1):M_H_DQ(27)
 D71 M_H_DQ<26> DDR1_DQ<26> @BASEBOARD_FAB2_LIB.BASEBOARD_FAB2(SCH_1):M_H_DQ(26)
 C74 M_H_DQ<25> DDR1_DQ<25> @BASEBOARD_FAB2_LIB.BASEBOARD_FAB2(SCH_1):M_H_DQ(25)
 D75 M_H_DQ<24> DDR1_DQ<24> @BASEBOARD_FAB2_LIB.BASEBOARD_FAB2(SCH_1):M_H_DQ(24)
 J78 M_H_DQ<23> DDR1_DQ<23> @BASEBOARD_FAB2_LIB.BASEBOARD_FAB2(SCH_1):M_H_DQ(23)
 E78 M_H_DQ<22> DDR1_DQ<22> @BASEBOARD_FAB2_LIB.BASEBOARD_FAB2(SCH_1):M_H_DQ(22)
 H81 M_H_DQ<21> DDR1_DQ<21> @BASEBOARD_FAB2_LIB.BASEBOARD_FAB2(SCH_1):M_H_DQ(21)
 F81 M_H_DQ<20> DDR1_DQ<20> @BASEBOARD_FAB2_LIB.BASEBOARD_FAB2(SCH_1):M_H_DQ(20)
 H77 M_H_DQ<19> DDR1_DQ<19> @BASEBOARD_FAB2_LIB.BASEBOARD_FAB2(SCH_1):M_H_DQ(19)
 F77 M_H_DQ<18> DDR1_DQ<18> @BASEBOARD_FAB2_LIB.BASEBOARD_FAB2(SCH_1):M_H_DQ(18)
 J80 M_H_DQ<17> DDR1_DQ<17> @BASEBOARD_FAB2_LIB.BASEBOARD_FAB2(SCH_1):M_H_DQ(17)
 E80 M_H_DQ<16> DDR1_DQ<16> @BASEBOARD_FAB2_LIB.BASEBOARD_FAB2(SCH_1):M_H_DQ(16)
AC80 M_H_DQ<15> DDR1_DQ<15> @BASEBOARD_FAB2_LIB.BASEBOARD_FAB2(SCH_1):M_H_DQ(15)
AE82 M_H_DQ<14> DDR1_DQ<14> @BASEBOARD_FAB2_LIB.BASEBOARD_FAB2(SCH_1):M_H_DQ(14)
AH79 M_H_DQ<13> DDR1_DQ<13> @BASEBOARD_FAB2_LIB.BASEBOARD_FAB2(SCH_1):M_H_DQ(13)
AJ80 M_H_DQ<12> DDR1_DQ<12> @BASEBOARD_FAB2_LIB.BASEBOARD_FAB2(SCH_1):M_H_DQ(12)
AB81 M_H_DQ<11> DDR1_DQ<11> @BASEBOARD_FAB2_LIB.BASEBOARD_FAB2(SCH_1):M_H_DQ(11)
AC82 M_H_DQ<10> DDR1_DQ<10> @BASEBOARD_FAB2_LIB.BASEBOARD_FAB2(SCH_1):M_H_DQ(10)
AF79 M_H_DQ<9> DDR1_DQ<9> @BASEBOARD_FAB2_LIB.BASEBOARD_FAB2(SCH_1):M_H_DQ(9)
AH81 M_H_DQ<8> DDR1_DQ<8> @BASEBOARD_FAB2_LIB.BASEBOARD_FAB2(SCH_1):M_H_DQ(8)
AN80 M_H_DQ<7> DDR1_DQ<7> @BASEBOARD_FAB2_LIB.BASEBOARD_FAB2(SCH_1):M_H_DQ(7)
AR82 M_H_DQ<6> DDR1_DQ<6> @BASEBOARD_FAB2_LIB.BASEBOARD_FAB2(SCH_1):M_H_DQ(6)
AV79 M_H_DQ<5> DDR1_DQ<5> @BASEBOARD_FAB2_LIB.BASEBOARD_FAB2(SCH_1):M_H_DQ(5)
AW80 M_H_DQ<4> DDR1_DQ<4> @BASEBOARD_FAB2_LIB.BASEBOARD_FAB2(SCH_1):M_H_DQ(4)
AM81 M_H_DQ<3> DDR1_DQ<3> @BASEBOARD_FAB2_LIB.BASEBOARD_FAB2(SCH_1):M_H_DQ(3)
AN82 M_H_DQ<2> DDR1_DQ<2> @BASEBOARD_FAB2_LIB.BASEBOARD_FAB2(SCH_1):M_H_DQ(2)
AT79 M_H_DQ<1> DDR1_DQ<1> @BASEBOARD_FAB2_LIB.BASEBOARD_FAB2(SCH_1):M_H_DQ(1)
AV81 M_H_DQ<0> DDR1_DQ<0> @BASEBOARD_FAB2_LIB.BASEBOARD_FAB2(SCH_1):M_H_DQ(0)
 G68 M_H_DQS_DN<17> DDR1_DQS_DN<17> @BASEBOARD_FAB2_LIB.BASEBOARD_FAB2(SCH_1):M_H_DQS_DN(17)
 T27 M_H_DQS_DN<16> DDR1_DQS_DN<16> @BASEBOARD_FAB2_LIB.BASEBOARD_FAB2(SCH_1):M_H_DQS_DN(16)
 A28 M_H_DQS_DN<15> DDR1_DQS_DN<15> @BASEBOARD_FAB2_LIB.BASEBOARD_FAB2(SCH_1):M_H_DQS_DN(15)
 A34 M_H_DQS_DN<14> DDR1_DQS_DN<14> @BASEBOARD_FAB2_LIB.BASEBOARD_FAB2(SCH_1):M_H_DQS_DN(14)
 J42 M_H_DQS_DN<13> DDR1_DQS_DN<13> @BASEBOARD_FAB2_LIB.BASEBOARD_FAB2(SCH_1):M_H_DQS_DN(13)
 B73 M_H_DQS_DN<12> DDR1_DQS_DN<12> @BASEBOARD_FAB2_LIB.BASEBOARD_FAB2(SCH_1):M_H_DQS_DN(12)
 D79 M_H_DQS_DN<11> DDR1_DQS_DN<11> @BASEBOARD_FAB2_LIB.BASEBOARD_FAB2(SCH_1):M_H_DQS_DN(11)
AG82 M_H_DQS_DN<10> DDR1_DQS_DN<10> @BASEBOARD_FAB2_LIB.BASEBOARD_FAB2(SCH_1):M_H_DQS_DN(10)
AU82 M_H_DQS_DN<9> DDR1_DQS_DN<9> @BASEBOARD_FAB2_LIB.BASEBOARD_FAB2(SCH_1):M_H_DQS_DN(9)
 N68 M_H_DQS_DN<8> DDR1_DQS_DN<8> @BASEBOARD_FAB2_LIB.BASEBOARD_FAB2(SCH_1):M_H_DQS_DN(8)
AB27 M_H_DQS_DN<7> DDR1_DQS_DN<7> @BASEBOARD_FAB2_LIB.BASEBOARD_FAB2(SCH_1):M_H_DQS_DN(7)
 G28 M_H_DQS_DN<6> DDR1_DQS_DN<6> @BASEBOARD_FAB2_LIB.BASEBOARD_FAB2(SCH_1):M_H_DQS_DN(6)
 G34 M_H_DQS_DN<5> DDR1_DQS_DN<5> @BASEBOARD_FAB2_LIB.BASEBOARD_FAB2(SCH_1):M_H_DQS_DN(5)
 N42 M_H_DQS_DN<4> DDR1_DQS_DN<4> @BASEBOARD_FAB2_LIB.BASEBOARD_FAB2(SCH_1):M_H_DQS_DN(4)
 H73 M_H_DQS_DN<3> DDR1_DQS_DN<3> @BASEBOARD_FAB2_LIB.BASEBOARD_FAB2(SCH_1):M_H_DQS_DN(3)
 K79 M_H_DQS_DN<2> DDR1_DQS_DN<2> @BASEBOARD_FAB2_LIB.BASEBOARD_FAB2(SCH_1):M_H_DQS_DN(2)
AD79 M_H_DQS_DN<1> DDR1_DQS_DN<1> @BASEBOARD_FAB2_LIB.BASEBOARD_FAB2(SCH_1):M_H_DQS_DN(1)
AP79 M_H_DQS_DN<0> DDR1_DQS_DN<0> @BASEBOARD_FAB2_LIB.BASEBOARD_FAB2(SCH_1):M_H_DQS_DN(0)
 J68 M_H_DQS_DP<17> DDR1_DQS_DP<17> @BASEBOARD_FAB2_LIB.BASEBOARD_FAB2(SCH_1):M_H_DQS_DP(17)
 V27 M_H_DQS_DP<16> DDR1_DQS_DP<16> @BASEBOARD_FAB2_LIB.BASEBOARD_FAB2(SCH_1):M_H_DQS_DP(16)
 C28 M_H_DQS_DP<15> DDR1_DQS_DP<15> @BASEBOARD_FAB2_LIB.BASEBOARD_FAB2(SCH_1):M_H_DQS_DP(15)
 C34 M_H_DQS_DP<14> DDR1_DQS_DP<14> @BASEBOARD_FAB2_LIB.BASEBOARD_FAB2(SCH_1):M_H_DQS_DP(14)
 L42 M_H_DQS_DP<13> DDR1_DQS_DP<13> @BASEBOARD_FAB2_LIB.BASEBOARD_FAB2(SCH_1):M_H_DQS_DP(13)
 D73 M_H_DQS_DP<12> DDR1_DQS_DP<12> @BASEBOARD_FAB2_LIB.BASEBOARD_FAB2(SCH_1):M_H_DQS_DP(12)
 F79 M_H_DQS_DP<11> DDR1_DQS_DP<11> @BASEBOARD_FAB2_LIB.BASEBOARD_FAB2(SCH_1):M_H_DQS_DP(11)
AF81 M_H_DQS_DP<10> DDR1_DQS_DP<10> @BASEBOARD_FAB2_LIB.BASEBOARD_FAB2(SCH_1):M_H_DQS_DP(10)
AT81 M_H_DQS_DP<9> DDR1_DQS_DP<9> @BASEBOARD_FAB2_LIB.BASEBOARD_FAB2(SCH_1):M_H_DQS_DP(9)
 L68 M_H_DQS_DP<8> DDR1_DQS_DP<8> @BASEBOARD_FAB2_LIB.BASEBOARD_FAB2(SCH_1):M_H_DQS_DP(8)
 Y27 M_H_DQS_DP<7> DDR1_DQS_DP<7> @BASEBOARD_FAB2_LIB.BASEBOARD_FAB2(SCH_1):M_H_DQS_DP(7)
 E28 M_H_DQS_DP<6> DDR1_DQS_DP<6> @BASEBOARD_FAB2_LIB.BASEBOARD_FAB2(SCH_1):M_H_DQS_DP(6)
 E34 M_H_DQS_DP<5> DDR1_DQS_DP<5> @BASEBOARD_FAB2_LIB.BASEBOARD_FAB2(SCH_1):M_H_DQS_DP(5)
 R42 M_H_DQS_DP<4> DDR1_DQS_DP<4> @BASEBOARD_FAB2_LIB.BASEBOARD_FAB2(SCH_1):M_H_DQS_DP(4)
 F73 M_H_DQS_DP<3> DDR1_DQS_DP<3> @BASEBOARD_FAB2_LIB.BASEBOARD_FAB2(SCH_1):M_H_DQS_DP(3)
 H79 M_H_DQS_DP<2> DDR1_DQS_DP<2> @BASEBOARD_FAB2_LIB.BASEBOARD_FAB2(SCH_1):M_H_DQS_DP(2)
AE80 M_H_DQS_DP<1> DDR1_DQS_DP<1> @BASEBOARD_FAB2_LIB.BASEBOARD_FAB2(SCH_1):M_H_DQS_DP(1)
AR80 M_H_DQS_DP<0> DDR1_DQS_DP<0> @BASEBOARD_FAB2_LIB.BASEBOARD_FAB2(SCH_1):M_H_DQS_DP(0)
 M67 M_H_ECC<7> DDR1_ECC<7> @BASEBOARD_FAB2_LIB.BASEBOARD_FAB2(SCH_1):M_H_ECC(7)
 H67 M_H_ECC<6> DDR1_ECC<6> @BASEBOARD_FAB2_LIB.BASEBOARD_FAB2(SCH_1):M_H_ECC(6)
 M69 M_H_ECC<5> DDR1_ECC<5> @BASEBOARD_FAB2_LIB.BASEBOARD_FAB2(SCH_1):M_H_ECC(5)
 L70 M_H_ECC<4> DDR1_ECC<4> @BASEBOARD_FAB2_LIB.BASEBOARD_FAB2(SCH_1):M_H_ECC(4)
 L66 M_H_ECC<3> DDR1_ECC<3> @BASEBOARD_FAB2_LIB.BASEBOARD_FAB2(SCH_1):M_H_ECC(3)
 J66 M_H_ECC<2> DDR1_ECC<2> @BASEBOARD_FAB2_LIB.BASEBOARD_FAB2(SCH_1):M_H_ECC(2)
 H69 M_H_ECC<1> DDR1_ECC<1> @BASEBOARD_FAB2_LIB.BASEBOARD_FAB2(SCH_1):M_H_ECC(1)
 J70 M_H_ECC<0> DDR1_ECC<0> @BASEBOARD_FAB2_LIB.BASEBOARD_FAB2(SCH_1):M_H_ECC(0)
 N48 M_H_MA<17> DDR1_MA<17> @BASEBOARD_FAB2_LIB.BASEBOARD_FAB2(SCH_1):M_H_MA(17)
 R52 M_H_MA<16> DDR1_MA<16> @BASEBOARD_FAB2_LIB.BASEBOARD_FAB2(SCH_1):M_H_MA(16)
 N52 M_H_MA<15> DDR1_MA<15> @BASEBOARD_FAB2_LIB.BASEBOARD_FAB2(SCH_1):M_H_MA(15)
 T51 M_H_MA<14> DDR1_MA<14> @BASEBOARD_FAB2_LIB.BASEBOARD_FAB2(SCH_1):M_H_MA(14)
 M51 M_H_MA<13> DDR1_MA<13> @BASEBOARD_FAB2_LIB.BASEBOARD_FAB2(SCH_1):M_H_MA(13)
 T61 M_H_MA<12> DDR1_MA<12> @BASEBOARD_FAB2_LIB.BASEBOARD_FAB2(SCH_1):M_H_MA(12)
 R60 M_H_MA<11> DDR1_MA<11> @BASEBOARD_FAB2_LIB.BASEBOARD_FAB2(SCH_1):M_H_MA(11)
 M55 M_H_MA<10> DDR1_MA<10> @BASEBOARD_FAB2_LIB.BASEBOARD_FAB2(SCH_1):M_H_MA(10)
 K59 M_H_MA<9> DDR1_MA<9> @BASEBOARD_FAB2_LIB.BASEBOARD_FAB2(SCH_1):M_H_MA(9)
 W60 M_H_MA<8> DDR1_MA<8> @BASEBOARD_FAB2_LIB.BASEBOARD_FAB2(SCH_1):M_H_MA(8)
 V61 M_H_MA<7> DDR1_MA<7> @BASEBOARD_FAB2_LIB.BASEBOARD_FAB2(SCH_1):M_H_MA(7)
 T59 M_H_MA<6> DDR1_MA<6> @BASEBOARD_FAB2_LIB.BASEBOARD_FAB2(SCH_1):M_H_MA(6)
 R58 M_H_MA<5> DDR1_MA<5> @BASEBOARD_FAB2_LIB.BASEBOARD_FAB2(SCH_1):M_H_MA(5)
 M59 M_H_MA<4> DDR1_MA<4> @BASEBOARD_FAB2_LIB.BASEBOARD_FAB2(SCH_1):M_H_MA(4)
 N58 M_H_MA<3> DDR1_MA<3> @BASEBOARD_FAB2_LIB.BASEBOARD_FAB2(SCH_1):M_H_MA(3)
 K57 M_H_MA<2> DDR1_MA<2> @BASEBOARD_FAB2_LIB.BASEBOARD_FAB2(SCH_1):M_H_MA(2)
 J58 M_H_MA<1> DDR1_MA<1> @BASEBOARD_FAB2_LIB.BASEBOARD_FAB2(SCH_1):M_H_MA(1)
 J52 M_H_MA<0> DDR1_MA<0> @BASEBOARD_FAB2_LIB.BASEBOARD_FAB2(SCH_1):M_H_MA(0)
 T47 M_H_ODT<3> DDR1_ODT<3> @BASEBOARD_FAB2_LIB.BASEBOARD_FAB2(SCH_1):M_H_ODT(3)
 M49 M_H_ODT<2> DDR1_ODT<2> @BASEBOARD_FAB2_LIB.BASEBOARD_FAB2(SCH_1):M_H_ODT(2)
 R48 M_H_ODT<1> DDR1_ODT<1> @BASEBOARD_FAB2_LIB.BASEBOARD_FAB2(SCH_1):M_H_ODT(1)
 N50 M_H_ODT<0> DDR1_ODT<0> @BASEBOARD_FAB2_LIB.BASEBOARD_FAB2(SCH_1):M_H_ODT(0)
 K53 M_H_PAR DDR1_PAR @BASEBOARD_FAB2_LIB.BASEBOARD_FAB2(SCH_1):M_H_PAR


DRAWING: @BASEBOARD_FAB2_LIB.BASEBOARD_FAB2(SCH_1):PAGE59 

SKX_EXT_B_BGA1-IC,TBD  I172  U2D1
AB61 M_J_ACT_N DDR2_ACT_N @BASEBOARD_FAB2_LIB.BASEBOARD_FAB2(SCH_1):M_J_ACT_N
AD61 M_J_ALERT_N DDR2_ALERT_N @BASEBOARD_FAB2_LIB.BASEBOARD_FAB2(SCH_1):M_J_ALERT_N
AE56 M_J_BA<1> DDR2_BA<1> @BASEBOARD_FAB2_LIB.BASEBOARD_FAB2(SCH_1):M_J_BA(1)
 W52 M_J_BA<0> DDR2_BA<0> @BASEBOARD_FAB2_LIB.BASEBOARD_FAB2(SCH_1):M_J_BA(0)
AE62 M_J_BG<1> DDR2_BG<1> @BASEBOARD_FAB2_LIB.BASEBOARD_FAB2(SCH_1):M_J_BG(1)
AA60 M_J_BG<0> DDR2_BG<0> @BASEBOARD_FAB2_LIB.BASEBOARD_FAB2(SCH_1):M_J_BG(0)
AB45 M_J_C<2> DDR2_CID<2> @BASEBOARD_FAB2_LIB.BASEBOARD_FAB2(SCH_1):M_J_C(2)
AB63 M_J_CKE<3> DDR2_CKE<3> @BASEBOARD_FAB2_LIB.BASEBOARD_FAB2(SCH_1):M_J_CKE(3)
 V63 M_J_CKE<2> DDR2_CKE<2> @BASEBOARD_FAB2_LIB.BASEBOARD_FAB2(SCH_1):M_J_CKE(2)
AD63 M_J_CKE<1> DDR2_CKE<1> @BASEBOARD_FAB2_LIB.BASEBOARD_FAB2(SCH_1):M_J_CKE(1)
AA62 M_J_CKE<0> DDR2_CKE<0> @BASEBOARD_FAB2_LIB.BASEBOARD_FAB2(SCH_1):M_J_CKE(0)
 W56 M_J_CLK_DN<3> DDR2_CLK_DN<3> @BASEBOARD_FAB2_LIB.BASEBOARD_FAB2(SCH_1):M_J_CLK_DN(3)
AA56 M_J_CLK_DN<2> DDR2_CLK_DN<2> @BASEBOARD_FAB2_LIB.BASEBOARD_FAB2(SCH_1):M_J_CLK_DN(2)
 W54 M_J_CLK_DN<1> DDR2_CLK_DN<1> @BASEBOARD_FAB2_LIB.BASEBOARD_FAB2(SCH_1):M_J_CLK_DN(1)
AA54 M_J_CLK_DN<0> DDR2_CLK_DN<0> @BASEBOARD_FAB2_LIB.BASEBOARD_FAB2(SCH_1):M_J_CLK_DN(0)
 V57 M_J_CLK_DP<3> DDR2_CLK_DP<3> @BASEBOARD_FAB2_LIB.BASEBOARD_FAB2(SCH_1):M_J_CLK_DP(3)
AB57 M_J_CLK_DP<2> DDR2_CLK_DP<2> @BASEBOARD_FAB2_LIB.BASEBOARD_FAB2(SCH_1):M_J_CLK_DP(2)
 V55 M_J_CLK_DP<1> DDR2_CLK_DP<1> @BASEBOARD_FAB2_LIB.BASEBOARD_FAB2(SCH_1):M_J_CLK_DP(1)
AB55 M_J_CLK_DP<0> DDR2_CLK_DP<0> @BASEBOARD_FAB2_LIB.BASEBOARD_FAB2(SCH_1):M_J_CLK_DP(0)
 V45 M_J_CS_N<7> DDR2_CS_N<7> @BASEBOARD_FAB2_LIB.BASEBOARD_FAB2(SCH_1):M_J_CS_N(7)
 T45 M_J_CS_N<6> DDR2_CS_N<6> @BASEBOARD_FAB2_LIB.BASEBOARD_FAB2(SCH_1):M_J_CS_N(6)
 W48 M_J_CS_N<5> DDR2_CS_N<5> @BASEBOARD_FAB2_LIB.BASEBOARD_FAB2(SCH_1):M_J_CS_N(5)
AB51 M_J_CS_N<4> DDR2_CS_N<4> @BASEBOARD_FAB2_LIB.BASEBOARD_FAB2(SCH_1):M_J_CS_N(4)
AA46 M_J_CS_N<3> DDR2_CS_N<3> @BASEBOARD_FAB2_LIB.BASEBOARD_FAB2(SCH_1):M_J_CS_N(3)
 W46 M_J_CS_N<2> DDR2_CS_N<2> @BASEBOARD_FAB2_LIB.BASEBOARD_FAB2(SCH_1):M_J_CS_N(2)
AB49 M_J_CS_N<1> DDR2_CS_N<1> @BASEBOARD_FAB2_LIB.BASEBOARD_FAB2(SCH_1):M_J_CS_N(1)
 V51 M_J_CS_N<0> DDR2_CS_N<0> @BASEBOARD_FAB2_LIB.BASEBOARD_FAB2(SCH_1):M_J_CS_N(0)
AH23 M_J_DQ<63> DDR2_DQ<63> @BASEBOARD_FAB2_LIB.BASEBOARD_FAB2(SCH_1):M_J_DQ(63)
AD23 M_J_DQ<62> DDR2_DQ<62> @BASEBOARD_FAB2_LIB.BASEBOARD_FAB2(SCH_1):M_J_DQ(62)
AG26 M_J_DQ<61> DDR2_DQ<61> @BASEBOARD_FAB2_LIB.BASEBOARD_FAB2(SCH_1):M_J_DQ(61)
AE26 M_J_DQ<60> DDR2_DQ<60> @BASEBOARD_FAB2_LIB.BASEBOARD_FAB2(SCH_1):M_J_DQ(60)
AG22 M_J_DQ<59> DDR2_DQ<59> @BASEBOARD_FAB2_LIB.BASEBOARD_FAB2(SCH_1):M_J_DQ(59)
AE22 M_J_DQ<58> DDR2_DQ<58> @BASEBOARD_FAB2_LIB.BASEBOARD_FAB2(SCH_1):M_J_DQ(58)
AH25 M_J_DQ<57> DDR2_DQ<57> @BASEBOARD_FAB2_LIB.BASEBOARD_FAB2(SCH_1):M_J_DQ(57)
AD25 M_J_DQ<56> DDR2_DQ<56> @BASEBOARD_FAB2_LIB.BASEBOARD_FAB2(SCH_1):M_J_DQ(56)
AH29 M_J_DQ<55> DDR2_DQ<55> @BASEBOARD_FAB2_LIB.BASEBOARD_FAB2(SCH_1):M_J_DQ(55)
AD29 M_J_DQ<54> DDR2_DQ<54> @BASEBOARD_FAB2_LIB.BASEBOARD_FAB2(SCH_1):M_J_DQ(54)
AG32 M_J_DQ<53> DDR2_DQ<53> @BASEBOARD_FAB2_LIB.BASEBOARD_FAB2(SCH_1):M_J_DQ(53)
AE32 M_J_DQ<52> DDR2_DQ<52> @BASEBOARD_FAB2_LIB.BASEBOARD_FAB2(SCH_1):M_J_DQ(52)
AG28 M_J_DQ<51> DDR2_DQ<51> @BASEBOARD_FAB2_LIB.BASEBOARD_FAB2(SCH_1):M_J_DQ(51)
AE28 M_J_DQ<50> DDR2_DQ<50> @BASEBOARD_FAB2_LIB.BASEBOARD_FAB2(SCH_1):M_J_DQ(50)
AH31 M_J_DQ<49> DDR2_DQ<49> @BASEBOARD_FAB2_LIB.BASEBOARD_FAB2(SCH_1):M_J_DQ(49)
AD31 M_J_DQ<48> DDR2_DQ<48> @BASEBOARD_FAB2_LIB.BASEBOARD_FAB2(SCH_1):M_J_DQ(48)
AA32 M_J_DQ<47> DDR2_DQ<47> @BASEBOARD_FAB2_LIB.BASEBOARD_FAB2(SCH_1):M_J_DQ(47)
 U32 M_J_DQ<46> DDR2_DQ<46> @BASEBOARD_FAB2_LIB.BASEBOARD_FAB2(SCH_1):M_J_DQ(46)
 Y35 M_J_DQ<45> DDR2_DQ<45> @BASEBOARD_FAB2_LIB.BASEBOARD_FAB2(SCH_1):M_J_DQ(45)
 V35 M_J_DQ<44> DDR2_DQ<44> @BASEBOARD_FAB2_LIB.BASEBOARD_FAB2(SCH_1):M_J_DQ(44)
 Y31 M_J_DQ<43> DDR2_DQ<43> @BASEBOARD_FAB2_LIB.BASEBOARD_FAB2(SCH_1):M_J_DQ(43)
 V31 M_J_DQ<42> DDR2_DQ<42> @BASEBOARD_FAB2_LIB.BASEBOARD_FAB2(SCH_1):M_J_DQ(42)
AA34 M_J_DQ<41> DDR2_DQ<41> @BASEBOARD_FAB2_LIB.BASEBOARD_FAB2(SCH_1):M_J_DQ(41)
 U34 M_J_DQ<40> DDR2_DQ<40> @BASEBOARD_FAB2_LIB.BASEBOARD_FAB2(SCH_1):M_J_DQ(40)
AA38 M_J_DQ<39> DDR2_DQ<39> @BASEBOARD_FAB2_LIB.BASEBOARD_FAB2(SCH_1):M_J_DQ(39)
 U38 M_J_DQ<38> DDR2_DQ<38> @BASEBOARD_FAB2_LIB.BASEBOARD_FAB2(SCH_1):M_J_DQ(38)
 Y41 M_J_DQ<37> DDR2_DQ<37> @BASEBOARD_FAB2_LIB.BASEBOARD_FAB2(SCH_1):M_J_DQ(37)
 V41 M_J_DQ<36> DDR2_DQ<36> @BASEBOARD_FAB2_LIB.BASEBOARD_FAB2(SCH_1):M_J_DQ(36)
 Y37 M_J_DQ<35> DDR2_DQ<35> @BASEBOARD_FAB2_LIB.BASEBOARD_FAB2(SCH_1):M_J_DQ(35)
 V37 M_J_DQ<34> DDR2_DQ<34> @BASEBOARD_FAB2_LIB.BASEBOARD_FAB2(SCH_1):M_J_DQ(34)
AA40 M_J_DQ<33> DDR2_DQ<33> @BASEBOARD_FAB2_LIB.BASEBOARD_FAB2(SCH_1):M_J_DQ(33)
 U40 M_J_DQ<32> DDR2_DQ<32> @BASEBOARD_FAB2_LIB.BASEBOARD_FAB2(SCH_1):M_J_DQ(32)
AT65 M_J_DQ<31> DDR2_DQ<31> @BASEBOARD_FAB2_LIB.BASEBOARD_FAB2(SCH_1):M_J_DQ(31)
AM65 M_J_DQ<30> DDR2_DQ<30> @BASEBOARD_FAB2_LIB.BASEBOARD_FAB2(SCH_1):M_J_DQ(30)
AR68 M_J_DQ<29> DDR2_DQ<29> @BASEBOARD_FAB2_LIB.BASEBOARD_FAB2(SCH_1):M_J_DQ(29)
AN68 M_J_DQ<28> DDR2_DQ<28> @BASEBOARD_FAB2_LIB.BASEBOARD_FAB2(SCH_1):M_J_DQ(28)
AR64 M_J_DQ<27> DDR2_DQ<27> @BASEBOARD_FAB2_LIB.BASEBOARD_FAB2(SCH_1):M_J_DQ(27)
AN64 M_J_DQ<26> DDR2_DQ<26> @BASEBOARD_FAB2_LIB.BASEBOARD_FAB2(SCH_1):M_J_DQ(26)
AT67 M_J_DQ<25> DDR2_DQ<25> @BASEBOARD_FAB2_LIB.BASEBOARD_FAB2(SCH_1):M_J_DQ(25)
AM67 M_J_DQ<24> DDR2_DQ<24> @BASEBOARD_FAB2_LIB.BASEBOARD_FAB2(SCH_1):M_J_DQ(24)
 V69 M_J_DQ<23> DDR2_DQ<23> @BASEBOARD_FAB2_LIB.BASEBOARD_FAB2(SCH_1):M_J_DQ(23)
 T71 M_J_DQ<22> DDR2_DQ<22> @BASEBOARD_FAB2_LIB.BASEBOARD_FAB2(SCH_1):M_J_DQ(22)
AB71 M_J_DQ<21> DDR2_DQ<21> @BASEBOARD_FAB2_LIB.BASEBOARD_FAB2(SCH_1):M_J_DQ(21)
AA72 M_J_DQ<20> DDR2_DQ<20> @BASEBOARD_FAB2_LIB.BASEBOARD_FAB2(SCH_1):M_J_DQ(20)
 T69 M_J_DQ<19> DDR2_DQ<19> @BASEBOARD_FAB2_LIB.BASEBOARD_FAB2(SCH_1):M_J_DQ(19)
 R70 M_J_DQ<18> DDR2_DQ<18> @BASEBOARD_FAB2_LIB.BASEBOARD_FAB2(SCH_1):M_J_DQ(18)
AA70 M_J_DQ<17> DDR2_DQ<17> @BASEBOARD_FAB2_LIB.BASEBOARD_FAB2(SCH_1):M_J_DQ(17)
 W72 M_J_DQ<16> DDR2_DQ<16> @BASEBOARD_FAB2_LIB.BASEBOARD_FAB2(SCH_1):M_J_DQ(16)
 Y75 M_J_DQ<15> DDR2_DQ<15> @BASEBOARD_FAB2_LIB.BASEBOARD_FAB2(SCH_1):M_J_DQ(15)
AB77 M_J_DQ<14> DDR2_DQ<14> @BASEBOARD_FAB2_LIB.BASEBOARD_FAB2(SCH_1):M_J_DQ(14)
AE74 M_J_DQ<13> DDR2_DQ<13> @BASEBOARD_FAB2_LIB.BASEBOARD_FAB2(SCH_1):M_J_DQ(13)
AF75 M_J_DQ<12> DDR2_DQ<12> @BASEBOARD_FAB2_LIB.BASEBOARD_FAB2(SCH_1):M_J_DQ(12)
 W76 M_J_DQ<11> DDR2_DQ<11> @BASEBOARD_FAB2_LIB.BASEBOARD_FAB2(SCH_1):M_J_DQ(11)
 Y77 M_J_DQ<10> DDR2_DQ<10> @BASEBOARD_FAB2_LIB.BASEBOARD_FAB2(SCH_1):M_J_DQ(10)
AC74 M_J_DQ<9> DDR2_DQ<9> @BASEBOARD_FAB2_LIB.BASEBOARD_FAB2(SCH_1):M_J_DQ(9)
AE76 M_J_DQ<8> DDR2_DQ<8> @BASEBOARD_FAB2_LIB.BASEBOARD_FAB2(SCH_1):M_J_DQ(8)
AK75 M_J_DQ<7> DDR2_DQ<7> @BASEBOARD_FAB2_LIB.BASEBOARD_FAB2(SCH_1):M_J_DQ(7)
AM77 M_J_DQ<6> DDR2_DQ<6> @BASEBOARD_FAB2_LIB.BASEBOARD_FAB2(SCH_1):M_J_DQ(6)
AR74 M_J_DQ<5> DDR2_DQ<5> @BASEBOARD_FAB2_LIB.BASEBOARD_FAB2(SCH_1):M_J_DQ(5)
AT75 M_J_DQ<4> DDR2_DQ<4> @BASEBOARD_FAB2_LIB.BASEBOARD_FAB2(SCH_1):M_J_DQ(4)
AJ76 M_J_DQ<3> DDR2_DQ<3> @BASEBOARD_FAB2_LIB.BASEBOARD_FAB2(SCH_1):M_J_DQ(3)
AK77 M_J_DQ<2> DDR2_DQ<2> @BASEBOARD_FAB2_LIB.BASEBOARD_FAB2(SCH_1):M_J_DQ(2)
AN74 M_J_DQ<1> DDR2_DQ<1> @BASEBOARD_FAB2_LIB.BASEBOARD_FAB2(SCH_1):M_J_DQ(1)
AR76 M_J_DQ<0> DDR2_DQ<0> @BASEBOARD_FAB2_LIB.BASEBOARD_FAB2(SCH_1):M_J_DQ(0)
AT71 M_J_DQS_DN<17> DDR2_DQS_DN<17> @BASEBOARD_FAB2_LIB.BASEBOARD_FAB2(SCH_1):M_J_DQS_DN(17)
AC24 M_J_DQS_DN<16> DDR2_DQS_DN<16> @BASEBOARD_FAB2_LIB.BASEBOARD_FAB2(SCH_1):M_J_DQS_DN(16)
AC30 M_J_DQS_DN<15> DDR2_DQS_DN<15> @BASEBOARD_FAB2_LIB.BASEBOARD_FAB2(SCH_1):M_J_DQS_DN(15)
 T33 M_J_DQS_DN<14> DDR2_DQS_DN<14> @BASEBOARD_FAB2_LIB.BASEBOARD_FAB2(SCH_1):M_J_DQS_DN(14)
 T39 M_J_DQS_DN<13> DDR2_DQS_DN<13> @BASEBOARD_FAB2_LIB.BASEBOARD_FAB2(SCH_1):M_J_DQS_DN(13)
AL66 M_J_DQS_DN<12> DDR2_DQS_DN<12> @BASEBOARD_FAB2_LIB.BASEBOARD_FAB2(SCH_1):M_J_DQS_DN(12)
 U72 M_J_DQS_DN<11> DDR2_DQS_DN<11> @BASEBOARD_FAB2_LIB.BASEBOARD_FAB2(SCH_1):M_J_DQS_DN(11)
AD77 M_J_DQS_DN<10> DDR2_DQS_DN<10> @BASEBOARD_FAB2_LIB.BASEBOARD_FAB2(SCH_1):M_J_DQS_DN(10)
AP77 M_J_DQS_DN<9> DDR2_DQS_DN<9> @BASEBOARD_FAB2_LIB.BASEBOARD_FAB2(SCH_1):M_J_DQS_DN(9)
BB71 M_J_DQS_DN<8> DDR2_DQS_DN<8> @BASEBOARD_FAB2_LIB.BASEBOARD_FAB2(SCH_1):M_J_DQS_DN(8)
AJ24 M_J_DQS_DN<7> DDR2_DQS_DN<7> @BASEBOARD_FAB2_LIB.BASEBOARD_FAB2(SCH_1):M_J_DQS_DN(7)
AJ30 M_J_DQS_DN<6> DDR2_DQS_DN<6> @BASEBOARD_FAB2_LIB.BASEBOARD_FAB2(SCH_1):M_J_DQS_DN(6)
AB33 M_J_DQS_DN<5> DDR2_DQS_DN<5> @BASEBOARD_FAB2_LIB.BASEBOARD_FAB2(SCH_1):M_J_DQS_DN(5)
AB39 M_J_DQS_DN<4> DDR2_DQS_DN<4> @BASEBOARD_FAB2_LIB.BASEBOARD_FAB2(SCH_1):M_J_DQS_DN(4)
AU66 M_J_DQS_DN<3> DDR2_DQS_DN<3> @BASEBOARD_FAB2_LIB.BASEBOARD_FAB2(SCH_1):M_J_DQS_DN(3)
 Y69 M_J_DQS_DN<2> DDR2_DQS_DN<2> @BASEBOARD_FAB2_LIB.BASEBOARD_FAB2(SCH_1):M_J_DQS_DN(2)
AA74 M_J_DQS_DN<1> DDR2_DQS_DN<1> @BASEBOARD_FAB2_LIB.BASEBOARD_FAB2(SCH_1):M_J_DQS_DN(1)
AL74 M_J_DQS_DN<0> DDR2_DQS_DN<0> @BASEBOARD_FAB2_LIB.BASEBOARD_FAB2(SCH_1):M_J_DQS_DN(0)
AV71 M_J_DQS_DP<17> DDR2_DQS_DP<17> @BASEBOARD_FAB2_LIB.BASEBOARD_FAB2(SCH_1):M_J_DQS_DP(17)
AE24 M_J_DQS_DP<16> DDR2_DQS_DP<16> @BASEBOARD_FAB2_LIB.BASEBOARD_FAB2(SCH_1):M_J_DQS_DP(16)
AE30 M_J_DQS_DP<15> DDR2_DQS_DP<15> @BASEBOARD_FAB2_LIB.BASEBOARD_FAB2(SCH_1):M_J_DQS_DP(15)
 V33 M_J_DQS_DP<14> DDR2_DQS_DP<14> @BASEBOARD_FAB2_LIB.BASEBOARD_FAB2(SCH_1):M_J_DQS_DP(14)
 V39 M_J_DQS_DP<13> DDR2_DQS_DP<13> @BASEBOARD_FAB2_LIB.BASEBOARD_FAB2(SCH_1):M_J_DQS_DP(13)
AN66 M_J_DQS_DP<12> DDR2_DQS_DP<12> @BASEBOARD_FAB2_LIB.BASEBOARD_FAB2(SCH_1):M_J_DQS_DP(12)
 V71 M_J_DQS_DP<11> DDR2_DQS_DP<11> @BASEBOARD_FAB2_LIB.BASEBOARD_FAB2(SCH_1):M_J_DQS_DP(11)
AC76 M_J_DQS_DP<10> DDR2_DQS_DP<10> @BASEBOARD_FAB2_LIB.BASEBOARD_FAB2(SCH_1):M_J_DQS_DP(10)
AN76 M_J_DQS_DP<9> DDR2_DQS_DP<9> @BASEBOARD_FAB2_LIB.BASEBOARD_FAB2(SCH_1):M_J_DQS_DP(9)
AY71 M_J_DQS_DP<8> DDR2_DQS_DP<8> @BASEBOARD_FAB2_LIB.BASEBOARD_FAB2(SCH_1):M_J_DQS_DP(8)
AG24 M_J_DQS_DP<7> DDR2_DQS_DP<7> @BASEBOARD_FAB2_LIB.BASEBOARD_FAB2(SCH_1):M_J_DQS_DP(7)
AG30 M_J_DQS_DP<6> DDR2_DQS_DP<6> @BASEBOARD_FAB2_LIB.BASEBOARD_FAB2(SCH_1):M_J_DQS_DP(6)
 Y33 M_J_DQS_DP<5> DDR2_DQS_DP<5> @BASEBOARD_FAB2_LIB.BASEBOARD_FAB2(SCH_1):M_J_DQS_DP(5)
 Y39 M_J_DQS_DP<4> DDR2_DQS_DP<4> @BASEBOARD_FAB2_LIB.BASEBOARD_FAB2(SCH_1):M_J_DQS_DP(4)
AR66 M_J_DQS_DP<3> DDR2_DQS_DP<3> @BASEBOARD_FAB2_LIB.BASEBOARD_FAB2(SCH_1):M_J_DQS_DP(3)
 W70 M_J_DQS_DP<2> DDR2_DQS_DP<2> @BASEBOARD_FAB2_LIB.BASEBOARD_FAB2(SCH_1):M_J_DQS_DP(2)
AB75 M_J_DQS_DP<1> DDR2_DQS_DP<1> @BASEBOARD_FAB2_LIB.BASEBOARD_FAB2(SCH_1):M_J_DQS_DP(1)
AM75 M_J_DQS_DP<0> DDR2_DQS_DP<0> @BASEBOARD_FAB2_LIB.BASEBOARD_FAB2(SCH_1):M_J_DQS_DP(0)
BA70 M_J_ECC<7> DDR2_ECC<7> @BASEBOARD_FAB2_LIB.BASEBOARD_FAB2(SCH_1):M_J_ECC(7)
AU70 M_J_ECC<6> DDR2_ECC<6> @BASEBOARD_FAB2_LIB.BASEBOARD_FAB2(SCH_1):M_J_ECC(6)
AY73 M_J_ECC<5> DDR2_ECC<5> @BASEBOARD_FAB2_LIB.BASEBOARD_FAB2(SCH_1):M_J_ECC(5)
AV73 M_J_ECC<4> DDR2_ECC<4> @BASEBOARD_FAB2_LIB.BASEBOARD_FAB2(SCH_1):M_J_ECC(4)
AY69 M_J_ECC<3> DDR2_ECC<3> @BASEBOARD_FAB2_LIB.BASEBOARD_FAB2(SCH_1):M_J_ECC(3)
AV69 M_J_ECC<2> DDR2_ECC<2> @BASEBOARD_FAB2_LIB.BASEBOARD_FAB2(SCH_1):M_J_ECC(2)
BA72 M_J_ECC<1> DDR2_ECC<1> @BASEBOARD_FAB2_LIB.BASEBOARD_FAB2(SCH_1):M_J_ECC(1)
AU72 M_J_ECC<0> DDR2_ECC<0> @BASEBOARD_FAB2_LIB.BASEBOARD_FAB2(SCH_1):M_J_ECC(0)
AC46 M_J_MA<17> DDR2_MA<17> @BASEBOARD_FAB2_LIB.BASEBOARD_FAB2(SCH_1):M_J_MA(17)
AA52 M_J_MA<16> DDR2_MA<16> @BASEBOARD_FAB2_LIB.BASEBOARD_FAB2(SCH_1):M_J_MA(16)
AE54 M_J_MA<15> DDR2_MA<15> @BASEBOARD_FAB2_LIB.BASEBOARD_FAB2(SCH_1):M_J_MA(15)
 W50 M_J_MA<14> DDR2_MA<14> @BASEBOARD_FAB2_LIB.BASEBOARD_FAB2(SCH_1):M_J_MA(14)
AD53 M_J_MA<13> DDR2_MA<13> @BASEBOARD_FAB2_LIB.BASEBOARD_FAB2(SCH_1):M_J_MA(13)
AG62 M_J_MA<12> DDR2_MA<12> @BASEBOARD_FAB2_LIB.BASEBOARD_FAB2(SCH_1):M_J_MA(12)
AG60 M_J_MA<11> DDR2_MA<11> @BASEBOARD_FAB2_LIB.BASEBOARD_FAB2(SCH_1):M_J_MA(11)
AD55 M_J_MA<10> DDR2_MA<10> @BASEBOARD_FAB2_LIB.BASEBOARD_FAB2(SCH_1):M_J_MA(10)
AG58 M_J_MA<9> DDR2_MA<9> @BASEBOARD_FAB2_LIB.BASEBOARD_FAB2(SCH_1):M_J_MA(9)
AD59 M_J_MA<8> DDR2_MA<8> @BASEBOARD_FAB2_LIB.BASEBOARD_FAB2(SCH_1):M_J_MA(8)
AE60 M_J_MA<7> DDR2_MA<7> @BASEBOARD_FAB2_LIB.BASEBOARD_FAB2(SCH_1):M_J_MA(7)
AB59 M_J_MA<6> DDR2_MA<6> @BASEBOARD_FAB2_LIB.BASEBOARD_FAB2(SCH_1):M_J_MA(6)
 V59 M_J_MA<5> DDR2_MA<5> @BASEBOARD_FAB2_LIB.BASEBOARD_FAB2(SCH_1):M_J_MA(5)
AA58 M_J_MA<4> DDR2_MA<4> @BASEBOARD_FAB2_LIB.BASEBOARD_FAB2(SCH_1):M_J_MA(4)
 W58 M_J_MA<3> DDR2_MA<3> @BASEBOARD_FAB2_LIB.BASEBOARD_FAB2(SCH_1):M_J_MA(3)
AD57 M_J_MA<2> DDR2_MA<2> @BASEBOARD_FAB2_LIB.BASEBOARD_FAB2(SCH_1):M_J_MA(2)
AE58 M_J_MA<1> DDR2_MA<1> @BASEBOARD_FAB2_LIB.BASEBOARD_FAB2(SCH_1):M_J_MA(1)
AB53 M_J_MA<0> DDR2_MA<0> @BASEBOARD_FAB2_LIB.BASEBOARD_FAB2(SCH_1):M_J_MA(0)
AB47 M_J_ODT<3> DDR2_ODT<3> @BASEBOARD_FAB2_LIB.BASEBOARD_FAB2(SCH_1):M_J_ODT(3)
 V49 M_J_ODT<2> DDR2_ODT<2> @BASEBOARD_FAB2_LIB.BASEBOARD_FAB2(SCH_1):M_J_ODT(2)
AA48 M_J_ODT<1> DDR2_ODT<1> @BASEBOARD_FAB2_LIB.BASEBOARD_FAB2(SCH_1):M_J_ODT(1)
AA50 M_J_ODT<0> DDR2_ODT<0> @BASEBOARD_FAB2_LIB.BASEBOARD_FAB2(SCH_1):M_J_ODT(0)
 V53 M_J_PAR DDR2_PAR @BASEBOARD_FAB2_LIB.BASEBOARD_FAB2(SCH_1):M_J_PAR


DRAWING: @BASEBOARD_FAB2_LIB.BASEBOARD_FAB2(SCH_1):PAGE60 

SKX_EXT_B_BGA1-IC,TBD  I172  U2D1
DW60 M_K_ACT_N DDR3_ACT_N @BASEBOARD_FAB2_LIB.BASEBOARD_FAB2(SCH_1):M_K_ACT_N
ED63 M_K_ALERT_N DDR3_ALERT_N @BASEBOARD_FAB2_LIB.BASEBOARD_FAB2(SCH_1):M_K_ALERT_N
EA54 M_K_BA<1> DDR3_BA<1> @BASEBOARD_FAB2_LIB.BASEBOARD_FAB2(SCH_1):M_K_BA(1)
EE52 M_K_BA<0> DDR3_BA<0> @BASEBOARD_FAB2_LIB.BASEBOARD_FAB2(SCH_1):M_K_BA(0)
DW62 M_K_BG<1> DDR3_BG<1> @BASEBOARD_FAB2_LIB.BASEBOARD_FAB2(SCH_1):M_K_BG(1)
ED61 M_K_BG<0> DDR3_BG<0> @BASEBOARD_FAB2_LIB.BASEBOARD_FAB2(SCH_1):M_K_BG(0)
DV47 M_K_C<2> DDR3_CID<2> @BASEBOARD_FAB2_LIB.BASEBOARD_FAB2(SCH_1):M_K_C(2)
EB63 M_K_CKE<3> DDR3_CKE<3> @BASEBOARD_FAB2_LIB.BASEBOARD_FAB2(SCH_1):M_K_CKE(3)
EA62 M_K_CKE<2> DDR3_CKE<2> @BASEBOARD_FAB2_LIB.BASEBOARD_FAB2(SCH_1):M_K_CKE(2)
EF63 M_K_CKE<1> DDR3_CKE<1> @BASEBOARD_FAB2_LIB.BASEBOARD_FAB2(SCH_1):M_K_CKE(1)
EE62 M_K_CKE<0> DDR3_CKE<0> @BASEBOARD_FAB2_LIB.BASEBOARD_FAB2(SCH_1):M_K_CKE(0)
EF57 M_K_CLK_DN<3> DDR3_CLK_DN<3> @BASEBOARD_FAB2_LIB.BASEBOARD_FAB2(SCH_1):M_K_CLK_DN(3)
DW56 M_K_CLK_DN<2> DDR3_CLK_DN<2> @BASEBOARD_FAB2_LIB.BASEBOARD_FAB2(SCH_1):M_K_CLK_DN(2)
EF55 M_K_CLK_DN<1> DDR3_CLK_DN<1> @BASEBOARD_FAB2_LIB.BASEBOARD_FAB2(SCH_1):M_K_CLK_DN(1)
ED55 M_K_CLK_DN<0> DDR3_CLK_DN<0> @BASEBOARD_FAB2_LIB.BASEBOARD_FAB2(SCH_1):M_K_CLK_DN(0)
EE56 M_K_CLK_DP<3> DDR3_CLK_DP<3> @BASEBOARD_FAB2_LIB.BASEBOARD_FAB2(SCH_1):M_K_CLK_DP(3)
EA56 M_K_CLK_DP<2> DDR3_CLK_DP<2> @BASEBOARD_FAB2_LIB.BASEBOARD_FAB2(SCH_1):M_K_CLK_DP(2)
EE54 M_K_CLK_DP<1> DDR3_CLK_DP<1> @BASEBOARD_FAB2_LIB.BASEBOARD_FAB2(SCH_1):M_K_CLK_DP(1)
EB55 M_K_CLK_DP<0> DDR3_CLK_DP<0> @BASEBOARD_FAB2_LIB.BASEBOARD_FAB2(SCH_1):M_K_CLK_DP(0)
EB45 M_K_CS_N<7> DDR3_CS_N<7> @BASEBOARD_FAB2_LIB.BASEBOARD_FAB2(SCH_1):M_K_CS_N(7)
DV45 M_K_CS_N<6> DDR3_CS_N<6> @BASEBOARD_FAB2_LIB.BASEBOARD_FAB2(SCH_1):M_K_CS_N(6)
EB49 M_K_CS_N<5> DDR3_CS_N<5> @BASEBOARD_FAB2_LIB.BASEBOARD_FAB2(SCH_1):M_K_CS_N(5)
EB51 M_K_CS_N<4> DDR3_CS_N<4> @BASEBOARD_FAB2_LIB.BASEBOARD_FAB2(SCH_1):M_K_CS_N(4)
EB47 M_K_CS_N<3> DDR3_CS_N<3> @BASEBOARD_FAB2_LIB.BASEBOARD_FAB2(SCH_1):M_K_CS_N(3)
ED47 M_K_CS_N<2> DDR3_CS_N<2> @BASEBOARD_FAB2_LIB.BASEBOARD_FAB2(SCH_1):M_K_CS_N(2)
ED49 M_K_CS_N<1> DDR3_CS_N<1> @BASEBOARD_FAB2_LIB.BASEBOARD_FAB2(SCH_1):M_K_CS_N(1)
EF51 M_K_CS_N<0> DDR3_CS_N<0> @BASEBOARD_FAB2_LIB.BASEBOARD_FAB2(SCH_1):M_K_CS_N(0)
DW22 M_K_DQ<63> DDR3_DQ<63> @BASEBOARD_FAB2_LIB.BASEBOARD_FAB2(SCH_1):M_K_DQ(63)
EC22 M_K_DQ<62> DDR3_DQ<62> @BASEBOARD_FAB2_LIB.BASEBOARD_FAB2(SCH_1):M_K_DQ(62)
DT25 M_K_DQ<61> DDR3_DQ<61> @BASEBOARD_FAB2_LIB.BASEBOARD_FAB2(SCH_1):M_K_DQ(61)
DP25 M_K_DQ<60> DDR3_DQ<60> @BASEBOARD_FAB2_LIB.BASEBOARD_FAB2(SCH_1):M_K_DQ(60)
EB21 M_K_DQ<59> DDR3_DQ<59> @BASEBOARD_FAB2_LIB.BASEBOARD_FAB2(SCH_1):M_K_DQ(59)
DY21 M_K_DQ<58> DDR3_DQ<58> @BASEBOARD_FAB2_LIB.BASEBOARD_FAB2(SCH_1):M_K_DQ(58)
DU24 M_K_DQ<57> DDR3_DQ<57> @BASEBOARD_FAB2_LIB.BASEBOARD_FAB2(SCH_1):M_K_DQ(57)
DN24 M_K_DQ<56> DDR3_DQ<56> @BASEBOARD_FAB2_LIB.BASEBOARD_FAB2(SCH_1):M_K_DQ(56)
DU28 M_K_DQ<55> DDR3_DQ<55> @BASEBOARD_FAB2_LIB.BASEBOARD_FAB2(SCH_1):M_K_DQ(55)
DN28 M_K_DQ<54> DDR3_DQ<54> @BASEBOARD_FAB2_LIB.BASEBOARD_FAB2(SCH_1):M_K_DQ(54)
DT31 M_K_DQ<53> DDR3_DQ<53> @BASEBOARD_FAB2_LIB.BASEBOARD_FAB2(SCH_1):M_K_DQ(53)
DP31 M_K_DQ<52> DDR3_DQ<52> @BASEBOARD_FAB2_LIB.BASEBOARD_FAB2(SCH_1):M_K_DQ(52)
DT27 M_K_DQ<51> DDR3_DQ<51> @BASEBOARD_FAB2_LIB.BASEBOARD_FAB2(SCH_1):M_K_DQ(51)
DP27 M_K_DQ<50> DDR3_DQ<50> @BASEBOARD_FAB2_LIB.BASEBOARD_FAB2(SCH_1):M_K_DQ(50)
DU30 M_K_DQ<49> DDR3_DQ<49> @BASEBOARD_FAB2_LIB.BASEBOARD_FAB2(SCH_1):M_K_DQ(49)
DN30 M_K_DQ<48> DDR3_DQ<48> @BASEBOARD_FAB2_LIB.BASEBOARD_FAB2(SCH_1):M_K_DQ(48)
DU34 M_K_DQ<47> DDR3_DQ<47> @BASEBOARD_FAB2_LIB.BASEBOARD_FAB2(SCH_1):M_K_DQ(47)
DN34 M_K_DQ<46> DDR3_DQ<46> @BASEBOARD_FAB2_LIB.BASEBOARD_FAB2(SCH_1):M_K_DQ(46)
DT37 M_K_DQ<45> DDR3_DQ<45> @BASEBOARD_FAB2_LIB.BASEBOARD_FAB2(SCH_1):M_K_DQ(45)
DP37 M_K_DQ<44> DDR3_DQ<44> @BASEBOARD_FAB2_LIB.BASEBOARD_FAB2(SCH_1):M_K_DQ(44)
DT33 M_K_DQ<43> DDR3_DQ<43> @BASEBOARD_FAB2_LIB.BASEBOARD_FAB2(SCH_1):M_K_DQ(43)
DP33 M_K_DQ<42> DDR3_DQ<42> @BASEBOARD_FAB2_LIB.BASEBOARD_FAB2(SCH_1):M_K_DQ(42)
DU36 M_K_DQ<41> DDR3_DQ<41> @BASEBOARD_FAB2_LIB.BASEBOARD_FAB2(SCH_1):M_K_DQ(41)
DN36 M_K_DQ<40> DDR3_DQ<40> @BASEBOARD_FAB2_LIB.BASEBOARD_FAB2(SCH_1):M_K_DQ(40)
ED37 M_K_DQ<39> DDR3_DQ<39> @BASEBOARD_FAB2_LIB.BASEBOARD_FAB2(SCH_1):M_K_DQ(39)
DY37 M_K_DQ<38> DDR3_DQ<38> @BASEBOARD_FAB2_LIB.BASEBOARD_FAB2(SCH_1):M_K_DQ(38)
EA40 M_K_DQ<37> DDR3_DQ<37> @BASEBOARD_FAB2_LIB.BASEBOARD_FAB2(SCH_1):M_K_DQ(37)
DY39 M_K_DQ<36> DDR3_DQ<36> @BASEBOARD_FAB2_LIB.BASEBOARD_FAB2(SCH_1):M_K_DQ(36)
EC36 M_K_DQ<35> DDR3_DQ<35> @BASEBOARD_FAB2_LIB.BASEBOARD_FAB2(SCH_1):M_K_DQ(35)
EA36 M_K_DQ<34> DDR3_DQ<34> @BASEBOARD_FAB2_LIB.BASEBOARD_FAB2(SCH_1):M_K_DQ(34)
ED39 M_K_DQ<33> DDR3_DQ<33> @BASEBOARD_FAB2_LIB.BASEBOARD_FAB2(SCH_1):M_K_DQ(33)
EC40 M_K_DQ<32> DDR3_DQ<32> @BASEBOARD_FAB2_LIB.BASEBOARD_FAB2(SCH_1):M_K_DQ(32)
DU74 M_K_DQ<31> DDR3_DQ<31> @BASEBOARD_FAB2_LIB.BASEBOARD_FAB2(SCH_1):M_K_DQ(31)
DN74 M_K_DQ<30> DDR3_DQ<30> @BASEBOARD_FAB2_LIB.BASEBOARD_FAB2(SCH_1):M_K_DQ(30)
DT77 M_K_DQ<29> DDR3_DQ<29> @BASEBOARD_FAB2_LIB.BASEBOARD_FAB2(SCH_1):M_K_DQ(29)
DP77 M_K_DQ<28> DDR3_DQ<28> @BASEBOARD_FAB2_LIB.BASEBOARD_FAB2(SCH_1):M_K_DQ(28)
DT73 M_K_DQ<27> DDR3_DQ<27> @BASEBOARD_FAB2_LIB.BASEBOARD_FAB2(SCH_1):M_K_DQ(27)
DP73 M_K_DQ<26> DDR3_DQ<26> @BASEBOARD_FAB2_LIB.BASEBOARD_FAB2(SCH_1):M_K_DQ(26)
DU76 M_K_DQ<25> DDR3_DQ<25> @BASEBOARD_FAB2_LIB.BASEBOARD_FAB2(SCH_1):M_K_DQ(25)
DN76 M_K_DQ<24> DDR3_DQ<24> @BASEBOARD_FAB2_LIB.BASEBOARD_FAB2(SCH_1):M_K_DQ(24)
DN82 M_K_DQ<23> DDR3_DQ<23> @BASEBOARD_FAB2_LIB.BASEBOARD_FAB2(SCH_1):M_K_DQ(23)
DR80 M_K_DQ<22> DDR3_DQ<22> @BASEBOARD_FAB2_LIB.BASEBOARD_FAB2(SCH_1):M_K_DQ(22)
DJ80 M_K_DQ<21> DDR3_DQ<21> @BASEBOARD_FAB2_LIB.BASEBOARD_FAB2(SCH_1):M_K_DQ(21)
DK79 M_K_DQ<20> DDR3_DQ<20> @BASEBOARD_FAB2_LIB.BASEBOARD_FAB2(SCH_1):M_K_DQ(20)
DR82 M_K_DQ<19> DDR3_DQ<19> @BASEBOARD_FAB2_LIB.BASEBOARD_FAB2(SCH_1):M_K_DQ(19)
DT81 M_K_DQ<18> DDR3_DQ<18> @BASEBOARD_FAB2_LIB.BASEBOARD_FAB2(SCH_1):M_K_DQ(18)
DK81 M_K_DQ<17> DDR3_DQ<17> @BASEBOARD_FAB2_LIB.BASEBOARD_FAB2(SCH_1):M_K_DQ(17)
DM79 M_K_DQ<16> DDR3_DQ<16> @BASEBOARD_FAB2_LIB.BASEBOARD_FAB2(SCH_1):M_K_DQ(16)
DV85 M_K_DQ<15> DDR3_DQ<15> @BASEBOARD_FAB2_LIB.BASEBOARD_FAB2(SCH_1):M_K_DQ(15)
DR84 M_K_DQ<14> DDR3_DQ<14> @BASEBOARD_FAB2_LIB.BASEBOARD_FAB2(SCH_1):M_K_DQ(14)
DE84 M_K_DQ<13> DDR3_DQ<13> @BASEBOARD_FAB2_LIB.BASEBOARD_FAB2(SCH_1):M_K_DQ(13)
DD85 M_K_DQ<12> DDR3_DQ<12> @BASEBOARD_FAB2_LIB.BASEBOARD_FAB2(SCH_1):M_K_DQ(12)
DY83 M_K_DQ<11> DDR3_DQ<11> @BASEBOARD_FAB2_LIB.BASEBOARD_FAB2(SCH_1):M_K_DQ(11)
DV83 M_K_DQ<10> DDR3_DQ<10> @BASEBOARD_FAB2_LIB.BASEBOARD_FAB2(SCH_1):M_K_DQ(10)
DH85 M_K_DQ<9> DDR3_DQ<9> @BASEBOARD_FAB2_LIB.BASEBOARD_FAB2(SCH_1):M_K_DQ(9)
DG84 M_K_DQ<8> DDR3_DQ<8> @BASEBOARD_FAB2_LIB.BASEBOARD_FAB2(SCH_1):M_K_DQ(8)
CW84 M_K_DQ<7> DDR3_DQ<7> @BASEBOARD_FAB2_LIB.BASEBOARD_FAB2(SCH_1):M_K_DQ(7)
CW86 M_K_DQ<6> DDR3_DQ<6> @BASEBOARD_FAB2_LIB.BASEBOARD_FAB2(SCH_1):M_K_DQ(6)
CL86 M_K_DQ<5> DDR3_DQ<5> @BASEBOARD_FAB2_LIB.BASEBOARD_FAB2(SCH_1):M_K_DQ(5)
CL84 M_K_DQ<4> DDR3_DQ<4> @BASEBOARD_FAB2_LIB.BASEBOARD_FAB2(SCH_1):M_K_DQ(4)
DA84 M_K_DQ<3> DDR3_DQ<3> @BASEBOARD_FAB2_LIB.BASEBOARD_FAB2(SCH_1):M_K_DQ(3)
DA86 M_K_DQ<2> DDR3_DQ<2> @BASEBOARD_FAB2_LIB.BASEBOARD_FAB2(SCH_1):M_K_DQ(2)
CN86 M_K_DQ<1> DDR3_DQ<1> @BASEBOARD_FAB2_LIB.BASEBOARD_FAB2(SCH_1):M_K_DQ(1)
CN84 M_K_DQ<0> DDR3_DQ<0> @BASEBOARD_FAB2_LIB.BASEBOARD_FAB2(SCH_1):M_K_DQ(0)
DB67 M_K_DQS_DN<17> DDR3_DQS_DN<17> @BASEBOARD_FAB2_LIB.BASEBOARD_FAB2(SCH_1):M_K_DQS_DN(17)
DM23 M_K_DQS_DN<16> DDR3_DQS_DN<16> @BASEBOARD_FAB2_LIB.BASEBOARD_FAB2(SCH_1):M_K_DQS_DN(16)
DM29 M_K_DQS_DN<15> DDR3_DQS_DN<15> @BASEBOARD_FAB2_LIB.BASEBOARD_FAB2(SCH_1):M_K_DQS_DN(15)
DP35 M_K_DQS_DN<14> DDR3_DQS_DN<14> @BASEBOARD_FAB2_LIB.BASEBOARD_FAB2(SCH_1):M_K_DQS_DN(14)
EA38 M_K_DQS_DN<13> DDR3_DQS_DN<13> @BASEBOARD_FAB2_LIB.BASEBOARD_FAB2(SCH_1):M_K_DQS_DN(13)
DP75 M_K_DQS_DN<12> DDR3_DQS_DN<12> @BASEBOARD_FAB2_LIB.BASEBOARD_FAB2(SCH_1):M_K_DQS_DN(12)
DN80 M_K_DQS_DN<11> DDR3_DQS_DN<11> @BASEBOARD_FAB2_LIB.BASEBOARD_FAB2(SCH_1):M_K_DQS_DN(11)
DM85 M_K_DQS_DN<10> DDR3_DQS_DN<10> @BASEBOARD_FAB2_LIB.BASEBOARD_FAB2(SCH_1):M_K_DQS_DN(10)
CR84 M_K_DQS_DN<9> DDR3_DQS_DN<9> @BASEBOARD_FAB2_LIB.BASEBOARD_FAB2(SCH_1):M_K_DQS_DN(9)
DF67 M_K_DQS_DN<8> DDR3_DQS_DN<8> @BASEBOARD_FAB2_LIB.BASEBOARD_FAB2(SCH_1):M_K_DQS_DN(8)
DV23 M_K_DQS_DN<7> DDR3_DQS_DN<7> @BASEBOARD_FAB2_LIB.BASEBOARD_FAB2(SCH_1):M_K_DQS_DN(7)
DV29 M_K_DQS_DN<6> DDR3_DQS_DN<6> @BASEBOARD_FAB2_LIB.BASEBOARD_FAB2(SCH_1):M_K_DQS_DN(6)
DV35 M_K_DQS_DN<5> DDR3_DQS_DN<5> @BASEBOARD_FAB2_LIB.BASEBOARD_FAB2(SCH_1):M_K_DQS_DN(5)
EE38 M_K_DQS_DN<4> DDR3_DQS_DN<4> @BASEBOARD_FAB2_LIB.BASEBOARD_FAB2(SCH_1):M_K_DQS_DN(4)
DV75 M_K_DQS_DN<3> DDR3_DQS_DN<3> @BASEBOARD_FAB2_LIB.BASEBOARD_FAB2(SCH_1):M_K_DQS_DN(3)
DL82 M_K_DQS_DN<2> DDR3_DQS_DN<2> @BASEBOARD_FAB2_LIB.BASEBOARD_FAB2(SCH_1):M_K_DQS_DN(2)
DN84 M_K_DQS_DN<1> DDR3_DQS_DN<1> @BASEBOARD_FAB2_LIB.BASEBOARD_FAB2(SCH_1):M_K_DQS_DN(1)
CU84 M_K_DQS_DN<0> DDR3_DQS_DN<0> @BASEBOARD_FAB2_LIB.BASEBOARD_FAB2(SCH_1):M_K_DQS_DN(0)
CY67 M_K_DQS_DP<17> DDR3_DQS_DP<17> @BASEBOARD_FAB2_LIB.BASEBOARD_FAB2(SCH_1):M_K_DQS_DP(17)
DP23 M_K_DQS_DP<16> DDR3_DQS_DP<16> @BASEBOARD_FAB2_LIB.BASEBOARD_FAB2(SCH_1):M_K_DQS_DP(16)
DP29 M_K_DQS_DP<15> DDR3_DQS_DP<15> @BASEBOARD_FAB2_LIB.BASEBOARD_FAB2(SCH_1):M_K_DQS_DP(15)
DM35 M_K_DQS_DP<14> DDR3_DQS_DP<14> @BASEBOARD_FAB2_LIB.BASEBOARD_FAB2(SCH_1):M_K_DQS_DP(14)
DW38 M_K_DQS_DP<13> DDR3_DQS_DP<13> @BASEBOARD_FAB2_LIB.BASEBOARD_FAB2(SCH_1):M_K_DQS_DP(13)
DM75 M_K_DQS_DP<12> DDR3_DQS_DP<12> @BASEBOARD_FAB2_LIB.BASEBOARD_FAB2(SCH_1):M_K_DQS_DP(12)
DP79 M_K_DQS_DP<11> DDR3_DQS_DP<11> @BASEBOARD_FAB2_LIB.BASEBOARD_FAB2(SCH_1):M_K_DQS_DP(11)
DL84 M_K_DQS_DP<10> DDR3_DQS_DP<10> @BASEBOARD_FAB2_LIB.BASEBOARD_FAB2(SCH_1):M_K_DQS_DP(10)
CP85 M_K_DQS_DP<9> DDR3_DQS_DP<9> @BASEBOARD_FAB2_LIB.BASEBOARD_FAB2(SCH_1):M_K_DQS_DP(9)
DD67 M_K_DQS_DP<8> DDR3_DQS_DP<8> @BASEBOARD_FAB2_LIB.BASEBOARD_FAB2(SCH_1):M_K_DQS_DP(8)
DT23 M_K_DQS_DP<7> DDR3_DQS_DP<7> @BASEBOARD_FAB2_LIB.BASEBOARD_FAB2(SCH_1):M_K_DQS_DP(7)
DT29 M_K_DQS_DP<6> DDR3_DQS_DP<6> @BASEBOARD_FAB2_LIB.BASEBOARD_FAB2(SCH_1):M_K_DQS_DP(6)
DT35 M_K_DQS_DP<5> DDR3_DQS_DP<5> @BASEBOARD_FAB2_LIB.BASEBOARD_FAB2(SCH_1):M_K_DQS_DP(5)
EC38 M_K_DQS_DP<4> DDR3_DQS_DP<4> @BASEBOARD_FAB2_LIB.BASEBOARD_FAB2(SCH_1):M_K_DQS_DP(4)
DT75 M_K_DQS_DP<3> DDR3_DQS_DP<3> @BASEBOARD_FAB2_LIB.BASEBOARD_FAB2(SCH_1):M_K_DQS_DP(3)
DM81 M_K_DQS_DP<2> DDR3_DQS_DP<2> @BASEBOARD_FAB2_LIB.BASEBOARD_FAB2(SCH_1):M_K_DQS_DP(2)
DP85 M_K_DQS_DP<1> DDR3_DQS_DP<1> @BASEBOARD_FAB2_LIB.BASEBOARD_FAB2(SCH_1):M_K_DQS_DP(1)
CV85 M_K_DQS_DP<0> DDR3_DQS_DP<0> @BASEBOARD_FAB2_LIB.BASEBOARD_FAB2(SCH_1):M_K_DQS_DP(0)
DE66 M_K_ECC<7> DDR3_ECC<7> @BASEBOARD_FAB2_LIB.BASEBOARD_FAB2(SCH_1):M_K_ECC(7)
DA66 M_K_ECC<6> DDR3_ECC<6> @BASEBOARD_FAB2_LIB.BASEBOARD_FAB2(SCH_1):M_K_ECC(6)
DD69 M_K_ECC<5> DDR3_ECC<5> @BASEBOARD_FAB2_LIB.BASEBOARD_FAB2(SCH_1):M_K_ECC(5)
DB69 M_K_ECC<4> DDR3_ECC<4> @BASEBOARD_FAB2_LIB.BASEBOARD_FAB2(SCH_1):M_K_ECC(4)
DD65 M_K_ECC<3> DDR3_ECC<3> @BASEBOARD_FAB2_LIB.BASEBOARD_FAB2(SCH_1):M_K_ECC(3)
DB65 M_K_ECC<2> DDR3_ECC<2> @BASEBOARD_FAB2_LIB.BASEBOARD_FAB2(SCH_1):M_K_ECC(2)
DE68 M_K_ECC<1> DDR3_ECC<1> @BASEBOARD_FAB2_LIB.BASEBOARD_FAB2(SCH_1):M_K_ECC(1)
DA68 M_K_ECC<0> DDR3_ECC<0> @BASEBOARD_FAB2_LIB.BASEBOARD_FAB2(SCH_1):M_K_ECC(0)
EA46 M_K_MA<17> DDR3_MA<17> @BASEBOARD_FAB2_LIB.BASEBOARD_FAB2(SCH_1):M_K_MA(17)
EA52 M_K_MA<16> DDR3_MA<16> @BASEBOARD_FAB2_LIB.BASEBOARD_FAB2(SCH_1):M_K_MA(16)
DV49 M_K_MA<15> DDR3_MA<15> @BASEBOARD_FAB2_LIB.BASEBOARD_FAB2(SCH_1):M_K_MA(15)
ED51 M_K_MA<14> DDR3_MA<14> @BASEBOARD_FAB2_LIB.BASEBOARD_FAB2(SCH_1):M_K_MA(14)
DW48 M_K_MA<13> DDR3_MA<13> @BASEBOARD_FAB2_LIB.BASEBOARD_FAB2(SCH_1):M_K_MA(13)
DT63 M_K_MA<12> DDR3_MA<12> @BASEBOARD_FAB2_LIB.BASEBOARD_FAB2(SCH_1):M_K_MA(12)
EB61 M_K_MA<11> DDR3_MA<11> @BASEBOARD_FAB2_LIB.BASEBOARD_FAB2(SCH_1):M_K_MA(11)
DW54 M_K_MA<10> DDR3_MA<10> @BASEBOARD_FAB2_LIB.BASEBOARD_FAB2(SCH_1):M_K_MA(10)
EF61 M_K_MA<9> DDR3_MA<9> @BASEBOARD_FAB2_LIB.BASEBOARD_FAB2(SCH_1):M_K_MA(9)
EB59 M_K_MA<8> DDR3_MA<8> @BASEBOARD_FAB2_LIB.BASEBOARD_FAB2(SCH_1):M_K_MA(8)
EA60 M_K_MA<7> DDR3_MA<7> @BASEBOARD_FAB2_LIB.BASEBOARD_FAB2(SCH_1):M_K_MA(7)
EE60 M_K_MA<6> DDR3_MA<6> @BASEBOARD_FAB2_LIB.BASEBOARD_FAB2(SCH_1):M_K_MA(6)
EA58 M_K_MA<5> DDR3_MA<5> @BASEBOARD_FAB2_LIB.BASEBOARD_FAB2(SCH_1):M_K_MA(5)
ED59 M_K_MA<4> DDR3_MA<4> @BASEBOARD_FAB2_LIB.BASEBOARD_FAB2(SCH_1):M_K_MA(4)
EB57 M_K_MA<3> DDR3_MA<3> @BASEBOARD_FAB2_LIB.BASEBOARD_FAB2(SCH_1):M_K_MA(3)
EE58 M_K_MA<2> DDR3_MA<2> @BASEBOARD_FAB2_LIB.BASEBOARD_FAB2(SCH_1):M_K_MA(2)
ED57 M_K_MA<1> DDR3_MA<1> @BASEBOARD_FAB2_LIB.BASEBOARD_FAB2(SCH_1):M_K_MA(1)
EB53 M_K_MA<0> DDR3_MA<0> @BASEBOARD_FAB2_LIB.BASEBOARD_FAB2(SCH_1):M_K_MA(0)
EA48 M_K_ODT<3> DDR3_ODT<3> @BASEBOARD_FAB2_LIB.BASEBOARD_FAB2(SCH_1):M_K_ODT(3)
EA50 M_K_ODT<2> DDR3_ODT<2> @BASEBOARD_FAB2_LIB.BASEBOARD_FAB2(SCH_1):M_K_ODT(2)
EE48 M_K_ODT<1> DDR3_ODT<1> @BASEBOARD_FAB2_LIB.BASEBOARD_FAB2(SCH_1):M_K_ODT(1)
EE50 M_K_ODT<0> DDR3_ODT<0> @BASEBOARD_FAB2_LIB.BASEBOARD_FAB2(SCH_1):M_K_ODT(0)
ED53 M_K_PAR DDR3_PAR @BASEBOARD_FAB2_LIB.BASEBOARD_FAB2(SCH_1):M_K_PAR


DRAWING: @BASEBOARD_FAB2_LIB.BASEBOARD_FAB2(SCH_1):PAGE61 

SKX_EXT_B_BGA1-IC,TBD  I172  U2D1
DR62 M_L_ACT_N DDR4_ACT_N @BASEBOARD_FAB2_LIB.BASEBOARD_FAB2(SCH_1):M_L_ACT_N
DT61 M_L_ALERT_N DDR4_ALERT_N @BASEBOARD_FAB2_LIB.BASEBOARD_FAB2(SCH_1):M_L_ALERT_N
DV55 M_L_BA<1> DDR4_BA<1> @BASEBOARD_FAB2_LIB.BASEBOARD_FAB2(SCH_1):M_L_BA(1)
DM53 M_L_BA<0> DDR4_BA<0> @BASEBOARD_FAB2_LIB.BASEBOARD_FAB2(SCH_1):M_L_BA(0)
DM61 M_L_BG<1> DDR4_BG<1> @BASEBOARD_FAB2_LIB.BASEBOARD_FAB2(SCH_1):M_L_BG(1)
DJ62 M_L_BG<0> DDR4_BG<0> @BASEBOARD_FAB2_LIB.BASEBOARD_FAB2(SCH_1):M_L_BG(0)
DT47 M_L_C<2> DDR4_CID<2> @BASEBOARD_FAB2_LIB.BASEBOARD_FAB2(SCH_1):M_L_C(2)
DR64 M_L_CKE<3> DDR4_CKE<3> @BASEBOARD_FAB2_LIB.BASEBOARD_FAB2(SCH_1):M_L_CKE(3)
DL64 M_L_CKE<2> DDR4_CKE<2> @BASEBOARD_FAB2_LIB.BASEBOARD_FAB2(SCH_1):M_L_CKE(2)
DN64 M_L_CKE<1> DDR4_CKE<1> @BASEBOARD_FAB2_LIB.BASEBOARD_FAB2(SCH_1):M_L_CKE(1)
DM63 M_L_CKE<0> DDR4_CKE<0> @BASEBOARD_FAB2_LIB.BASEBOARD_FAB2(SCH_1):M_L_CKE(0)
DT57 M_L_CLK_DN<3> DDR4_CLK_DN<3> @BASEBOARD_FAB2_LIB.BASEBOARD_FAB2(SCH_1):M_L_CLK_DN(3)
DM57 M_L_CLK_DN<2> DDR4_CLK_DN<2> @BASEBOARD_FAB2_LIB.BASEBOARD_FAB2(SCH_1):M_L_CLK_DN(2)
DR54 M_L_CLK_DN<1> DDR4_CLK_DN<1> @BASEBOARD_FAB2_LIB.BASEBOARD_FAB2(SCH_1):M_L_CLK_DN(1)
DM55 M_L_CLK_DN<0> DDR4_CLK_DN<0> @BASEBOARD_FAB2_LIB.BASEBOARD_FAB2(SCH_1):M_L_CLK_DN(0)
DR56 M_L_CLK_DP<3> DDR4_CLK_DP<3> @BASEBOARD_FAB2_LIB.BASEBOARD_FAB2(SCH_1):M_L_CLK_DP(3)
DN56 M_L_CLK_DP<2> DDR4_CLK_DP<2> @BASEBOARD_FAB2_LIB.BASEBOARD_FAB2(SCH_1):M_L_CLK_DP(2)
DT53 M_L_CLK_DP<1> DDR4_CLK_DP<1> @BASEBOARD_FAB2_LIB.BASEBOARD_FAB2(SCH_1):M_L_CLK_DP(1)
DN54 M_L_CLK_DP<0> DDR4_CLK_DP<0> @BASEBOARD_FAB2_LIB.BASEBOARD_FAB2(SCH_1):M_L_CLK_DP(0)
DN46 M_L_CS_N<7> DDR4_CS_N<7> @BASEBOARD_FAB2_LIB.BASEBOARD_FAB2(SCH_1):M_L_CS_N(7)
DT45 M_L_CS_N<6> DDR4_CS_N<6> @BASEBOARD_FAB2_LIB.BASEBOARD_FAB2(SCH_1):M_L_CS_N(6)
DM49 M_L_CS_N<5> DDR4_CS_N<5> @BASEBOARD_FAB2_LIB.BASEBOARD_FAB2(SCH_1):M_L_CS_N(5)
DW50 M_L_CS_N<4> DDR4_CS_N<4> @BASEBOARD_FAB2_LIB.BASEBOARD_FAB2(SCH_1):M_L_CS_N(4)
DK47 M_L_CS_N<3> DDR4_CS_N<3> @BASEBOARD_FAB2_LIB.BASEBOARD_FAB2(SCH_1):M_L_CS_N(3)
DR46 M_L_CS_N<2> DDR4_CS_N<2> @BASEBOARD_FAB2_LIB.BASEBOARD_FAB2(SCH_1):M_L_CS_N(2)
DN50 M_L_CS_N<1> DDR4_CS_N<1> @BASEBOARD_FAB2_LIB.BASEBOARD_FAB2(SCH_1):M_L_CS_N(1)
DV51 M_L_CS_N<0> DDR4_CS_N<0> @BASEBOARD_FAB2_LIB.BASEBOARD_FAB2(SCH_1):M_L_CS_N(0)
DK25 M_L_DQ<63> DDR4_DQ<63> @BASEBOARD_FAB2_LIB.BASEBOARD_FAB2(SCH_1):M_L_DQ(63)
DF25 M_L_DQ<62> DDR4_DQ<62> @BASEBOARD_FAB2_LIB.BASEBOARD_FAB2(SCH_1):M_L_DQ(62)
DJ28 M_L_DQ<61> DDR4_DQ<61> @BASEBOARD_FAB2_LIB.BASEBOARD_FAB2(SCH_1):M_L_DQ(61)
DG28 M_L_DQ<60> DDR4_DQ<60> @BASEBOARD_FAB2_LIB.BASEBOARD_FAB2(SCH_1):M_L_DQ(60)
DJ24 M_L_DQ<59> DDR4_DQ<59> @BASEBOARD_FAB2_LIB.BASEBOARD_FAB2(SCH_1):M_L_DQ(59)
DD25 M_L_DQ<58> DDR4_DQ<58> @BASEBOARD_FAB2_LIB.BASEBOARD_FAB2(SCH_1):M_L_DQ(58)
DK27 M_L_DQ<57> DDR4_DQ<57> @BASEBOARD_FAB2_LIB.BASEBOARD_FAB2(SCH_1):M_L_DQ(57)
DF27 M_L_DQ<56> DDR4_DQ<56> @BASEBOARD_FAB2_LIB.BASEBOARD_FAB2(SCH_1):M_L_DQ(56)
ED25 M_L_DQ<55> DDR4_DQ<55> @BASEBOARD_FAB2_LIB.BASEBOARD_FAB2(SCH_1):M_L_DQ(55)
DY25 M_L_DQ<54> DDR4_DQ<54> @BASEBOARD_FAB2_LIB.BASEBOARD_FAB2(SCH_1):M_L_DQ(54)
EA28 M_L_DQ<53> DDR4_DQ<53> @BASEBOARD_FAB2_LIB.BASEBOARD_FAB2(SCH_1):M_L_DQ(53)
DY27 M_L_DQ<52> DDR4_DQ<52> @BASEBOARD_FAB2_LIB.BASEBOARD_FAB2(SCH_1):M_L_DQ(52)
EC24 M_L_DQ<51> DDR4_DQ<51> @BASEBOARD_FAB2_LIB.BASEBOARD_FAB2(SCH_1):M_L_DQ(51)
EA24 M_L_DQ<50> DDR4_DQ<50> @BASEBOARD_FAB2_LIB.BASEBOARD_FAB2(SCH_1):M_L_DQ(50)
ED27 M_L_DQ<49> DDR4_DQ<49> @BASEBOARD_FAB2_LIB.BASEBOARD_FAB2(SCH_1):M_L_DQ(49)
EC28 M_L_DQ<48> DDR4_DQ<48> @BASEBOARD_FAB2_LIB.BASEBOARD_FAB2(SCH_1):M_L_DQ(48)
ED31 M_L_DQ<47> DDR4_DQ<47> @BASEBOARD_FAB2_LIB.BASEBOARD_FAB2(SCH_1):M_L_DQ(47)
DY31 M_L_DQ<46> DDR4_DQ<46> @BASEBOARD_FAB2_LIB.BASEBOARD_FAB2(SCH_1):M_L_DQ(46)
EA34 M_L_DQ<45> DDR4_DQ<45> @BASEBOARD_FAB2_LIB.BASEBOARD_FAB2(SCH_1):M_L_DQ(45)
DY33 M_L_DQ<44> DDR4_DQ<44> @BASEBOARD_FAB2_LIB.BASEBOARD_FAB2(SCH_1):M_L_DQ(44)
EC30 M_L_DQ<43> DDR4_DQ<43> @BASEBOARD_FAB2_LIB.BASEBOARD_FAB2(SCH_1):M_L_DQ(43)
EA30 M_L_DQ<42> DDR4_DQ<42> @BASEBOARD_FAB2_LIB.BASEBOARD_FAB2(SCH_1):M_L_DQ(42)
ED33 M_L_DQ<41> DDR4_DQ<41> @BASEBOARD_FAB2_LIB.BASEBOARD_FAB2(SCH_1):M_L_DQ(41)
EC34 M_L_DQ<40> DDR4_DQ<40> @BASEBOARD_FAB2_LIB.BASEBOARD_FAB2(SCH_1):M_L_DQ(40)
DU40 M_L_DQ<39> DDR4_DQ<39> @BASEBOARD_FAB2_LIB.BASEBOARD_FAB2(SCH_1):M_L_DQ(39)
DN40 M_L_DQ<38> DDR4_DQ<38> @BASEBOARD_FAB2_LIB.BASEBOARD_FAB2(SCH_1):M_L_DQ(38)
DN42 M_L_DQ<37> DDR4_DQ<37> @BASEBOARD_FAB2_LIB.BASEBOARD_FAB2(SCH_1):M_L_DQ(37)
DL42 M_L_DQ<36> DDR4_DQ<36> @BASEBOARD_FAB2_LIB.BASEBOARD_FAB2(SCH_1):M_L_DQ(36)
DT39 M_L_DQ<35> DDR4_DQ<35> @BASEBOARD_FAB2_LIB.BASEBOARD_FAB2(SCH_1):M_L_DQ(35)
DP39 M_L_DQ<34> DDR4_DQ<34> @BASEBOARD_FAB2_LIB.BASEBOARD_FAB2(SCH_1):M_L_DQ(34)
DW42 M_L_DQ<33> DDR4_DQ<33> @BASEBOARD_FAB2_LIB.BASEBOARD_FAB2(SCH_1):M_L_DQ(33)
DU42 M_L_DQ<32> DDR4_DQ<32> @BASEBOARD_FAB2_LIB.BASEBOARD_FAB2(SCH_1):M_L_DQ(32)
EE72 M_L_DQ<31> DDR4_DQ<31> @BASEBOARD_FAB2_LIB.BASEBOARD_FAB2(SCH_1):M_L_DQ(31)
EA72 M_L_DQ<30> DDR4_DQ<30> @BASEBOARD_FAB2_LIB.BASEBOARD_FAB2(SCH_1):M_L_DQ(30)
EB75 M_L_DQ<29> DDR4_DQ<29> @BASEBOARD_FAB2_LIB.BASEBOARD_FAB2(SCH_1):M_L_DQ(29)
EA74 M_L_DQ<28> DDR4_DQ<28> @BASEBOARD_FAB2_LIB.BASEBOARD_FAB2(SCH_1):M_L_DQ(28)
ED71 M_L_DQ<27> DDR4_DQ<27> @BASEBOARD_FAB2_LIB.BASEBOARD_FAB2(SCH_1):M_L_DQ(27)
EB71 M_L_DQ<26> DDR4_DQ<26> @BASEBOARD_FAB2_LIB.BASEBOARD_FAB2(SCH_1):M_L_DQ(26)
EE74 M_L_DQ<25> DDR4_DQ<25> @BASEBOARD_FAB2_LIB.BASEBOARD_FAB2(SCH_1):M_L_DQ(25)
ED75 M_L_DQ<24> DDR4_DQ<24> @BASEBOARD_FAB2_LIB.BASEBOARD_FAB2(SCH_1):M_L_DQ(24)
EC78 M_L_DQ<23> DDR4_DQ<23> @BASEBOARD_FAB2_LIB.BASEBOARD_FAB2(SCH_1):M_L_DQ(23)
DW78 M_L_DQ<22> DDR4_DQ<22> @BASEBOARD_FAB2_LIB.BASEBOARD_FAB2(SCH_1):M_L_DQ(22)
EB81 M_L_DQ<21> DDR4_DQ<21> @BASEBOARD_FAB2_LIB.BASEBOARD_FAB2(SCH_1):M_L_DQ(21)
DY81 M_L_DQ<20> DDR4_DQ<20> @BASEBOARD_FAB2_LIB.BASEBOARD_FAB2(SCH_1):M_L_DQ(20)
EB77 M_L_DQ<19> DDR4_DQ<19> @BASEBOARD_FAB2_LIB.BASEBOARD_FAB2(SCH_1):M_L_DQ(19)
DY77 M_L_DQ<18> DDR4_DQ<18> @BASEBOARD_FAB2_LIB.BASEBOARD_FAB2(SCH_1):M_L_DQ(18)
EC80 M_L_DQ<17> DDR4_DQ<17> @BASEBOARD_FAB2_LIB.BASEBOARD_FAB2(SCH_1):M_L_DQ(17)
DW80 M_L_DQ<16> DDR4_DQ<16> @BASEBOARD_FAB2_LIB.BASEBOARD_FAB2(SCH_1):M_L_DQ(16)
DE82 M_L_DQ<15> DDR4_DQ<15> @BASEBOARD_FAB2_LIB.BASEBOARD_FAB2(SCH_1):M_L_DQ(15)
DC82 M_L_DQ<14> DDR4_DQ<14> @BASEBOARD_FAB2_LIB.BASEBOARD_FAB2(SCH_1):M_L_DQ(14)
CW80 M_L_DQ<13> DDR4_DQ<13> @BASEBOARD_FAB2_LIB.BASEBOARD_FAB2(SCH_1):M_L_DQ(13)
CY79 M_L_DQ<12> DDR4_DQ<12> @BASEBOARD_FAB2_LIB.BASEBOARD_FAB2(SCH_1):M_L_DQ(12)
DF81 M_L_DQ<11> DDR4_DQ<11> @BASEBOARD_FAB2_LIB.BASEBOARD_FAB2(SCH_1):M_L_DQ(11)
DE80 M_L_DQ<10> DDR4_DQ<10> @BASEBOARD_FAB2_LIB.BASEBOARD_FAB2(SCH_1):M_L_DQ(10)
CY81 M_L_DQ<9> DDR4_DQ<9> @BASEBOARD_FAB2_LIB.BASEBOARD_FAB2(SCH_1):M_L_DQ(9)
DB79 M_L_DQ<8> DDR4_DQ<8> @BASEBOARD_FAB2_LIB.BASEBOARD_FAB2(SCH_1):M_L_DQ(8)
CN82 M_L_DQ<7> DDR4_DQ<7> @BASEBOARD_FAB2_LIB.BASEBOARD_FAB2(SCH_1):M_L_DQ(7)
CR80 M_L_DQ<6> DDR4_DQ<6> @BASEBOARD_FAB2_LIB.BASEBOARD_FAB2(SCH_1):M_L_DQ(6)
CJ80 M_L_DQ<5> DDR4_DQ<5> @BASEBOARD_FAB2_LIB.BASEBOARD_FAB2(SCH_1):M_L_DQ(5)
CK79 M_L_DQ<4> DDR4_DQ<4> @BASEBOARD_FAB2_LIB.BASEBOARD_FAB2(SCH_1):M_L_DQ(4)
CR82 M_L_DQ<3> DDR4_DQ<3> @BASEBOARD_FAB2_LIB.BASEBOARD_FAB2(SCH_1):M_L_DQ(3)
CT81 M_L_DQ<2> DDR4_DQ<2> @BASEBOARD_FAB2_LIB.BASEBOARD_FAB2(SCH_1):M_L_DQ(2)
CK81 M_L_DQ<1> DDR4_DQ<1> @BASEBOARD_FAB2_LIB.BASEBOARD_FAB2(SCH_1):M_L_DQ(1)
CM79 M_L_DQ<0> DDR4_DQ<0> @BASEBOARD_FAB2_LIB.BASEBOARD_FAB2(SCH_1):M_L_DQ(0)
DV67 M_L_DQS_DN<17> DDR4_DQS_DN<17> @BASEBOARD_FAB2_LIB.BASEBOARD_FAB2(SCH_1):M_L_DQS_DN(17)
DG26 M_L_DQS_DN<16> DDR4_DQS_DN<16> @BASEBOARD_FAB2_LIB.BASEBOARD_FAB2(SCH_1):M_L_DQS_DN(16)
EA26 M_L_DQS_DN<15> DDR4_DQS_DN<15> @BASEBOARD_FAB2_LIB.BASEBOARD_FAB2(SCH_1):M_L_DQS_DN(15)
EA32 M_L_DQS_DN<14> DDR4_DQS_DN<14> @BASEBOARD_FAB2_LIB.BASEBOARD_FAB2(SCH_1):M_L_DQS_DN(14)
DP41 M_L_DQS_DN<13> DDR4_DQS_DN<13> @BASEBOARD_FAB2_LIB.BASEBOARD_FAB2(SCH_1):M_L_DQS_DN(13)
EB73 M_L_DQS_DN<12> DDR4_DQS_DN<12> @BASEBOARD_FAB2_LIB.BASEBOARD_FAB2(SCH_1):M_L_DQS_DN(12)
DY79 M_L_DQS_DN<11> DDR4_DQS_DN<11> @BASEBOARD_FAB2_LIB.BASEBOARD_FAB2(SCH_1):M_L_DQS_DN(11)
DC80 M_L_DQS_DN<10> DDR4_DQS_DN<10> @BASEBOARD_FAB2_LIB.BASEBOARD_FAB2(SCH_1):M_L_DQS_DN(10)
CN80 M_L_DQS_DN<9> DDR4_DQS_DN<9> @BASEBOARD_FAB2_LIB.BASEBOARD_FAB2(SCH_1):M_L_DQS_DN(9)
EB67 M_L_DQS_DN<8> DDR4_DQS_DN<8> @BASEBOARD_FAB2_LIB.BASEBOARD_FAB2(SCH_1):M_L_DQS_DN(8)
DL26 M_L_DQS_DN<7> DDR4_DQS_DN<7> @BASEBOARD_FAB2_LIB.BASEBOARD_FAB2(SCH_1):M_L_DQS_DN(7)
EE26 M_L_DQS_DN<6> DDR4_DQS_DN<6> @BASEBOARD_FAB2_LIB.BASEBOARD_FAB2(SCH_1):M_L_DQS_DN(6)
EE32 M_L_DQS_DN<5> DDR4_DQS_DN<5> @BASEBOARD_FAB2_LIB.BASEBOARD_FAB2(SCH_1):M_L_DQS_DN(5)
DV41 M_L_DQS_DN<4> DDR4_DQS_DN<4> @BASEBOARD_FAB2_LIB.BASEBOARD_FAB2(SCH_1):M_L_DQS_DN(4)
EF73 M_L_DQS_DN<3> DDR4_DQS_DN<3> @BASEBOARD_FAB2_LIB.BASEBOARD_FAB2(SCH_1):M_L_DQS_DN(3)
ED79 M_L_DQS_DN<2> DDR4_DQS_DN<2> @BASEBOARD_FAB2_LIB.BASEBOARD_FAB2(SCH_1):M_L_DQS_DN(2)
DA82 M_L_DQS_DN<1> DDR4_DQS_DN<1> @BASEBOARD_FAB2_LIB.BASEBOARD_FAB2(SCH_1):M_L_DQS_DN(1)
CL82 M_L_DQS_DN<0> DDR4_DQS_DN<0> @BASEBOARD_FAB2_LIB.BASEBOARD_FAB2(SCH_1):M_L_DQS_DN(0)
DT67 M_L_DQS_DP<17> DDR4_DQS_DP<17> @BASEBOARD_FAB2_LIB.BASEBOARD_FAB2(SCH_1):M_L_DQS_DP(17)
DE26 M_L_DQS_DP<16> DDR4_DQS_DP<16> @BASEBOARD_FAB2_LIB.BASEBOARD_FAB2(SCH_1):M_L_DQS_DP(16)
DW26 M_L_DQS_DP<15> DDR4_DQS_DP<15> @BASEBOARD_FAB2_LIB.BASEBOARD_FAB2(SCH_1):M_L_DQS_DP(15)
DW32 M_L_DQS_DP<14> DDR4_DQS_DP<14> @BASEBOARD_FAB2_LIB.BASEBOARD_FAB2(SCH_1):M_L_DQS_DP(14)
DM41 M_L_DQS_DP<13> DDR4_DQS_DP<13> @BASEBOARD_FAB2_LIB.BASEBOARD_FAB2(SCH_1):M_L_DQS_DP(13)
DY73 M_L_DQS_DP<12> DDR4_DQS_DP<12> @BASEBOARD_FAB2_LIB.BASEBOARD_FAB2(SCH_1):M_L_DQS_DP(12)
DV79 M_L_DQS_DP<11> DDR4_DQS_DP<11> @BASEBOARD_FAB2_LIB.BASEBOARD_FAB2(SCH_1):M_L_DQS_DP(11)
DD79 M_L_DQS_DP<10> DDR4_DQS_DP<10> @BASEBOARD_FAB2_LIB.BASEBOARD_FAB2(SCH_1):M_L_DQS_DP(10)
CP79 M_L_DQS_DP<9> DDR4_DQS_DP<9> @BASEBOARD_FAB2_LIB.BASEBOARD_FAB2(SCH_1):M_L_DQS_DP(9)
DY67 M_L_DQS_DP<8> DDR4_DQS_DP<8> @BASEBOARD_FAB2_LIB.BASEBOARD_FAB2(SCH_1):M_L_DQS_DP(8)
DJ26 M_L_DQS_DP<7> DDR4_DQS_DP<7> @BASEBOARD_FAB2_LIB.BASEBOARD_FAB2(SCH_1):M_L_DQS_DP(7)
EC26 M_L_DQS_DP<6> DDR4_DQS_DP<6> @BASEBOARD_FAB2_LIB.BASEBOARD_FAB2(SCH_1):M_L_DQS_DP(6)
EC32 M_L_DQS_DP<5> DDR4_DQS_DP<5> @BASEBOARD_FAB2_LIB.BASEBOARD_FAB2(SCH_1):M_L_DQS_DP(5)
DT41 M_L_DQS_DP<4> DDR4_DQS_DP<4> @BASEBOARD_FAB2_LIB.BASEBOARD_FAB2(SCH_1):M_L_DQS_DP(4)
ED73 M_L_DQS_DP<3> DDR4_DQS_DP<3> @BASEBOARD_FAB2_LIB.BASEBOARD_FAB2(SCH_1):M_L_DQS_DP(3)
EB79 M_L_DQS_DP<2> DDR4_DQS_DP<2> @BASEBOARD_FAB2_LIB.BASEBOARD_FAB2(SCH_1):M_L_DQS_DP(2)
DB81 M_L_DQS_DP<1> DDR4_DQS_DP<1> @BASEBOARD_FAB2_LIB.BASEBOARD_FAB2(SCH_1):M_L_DQS_DP(1)
CM81 M_L_DQS_DP<0> DDR4_DQS_DP<0> @BASEBOARD_FAB2_LIB.BASEBOARD_FAB2(SCH_1):M_L_DQS_DP(0)
EA66 M_L_ECC<7> DDR4_ECC<7> @BASEBOARD_FAB2_LIB.BASEBOARD_FAB2(SCH_1):M_L_ECC(7)
DU66 M_L_ECC<6> DDR4_ECC<6> @BASEBOARD_FAB2_LIB.BASEBOARD_FAB2(SCH_1):M_L_ECC(6)
DV69 M_L_ECC<5> DDR4_ECC<5> @BASEBOARD_FAB2_LIB.BASEBOARD_FAB2(SCH_1):M_L_ECC(5)
DU68 M_L_ECC<4> DDR4_ECC<4> @BASEBOARD_FAB2_LIB.BASEBOARD_FAB2(SCH_1):M_L_ECC(4)
DY65 M_L_ECC<3> DDR4_ECC<3> @BASEBOARD_FAB2_LIB.BASEBOARD_FAB2(SCH_1):M_L_ECC(3)
DV65 M_L_ECC<2> DDR4_ECC<2> @BASEBOARD_FAB2_LIB.BASEBOARD_FAB2(SCH_1):M_L_ECC(2)
EA68 M_L_ECC<1> DDR4_ECC<1> @BASEBOARD_FAB2_LIB.BASEBOARD_FAB2(SCH_1):M_L_ECC(1)
DY69 M_L_ECC<0> DDR4_ECC<0> @BASEBOARD_FAB2_LIB.BASEBOARD_FAB2(SCH_1):M_L_ECC(0)
DR48 M_L_MA<17> DDR4_MA<17> @BASEBOARD_FAB2_LIB.BASEBOARD_FAB2(SCH_1):M_L_MA(17)
DN52 M_L_MA<16> DDR4_MA<16> @BASEBOARD_FAB2_LIB.BASEBOARD_FAB2(SCH_1):M_L_MA(16)
DR52 M_L_MA<15> DDR4_MA<15> @BASEBOARD_FAB2_LIB.BASEBOARD_FAB2(SCH_1):M_L_MA(15)
DM51 M_L_MA<14> DDR4_MA<14> @BASEBOARD_FAB2_LIB.BASEBOARD_FAB2(SCH_1):M_L_MA(14)
DT51 M_L_MA<13> DDR4_MA<13> @BASEBOARD_FAB2_LIB.BASEBOARD_FAB2(SCH_1):M_L_MA(13)
DN60 M_L_MA<12> DDR4_MA<12> @BASEBOARD_FAB2_LIB.BASEBOARD_FAB2(SCH_1):M_L_MA(12)
DR60 M_L_MA<11> DDR4_MA<11> @BASEBOARD_FAB2_LIB.BASEBOARD_FAB2(SCH_1):M_L_MA(11)
DT55 M_L_MA<10> DDR4_MA<10> @BASEBOARD_FAB2_LIB.BASEBOARD_FAB2(SCH_1):M_L_MA(10)
DV59 M_L_MA<9> DDR4_MA<9> @BASEBOARD_FAB2_LIB.BASEBOARD_FAB2(SCH_1):M_L_MA(9)
DJ60 M_L_MA<8> DDR4_MA<8> @BASEBOARD_FAB2_LIB.BASEBOARD_FAB2(SCH_1):M_L_MA(8)
DK61 M_L_MA<7> DDR4_MA<7> @BASEBOARD_FAB2_LIB.BASEBOARD_FAB2(SCH_1):M_L_MA(7)
DM59 M_L_MA<6> DDR4_MA<6> @BASEBOARD_FAB2_LIB.BASEBOARD_FAB2(SCH_1):M_L_MA(6)
DN58 M_L_MA<5> DDR4_MA<5> @BASEBOARD_FAB2_LIB.BASEBOARD_FAB2(SCH_1):M_L_MA(5)
DT59 M_L_MA<4> DDR4_MA<4> @BASEBOARD_FAB2_LIB.BASEBOARD_FAB2(SCH_1):M_L_MA(4)
DR58 M_L_MA<3> DDR4_MA<3> @BASEBOARD_FAB2_LIB.BASEBOARD_FAB2(SCH_1):M_L_MA(3)
DV57 M_L_MA<2> DDR4_MA<2> @BASEBOARD_FAB2_LIB.BASEBOARD_FAB2(SCH_1):M_L_MA(2)
DW58 M_L_MA<1> DDR4_MA<1> @BASEBOARD_FAB2_LIB.BASEBOARD_FAB2(SCH_1):M_L_MA(1)
DW52 M_L_MA<0> DDR4_MA<0> @BASEBOARD_FAB2_LIB.BASEBOARD_FAB2(SCH_1):M_L_MA(0)
DM47 M_L_ODT<3> DDR4_ODT<3> @BASEBOARD_FAB2_LIB.BASEBOARD_FAB2(SCH_1):M_L_ODT(3)
DT49 M_L_ODT<2> DDR4_ODT<2> @BASEBOARD_FAB2_LIB.BASEBOARD_FAB2(SCH_1):M_L_ODT(2)
DN48 M_L_ODT<1> DDR4_ODT<1> @BASEBOARD_FAB2_LIB.BASEBOARD_FAB2(SCH_1):M_L_ODT(1)
DR50 M_L_ODT<0> DDR4_ODT<0> @BASEBOARD_FAB2_LIB.BASEBOARD_FAB2(SCH_1):M_L_ODT(0)
DV53 M_L_PAR DDR4_PAR @BASEBOARD_FAB2_LIB.BASEBOARD_FAB2(SCH_1):M_L_PAR


DRAWING: @BASEBOARD_FAB2_LIB.BASEBOARD_FAB2(SCH_1):PAGE62 

SKX_EXT_B_BGA1-IC,TBD  I172  U2D1
DC62 M_M_ACT_N DDR5_ACT_N @BASEBOARD_FAB2_LIB.BASEBOARD_FAB2(SCH_1):M_M_ACT_N
DD61 M_M_ALERT_N DDR5_ALERT_N @BASEBOARD_FAB2_LIB.BASEBOARD_FAB2(SCH_1):M_M_ALERT_N
DC56 M_M_BA<1> DDR5_BA<1> @BASEBOARD_FAB2_LIB.BASEBOARD_FAB2(SCH_1):M_M_BA(1)
DJ52 M_M_BA<0> DDR5_BA<0> @BASEBOARD_FAB2_LIB.BASEBOARD_FAB2(SCH_1):M_M_BA(0)
DF61 M_M_BG<1> DDR5_BG<1> @BASEBOARD_FAB2_LIB.BASEBOARD_FAB2(SCH_1):M_M_BG(1)
DA62 M_M_BG<0> DDR5_BG<0> @BASEBOARD_FAB2_LIB.BASEBOARD_FAB2(SCH_1):M_M_BG(0)
DF45 M_M_C<2> DDR5_CID<2> @BASEBOARD_FAB2_LIB.BASEBOARD_FAB2(SCH_1):M_M_C(2)
DF63 M_M_CKE<3> DDR5_CKE<3> @BASEBOARD_FAB2_LIB.BASEBOARD_FAB2(SCH_1):M_M_CKE(3)
DK63 M_M_CKE<2> DDR5_CKE<2> @BASEBOARD_FAB2_LIB.BASEBOARD_FAB2(SCH_1):M_M_CKE(2)
DD63 M_M_CKE<1> DDR5_CKE<1> @BASEBOARD_FAB2_LIB.BASEBOARD_FAB2(SCH_1):M_M_CKE(1)
DG62 M_M_CKE<0> DDR5_CKE<0> @BASEBOARD_FAB2_LIB.BASEBOARD_FAB2(SCH_1):M_M_CKE(0)
DF57 M_M_CLK_DN<3> DDR5_CLK_DN<3> @BASEBOARD_FAB2_LIB.BASEBOARD_FAB2(SCH_1):M_M_CLK_DN(3)
DK57 M_M_CLK_DN<2> DDR5_CLK_DN<2> @BASEBOARD_FAB2_LIB.BASEBOARD_FAB2(SCH_1):M_M_CLK_DN(2)
DF55 M_M_CLK_DN<1> DDR5_CLK_DN<1> @BASEBOARD_FAB2_LIB.BASEBOARD_FAB2(SCH_1):M_M_CLK_DN(1)
DK55 M_M_CLK_DN<0> DDR5_CLK_DN<0> @BASEBOARD_FAB2_LIB.BASEBOARD_FAB2(SCH_1):M_M_CLK_DN(0)
DG56 M_M_CLK_DP<3> DDR5_CLK_DP<3> @BASEBOARD_FAB2_LIB.BASEBOARD_FAB2(SCH_1):M_M_CLK_DP(3)
DJ56 M_M_CLK_DP<2> DDR5_CLK_DP<2> @BASEBOARD_FAB2_LIB.BASEBOARD_FAB2(SCH_1):M_M_CLK_DP(2)
DG54 M_M_CLK_DP<1> DDR5_CLK_DP<1> @BASEBOARD_FAB2_LIB.BASEBOARD_FAB2(SCH_1):M_M_CLK_DP(1)
DJ54 M_M_CLK_DP<0> DDR5_CLK_DP<0> @BASEBOARD_FAB2_LIB.BASEBOARD_FAB2(SCH_1):M_M_CLK_DP(0)
DK45 M_M_CS_N<7> DDR5_CS_N<7> @BASEBOARD_FAB2_LIB.BASEBOARD_FAB2(SCH_1):M_M_CS_N(7)
DM45 M_M_CS_N<6> DDR5_CS_N<6> @BASEBOARD_FAB2_LIB.BASEBOARD_FAB2(SCH_1):M_M_CS_N(6)
DJ48 M_M_CS_N<5> DDR5_CS_N<5> @BASEBOARD_FAB2_LIB.BASEBOARD_FAB2(SCH_1):M_M_CS_N(5)
DF51 M_M_CS_N<4> DDR5_CS_N<4> @BASEBOARD_FAB2_LIB.BASEBOARD_FAB2(SCH_1):M_M_CS_N(4)
DG46 M_M_CS_N<3> DDR5_CS_N<3> @BASEBOARD_FAB2_LIB.BASEBOARD_FAB2(SCH_1):M_M_CS_N(3)
DJ46 M_M_CS_N<2> DDR5_CS_N<2> @BASEBOARD_FAB2_LIB.BASEBOARD_FAB2(SCH_1):M_M_CS_N(2)
DF49 M_M_CS_N<1> DDR5_CS_N<1> @BASEBOARD_FAB2_LIB.BASEBOARD_FAB2(SCH_1):M_M_CS_N(1)
DK51 M_M_CS_N<0> DDR5_CS_N<0> @BASEBOARD_FAB2_LIB.BASEBOARD_FAB2(SCH_1):M_M_CS_N(0)
DC28 M_M_DQ<63> DDR5_DQ<63> @BASEBOARD_FAB2_LIB.BASEBOARD_FAB2(SCH_1):M_M_DQ(63)
CW28 M_M_DQ<62> DDR5_DQ<62> @BASEBOARD_FAB2_LIB.BASEBOARD_FAB2(SCH_1):M_M_DQ(62)
DB31 M_M_DQ<61> DDR5_DQ<61> @BASEBOARD_FAB2_LIB.BASEBOARD_FAB2(SCH_1):M_M_DQ(61)
CY31 M_M_DQ<60> DDR5_DQ<60> @BASEBOARD_FAB2_LIB.BASEBOARD_FAB2(SCH_1):M_M_DQ(60)
DB27 M_M_DQ<59> DDR5_DQ<59> @BASEBOARD_FAB2_LIB.BASEBOARD_FAB2(SCH_1):M_M_DQ(59)
CY27 M_M_DQ<58> DDR5_DQ<58> @BASEBOARD_FAB2_LIB.BASEBOARD_FAB2(SCH_1):M_M_DQ(58)
DC30 M_M_DQ<57> DDR5_DQ<57> @BASEBOARD_FAB2_LIB.BASEBOARD_FAB2(SCH_1):M_M_DQ(57)
CW30 M_M_DQ<56> DDR5_DQ<56> @BASEBOARD_FAB2_LIB.BASEBOARD_FAB2(SCH_1):M_M_DQ(56)
DC34 M_M_DQ<55> DDR5_DQ<55> @BASEBOARD_FAB2_LIB.BASEBOARD_FAB2(SCH_1):M_M_DQ(55)
CW34 M_M_DQ<54> DDR5_DQ<54> @BASEBOARD_FAB2_LIB.BASEBOARD_FAB2(SCH_1):M_M_DQ(54)
DB37 M_M_DQ<53> DDR5_DQ<53> @BASEBOARD_FAB2_LIB.BASEBOARD_FAB2(SCH_1):M_M_DQ(53)
CY37 M_M_DQ<52> DDR5_DQ<52> @BASEBOARD_FAB2_LIB.BASEBOARD_FAB2(SCH_1):M_M_DQ(52)
DB33 M_M_DQ<51> DDR5_DQ<51> @BASEBOARD_FAB2_LIB.BASEBOARD_FAB2(SCH_1):M_M_DQ(51)
CY33 M_M_DQ<50> DDR5_DQ<50> @BASEBOARD_FAB2_LIB.BASEBOARD_FAB2(SCH_1):M_M_DQ(50)
DC36 M_M_DQ<49> DDR5_DQ<49> @BASEBOARD_FAB2_LIB.BASEBOARD_FAB2(SCH_1):M_M_DQ(49)
CW36 M_M_DQ<48> DDR5_DQ<48> @BASEBOARD_FAB2_LIB.BASEBOARD_FAB2(SCH_1):M_M_DQ(48)
DK31 M_M_DQ<47> DDR5_DQ<47> @BASEBOARD_FAB2_LIB.BASEBOARD_FAB2(SCH_1):M_M_DQ(47)
DF31 M_M_DQ<46> DDR5_DQ<46> @BASEBOARD_FAB2_LIB.BASEBOARD_FAB2(SCH_1):M_M_DQ(46)
DJ34 M_M_DQ<45> DDR5_DQ<45> @BASEBOARD_FAB2_LIB.BASEBOARD_FAB2(SCH_1):M_M_DQ(45)
DG34 M_M_DQ<44> DDR5_DQ<44> @BASEBOARD_FAB2_LIB.BASEBOARD_FAB2(SCH_1):M_M_DQ(44)
DJ30 M_M_DQ<43> DDR5_DQ<43> @BASEBOARD_FAB2_LIB.BASEBOARD_FAB2(SCH_1):M_M_DQ(43)
DG30 M_M_DQ<42> DDR5_DQ<42> @BASEBOARD_FAB2_LIB.BASEBOARD_FAB2(SCH_1):M_M_DQ(42)
DK33 M_M_DQ<41> DDR5_DQ<41> @BASEBOARD_FAB2_LIB.BASEBOARD_FAB2(SCH_1):M_M_DQ(41)
DF33 M_M_DQ<40> DDR5_DQ<40> @BASEBOARD_FAB2_LIB.BASEBOARD_FAB2(SCH_1):M_M_DQ(40)
DH39 M_M_DQ<39> DDR5_DQ<39> @BASEBOARD_FAB2_LIB.BASEBOARD_FAB2(SCH_1):M_M_DQ(39)
DD39 M_M_DQ<38> DDR5_DQ<38> @BASEBOARD_FAB2_LIB.BASEBOARD_FAB2(SCH_1):M_M_DQ(38)
DE42 M_M_DQ<37> DDR5_DQ<37> @BASEBOARD_FAB2_LIB.BASEBOARD_FAB2(SCH_1):M_M_DQ(37)
DA42 M_M_DQ<36> DDR5_DQ<36> @BASEBOARD_FAB2_LIB.BASEBOARD_FAB2(SCH_1):M_M_DQ(36)
DG38 M_M_DQ<35> DDR5_DQ<35> @BASEBOARD_FAB2_LIB.BASEBOARD_FAB2(SCH_1):M_M_DQ(35)
DE38 M_M_DQ<34> DDR5_DQ<34> @BASEBOARD_FAB2_LIB.BASEBOARD_FAB2(SCH_1):M_M_DQ(34)
DG42 M_M_DQ<33> DDR5_DQ<33> @BASEBOARD_FAB2_LIB.BASEBOARD_FAB2(SCH_1):M_M_DQ(33)
DD41 M_M_DQ<32> DDR5_DQ<32> @BASEBOARD_FAB2_LIB.BASEBOARD_FAB2(SCH_1):M_M_DQ(32)
CU64 M_M_DQ<31> DDR5_DQ<31> @BASEBOARD_FAB2_LIB.BASEBOARD_FAB2(SCH_1):M_M_DQ(31)
CN64 M_M_DQ<30> DDR5_DQ<30> @BASEBOARD_FAB2_LIB.BASEBOARD_FAB2(SCH_1):M_M_DQ(30)
CT67 M_M_DQ<29> DDR5_DQ<29> @BASEBOARD_FAB2_LIB.BASEBOARD_FAB2(SCH_1):M_M_DQ(29)
CP67 M_M_DQ<28> DDR5_DQ<28> @BASEBOARD_FAB2_LIB.BASEBOARD_FAB2(SCH_1):M_M_DQ(28)
CT63 M_M_DQ<27> DDR5_DQ<27> @BASEBOARD_FAB2_LIB.BASEBOARD_FAB2(SCH_1):M_M_DQ(27)
CP63 M_M_DQ<26> DDR5_DQ<26> @BASEBOARD_FAB2_LIB.BASEBOARD_FAB2(SCH_1):M_M_DQ(26)
CU66 M_M_DQ<25> DDR5_DQ<25> @BASEBOARD_FAB2_LIB.BASEBOARD_FAB2(SCH_1):M_M_DQ(25)
CN66 M_M_DQ<24> DDR5_DQ<24> @BASEBOARD_FAB2_LIB.BASEBOARD_FAB2(SCH_1):M_M_DQ(24)
DM71 M_M_DQ<23> DDR5_DQ<23> @BASEBOARD_FAB2_LIB.BASEBOARD_FAB2(SCH_1):M_M_DQ(23)
DK69 M_M_DQ<22> DDR5_DQ<22> @BASEBOARD_FAB2_LIB.BASEBOARD_FAB2(SCH_1):M_M_DQ(22)
DG72 M_M_DQ<21> DDR5_DQ<21> @BASEBOARD_FAB2_LIB.BASEBOARD_FAB2(SCH_1):M_M_DQ(21)
DF71 M_M_DQ<20> DDR5_DQ<20> @BASEBOARD_FAB2_LIB.BASEBOARD_FAB2(SCH_1):M_M_DQ(20)
DN70 M_M_DQ<19> DDR5_DQ<19> @BASEBOARD_FAB2_LIB.BASEBOARD_FAB2(SCH_1):M_M_DQ(19)
DM69 M_M_DQ<18> DDR5_DQ<18> @BASEBOARD_FAB2_LIB.BASEBOARD_FAB2(SCH_1):M_M_DQ(18)
DJ72 M_M_DQ<17> DDR5_DQ<17> @BASEBOARD_FAB2_LIB.BASEBOARD_FAB2(SCH_1):M_M_DQ(17)
DG70 M_M_DQ<16> DDR5_DQ<16> @BASEBOARD_FAB2_LIB.BASEBOARD_FAB2(SCH_1):M_M_DQ(16)
DH77 M_M_DQ<15> DDR5_DQ<15> @BASEBOARD_FAB2_LIB.BASEBOARD_FAB2(SCH_1):M_M_DQ(15)
DF77 M_M_DQ<14> DDR5_DQ<14> @BASEBOARD_FAB2_LIB.BASEBOARD_FAB2(SCH_1):M_M_DQ(14)
DB75 M_M_DQ<13> DDR5_DQ<13> @BASEBOARD_FAB2_LIB.BASEBOARD_FAB2(SCH_1):M_M_DQ(13)
DC74 M_M_DQ<12> DDR5_DQ<12> @BASEBOARD_FAB2_LIB.BASEBOARD_FAB2(SCH_1):M_M_DQ(12)
DJ76 M_M_DQ<11> DDR5_DQ<11> @BASEBOARD_FAB2_LIB.BASEBOARD_FAB2(SCH_1):M_M_DQ(11)
DH75 M_M_DQ<10> DDR5_DQ<10> @BASEBOARD_FAB2_LIB.BASEBOARD_FAB2(SCH_1):M_M_DQ(10)
DC76 M_M_DQ<9> DDR5_DQ<9> @BASEBOARD_FAB2_LIB.BASEBOARD_FAB2(SCH_1):M_M_DQ(9)
DE74 M_M_DQ<8> DDR5_DQ<8> @BASEBOARD_FAB2_LIB.BASEBOARD_FAB2(SCH_1):M_M_DQ(8)
CT77 M_M_DQ<7> DDR5_DQ<7> @BASEBOARD_FAB2_LIB.BASEBOARD_FAB2(SCH_1):M_M_DQ(7)
CV75 M_M_DQ<6> DDR5_DQ<6> @BASEBOARD_FAB2_LIB.BASEBOARD_FAB2(SCH_1):M_M_DQ(6)
CM75 M_M_DQ<5> DDR5_DQ<5> @BASEBOARD_FAB2_LIB.BASEBOARD_FAB2(SCH_1):M_M_DQ(5)
CN74 M_M_DQ<4> DDR5_DQ<4> @BASEBOARD_FAB2_LIB.BASEBOARD_FAB2(SCH_1):M_M_DQ(4)
CV77 M_M_DQ<3> DDR5_DQ<3> @BASEBOARD_FAB2_LIB.BASEBOARD_FAB2(SCH_1):M_M_DQ(3)
CW76 M_M_DQ<2> DDR5_DQ<2> @BASEBOARD_FAB2_LIB.BASEBOARD_FAB2(SCH_1):M_M_DQ(2)
CN76 M_M_DQ<1> DDR5_DQ<1> @BASEBOARD_FAB2_LIB.BASEBOARD_FAB2(SCH_1):M_M_DQ(1)
CR74 M_M_DQ<0> DDR5_DQ<0> @BASEBOARD_FAB2_LIB.BASEBOARD_FAB2(SCH_1):M_M_DQ(0)
CJ70 M_M_DQS_DN<17> DDR5_DQS_DN<17> @BASEBOARD_FAB2_LIB.BASEBOARD_FAB2(SCH_1):M_M_DQS_DN(17)
CY29 M_M_DQS_DN<16> DDR5_DQS_DN<16> @BASEBOARD_FAB2_LIB.BASEBOARD_FAB2(SCH_1):M_M_DQS_DN(16)
CY35 M_M_DQS_DN<15> DDR5_DQS_DN<15> @BASEBOARD_FAB2_LIB.BASEBOARD_FAB2(SCH_1):M_M_DQS_DN(15)
DG32 M_M_DQS_DN<14> DDR5_DQS_DN<14> @BASEBOARD_FAB2_LIB.BASEBOARD_FAB2(SCH_1):M_M_DQS_DN(14)
DE40 M_M_DQS_DN<13> DDR5_DQS_DN<13> @BASEBOARD_FAB2_LIB.BASEBOARD_FAB2(SCH_1):M_M_DQS_DN(13)
CP65 M_M_DQS_DN<12> DDR5_DQS_DN<12> @BASEBOARD_FAB2_LIB.BASEBOARD_FAB2(SCH_1):M_M_DQS_DN(12)
DJ70 M_M_DQS_DN<11> DDR5_DQS_DN<11> @BASEBOARD_FAB2_LIB.BASEBOARD_FAB2(SCH_1):M_M_DQS_DN(11)
DF75 M_M_DQS_DN<10> DDR5_DQS_DN<10> @BASEBOARD_FAB2_LIB.BASEBOARD_FAB2(SCH_1):M_M_DQS_DN(10)
CT75 M_M_DQS_DN<9> DDR5_DQS_DN<9> @BASEBOARD_FAB2_LIB.BASEBOARD_FAB2(SCH_1):M_M_DQS_DN(9)
CN70 M_M_DQS_DN<8> DDR5_DQS_DN<8> @BASEBOARD_FAB2_LIB.BASEBOARD_FAB2(SCH_1):M_M_DQS_DN(8)
DD29 M_M_DQS_DN<7> DDR5_DQS_DN<7> @BASEBOARD_FAB2_LIB.BASEBOARD_FAB2(SCH_1):M_M_DQS_DN(7)
DD35 M_M_DQS_DN<6> DDR5_DQS_DN<6> @BASEBOARD_FAB2_LIB.BASEBOARD_FAB2(SCH_1):M_M_DQS_DN(6)
DL32 M_M_DQS_DN<5> DDR5_DQS_DN<5> @BASEBOARD_FAB2_LIB.BASEBOARD_FAB2(SCH_1):M_M_DQS_DN(5)
DG40 M_M_DQS_DN<4> DDR5_DQS_DN<4> @BASEBOARD_FAB2_LIB.BASEBOARD_FAB2(SCH_1):M_M_DQS_DN(4)
CV65 M_M_DQS_DN<3> DDR5_DQS_DN<3> @BASEBOARD_FAB2_LIB.BASEBOARD_FAB2(SCH_1):M_M_DQS_DN(3)
DL72 M_M_DQS_DN<2> DDR5_DQS_DN<2> @BASEBOARD_FAB2_LIB.BASEBOARD_FAB2(SCH_1):M_M_DQS_DN(2)
DD77 M_M_DQS_DN<1> DDR5_DQS_DN<1> @BASEBOARD_FAB2_LIB.BASEBOARD_FAB2(SCH_1):M_M_DQS_DN(1)
CP77 M_M_DQS_DN<0> DDR5_DQS_DN<0> @BASEBOARD_FAB2_LIB.BASEBOARD_FAB2(SCH_1):M_M_DQS_DN(0)
CG70 M_M_DQS_DP<17> DDR5_DQS_DP<17> @BASEBOARD_FAB2_LIB.BASEBOARD_FAB2(SCH_1):M_M_DQS_DP(17)
CV29 M_M_DQS_DP<16> DDR5_DQS_DP<16> @BASEBOARD_FAB2_LIB.BASEBOARD_FAB2(SCH_1):M_M_DQS_DP(16)
CV35 M_M_DQS_DP<15> DDR5_DQS_DP<15> @BASEBOARD_FAB2_LIB.BASEBOARD_FAB2(SCH_1):M_M_DQS_DP(15)
DE32 M_M_DQS_DP<14> DDR5_DQS_DP<14> @BASEBOARD_FAB2_LIB.BASEBOARD_FAB2(SCH_1):M_M_DQS_DP(14)
DC40 M_M_DQS_DP<13> DDR5_DQS_DP<13> @BASEBOARD_FAB2_LIB.BASEBOARD_FAB2(SCH_1):M_M_DQS_DP(13)
CM65 M_M_DQS_DP<12> DDR5_DQS_DP<12> @BASEBOARD_FAB2_LIB.BASEBOARD_FAB2(SCH_1):M_M_DQS_DP(12)
DH69 M_M_DQS_DP<11> DDR5_DQS_DP<11> @BASEBOARD_FAB2_LIB.BASEBOARD_FAB2(SCH_1):M_M_DQS_DP(11)
DG74 M_M_DQS_DP<10> DDR5_DQS_DP<10> @BASEBOARD_FAB2_LIB.BASEBOARD_FAB2(SCH_1):M_M_DQS_DP(10)
CU74 M_M_DQS_DP<9> DDR5_DQS_DP<9> @BASEBOARD_FAB2_LIB.BASEBOARD_FAB2(SCH_1):M_M_DQS_DP(9)
CL70 M_M_DQS_DP<8> DDR5_DQS_DP<8> @BASEBOARD_FAB2_LIB.BASEBOARD_FAB2(SCH_1):M_M_DQS_DP(8)
DB29 M_M_DQS_DP<7> DDR5_DQS_DP<7> @BASEBOARD_FAB2_LIB.BASEBOARD_FAB2(SCH_1):M_M_DQS_DP(7)
DB35 M_M_DQS_DP<6> DDR5_DQS_DP<6> @BASEBOARD_FAB2_LIB.BASEBOARD_FAB2(SCH_1):M_M_DQS_DP(6)
DJ32 M_M_DQS_DP<5> DDR5_DQS_DP<5> @BASEBOARD_FAB2_LIB.BASEBOARD_FAB2(SCH_1):M_M_DQS_DP(5)
DJ40 M_M_DQS_DP<4> DDR5_DQS_DP<4> @BASEBOARD_FAB2_LIB.BASEBOARD_FAB2(SCH_1):M_M_DQS_DP(4)
CT65 M_M_DQS_DP<3> DDR5_DQS_DP<3> @BASEBOARD_FAB2_LIB.BASEBOARD_FAB2(SCH_1):M_M_DQS_DP(3)
DK71 M_M_DQS_DP<2> DDR5_DQS_DP<2> @BASEBOARD_FAB2_LIB.BASEBOARD_FAB2(SCH_1):M_M_DQS_DP(2)
DE76 M_M_DQS_DP<1> DDR5_DQS_DP<1> @BASEBOARD_FAB2_LIB.BASEBOARD_FAB2(SCH_1):M_M_DQS_DP(1)
CR76 M_M_DQS_DP<0> DDR5_DQS_DP<0> @BASEBOARD_FAB2_LIB.BASEBOARD_FAB2(SCH_1):M_M_DQS_DP(0)
CM69 M_M_ECC<7> DDR5_ECC<7> @BASEBOARD_FAB2_LIB.BASEBOARD_FAB2(SCH_1):M_M_ECC(7)
CH69 M_M_ECC<6> DDR5_ECC<6> @BASEBOARD_FAB2_LIB.BASEBOARD_FAB2(SCH_1):M_M_ECC(6)
CL72 M_M_ECC<5> DDR5_ECC<5> @BASEBOARD_FAB2_LIB.BASEBOARD_FAB2(SCH_1):M_M_ECC(5)
CJ72 M_M_ECC<4> DDR5_ECC<4> @BASEBOARD_FAB2_LIB.BASEBOARD_FAB2(SCH_1):M_M_ECC(4)
CL68 M_M_ECC<3> DDR5_ECC<3> @BASEBOARD_FAB2_LIB.BASEBOARD_FAB2(SCH_1):M_M_ECC(3)
CJ68 M_M_ECC<2> DDR5_ECC<2> @BASEBOARD_FAB2_LIB.BASEBOARD_FAB2(SCH_1):M_M_ECC(2)
CM71 M_M_ECC<1> DDR5_ECC<1> @BASEBOARD_FAB2_LIB.BASEBOARD_FAB2(SCH_1):M_M_ECC(1)
CH71 M_M_ECC<0> DDR5_ECC<0> @BASEBOARD_FAB2_LIB.BASEBOARD_FAB2(SCH_1):M_M_ECC(0)
DE46 M_M_MA<17> DDR5_MA<17> @BASEBOARD_FAB2_LIB.BASEBOARD_FAB2(SCH_1):M_M_MA(17)
DG52 M_M_MA<16> DDR5_MA<16> @BASEBOARD_FAB2_LIB.BASEBOARD_FAB2(SCH_1):M_M_MA(16)
DC54 M_M_MA<15> DDR5_MA<15> @BASEBOARD_FAB2_LIB.BASEBOARD_FAB2(SCH_1):M_M_MA(15)
DJ50 M_M_MA<14> DDR5_MA<14> @BASEBOARD_FAB2_LIB.BASEBOARD_FAB2(SCH_1):M_M_MA(14)
DD53 M_M_MA<13> DDR5_MA<13> @BASEBOARD_FAB2_LIB.BASEBOARD_FAB2(SCH_1):M_M_MA(13)
DG60 M_M_MA<12> DDR5_MA<12> @BASEBOARD_FAB2_LIB.BASEBOARD_FAB2(SCH_1):M_M_MA(12)
DA60 M_M_MA<11> DDR5_MA<11> @BASEBOARD_FAB2_LIB.BASEBOARD_FAB2(SCH_1):M_M_MA(11)
DD55 M_M_MA<10> DDR5_MA<10> @BASEBOARD_FAB2_LIB.BASEBOARD_FAB2(SCH_1):M_M_MA(10)
DA58 M_M_MA<9> DDR5_MA<9> @BASEBOARD_FAB2_LIB.BASEBOARD_FAB2(SCH_1):M_M_MA(9)
DD59 M_M_MA<8> DDR5_MA<8> @BASEBOARD_FAB2_LIB.BASEBOARD_FAB2(SCH_1):M_M_MA(8)
DC60 M_M_MA<7> DDR5_MA<7> @BASEBOARD_FAB2_LIB.BASEBOARD_FAB2(SCH_1):M_M_MA(7)
DK59 M_M_MA<6> DDR5_MA<6> @BASEBOARD_FAB2_LIB.BASEBOARD_FAB2(SCH_1):M_M_MA(6)
DF59 M_M_MA<5> DDR5_MA<5> @BASEBOARD_FAB2_LIB.BASEBOARD_FAB2(SCH_1):M_M_MA(5)
DJ58 M_M_MA<4> DDR5_MA<4> @BASEBOARD_FAB2_LIB.BASEBOARD_FAB2(SCH_1):M_M_MA(4)
DG58 M_M_MA<3> DDR5_MA<3> @BASEBOARD_FAB2_LIB.BASEBOARD_FAB2(SCH_1):M_M_MA(3)
DD57 M_M_MA<2> DDR5_MA<2> @BASEBOARD_FAB2_LIB.BASEBOARD_FAB2(SCH_1):M_M_MA(2)
DC58 M_M_MA<1> DDR5_MA<1> @BASEBOARD_FAB2_LIB.BASEBOARD_FAB2(SCH_1):M_M_MA(1)
DF53 M_M_MA<0> DDR5_MA<0> @BASEBOARD_FAB2_LIB.BASEBOARD_FAB2(SCH_1):M_M_MA(0)
DF47 M_M_ODT<3> DDR5_ODT<3> @BASEBOARD_FAB2_LIB.BASEBOARD_FAB2(SCH_1):M_M_ODT(3)
DK49 M_M_ODT<2> DDR5_ODT<2> @BASEBOARD_FAB2_LIB.BASEBOARD_FAB2(SCH_1):M_M_ODT(2)
DG48 M_M_ODT<1> DDR5_ODT<1> @BASEBOARD_FAB2_LIB.BASEBOARD_FAB2(SCH_1):M_M_ODT(1)
DG50 M_M_ODT<0> DDR5_ODT<0> @BASEBOARD_FAB2_LIB.BASEBOARD_FAB2(SCH_1):M_M_ODT(0)
DK53 M_M_PAR DDR5_PAR @BASEBOARD_FAB2_LIB.BASEBOARD_FAB2(SCH_1):M_M_PAR


DRAWING: @BASEBOARD_FAB2_LIB.BASEBOARD_FAB2(SCH_1):PAGE63 

SKX_EXT_B_BGA1-IC,TBD  I23  U2D1
BN22 TP_SMB_CPU1_CD_HFI0_I2CCLK CD_HFI0_I2CCLK @BASEBOARD_FAB2_LIB.BASEBOARD_FAB2(SCH_1):TP_SMB_CPU1_CD_HFI0_I2CCLK
BP23 TP_SMB_CPU1_CD_HFI0_I2CDAT CD_HFI0_I2CDAT @BASEBOARD_FAB2_LIB.BASEBOARD_FAB2(SCH_1):TP_SMB_CPU1_CD_HFI0_I2CDAT
BP19 TP_IRQ_CPU1_CD_HFI0_N CD_HFI0_INT_N @BASEBOARD_FAB2_LIB.BASEBOARD_FAB2(SCH_1):TP_IRQ_CPU1_CD_HFI0_N
BK21 TP_LED_CPU1_CD_HFI0_N CD_HFI0_LED_N @BASEBOARD_FAB2_LIB.BASEBOARD_FAB2(SCH_1):TP_LED_CPU1_CD_HFI0_N
BR20 TP_FM_CPU1_CD_HFI0_MODPRST_N CD_HFI0_MODPRST_N @BASEBOARD_FAB2_LIB.BASEBOARD_FAB2(SCH_1):TP_FM_CPU1_CD_HFI0_MODPRST_N
BN24 TP_RST_CPU1_CD_HFI0_N CD_HFI0_RESET_N @BASEBOARD_FAB2_LIB.BASEBOARD_FAB2(SCH_1):TP_RST_CPU1_CD_HFI0_N
BJ22 TP_CD_HFI1_CPU1_I2CLK CD_HFI1_I2CCLK @BASEBOARD_FAB2_LIB.BASEBOARD_FAB2(SCH_1):TP_CD_HFI1_CPU1_I2CLK
BH23 TP_CD_HFI1_CPU1_I2CDAT CD_HFI1_I2CDAT @BASEBOARD_FAB2_LIB.BASEBOARD_FAB2(SCH_1):TP_CD_HFI1_CPU1_I2CDAT
BM21 TP_CD_HFI1_CPU1_INT_N CD_HFI1_INT_N @BASEBOARD_FAB2_LIB.BASEBOARD_FAB2(SCH_1):TP_CD_HFI1_CPU1_INT_N
BM23 TP_CD_HFI1_CPU1_LED_N CD_HFI1_LED_N @BASEBOARD_FAB2_LIB.BASEBOARD_FAB2(SCH_1):TP_CD_HFI1_CPU1_LED_N
BT19 TP_CD_HFI1_CPU1_MODPRST_N CD_HFI1_MODPRST_N @BASEBOARD_FAB2_LIB.BASEBOARD_FAB2(SCH_1):TP_CD_HFI1_CPU1_MODPRST_N
BK23 TP_CD_HFI1_CPU1_RESET_N CD_HFI1_RESET_N @BASEBOARD_FAB2_LIB.BASEBOARD_FAB2(SCH_1):TP_CD_HFI1_CPU1_RESET_N
BE16 CLK_156M_OSC_CPU1_HFI_DN CD_HFI_REFCLK_DN @BASEBOARD_FAB2_LIB.BASEBOARD_FAB2(SCH_1):CLK_156M_OSC_CPU1_HFI_DN
BG16 CLK_156M_OSC_CPU1_HFI_DP CD_HFI_REFCLK_DP @BASEBOARD_FAB2_LIB.BASEBOARD_FAB2(SCH_1):CLK_156M_OSC_CPU1_HFI_DP
BU24 CLK_100M_CPU1_PE_REFCLK_DN CD_PE_REFCLK_DN @BASEBOARD_FAB2_LIB.BASEBOARD_FAB2(SCH_1):CLK_100M_CPU1_PE_REFCLK_DN
BW24 CLK_100M_CPU1_PE_REFCLK_DP CD_PE_REFCLK_DP @BASEBOARD_FAB2_LIB.BASEBOARD_FAB2(SCH_1):CLK_100M_CPU1_PE_REFCLK_DP
CF25 RST_CD_CPU1_POR_N CD_POR_N @BASEBOARD_FAB2_LIB.BASEBOARD_FAB2(SCH_1):RST_CD_CPU1_POR_N
CB23 JTAG_MCP_TCK CD_TCLK @BASEBOARD_FAB2_LIB.BASEBOARD_FAB2(SCH_1):JTAG_MCP_TCK
BY21 JTAG_MCP_CPU1_TDI CD_TDI @BASEBOARD_FAB2_LIB.BASEBOARD_FAB2(SCH_1):JTAG_MCP_CPU1_TDI
CC22 JTAG_MCP_CPU1_TDO CD_TDO @BASEBOARD_FAB2_LIB.BASEBOARD_FAB2(SCH_1):JTAG_MCP_CPU1_TDO
CE24 JTAG_MCP_TMS CD_TMS @BASEBOARD_FAB2_LIB.BASEBOARD_FAB2(SCH_1):JTAG_MCP_TMS
CD23 JTAG_MCP_TRST_N CD_TRST_N @BASEBOARD_FAB2_LIB.BASEBOARD_FAB2(SCH_1):JTAG_MCP_TRST_N
CT11 TP_CPU1_DMI_RX_DN3 DMI_RX_DN<3> @BASEBOARD_FAB2_LIB.BASEBOARD_FAB2(SCH_1):TP_CPU1_DMI_RX_DN3
CR12 TP_CPU1_DMI_RX_DN2 DMI_RX_DN<2> @BASEBOARD_FAB2_LIB.BASEBOARD_FAB2(SCH_1):TP_CPU1_DMI_RX_DN2
CM11 TP_CPU1_DMI_RX_DN1 DMI_RX_DN<1> @BASEBOARD_FAB2_LIB.BASEBOARD_FAB2(SCH_1):TP_CPU1_DMI_RX_DN1
 CK9 TP_CPU1_DMI_RX_DN0 DMI_RX_DN<0> @BASEBOARD_FAB2_LIB.BASEBOARD_FAB2(SCH_1):TP_CPU1_DMI_RX_DN0
CV11 TP_CPU1_DMI_RX_DP3 DMI_RX_DP<3> @BASEBOARD_FAB2_LIB.BASEBOARD_FAB2(SCH_1):TP_CPU1_DMI_RX_DP3
CP11 TP_CPU1_DMI_RX_DP2 DMI_RX_DP<2> @BASEBOARD_FAB2_LIB.BASEBOARD_FAB2(SCH_1):TP_CPU1_DMI_RX_DP2
CN10 TP_CPU1_DMI_RX_DP1 DMI_RX_DP<1> @BASEBOARD_FAB2_LIB.BASEBOARD_FAB2(SCH_1):TP_CPU1_DMI_RX_DP1
CL10 TP_CPU1_DMI_RX_DP0 DMI_RX_DP<0> @BASEBOARD_FAB2_LIB.BASEBOARD_FAB2(SCH_1):TP_CPU1_DMI_RX_DP0
 CP5 TP_CPU1_DMI_TX_DN3 DMI_TX_DN<3> @BASEBOARD_FAB2_LIB.BASEBOARD_FAB2(SCH_1):TP_CPU1_DMI_TX_DN3
 CN4 TP_CPU1_DMI_TX_DN2 DMI_TX_DN<2> @BASEBOARD_FAB2_LIB.BASEBOARD_FAB2(SCH_1):TP_CPU1_DMI_TX_DN2
 CJ4 TP_CPU1_DMI_TX_DN1 DMI_TX_DN<1> @BASEBOARD_FAB2_LIB.BASEBOARD_FAB2(SCH_1):TP_CPU1_DMI_TX_DN1
 CG4 TP_CPU1_DMI_TX_DN0 DMI_TX_DN<0> @BASEBOARD_FAB2_LIB.BASEBOARD_FAB2(SCH_1):TP_CPU1_DMI_TX_DN0
 CR4 TP_CPU1_DMI_TX_DP3 DMI_TX_DP<3> @BASEBOARD_FAB2_LIB.BASEBOARD_FAB2(SCH_1):TP_CPU1_DMI_TX_DP3
 CM3 TP_CPU1_DMI_TX_DP2 DMI_TX_DP<2> @BASEBOARD_FAB2_LIB.BASEBOARD_FAB2(SCH_1):TP_CPU1_DMI_TX_DP2
 CL4 TP_CPU1_DMI_TX_DP1 DMI_TX_DP<1> @BASEBOARD_FAB2_LIB.BASEBOARD_FAB2(SCH_1):TP_CPU1_DMI_TX_DP1
 CH5 TP_CPU1_DMI_TX_DP0 DMI_TX_DP<0> @BASEBOARD_FAB2_LIB.BASEBOARD_FAB2(SCH_1):TP_CPU1_DMI_TX_DP0
AR20 PVCCMCP_CPU1 RSVD<193> @BASEBOARD_FAB2_LIB.BASEBOARD_FAB2(SCH_1):PVCCMCP_CPU1
AR22 PVCCMCP_CPU1 RSVD<192> @BASEBOARD_FAB2_LIB.BASEBOARD_FAB2(SCH_1):PVCCMCP_CPU1
AR26 PVCCMCP_CPU1 RSVD<191> @BASEBOARD_FAB2_LIB.BASEBOARD_FAB2(SCH_1):PVCCMCP_CPU1
AR62 TP_CPU1_RSVD_190 RSVD<190> @BASEBOARD_FAB2_LIB.BASEBOARD_FAB2(SCH_1):TP_CPU1_RSVD_190
AT13 TP_CPU1_RSVD_189 RSVD<189> @BASEBOARD_FAB2_LIB.BASEBOARD_FAB2(SCH_1):TP_CPU1_RSVD_189
AT23 PVCCMCP_CPU1 RSVD<188> @BASEBOARD_FAB2_LIB.BASEBOARD_FAB2(SCH_1):PVCCMCP_CPU1
AT25 PVCCMCP_CPU1 RSVD<187> @BASEBOARD_FAB2_LIB.BASEBOARD_FAB2(SCH_1):PVCCMCP_CPU1
AV77 TP_CPU1_RSVD_186 RSVD<186> @BASEBOARD_FAB2_LIB.BASEBOARD_FAB2(SCH_1):TP_CPU1_RSVD_186
AW64 TP_CPU1_RSVD_184 RSVD<184> @BASEBOARD_FAB2_LIB.BASEBOARD_FAB2(SCH_1):TP_CPU1_RSVD_184
AW76 TP_CPU1_RSVD_183 RSVD<183> @BASEBOARD_FAB2_LIB.BASEBOARD_FAB2(SCH_1):TP_CPU1_RSVD_183
AY65 TP_CPU1_RSVD_182 RSVD<182> @BASEBOARD_FAB2_LIB.BASEBOARD_FAB2(SCH_1):TP_CPU1_RSVD_182
AY67 TP_CPU1_RSVD_181 RSVD<181> @BASEBOARD_FAB2_LIB.BASEBOARD_FAB2(SCH_1):TP_CPU1_RSVD_181
AY75 TP_CPU1_RSVD_180 RSVD<180> @BASEBOARD_FAB2_LIB.BASEBOARD_FAB2(SCH_1):TP_CPU1_RSVD_180
AY77 TP_CPU1_RSVD_179 RSVD<179> @BASEBOARD_FAB2_LIB.BASEBOARD_FAB2(SCH_1):TP_CPU1_RSVD_179
BA14 TP_CPU1_RSVD_178 RSVD<178> @BASEBOARD_FAB2_LIB.BASEBOARD_FAB2(SCH_1):TP_CPU1_RSVD_178
BA16 TP_CPU1_RSVD_177 RSVD<177> @BASEBOARD_FAB2_LIB.BASEBOARD_FAB2(SCH_1):TP_CPU1_RSVD_177
BA18 TP_CPU1_RSVD_176 RSVD<176> @BASEBOARD_FAB2_LIB.BASEBOARD_FAB2(SCH_1):TP_CPU1_RSVD_176
BA22 TP_CPU1_RSVD_175 RSVD<175> @BASEBOARD_FAB2_LIB.BASEBOARD_FAB2(SCH_1):TP_CPU1_RSVD_175
BA64 TP_CPU1_RSVD_174 RSVD<174> @BASEBOARD_FAB2_LIB.BASEBOARD_FAB2(SCH_1):TP_CPU1_RSVD_174
BA66 TP_CPU1_RSVD_173 RSVD<173> @BASEBOARD_FAB2_LIB.BASEBOARD_FAB2(SCH_1):TP_CPU1_RSVD_173
BA76 TP_CPU1_RSVD_172 RSVD<172> @BASEBOARD_FAB2_LIB.BASEBOARD_FAB2(SCH_1):TP_CPU1_RSVD_172


DRAWING: @BASEBOARD_FAB2_LIB.BASEBOARD_FAB2(SCH_1):PAGE64 

SKX_EXT_B_BGA1-IC,TBD  I68  U2D1
DU16 TP_P3E_CPU1_PE1_RSR3_RXN<15> PE1_RX_DN<15> @BASEBOARD_FAB2_LIB.BASEBOARD_FAB2(SCH_1):TP_P3E_CPU1_PE1_RSR3_RXN(15)
DY15 TP_P3E_CPU1_PE1_RSR3_RXN<14> PE1_RX_DN<14> @BASEBOARD_FAB2_LIB.BASEBOARD_FAB2(SCH_1):TP_P3E_CPU1_PE1_RSR3_RXN(14)
DW14 TP_P3E_CPU1_PE1_RSR3_RXN<13> PE1_RX_DN<13> @BASEBOARD_FAB2_LIB.BASEBOARD_FAB2(SCH_1):TP_P3E_CPU1_PE1_RSR3_RXN(13)
DV13 TP_P3E_CPU1_PE1_RSR3_RXN<12> PE1_RX_DN<12> @BASEBOARD_FAB2_LIB.BASEBOARD_FAB2(SCH_1):TP_P3E_CPU1_PE1_RSR3_RXN(12)
DT13 TP_P3E_CPU1_PE1_RSR3_RXN<11> PE1_RX_DN<11> @BASEBOARD_FAB2_LIB.BASEBOARD_FAB2(SCH_1):TP_P3E_CPU1_PE1_RSR3_RXN(11)
DT11 TP_P3E_CPU1_PE1_RSR3_RXN<10> PE1_RX_DN<10> @BASEBOARD_FAB2_LIB.BASEBOARD_FAB2(SCH_1):TP_P3E_CPU1_PE1_RSR3_RXN(10)
DP11 TP_P3E_CPU1_PE1_RSR3_RXN<9> PE1_RX_DN<9> @BASEBOARD_FAB2_LIB.BASEBOARD_FAB2(SCH_1):TP_P3E_CPU1_PE1_RSR3_RXN(9)
DM11 TP_P3E_CPU1_PE1_RSR3_RXN<8> PE1_RX_DN<8> @BASEBOARD_FAB2_LIB.BASEBOARD_FAB2(SCH_1):TP_P3E_CPU1_PE1_RSR3_RXN(8)
 DM9 TP_P3E_CPU1_PE1_MP_RXN<7> PE1_RX_DN<7> @BASEBOARD_FAB2_LIB.BASEBOARD_FAB2(SCH_1):TP_P3E_CPU1_PE1_MP_RXN(7)
 DK9 TP_P3E_CPU1_PE1_MP_RXN<6> PE1_RX_DN<6> @BASEBOARD_FAB2_LIB.BASEBOARD_FAB2(SCH_1):TP_P3E_CPU1_PE1_MP_RXN(6)
 DH9 TP_P3E_CPU1_PE1_MP_RXN<5> PE1_RX_DN<5> @BASEBOARD_FAB2_LIB.BASEBOARD_FAB2(SCH_1):TP_P3E_CPU1_PE1_MP_RXN(5)
DE10 TP_P3E_CPU1_PE1_MP_RXN<4> PE1_RX_DN<4> @BASEBOARD_FAB2_LIB.BASEBOARD_FAB2(SCH_1):TP_P3E_CPU1_PE1_MP_RXN(4)
DC10 TP_P3E_CPU1_PE1_MP_RXN<3> PE1_RX_DN<3> @BASEBOARD_FAB2_LIB.BASEBOARD_FAB2(SCH_1):TP_P3E_CPU1_PE1_MP_RXN(3)
 DC8 TP_P3E_CPU1_PE1_MP_RXN<2> PE1_RX_DN<2> @BASEBOARD_FAB2_LIB.BASEBOARD_FAB2(SCH_1):TP_P3E_CPU1_PE1_MP_RXN(2)
 DA8 TP_P3E_CPU1_PE1_MP_RXN<1> PE1_RX_DN<1> @BASEBOARD_FAB2_LIB.BASEBOARD_FAB2(SCH_1):TP_P3E_CPU1_PE1_MP_RXN(1)
 CW8 TP_P3E_CPU1_PE1_MP_RXN<0> PE1_RX_DN<0> @BASEBOARD_FAB2_LIB.BASEBOARD_FAB2(SCH_1):TP_P3E_CPU1_PE1_MP_RXN(0)
DT15 TP_P3E_CPU1_PE1_RSR3_RXP<15> PE1_RX_DP<15> @BASEBOARD_FAB2_LIB.BASEBOARD_FAB2(SCH_1):TP_P3E_CPU1_PE1_RSR3_RXP(15)
DV15 TP_P3E_CPU1_PE1_RSR3_RXP<14> PE1_RX_DP<14> @BASEBOARD_FAB2_LIB.BASEBOARD_FAB2(SCH_1):TP_P3E_CPU1_PE1_RSR3_RXP(14)
DY13 TP_P3E_CPU1_PE1_RSR3_RXP<13> PE1_RX_DP<13> @BASEBOARD_FAB2_LIB.BASEBOARD_FAB2(SCH_1):TP_P3E_CPU1_PE1_RSR3_RXP(13)
DU12 TP_P3E_CPU1_PE1_RSR3_RXP<12> PE1_RX_DP<12> @BASEBOARD_FAB2_LIB.BASEBOARD_FAB2(SCH_1):TP_P3E_CPU1_PE1_RSR3_RXP(12)
DP13 TP_P3E_CPU1_PE1_RSR3_RXP<11> PE1_RX_DP<11> @BASEBOARD_FAB2_LIB.BASEBOARD_FAB2(SCH_1):TP_P3E_CPU1_PE1_RSR3_RXP(11)
DR12 TP_P3E_CPU1_PE1_RSR3_RXP<10> PE1_RX_DP<10> @BASEBOARD_FAB2_LIB.BASEBOARD_FAB2(SCH_1):TP_P3E_CPU1_PE1_RSR3_RXP(10)
DN10 TP_P3E_CPU1_PE1_RSR3_RXP<9> PE1_RX_DP<9> @BASEBOARD_FAB2_LIB.BASEBOARD_FAB2(SCH_1):TP_P3E_CPU1_PE1_RSR3_RXP(9)
DK11 TP_P3E_CPU1_PE1_RSR3_RXP<8> PE1_RX_DP<8> @BASEBOARD_FAB2_LIB.BASEBOARD_FAB2(SCH_1):TP_P3E_CPU1_PE1_RSR3_RXP(8)
DL10 TP_P3E_CPU1_PE1_MP_RXP<7> PE1_RX_DP<7> @BASEBOARD_FAB2_LIB.BASEBOARD_FAB2(SCH_1):TP_P3E_CPU1_PE1_MP_RXP(7)
 DJ8 TP_P3E_CPU1_PE1_MP_RXP<6> PE1_RX_DP<6> @BASEBOARD_FAB2_LIB.BASEBOARD_FAB2(SCH_1):TP_P3E_CPU1_PE1_MP_RXP(6)
 DF9 TP_P3E_CPU1_PE1_MP_RXP<5> PE1_RX_DP<5> @BASEBOARD_FAB2_LIB.BASEBOARD_FAB2(SCH_1):TP_P3E_CPU1_PE1_MP_RXP(5)
 DD9 TP_P3E_CPU1_PE1_MP_RXP<4> PE1_RX_DP<4> @BASEBOARD_FAB2_LIB.BASEBOARD_FAB2(SCH_1):TP_P3E_CPU1_PE1_MP_RXP(4)
DA10 TP_P3E_CPU1_PE1_MP_RXP<3> PE1_RX_DP<3> @BASEBOARD_FAB2_LIB.BASEBOARD_FAB2(SCH_1):TP_P3E_CPU1_PE1_MP_RXP(3)
 DB9 TP_P3E_CPU1_PE1_MP_RXP<2> PE1_RX_DP<2> @BASEBOARD_FAB2_LIB.BASEBOARD_FAB2(SCH_1):TP_P3E_CPU1_PE1_MP_RXP(2)
 CY7 TP_P3E_CPU1_PE1_MP_RXP<1> PE1_RX_DP<1> @BASEBOARD_FAB2_LIB.BASEBOARD_FAB2(SCH_1):TP_P3E_CPU1_PE1_MP_RXP(1)
 CU8 TP_P3E_CPU1_PE1_MP_RXP<0> PE1_RX_DP<0> @BASEBOARD_FAB2_LIB.BASEBOARD_FAB2(SCH_1):TP_P3E_CPU1_PE1_MP_RXP(0)
 ED9 TP_P3E_CPU1_PE1_RSR3_TXN<15> PE1_TX_DN<15> @BASEBOARD_FAB2_LIB.BASEBOARD_FAB2(SCH_1):TP_P3E_CPU1_PE1_RSR3_TXN(15)
 EA8 TP_P3E_CPU1_PE1_RSR3_TXN<14> PE1_TX_DN<14> @BASEBOARD_FAB2_LIB.BASEBOARD_FAB2(SCH_1):TP_P3E_CPU1_PE1_RSR3_TXN(14)
 DY7 TP_P3E_CPU1_PE1_RSR3_TXN<13> PE1_TX_DN<13> @BASEBOARD_FAB2_LIB.BASEBOARD_FAB2(SCH_1):TP_P3E_CPU1_PE1_RSR3_TXN(13)
 DV7 TP_P3E_CPU1_PE1_RSR3_TXN<12> PE1_TX_DN<12> @BASEBOARD_FAB2_LIB.BASEBOARD_FAB2(SCH_1):TP_P3E_CPU1_PE1_RSR3_TXN(12)
 DU6 TP_P3E_CPU1_PE1_RSR3_TXN<11> PE1_TX_DN<11> @BASEBOARD_FAB2_LIB.BASEBOARD_FAB2(SCH_1):TP_P3E_CPU1_PE1_RSR3_TXN(11)
 DW4 TP_P3E_CPU1_PE1_RSR3_TXN<10> PE1_TX_DN<10> @BASEBOARD_FAB2_LIB.BASEBOARD_FAB2(SCH_1):TP_P3E_CPU1_PE1_RSR3_TXN(10)
 DV3 TP_P3E_CPU1_PE1_RSR3_TXN<9> PE1_TX_DN<9> @BASEBOARD_FAB2_LIB.BASEBOARD_FAB2(SCH_1):TP_P3E_CPU1_PE1_RSR3_TXN(9)
 DT5 TP_P3E_CPU1_PE1_RSR3_TXN<8> PE1_TX_DN<8> @BASEBOARD_FAB2_LIB.BASEBOARD_FAB2(SCH_1):TP_P3E_CPU1_PE1_RSR3_TXN(8)
 DN4 TP_P3E_CPU1_PE1_MP_TXN<7> PE1_TX_DN<7> @BASEBOARD_FAB2_LIB.BASEBOARD_FAB2(SCH_1):TP_P3E_CPU1_PE1_MP_TXN(7)
 DM3 TP_P3E_CPU1_PE1_MP_TXN<6> PE1_TX_DN<6> @BASEBOARD_FAB2_LIB.BASEBOARD_FAB2(SCH_1):TP_P3E_CPU1_PE1_MP_TXN(6)
 DK3 TP_P3E_CPU1_PE1_MP_TXN<5> PE1_TX_DN<5> @BASEBOARD_FAB2_LIB.BASEBOARD_FAB2(SCH_1):TP_P3E_CPU1_PE1_MP_TXN(5)
 DG4 TP_P3E_CPU1_PE1_MP_TXN<4> PE1_TX_DN<4> @BASEBOARD_FAB2_LIB.BASEBOARD_FAB2(SCH_1):TP_P3E_CPU1_PE1_MP_TXN(4)
 DE4 TP_P3E_CPU1_PE1_MP_TXN<3> PE1_TX_DN<3> @BASEBOARD_FAB2_LIB.BASEBOARD_FAB2(SCH_1):TP_P3E_CPU1_PE1_MP_TXN(3)
 DE2 TP_P3E_CPU1_PE1_MP_TXN<2> PE1_TX_DN<2> @BASEBOARD_FAB2_LIB.BASEBOARD_FAB2(SCH_1):TP_P3E_CPU1_PE1_MP_TXN(2)
 DC2 TP_P3E_CPU1_PE1_MP_TXN<1> PE1_TX_DN<1> @BASEBOARD_FAB2_LIB.BASEBOARD_FAB2(SCH_1):TP_P3E_CPU1_PE1_MP_TXN(1)
 DA2 TP_P3E_CPU1_PE1_MP_TXN<0> PE1_TX_DN<0> @BASEBOARD_FAB2_LIB.BASEBOARD_FAB2(SCH_1):TP_P3E_CPU1_PE1_MP_TXN(0)
 EC8 TP_P3E_CPU1_PE1_RSR3_TXP<15> PE1_TX_DP<15> @BASEBOARD_FAB2_LIB.BASEBOARD_FAB2(SCH_1):TP_P3E_CPU1_PE1_RSR3_TXP(15)
 EB7 TP_P3E_CPU1_PE1_RSR3_TXP<14> PE1_TX_DP<14> @BASEBOARD_FAB2_LIB.BASEBOARD_FAB2(SCH_1):TP_P3E_CPU1_PE1_RSR3_TXP(14)
 DW6 TP_P3E_CPU1_PE1_RSR3_TXP<13> PE1_TX_DP<13> @BASEBOARD_FAB2_LIB.BASEBOARD_FAB2(SCH_1):TP_P3E_CPU1_PE1_RSR3_TXP(13)
 DT7 TP_P3E_CPU1_PE1_RSR3_TXP<12> PE1_TX_DP<12> @BASEBOARD_FAB2_LIB.BASEBOARD_FAB2(SCH_1):TP_P3E_CPU1_PE1_RSR3_TXP(12)
 DV5 TP_P3E_CPU1_PE1_RSR3_TXP<11> PE1_TX_DP<11> @BASEBOARD_FAB2_LIB.BASEBOARD_FAB2(SCH_1):TP_P3E_CPU1_PE1_RSR3_TXP(11)
 DU4 TP_P3E_CPU1_PE1_RSR3_TXP<10> PE1_TX_DP<10> @BASEBOARD_FAB2_LIB.BASEBOARD_FAB2(SCH_1):TP_P3E_CPU1_PE1_RSR3_TXP(10)
 DU2 TP_P3E_CPU1_PE1_RSR3_TXP<9> PE1_TX_DP<9> @BASEBOARD_FAB2_LIB.BASEBOARD_FAB2(SCH_1):TP_P3E_CPU1_PE1_RSR3_TXP(9)
 DR4 TP_P3E_CPU1_PE1_RSR3_TXP<8> PE1_TX_DP<8> @BASEBOARD_FAB2_LIB.BASEBOARD_FAB2(SCH_1):TP_P3E_CPU1_PE1_RSR3_TXP(8)
 DP3 TP_P3E_CPU1_PE1_MP_TXP<7> PE1_TX_DP<7> @BASEBOARD_FAB2_LIB.BASEBOARD_FAB2(SCH_1):TP_P3E_CPU1_PE1_MP_TXP(7)
 DL2 TP_P3E_CPU1_PE1_MP_TXP<6> PE1_TX_DP<6> @BASEBOARD_FAB2_LIB.BASEBOARD_FAB2(SCH_1):TP_P3E_CPU1_PE1_MP_TXP(6)
 DH3 TP_P3E_CPU1_PE1_MP_TXP<5> PE1_TX_DP<5> @BASEBOARD_FAB2_LIB.BASEBOARD_FAB2(SCH_1):TP_P3E_CPU1_PE1_MP_TXP(5)
 DF3 TP_P3E_CPU1_PE1_MP_TXP<4> PE1_TX_DP<4> @BASEBOARD_FAB2_LIB.BASEBOARD_FAB2(SCH_1):TP_P3E_CPU1_PE1_MP_TXP(4)
 DC4 TP_P3E_CPU1_PE1_MP_TXP<3> PE1_TX_DP<3> @BASEBOARD_FAB2_LIB.BASEBOARD_FAB2(SCH_1):TP_P3E_CPU1_PE1_MP_TXP(3)
 DD3 TP_P3E_CPU1_PE1_MP_TXP<2> PE1_TX_DP<2> @BASEBOARD_FAB2_LIB.BASEBOARD_FAB2(SCH_1):TP_P3E_CPU1_PE1_MP_TXP(2)
 DB1 TP_P3E_CPU1_PE1_MP_TXP<1> PE1_TX_DP<1> @BASEBOARD_FAB2_LIB.BASEBOARD_FAB2(SCH_1):TP_P3E_CPU1_PE1_MP_TXP(1)
 CW2 TP_P3E_CPU1_PE1_MP_TXP<0> PE1_TX_DP<0> @BASEBOARD_FAB2_LIB.BASEBOARD_FAB2(SCH_1):TP_P3E_CPU1_PE1_MP_TXP(0)


DRAWING: @BASEBOARD_FAB2_LIB.BASEBOARD_FAB2(SCH_1):PAGE65 

SKX_EXT_B_BGA1-IC,TBD  I68  U2D1
 BK9 TP_P3E_CPU1_PE2_RSR_RXN<15> PE2_RX_DN<15> @BASEBOARD_FAB2_LIB.BASEBOARD_FAB2(SCH_1):TP_P3E_CPU1_PE2_RSR_RXN(15)
 BL8 TP_P3E_CPU1_PE2_RSR_RXN<14> PE2_RX_DN<14> @BASEBOARD_FAB2_LIB.BASEBOARD_FAB2(SCH_1):TP_P3E_CPU1_PE2_RSR_RXN(14)
 BN8 TP_P3E_CPU1_PE2_RSR_RXN<13> PE2_RX_DN<13> @BASEBOARD_FAB2_LIB.BASEBOARD_FAB2(SCH_1):TP_P3E_CPU1_PE2_RSR_RXN(13)
 BR8 TP_P3E_CPU1_PE2_RSR_RXN<12> PE2_RX_DN<12> @BASEBOARD_FAB2_LIB.BASEBOARD_FAB2(SCH_1):TP_P3E_CPU1_PE2_RSR_RXN(12)
 BT7 TP_P3E_CPU1_PE2_RSR_RXN<11> PE2_RX_DN<11> @BASEBOARD_FAB2_LIB.BASEBOARD_FAB2(SCH_1):TP_P3E_CPU1_PE2_RSR_RXN(11)
 BV7 TP_P3E_CPU1_PE2_RSR_RXN<10> PE2_RX_DN<10> @BASEBOARD_FAB2_LIB.BASEBOARD_FAB2(SCH_1):TP_P3E_CPU1_PE2_RSR_RXN(10)
 BY7 TP_P3E_CPU1_PE2_RSR_RXN<9> PE2_RX_DN<9> @BASEBOARD_FAB2_LIB.BASEBOARD_FAB2(SCH_1):TP_P3E_CPU1_PE2_RSR_RXN(9)
 BY9 TP_P3E_CPU1_PE2_RSR_RXN<8> PE2_RX_DN<8> @BASEBOARD_FAB2_LIB.BASEBOARD_FAB2(SCH_1):TP_P3E_CPU1_PE2_RSR_RXN(8)
 CE8 TP_P3E_CPU1_PE2_RSR_RXN<7> PE2_RX_DN<7> @BASEBOARD_FAB2_LIB.BASEBOARD_FAB2(SCH_1):TP_P3E_CPU1_PE2_RSR_RXN(7)
 CE6 TP_P3E_CPU1_PE2_RSR_RXN<6> PE2_RX_DN<6> @BASEBOARD_FAB2_LIB.BASEBOARD_FAB2(SCH_1):TP_P3E_CPU1_PE2_RSR_RXN(6)
 CG8 TP_P3E_CPU1_PE2_RSR_RXN<5> PE2_RX_DN<5> @BASEBOARD_FAB2_LIB.BASEBOARD_FAB2(SCH_1):TP_P3E_CPU1_PE2_RSR_RXN(5)
 CK7 TP_P3E_CPU1_PE2_RSR_RXN<4> PE2_RX_DN<4> @BASEBOARD_FAB2_LIB.BASEBOARD_FAB2(SCH_1):TP_P3E_CPU1_PE2_RSR_RXN(4)
 CM7 TP_P3E_CPU1_PE2_RSR_RXN<3> PE2_RX_DN<3> @BASEBOARD_FAB2_LIB.BASEBOARD_FAB2(SCH_1):TP_P3E_CPU1_PE2_RSR_RXN(3)
 CP7 TP_P3E_CPU1_PE2_RSR_RXN<2> PE2_RX_DN<2> @BASEBOARD_FAB2_LIB.BASEBOARD_FAB2(SCH_1):TP_P3E_CPU1_PE2_RSR_RXN(2)
 CP9 TP_P3E_CPU1_PE2_RSR_RXN<1> PE2_RX_DN<1> @BASEBOARD_FAB2_LIB.BASEBOARD_FAB2(SCH_1):TP_P3E_CPU1_PE2_RSR_RXN(1)
 CT9 TP_P3E_CPU1_PE2_RSR_RXN<0> PE2_RX_DN<0> @BASEBOARD_FAB2_LIB.BASEBOARD_FAB2(SCH_1):TP_P3E_CPU1_PE2_RSR_RXN(0)
BJ10 TP_P3E_CPU1_PE2_RSR_RXP<15> PE2_RX_DP<15> @BASEBOARD_FAB2_LIB.BASEBOARD_FAB2(SCH_1):TP_P3E_CPU1_PE2_RSR_RXP(15)
 BJ8 TP_P3E_CPU1_PE2_RSR_RXP<14> PE2_RX_DP<14> @BASEBOARD_FAB2_LIB.BASEBOARD_FAB2(SCH_1):TP_P3E_CPU1_PE2_RSR_RXP(14)
 BM7 TP_P3E_CPU1_PE2_RSR_RXP<13> PE2_RX_DP<13> @BASEBOARD_FAB2_LIB.BASEBOARD_FAB2(SCH_1):TP_P3E_CPU1_PE2_RSR_RXP(13)
 BP9 TP_P3E_CPU1_PE2_RSR_RXP<12> PE2_RX_DP<12> @BASEBOARD_FAB2_LIB.BASEBOARD_FAB2(SCH_1):TP_P3E_CPU1_PE2_RSR_RXP(12)
 BP7 TP_P3E_CPU1_PE2_RSR_RXP<11> PE2_RX_DP<11> @BASEBOARD_FAB2_LIB.BASEBOARD_FAB2(SCH_1):TP_P3E_CPU1_PE2_RSR_RXP(11)
 BU6 TP_P3E_CPU1_PE2_RSR_RXP<10> PE2_RX_DP<10> @BASEBOARD_FAB2_LIB.BASEBOARD_FAB2(SCH_1):TP_P3E_CPU1_PE2_RSR_RXP(10)
 BW8 TP_P3E_CPU1_PE2_RSR_RXP<9> PE2_RX_DP<9> @BASEBOARD_FAB2_LIB.BASEBOARD_FAB2(SCH_1):TP_P3E_CPU1_PE2_RSR_RXP(9)
 BV9 TP_P3E_CPU1_PE2_RSR_RXP<8> PE2_RX_DP<8> @BASEBOARD_FAB2_LIB.BASEBOARD_FAB2(SCH_1):TP_P3E_CPU1_PE2_RSR_RXP(8)
 CC8 TP_P3E_CPU1_PE2_RSR_RXP<7> PE2_RX_DP<7> @BASEBOARD_FAB2_LIB.BASEBOARD_FAB2(SCH_1):TP_P3E_CPU1_PE2_RSR_RXP(7)
 CD7 TP_P3E_CPU1_PE2_RSR_RXP<6> PE2_RX_DP<6> @BASEBOARD_FAB2_LIB.BASEBOARD_FAB2(SCH_1):TP_P3E_CPU1_PE2_RSR_RXP(6)
 CF7 TP_P3E_CPU1_PE2_RSR_RXP<5> PE2_RX_DP<5> @BASEBOARD_FAB2_LIB.BASEBOARD_FAB2(SCH_1):TP_P3E_CPU1_PE2_RSR_RXP(5)
 CH7 TP_P3E_CPU1_PE2_RSR_RXP<4> PE2_RX_DP<4> @BASEBOARD_FAB2_LIB.BASEBOARD_FAB2(SCH_1):TP_P3E_CPU1_PE2_RSR_RXP(4)
 CL6 TP_P3E_CPU1_PE2_RSR_RXP<3> PE2_RX_DP<3> @BASEBOARD_FAB2_LIB.BASEBOARD_FAB2(SCH_1):TP_P3E_CPU1_PE2_RSR_RXP(3)
 CN8 TP_P3E_CPU1_PE2_RSR_RXP<2> PE2_RX_DP<2> @BASEBOARD_FAB2_LIB.BASEBOARD_FAB2(SCH_1):TP_P3E_CPU1_PE2_RSR_RXP(2)
 CM9 TP_P3E_CPU1_PE2_RSR_RXP<1> PE2_RX_DP<1> @BASEBOARD_FAB2_LIB.BASEBOARD_FAB2(SCH_1):TP_P3E_CPU1_PE2_RSR_RXP(1)
 CR8 TP_P3E_CPU1_PE2_RSR_RXP<0> PE2_RX_DP<0> @BASEBOARD_FAB2_LIB.BASEBOARD_FAB2(SCH_1):TP_P3E_CPU1_PE2_RSR_RXP(0)
 BM5 TP_P3E_CPU1_PE2_RSR_TXN<15> PE2_TX_DN<15> @BASEBOARD_FAB2_LIB.BASEBOARD_FAB2(SCH_1):TP_P3E_CPU1_PE2_RSR_TXN(15)
 BL4 TP_P3E_CPU1_PE2_RSR_TXN<14> PE2_TX_DN<14> @BASEBOARD_FAB2_LIB.BASEBOARD_FAB2(SCH_1):TP_P3E_CPU1_PE2_RSR_TXN(14)
 BP5 TP_P3E_CPU1_PE2_RSR_TXN<13> PE2_TX_DN<13> @BASEBOARD_FAB2_LIB.BASEBOARD_FAB2(SCH_1):TP_P3E_CPU1_PE2_RSR_TXN(13)
 BU4 TP_P3E_CPU1_PE2_RSR_TXN<12> PE2_TX_DN<12> @BASEBOARD_FAB2_LIB.BASEBOARD_FAB2(SCH_1):TP_P3E_CPU1_PE2_RSR_TXN(12)
 BW4 TP_P3E_CPU1_PE2_RSR_TXN<11> PE2_TX_DN<11> @BASEBOARD_FAB2_LIB.BASEBOARD_FAB2(SCH_1):TP_P3E_CPU1_PE2_RSR_TXN(11)
 CA4 TP_P3E_CPU1_PE2_RSR_TXN<10> PE2_TX_DN<10> @BASEBOARD_FAB2_LIB.BASEBOARD_FAB2(SCH_1):TP_P3E_CPU1_PE2_RSR_TXN(10)
 CB3 TP_P3E_CPU1_PE2_RSR_TXN<9> PE2_TX_DN<9> @BASEBOARD_FAB2_LIB.BASEBOARD_FAB2(SCH_1):TP_P3E_CPU1_PE2_RSR_TXN(9)
 CC2 TP_P3E_CPU1_PE2_RSR_TXN<8> PE2_TX_DN<8> @BASEBOARD_FAB2_LIB.BASEBOARD_FAB2(SCH_1):TP_P3E_CPU1_PE2_RSR_TXN(8)
 CF3 TP_P3E_CPU1_PE2_RSR_TXN<7> PE2_TX_DN<7> @BASEBOARD_FAB2_LIB.BASEBOARD_FAB2(SCH_1):TP_P3E_CPU1_PE2_RSR_TXN(7)
 CG2 TP_P3E_CPU1_PE2_RSR_TXN<6> PE2_TX_DN<6> @BASEBOARD_FAB2_LIB.BASEBOARD_FAB2(SCH_1):TP_P3E_CPU1_PE2_RSR_TXN(6)
 CL2 TP_P3E_CPU1_PE2_RSR_TXN<5> PE2_TX_DN<5> @BASEBOARD_FAB2_LIB.BASEBOARD_FAB2(SCH_1):TP_P3E_CPU1_PE2_RSR_TXN(5)
 CM1 TP_P3E_CPU1_PE2_RSR_TXN<4> PE2_TX_DN<4> @BASEBOARD_FAB2_LIB.BASEBOARD_FAB2(SCH_1):TP_P3E_CPU1_PE2_RSR_TXN(4)
 CT3 TP_P3E_CPU1_PE2_RSR_TXN<3> PE2_TX_DN<3> @BASEBOARD_FAB2_LIB.BASEBOARD_FAB2(SCH_1):TP_P3E_CPU1_PE2_RSR_TXN(3)
 CT1 TP_P3E_CPU1_PE2_RSR_TXN<2> PE2_TX_DN<2> @BASEBOARD_FAB2_LIB.BASEBOARD_FAB2(SCH_1):TP_P3E_CPU1_PE2_RSR_TXN(2)
 CV3 TP_P3E_CPU1_PE2_RSR_TXN<1> PE2_TX_DN<1> @BASEBOARD_FAB2_LIB.BASEBOARD_FAB2(SCH_1):TP_P3E_CPU1_PE2_RSR_TXN(1)
 CY3 TP_P3E_CPU1_PE2_RSR_TXN<0> PE2_TX_DN<0> @BASEBOARD_FAB2_LIB.BASEBOARD_FAB2(SCH_1):TP_P3E_CPU1_PE2_RSR_TXN(0)
 BK5 TP_P3E_CPU1_PE2_RSR_TXP<15> PE2_TX_DP<15> @BASEBOARD_FAB2_LIB.BASEBOARD_FAB2(SCH_1):TP_P3E_CPU1_PE2_RSR_TXP(15)
 BM3 TP_P3E_CPU1_PE2_RSR_TXP<14> PE2_TX_DP<14> @BASEBOARD_FAB2_LIB.BASEBOARD_FAB2(SCH_1):TP_P3E_CPU1_PE2_RSR_TXP(14)
 BN4 TP_P3E_CPU1_PE2_RSR_TXP<13> PE2_TX_DP<13> @BASEBOARD_FAB2_LIB.BASEBOARD_FAB2(SCH_1):TP_P3E_CPU1_PE2_RSR_TXP(13)
 BR4 TP_P3E_CPU1_PE2_RSR_TXP<12> PE2_TX_DP<12> @BASEBOARD_FAB2_LIB.BASEBOARD_FAB2(SCH_1):TP_P3E_CPU1_PE2_RSR_TXP(12)
 BV3 TP_P3E_CPU1_PE2_RSR_TXP<11> PE2_TX_DP<11> @BASEBOARD_FAB2_LIB.BASEBOARD_FAB2(SCH_1):TP_P3E_CPU1_PE2_RSR_TXP(11)
 BY5 TP_P3E_CPU1_PE2_RSR_TXP<10> PE2_TX_DP<10> @BASEBOARD_FAB2_LIB.BASEBOARD_FAB2(SCH_1):TP_P3E_CPU1_PE2_RSR_TXP(10)
 BY3 TP_P3E_CPU1_PE2_RSR_TXP<9> PE2_TX_DP<9> @BASEBOARD_FAB2_LIB.BASEBOARD_FAB2(SCH_1):TP_P3E_CPU1_PE2_RSR_TXP(9)
 CD3 TP_P3E_CPU1_PE2_RSR_TXP<8> PE2_TX_DP<8> @BASEBOARD_FAB2_LIB.BASEBOARD_FAB2(SCH_1):TP_P3E_CPU1_PE2_RSR_TXP(8)
 CE4 TP_P3E_CPU1_PE2_RSR_TXP<7> PE2_TX_DP<7> @BASEBOARD_FAB2_LIB.BASEBOARD_FAB2(SCH_1):TP_P3E_CPU1_PE2_RSR_TXP(7)
 CE2 TP_P3E_CPU1_PE2_RSR_TXP<6> PE2_TX_DP<6> @BASEBOARD_FAB2_LIB.BASEBOARD_FAB2(SCH_1):TP_P3E_CPU1_PE2_RSR_TXP(6)
 CK3 TP_P3E_CPU1_PE2_RSR_TXP<5> PE2_TX_DP<5> @BASEBOARD_FAB2_LIB.BASEBOARD_FAB2(SCH_1):TP_P3E_CPU1_PE2_RSR_TXP(5)
 CK1 TP_P3E_CPU1_PE2_RSR_TXP<4> PE2_TX_DP<4> @BASEBOARD_FAB2_LIB.BASEBOARD_FAB2(SCH_1):TP_P3E_CPU1_PE2_RSR_TXP(4)
 CP3 TP_P3E_CPU1_PE2_RSR_TXP<3> PE2_TX_DP<3> @BASEBOARD_FAB2_LIB.BASEBOARD_FAB2(SCH_1):TP_P3E_CPU1_PE2_RSR_TXP(3)
 CR2 TP_P3E_CPU1_PE2_RSR_TXP<2> PE2_TX_DP<2> @BASEBOARD_FAB2_LIB.BASEBOARD_FAB2(SCH_1):TP_P3E_CPU1_PE2_RSR_TXP(2)
 CU2 TP_P3E_CPU1_PE2_RSR_TXP<1> PE2_TX_DP<1> @BASEBOARD_FAB2_LIB.BASEBOARD_FAB2(SCH_1):TP_P3E_CPU1_PE2_RSR_TXP(1)
 CW4 TP_P3E_CPU1_PE2_RSR_TXP<0> PE2_TX_DP<0> @BASEBOARD_FAB2_LIB.BASEBOARD_FAB2(SCH_1):TP_P3E_CPU1_PE2_RSR_TXP(0)


DRAWING: @BASEBOARD_FAB2_LIB.BASEBOARD_FAB2(SCH_1):PAGE66 

SKX_EXT_B_BGA1-IC,TBD  I84  U2D1
 CV9 P3E_CPU1_PE3_MP_RXN<15> PE3_RX_DN<15> @BASEBOARD_FAB2_LIB.BASEBOARD_FAB2(SCH_1):P3E_CPU1_PE3_MP_RXN(15)
CY11 P3E_CPU1_PE3_MP_RXN<14> PE3_RX_DN<14> @BASEBOARD_FAB2_LIB.BASEBOARD_FAB2(SCH_1):P3E_CPU1_PE3_MP_RXN(14)
DB11 P3E_CPU1_PE3_MP_RXN<13> PE3_RX_DN<13> @BASEBOARD_FAB2_LIB.BASEBOARD_FAB2(SCH_1):P3E_CPU1_PE3_MP_RXN(13)
DD13 P3E_CPU1_PE3_MP_RXP<12> PE3_RX_DN<12> @BASEBOARD_FAB2_LIB.BASEBOARD_FAB2(SCH_1):P3E_CPU1_PE3_MP_RXP(12)
DG10 P3E_CPU1_PE3_MP_RXN<11> PE3_RX_DN<11> @BASEBOARD_FAB2_LIB.BASEBOARD_FAB2(SCH_1):P3E_CPU1_PE3_MP_RXN(11)
DG12 P3E_CPU1_PE3_MP_RXN<10> PE3_RX_DN<10> @BASEBOARD_FAB2_LIB.BASEBOARD_FAB2(SCH_1):P3E_CPU1_PE3_MP_RXN(10)
DJ12 P3E_CPU1_PE3_MP_RXN<9> PE3_RX_DN<9> @BASEBOARD_FAB2_LIB.BASEBOARD_FAB2(SCH_1):P3E_CPU1_PE3_MP_RXN(9)
DL12 P3E_CPU1_PE3_MP_RXN<8> PE3_RX_DN<8> @BASEBOARD_FAB2_LIB.BASEBOARD_FAB2(SCH_1):P3E_CPU1_PE3_MP_RXN(8)
DL14 P3E_CPU1_PE3_MP_RXN<7> PE3_RX_DN<7> @BASEBOARD_FAB2_LIB.BASEBOARD_FAB2(SCH_1):P3E_CPU1_PE3_MP_RXN(7)
DN14 P3E_CPU1_PE3_MP_RXN<6> PE3_RX_DN<6> @BASEBOARD_FAB2_LIB.BASEBOARD_FAB2(SCH_1):P3E_CPU1_PE3_MP_RXN(6)
DR14 P3E_CPU1_PE3_MP_RXN<5> PE3_RX_DN<5> @BASEBOARD_FAB2_LIB.BASEBOARD_FAB2(SCH_1):P3E_CPU1_PE3_MP_RXN(5)
DR16 P3E_CPU1_PE3_MP_RXN<4> PE3_RX_DN<4> @BASEBOARD_FAB2_LIB.BASEBOARD_FAB2(SCH_1):P3E_CPU1_PE3_MP_RXN(4)
DT19 P3E_CPU1_PE3_MP_RXN<3> PE3_RX_DN<3> @BASEBOARD_FAB2_LIB.BASEBOARD_FAB2(SCH_1):P3E_CPU1_PE3_MP_RXN(3)
DW16 P3E_CPU1_PE3_MP_RXN<2> PE3_RX_DN<2> @BASEBOARD_FAB2_LIB.BASEBOARD_FAB2(SCH_1):P3E_CPU1_PE3_MP_RXN(2)
DW18 P3E_CPU1_PE3_MP_RXN<1> PE3_RX_DN<1> @BASEBOARD_FAB2_LIB.BASEBOARD_FAB2(SCH_1):P3E_CPU1_PE3_MP_RXN(1)
EA18 P3E_CPU1_PE3_MP_RXN<0> PE3_RX_DN<0> @BASEBOARD_FAB2_LIB.BASEBOARD_FAB2(SCH_1):P3E_CPU1_PE3_MP_RXN(0)
CU10 P3E_CPU1_PE3_MP_RXP<15> PE3_RX_DP<15> @BASEBOARD_FAB2_LIB.BASEBOARD_FAB2(SCH_1):P3E_CPU1_PE3_MP_RXP(15)
CW10 P3E_CPU1_PE3_MP_RXP<14> PE3_RX_DP<14> @BASEBOARD_FAB2_LIB.BASEBOARD_FAB2(SCH_1):P3E_CPU1_PE3_MP_RXP(14)
DA12 P3E_CPU1_PE3_MP_RXP<13> PE3_RX_DP<13> @BASEBOARD_FAB2_LIB.BASEBOARD_FAB2(SCH_1):P3E_CPU1_PE3_MP_RXP(13)
DC12 P3E_CPU1_PE3_MP_RXN<12> PE3_RX_DP<12> @BASEBOARD_FAB2_LIB.BASEBOARD_FAB2(SCH_1):P3E_CPU1_PE3_MP_RXN(12)
DF11 P3E_CPU1_PE3_MP_RXP<11> PE3_RX_DP<11> @BASEBOARD_FAB2_LIB.BASEBOARD_FAB2(SCH_1):P3E_CPU1_PE3_MP_RXP(11)
DE12 P3E_CPU1_PE3_MP_RXP<10> PE3_RX_DP<10> @BASEBOARD_FAB2_LIB.BASEBOARD_FAB2(SCH_1):P3E_CPU1_PE3_MP_RXP(10)
DH11 P3E_CPU1_PE3_MP_RXP<9> PE3_RX_DP<9> @BASEBOARD_FAB2_LIB.BASEBOARD_FAB2(SCH_1):P3E_CPU1_PE3_MP_RXP(9)
DK13 P3E_CPU1_PE3_MP_RXP<8> PE3_RX_DP<8> @BASEBOARD_FAB2_LIB.BASEBOARD_FAB2(SCH_1):P3E_CPU1_PE3_MP_RXP(8)
DJ14 P3E_CPU1_PE3_MP_RXP<7> PE3_RX_DP<7> @BASEBOARD_FAB2_LIB.BASEBOARD_FAB2(SCH_1):P3E_CPU1_PE3_MP_RXP(7)
DM13 P3E_CPU1_PE3_MP_RXP<6> PE3_RX_DP<6> @BASEBOARD_FAB2_LIB.BASEBOARD_FAB2(SCH_1):P3E_CPU1_PE3_MP_RXP(6)
DP15 P3E_CPU1_PE3_MP_RXP<5> PE3_RX_DP<5> @BASEBOARD_FAB2_LIB.BASEBOARD_FAB2(SCH_1):P3E_CPU1_PE3_MP_RXP(5)
DN16 P3E_CPU1_PE3_MP_RXP<4> PE3_RX_DP<4> @BASEBOARD_FAB2_LIB.BASEBOARD_FAB2(SCH_1):P3E_CPU1_PE3_MP_RXP(4)
DR18 P3E_CPU1_PE3_MP_RXP<3> PE3_RX_DP<3> @BASEBOARD_FAB2_LIB.BASEBOARD_FAB2(SCH_1):P3E_CPU1_PE3_MP_RXP(3)
DV17 P3E_CPU1_PE3_MP_RXP<2> PE3_RX_DP<2> @BASEBOARD_FAB2_LIB.BASEBOARD_FAB2(SCH_1):P3E_CPU1_PE3_MP_RXP(2)
DU18 P3E_CPU1_PE3_MP_RXP<1> PE3_RX_DP<1> @BASEBOARD_FAB2_LIB.BASEBOARD_FAB2(SCH_1):P3E_CPU1_PE3_MP_RXP(1)
DY17 P3E_CPU1_PE3_MP_RXP<0> PE3_RX_DP<0> @BASEBOARD_FAB2_LIB.BASEBOARD_FAB2(SCH_1):P3E_CPU1_PE3_MP_RXP(0)
 CY5 P3E_CPU1_PE3_MP_TXN<15> PE3_TX_DN<15> @BASEBOARD_FAB2_LIB.BASEBOARD_FAB2(SCH_1):P3E_CPU1_PE3_MP_TXN(15)
 DB5 P3E_CPU1_PE3_MP_TXN<14> PE3_TX_DN<14> @BASEBOARD_FAB2_LIB.BASEBOARD_FAB2(SCH_1):P3E_CPU1_PE3_MP_TXN(14)
 DD5 P3E_CPU1_PE3_MP_TXN<13> PE3_TX_DN<13> @BASEBOARD_FAB2_LIB.BASEBOARD_FAB2(SCH_1):P3E_CPU1_PE3_MP_TXN(13)
 DJ6 P3E_CPU1_PE3_MP_TXN<12> PE3_TX_DN<12> @BASEBOARD_FAB2_LIB.BASEBOARD_FAB2(SCH_1):P3E_CPU1_PE3_MP_TXN(12)
 DJ4 P3E_CPU1_PE3_MP_TXN<11> PE3_TX_DN<11> @BASEBOARD_FAB2_LIB.BASEBOARD_FAB2(SCH_1):P3E_CPU1_PE3_MP_TXN(11)
 DL6 P3E_CPU1_PE3_MP_TXN<10> PE3_TX_DN<10> @BASEBOARD_FAB2_LIB.BASEBOARD_FAB2(SCH_1):P3E_CPU1_PE3_MP_TXN(10)
 DP5 P3E_CPU1_PE3_MP_TXN<9> PE3_TX_DN<9> @BASEBOARD_FAB2_LIB.BASEBOARD_FAB2(SCH_1):P3E_CPU1_PE3_MP_TXN(9)
 DM7 P3E_CPU1_PE3_MP_TXN<8> PE3_TX_DN<8> @BASEBOARD_FAB2_LIB.BASEBOARD_FAB2(SCH_1):P3E_CPU1_PE3_MP_TXN(8)
 DR8 P3E_CPU1_PE3_MP_TXN<7> PE3_TX_DN<7> @BASEBOARD_FAB2_LIB.BASEBOARD_FAB2(SCH_1):P3E_CPU1_PE3_MP_TXN(7)
 DU8 P3E_CPU1_PE3_MP_TXN<6> PE3_TX_DN<6> @BASEBOARD_FAB2_LIB.BASEBOARD_FAB2(SCH_1):P3E_CPU1_PE3_MP_TXN(6)
DW10 P3E_CPU1_PE3_MP_TXN<5> PE3_TX_DN<5> @BASEBOARD_FAB2_LIB.BASEBOARD_FAB2(SCH_1):P3E_CPU1_PE3_MP_TXN(5)
 EB9 P3E_CPU1_PE3_MP_TXN<4> PE3_TX_DN<4> @BASEBOARD_FAB2_LIB.BASEBOARD_FAB2(SCH_1):P3E_CPU1_PE3_MP_TXN(4)
DY11 P3E_CPU1_PE3_MP_TXN<3> PE3_TX_DN<3> @BASEBOARD_FAB2_LIB.BASEBOARD_FAB2(SCH_1):P3E_CPU1_PE3_MP_TXN(3)
EC12 P3E_CPU1_PE3_MP_TXN<2> PE3_TX_DN<2> @BASEBOARD_FAB2_LIB.BASEBOARD_FAB2(SCH_1):P3E_CPU1_PE3_MP_TXN(2)
EE12 P3E_CPU1_PE3_MP_TXN<1> PE3_TX_DN<1> @BASEBOARD_FAB2_LIB.BASEBOARD_FAB2(SCH_1):P3E_CPU1_PE3_MP_TXN(1)
EE14 P3E_CPU1_PE3_MP_TXN<0> PE3_TX_DN<0> @BASEBOARD_FAB2_LIB.BASEBOARD_FAB2(SCH_1):P3E_CPU1_PE3_MP_TXN(0)
 CV5 P3E_CPU1_PE3_MP_TXP<15> PE3_TX_DP<15> @BASEBOARD_FAB2_LIB.BASEBOARD_FAB2(SCH_1):P3E_CPU1_PE3_MP_TXP(15)
 DA4 P3E_CPU1_PE3_MP_TXP<14> PE3_TX_DP<14> @BASEBOARD_FAB2_LIB.BASEBOARD_FAB2(SCH_1):P3E_CPU1_PE3_MP_TXP(14)
 DC6 P3E_CPU1_PE3_MP_TXP<13> PE3_TX_DP<13> @BASEBOARD_FAB2_LIB.BASEBOARD_FAB2(SCH_1):P3E_CPU1_PE3_MP_TXP(13)
 DG6 P3E_CPU1_PE3_MP_TXP<12> PE3_TX_DP<12> @BASEBOARD_FAB2_LIB.BASEBOARD_FAB2(SCH_1):P3E_CPU1_PE3_MP_TXP(12)
 DH5 P3E_CPU1_PE3_MP_TXP<11> PE3_TX_DP<11> @BASEBOARD_FAB2_LIB.BASEBOARD_FAB2(SCH_1):P3E_CPU1_PE3_MP_TXP(11)
 DK5 P3E_CPU1_PE3_MP_TXP<10> PE3_TX_DP<10> @BASEBOARD_FAB2_LIB.BASEBOARD_FAB2(SCH_1):P3E_CPU1_PE3_MP_TXP(10)
 DM5 P3E_CPU1_PE3_MP_TXP<9> PE3_TX_DP<9> @BASEBOARD_FAB2_LIB.BASEBOARD_FAB2(SCH_1):P3E_CPU1_PE3_MP_TXP(9)
 DN6 P3E_CPU1_PE3_MP_TXP<8> PE3_TX_DP<8> @BASEBOARD_FAB2_LIB.BASEBOARD_FAB2(SCH_1):P3E_CPU1_PE3_MP_TXP(8)
 DP7 P3E_CPU1_PE3_MP_TXP<7> PE3_TX_DP<7> @BASEBOARD_FAB2_LIB.BASEBOARD_FAB2(SCH_1):P3E_CPU1_PE3_MP_TXP(7)
 DT9 P3E_CPU1_PE3_MP_TXP<6> PE3_TX_DP<6> @BASEBOARD_FAB2_LIB.BASEBOARD_FAB2(SCH_1):P3E_CPU1_PE3_MP_TXP(6)
 DV9 P3E_CPU1_PE3_MP_TXP<5> PE3_TX_DP<5> @BASEBOARD_FAB2_LIB.BASEBOARD_FAB2(SCH_1):P3E_CPU1_PE3_MP_TXP(5)
 DY9 P3E_CPU1_PE3_MP_TXP<4> PE3_TX_DP<4> @BASEBOARD_FAB2_LIB.BASEBOARD_FAB2(SCH_1):P3E_CPU1_PE3_MP_TXP(4)
EA10 P3E_CPU1_PE3_MP_TXP<3> PE3_TX_DP<3> @BASEBOARD_FAB2_LIB.BASEBOARD_FAB2(SCH_1):P3E_CPU1_PE3_MP_TXP(3)
EB11 P3E_CPU1_PE3_MP_TXP<2> PE3_TX_DP<2> @BASEBOARD_FAB2_LIB.BASEBOARD_FAB2(SCH_1):P3E_CPU1_PE3_MP_TXP(2)
ED13 P3E_CPU1_PE3_MP_TXP<1> PE3_TX_DP<1> @BASEBOARD_FAB2_LIB.BASEBOARD_FAB2(SCH_1):P3E_CPU1_PE3_MP_TXP(1)
EC14 P3E_CPU1_PE3_MP_TXP<0> PE3_TX_DP<0> @BASEBOARD_FAB2_LIB.BASEBOARD_FAB2(SCH_1):P3E_CPU1_PE3_MP_TXP(0)


DRAWING: @BASEBOARD_FAB2_LIB.BASEBOARD_FAB2(SCH_1):PAGE67 

SKX_EXT_B_BGA1-IC,TBD  I132  U2D1
BB11 UPI_CPU0_CPU1_P0P0_DP<19> UPI0_RX_DN<19> @BASEBOARD_FAB2_LIB.BASEBOARD_FAB2(SCH_1):UPI_CPU0_CPU1_P0P0_DP(19)
 BD9 UPI_CPU0_CPU1_P0P0_DP<18> UPI0_RX_DN<18> @BASEBOARD_FAB2_LIB.BASEBOARD_FAB2(SCH_1):UPI_CPU0_CPU1_P0P0_DP(18)
 AY9 UPI_CPU0_CPU1_P0P0_DN<17> UPI0_RX_DN<17> @BASEBOARD_FAB2_LIB.BASEBOARD_FAB2(SCH_1):UPI_CPU0_CPU1_P0P0_DN(17)
 AW8 UPI_CPU0_CPU1_P0P0_DN<16> UPI0_RX_DN<16> @BASEBOARD_FAB2_LIB.BASEBOARD_FAB2(SCH_1):UPI_CPU0_CPU1_P0P0_DN(16)
 BD7 UPI_CPU0_CPU1_P0P0_DN<15> UPI0_RX_DN<15> @BASEBOARD_FAB2_LIB.BASEBOARD_FAB2(SCH_1):UPI_CPU0_CPU1_P0P0_DN(15)
 BC6 UPI_CPU0_CPU1_P0P0_DP<14> UPI0_RX_DN<14> @BASEBOARD_FAB2_LIB.BASEBOARD_FAB2(SCH_1):UPI_CPU0_CPU1_P0P0_DP(14)
 BA8 UPI_CPU0_CPU1_P0P0_DN<13> UPI0_RX_DN<13> @BASEBOARD_FAB2_LIB.BASEBOARD_FAB2(SCH_1):UPI_CPU0_CPU1_P0P0_DN(13)
AU10 UPI_CPU0_CPU1_P0P0_DN<12> UPI0_RX_DN<12> @BASEBOARD_FAB2_LIB.BASEBOARD_FAB2(SCH_1):UPI_CPU0_CPU1_P0P0_DN(12)
 AR8 UPI_CPU0_CPU1_P0P0_DP<11> UPI0_RX_DN<11> @BASEBOARD_FAB2_LIB.BASEBOARD_FAB2(SCH_1):UPI_CPU0_CPU1_P0P0_DP(11)
 AP7 UPI_CPU0_CPU1_P0P0_DN<10> UPI0_RX_DN<10> @BASEBOARD_FAB2_LIB.BASEBOARD_FAB2(SCH_1):UPI_CPU0_CPU1_P0P0_DN(10)
 AM9 UPI_CPU0_CPU1_P0P0_DP<9> UPI0_RX_DN<9> @BASEBOARD_FAB2_LIB.BASEBOARD_FAB2(SCH_1):UPI_CPU0_CPU1_P0P0_DP(9)
 AK7 UPI_CPU0_CPU1_P0P0_DP<8> UPI0_RX_DN<8> @BASEBOARD_FAB2_LIB.BASEBOARD_FAB2(SCH_1):UPI_CPU0_CPU1_P0P0_DP(8)
 AL6 UPI_CPU0_CPU1_P0P0_DP<7> UPI0_RX_DN<7> @BASEBOARD_FAB2_LIB.BASEBOARD_FAB2(SCH_1):UPI_CPU0_CPU1_P0P0_DP(7)
 AJ6 UPI_CPU0_CPU1_P0P0_DP<6> UPI0_RX_DN<6> @BASEBOARD_FAB2_LIB.BASEBOARD_FAB2(SCH_1):UPI_CPU0_CPU1_P0P0_DP(6)
 AG8 UPI_CPU0_CPU1_P0P0_DP<5> UPI0_RX_DN<5> @BASEBOARD_FAB2_LIB.BASEBOARD_FAB2(SCH_1):UPI_CPU0_CPU1_P0P0_DP(5)
 AE6 UPI_CPU0_CPU1_P0P0_DP<4> UPI0_RX_DN<4> @BASEBOARD_FAB2_LIB.BASEBOARD_FAB2(SCH_1):UPI_CPU0_CPU1_P0P0_DP(4)
 AD5 UPI_CPU0_CPU1_P0P0_DP<3> UPI0_RX_DN<3> @BASEBOARD_FAB2_LIB.BASEBOARD_FAB2(SCH_1):UPI_CPU0_CPU1_P0P0_DP(3)
 AB7 UPI_CPU0_CPU1_P0P0_DN<2> UPI0_RX_DN<2> @BASEBOARD_FAB2_LIB.BASEBOARD_FAB2(SCH_1):UPI_CPU0_CPU1_P0P0_DN(2)
 AA8 UPI_CPU0_CPU1_P0P0_DN<1> UPI0_RX_DN<1> @BASEBOARD_FAB2_LIB.BASEBOARD_FAB2(SCH_1):UPI_CPU0_CPU1_P0P0_DN(1)
AC10 UPI_CPU0_CPU1_P0P0_DP<0> UPI0_RX_DN<0> @BASEBOARD_FAB2_LIB.BASEBOARD_FAB2(SCH_1):UPI_CPU0_CPU1_P0P0_DP(0)
BA10 UPI_CPU0_CPU1_P0P0_DN<19> UPI0_RX_DP<19> @BASEBOARD_FAB2_LIB.BASEBOARD_FAB2(SCH_1):UPI_CPU0_CPU1_P0P0_DN(19)
BC10 UPI_CPU0_CPU1_P0P0_DN<18> UPI0_RX_DP<18> @BASEBOARD_FAB2_LIB.BASEBOARD_FAB2(SCH_1):UPI_CPU0_CPU1_P0P0_DN(18)
 BB9 UPI_CPU0_CPU1_P0P0_DP<17> UPI0_RX_DP<17> @BASEBOARD_FAB2_LIB.BASEBOARD_FAB2(SCH_1):UPI_CPU0_CPU1_P0P0_DP(17)
 AV9 UPI_CPU0_CPU1_P0P0_DP<16> UPI0_RX_DP<16> @BASEBOARD_FAB2_LIB.BASEBOARD_FAB2(SCH_1):UPI_CPU0_CPU1_P0P0_DP(16)
 BF7 UPI_CPU0_CPU1_P0P0_DP<15> UPI0_RX_DP<15> @BASEBOARD_FAB2_LIB.BASEBOARD_FAB2(SCH_1):UPI_CPU0_CPU1_P0P0_DP(15)
 BB7 UPI_CPU0_CPU1_P0P0_DN<14> UPI0_RX_DP<14> @BASEBOARD_FAB2_LIB.BASEBOARD_FAB2(SCH_1):UPI_CPU0_CPU1_P0P0_DN(14)
 AY7 UPI_CPU0_CPU1_P0P0_DP<13> UPI0_RX_DP<13> @BASEBOARD_FAB2_LIB.BASEBOARD_FAB2(SCH_1):UPI_CPU0_CPU1_P0P0_DP(13)
 AT9 UPI_CPU0_CPU1_P0P0_DP<12> UPI0_RX_DP<12> @BASEBOARD_FAB2_LIB.BASEBOARD_FAB2(SCH_1):UPI_CPU0_CPU1_P0P0_DP(12)
 AU8 UPI_CPU0_CPU1_P0P0_DN<11> UPI0_RX_DP<11> @BASEBOARD_FAB2_LIB.BASEBOARD_FAB2(SCH_1):UPI_CPU0_CPU1_P0P0_DN(11)
 AN8 UPI_CPU0_CPU1_P0P0_DP<10> UPI0_RX_DP<10> @BASEBOARD_FAB2_LIB.BASEBOARD_FAB2(SCH_1):UPI_CPU0_CPU1_P0P0_DP(10)
 AL8 UPI_CPU0_CPU1_P0P0_DN<9> UPI0_RX_DP<9> @BASEBOARD_FAB2_LIB.BASEBOARD_FAB2(SCH_1):UPI_CPU0_CPU1_P0P0_DN(9)
 AM7 UPI_CPU0_CPU1_P0P0_DN<8> UPI0_RX_DP<8> @BASEBOARD_FAB2_LIB.BASEBOARD_FAB2(SCH_1):UPI_CPU0_CPU1_P0P0_DN(8)
 AK5 UPI_CPU0_CPU1_P0P0_DN<7> UPI0_RX_DP<7> @BASEBOARD_FAB2_LIB.BASEBOARD_FAB2(SCH_1):UPI_CPU0_CPU1_P0P0_DN(7)
 AH7 UPI_CPU0_CPU1_P0P0_DN<6> UPI0_RX_DP<6> @BASEBOARD_FAB2_LIB.BASEBOARD_FAB2(SCH_1):UPI_CPU0_CPU1_P0P0_DN(6)
 AF7 UPI_CPU0_CPU1_P0P0_DN<5> UPI0_RX_DP<5> @BASEBOARD_FAB2_LIB.BASEBOARD_FAB2(SCH_1):UPI_CPU0_CPU1_P0P0_DN(5)
 AG6 UPI_CPU0_CPU1_P0P0_DN<4> UPI0_RX_DP<4> @BASEBOARD_FAB2_LIB.BASEBOARD_FAB2(SCH_1):UPI_CPU0_CPU1_P0P0_DN(4)
 AC6 UPI_CPU0_CPU1_P0P0_DN<3> UPI0_RX_DP<3> @BASEBOARD_FAB2_LIB.BASEBOARD_FAB2(SCH_1):UPI_CPU0_CPU1_P0P0_DN(3)
 AA6 UPI_CPU0_CPU1_P0P0_DP<2> UPI0_RX_DP<2> @BASEBOARD_FAB2_LIB.BASEBOARD_FAB2(SCH_1):UPI_CPU0_CPU1_P0P0_DP(2)
 AC8 UPI_CPU0_CPU1_P0P0_DP<1> UPI0_RX_DP<1> @BASEBOARD_FAB2_LIB.BASEBOARD_FAB2(SCH_1):UPI_CPU0_CPU1_P0P0_DP(1)
 AB9 UPI_CPU0_CPU1_P0P0_DN<0> UPI0_RX_DP<0> @BASEBOARD_FAB2_LIB.BASEBOARD_FAB2(SCH_1):UPI_CPU0_CPU1_P0P0_DN(0)
 BG4 UPI_CPU1_CPU0_P0P0_DP<19> UPI0_TX_DN<19> @BASEBOARD_FAB2_LIB.BASEBOARD_FAB2(SCH_1):UPI_CPU1_CPU0_P0P0_DP(19)
 BF3 UPI_CPU1_CPU0_P0P0_DN<18> UPI0_TX_DN<18> @BASEBOARD_FAB2_LIB.BASEBOARD_FAB2(SCH_1):UPI_CPU1_CPU0_P0P0_DN(18)
 BB3 UPI_CPU1_CPU0_P0P0_DN<17> UPI0_TX_DN<17> @BASEBOARD_FAB2_LIB.BASEBOARD_FAB2(SCH_1):UPI_CPU1_CPU0_P0P0_DN(17)
 BA4 UPI_CPU1_CPU0_P0P0_DP<16> UPI0_TX_DN<16> @BASEBOARD_FAB2_LIB.BASEBOARD_FAB2(SCH_1):UPI_CPU1_CPU0_P0P0_DP(16)
 AV5 UPI_CPU1_CPU0_P0P0_DP<15> UPI0_TX_DN<15> @BASEBOARD_FAB2_LIB.BASEBOARD_FAB2(SCH_1):UPI_CPU1_CPU0_P0P0_DP(15)
 AU4 UPI_CPU1_CPU0_P0P0_DP<14> UPI0_TX_DN<14> @BASEBOARD_FAB2_LIB.BASEBOARD_FAB2(SCH_1):UPI_CPU1_CPU0_P0P0_DP(14)
 AT3 UPI_CPU1_CPU0_P0P0_DP<13> UPI0_TX_DN<13> @BASEBOARD_FAB2_LIB.BASEBOARD_FAB2(SCH_1):UPI_CPU1_CPU0_P0P0_DP(13)
 AT1 UPI_CPU1_CPU0_P0P0_DP<12> UPI0_TX_DN<12> @BASEBOARD_FAB2_LIB.BASEBOARD_FAB2(SCH_1):UPI_CPU1_CPU0_P0P0_DP(12)
 AN4 UPI_CPU1_CPU0_P0P0_DP<11> UPI0_TX_DN<11> @BASEBOARD_FAB2_LIB.BASEBOARD_FAB2(SCH_1):UPI_CPU1_CPU0_P0P0_DP(11)
 AM3 UPI_CPU1_CPU0_P0P0_DP<10> UPI0_TX_DN<10> @BASEBOARD_FAB2_LIB.BASEBOARD_FAB2(SCH_1):UPI_CPU1_CPU0_P0P0_DP(10)
 AL2 UPI_CPU1_CPU0_P0P0_DN<9> UPI0_TX_DN<9> @BASEBOARD_FAB2_LIB.BASEBOARD_FAB2(SCH_1):UPI_CPU1_CPU0_P0P0_DN(9)
 AH3 UPI_CPU1_CPU0_P0P0_DP<8> UPI0_TX_DN<8> @BASEBOARD_FAB2_LIB.BASEBOARD_FAB2(SCH_1):UPI_CPU1_CPU0_P0P0_DP(8)
 AE2 UPI_CPU1_CPU0_P0P0_DN<7> UPI0_TX_DN<7> @BASEBOARD_FAB2_LIB.BASEBOARD_FAB2(SCH_1):UPI_CPU1_CPU0_P0P0_DN(7)
 AG4 UPI_CPU1_CPU0_P0P0_DN<6> UPI0_TX_DN<6> @BASEBOARD_FAB2_LIB.BASEBOARD_FAB2(SCH_1):UPI_CPU1_CPU0_P0P0_DN(6)
 AC2 UPI_CPU1_CPU0_P0P0_DP<5> UPI0_TX_DN<5> @BASEBOARD_FAB2_LIB.BASEBOARD_FAB2(SCH_1):UPI_CPU1_CPU0_P0P0_DP(5)
 AB3 UPI_CPU1_CPU0_P0P0_DN<4> UPI0_TX_DN<4> @BASEBOARD_FAB2_LIB.BASEBOARD_FAB2(SCH_1):UPI_CPU1_CPU0_P0P0_DN(4)
  Y1 UPI_CPU1_CPU0_P0P0_DN<3> UPI0_TX_DN<3> @BASEBOARD_FAB2_LIB.BASEBOARD_FAB2(SCH_1):UPI_CPU1_CPU0_P0P0_DN(3)
  V3 UPI_CPU1_CPU0_P0P0_DN<2> UPI0_TX_DN<2> @BASEBOARD_FAB2_LIB.BASEBOARD_FAB2(SCH_1):UPI_CPU1_CPU0_P0P0_DN(2)
  P1 UPI_CPU1_CPU0_P0P0_DP<1> UPI0_TX_DN<1> @BASEBOARD_FAB2_LIB.BASEBOARD_FAB2(SCH_1):UPI_CPU1_CPU0_P0P0_DP(1)
  N2 UPI_CPU1_CPU0_P0P0_DP<0> UPI0_TX_DN<0> @BASEBOARD_FAB2_LIB.BASEBOARD_FAB2(SCH_1):UPI_CPU1_CPU0_P0P0_DP(0)
 BH3 UPI_CPU1_CPU0_P0P0_DN<19> UPI0_TX_DP<19> @BASEBOARD_FAB2_LIB.BASEBOARD_FAB2(SCH_1):UPI_CPU1_CPU0_P0P0_DN(19)
 BD3 UPI_CPU1_CPU0_P0P0_DP<18> UPI0_TX_DP<18> @BASEBOARD_FAB2_LIB.BASEBOARD_FAB2(SCH_1):UPI_CPU1_CPU0_P0P0_DP(18)
 BC2 UPI_CPU1_CPU0_P0P0_DP<17> UPI0_TX_DP<17> @BASEBOARD_FAB2_LIB.BASEBOARD_FAB2(SCH_1):UPI_CPU1_CPU0_P0P0_DP(17)
 AY3 UPI_CPU1_CPU0_P0P0_DN<16> UPI0_TX_DP<16> @BASEBOARD_FAB2_LIB.BASEBOARD_FAB2(SCH_1):UPI_CPU1_CPU0_P0P0_DN(16)
 AW4 UPI_CPU1_CPU0_P0P0_DN<15> UPI0_TX_DP<15> @BASEBOARD_FAB2_LIB.BASEBOARD_FAB2(SCH_1):UPI_CPU1_CPU0_P0P0_DN(15)
 AR4 UPI_CPU1_CPU0_P0P0_DN<14> UPI0_TX_DP<14> @BASEBOARD_FAB2_LIB.BASEBOARD_FAB2(SCH_1):UPI_CPU1_CPU0_P0P0_DN(14)
 AR2 UPI_CPU1_CPU0_P0P0_DN<13> UPI0_TX_DP<13> @BASEBOARD_FAB2_LIB.BASEBOARD_FAB2(SCH_1):UPI_CPU1_CPU0_P0P0_DN(13)
 AP1 UPI_CPU1_CPU0_P0P0_DN<12> UPI0_TX_DP<12> @BASEBOARD_FAB2_LIB.BASEBOARD_FAB2(SCH_1):UPI_CPU1_CPU0_P0P0_DN(12)
 AP3 UPI_CPU1_CPU0_P0P0_DN<11> UPI0_TX_DP<11> @BASEBOARD_FAB2_LIB.BASEBOARD_FAB2(SCH_1):UPI_CPU1_CPU0_P0P0_DN(11)
 AK3 UPI_CPU1_CPU0_P0P0_DN<10> UPI0_TX_DP<10> @BASEBOARD_FAB2_LIB.BASEBOARD_FAB2(SCH_1):UPI_CPU1_CPU0_P0P0_DN(10)
 AK1 UPI_CPU1_CPU0_P0P0_DP<9> UPI0_TX_DP<9> @BASEBOARD_FAB2_LIB.BASEBOARD_FAB2(SCH_1):UPI_CPU1_CPU0_P0P0_DP(9)
 AJ2 UPI_CPU1_CPU0_P0P0_DN<8> UPI0_TX_DP<8> @BASEBOARD_FAB2_LIB.BASEBOARD_FAB2(SCH_1):UPI_CPU1_CPU0_P0P0_DN(8)
 AG2 UPI_CPU1_CPU0_P0P0_DP<7> UPI0_TX_DP<7> @BASEBOARD_FAB2_LIB.BASEBOARD_FAB2(SCH_1):UPI_CPU1_CPU0_P0P0_DP(7)
 AF3 UPI_CPU1_CPU0_P0P0_DP<6> UPI0_TX_DP<6> @BASEBOARD_FAB2_LIB.BASEBOARD_FAB2(SCH_1):UPI_CPU1_CPU0_P0P0_DP(6)
 AD1 UPI_CPU1_CPU0_P0P0_DN<5> UPI0_TX_DP<5> @BASEBOARD_FAB2_LIB.BASEBOARD_FAB2(SCH_1):UPI_CPU1_CPU0_P0P0_DN(5)
 AA2 UPI_CPU1_CPU0_P0P0_DP<4> UPI0_TX_DP<4> @BASEBOARD_FAB2_LIB.BASEBOARD_FAB2(SCH_1):UPI_CPU1_CPU0_P0P0_DP(4)
  W2 UPI_CPU1_CPU0_P0P0_DP<3> UPI0_TX_DP<3> @BASEBOARD_FAB2_LIB.BASEBOARD_FAB2(SCH_1):UPI_CPU1_CPU0_P0P0_DP(3)
  Y3 UPI_CPU1_CPU0_P0P0_DP<2> UPI0_TX_DP<2> @BASEBOARD_FAB2_LIB.BASEBOARD_FAB2(SCH_1):UPI_CPU1_CPU0_P0P0_DP(2)
  T1 UPI_CPU1_CPU0_P0P0_DN<1> UPI0_TX_DP<1> @BASEBOARD_FAB2_LIB.BASEBOARD_FAB2(SCH_1):UPI_CPU1_CPU0_P0P0_DN(1)
  M1 UPI_CPU1_CPU0_P0P0_DN<0> UPI0_TX_DP<0> @BASEBOARD_FAB2_LIB.BASEBOARD_FAB2(SCH_1):UPI_CPU1_CPU0_P0P0_DN(0)


DRAWING: @BASEBOARD_FAB2_LIB.BASEBOARD_FAB2(SCH_1):PAGE68 

SKX_EXT_B_BGA1-IC,TBD  I125  U2D1
AB19 UPI_CPU0_CPU1_P1P1_DP<19> UPI1_RX_DN<19> @BASEBOARD_FAB2_LIB.BASEBOARD_FAB2(SCH_1):UPI_CPU0_CPU1_P1P1_DP(19)
 Y21 UPI_CPU0_CPU1_P1P1_DP<18> UPI1_RX_DN<18> @BASEBOARD_FAB2_LIB.BASEBOARD_FAB2(SCH_1):UPI_CPU0_CPU1_P1P1_DP(18)
 V19 UPI_CPU0_CPU1_P1P1_DN<17> UPI1_RX_DN<17> @BASEBOARD_FAB2_LIB.BASEBOARD_FAB2(SCH_1):UPI_CPU0_CPU1_P1P1_DN(17)
 P21 UPI_CPU0_CPU1_P1P1_DN<16> UPI1_RX_DN<16> @BASEBOARD_FAB2_LIB.BASEBOARD_FAB2(SCH_1):UPI_CPU0_CPU1_P1P1_DN(16)
 U18 UPI_CPU0_CPU1_P1P1_DN<15> UPI1_RX_DN<15> @BASEBOARD_FAB2_LIB.BASEBOARD_FAB2(SCH_1):UPI_CPU0_CPU1_P1P1_DN(15)
 R20 UPI_CPU0_CPU1_P1P1_DN<14> UPI1_RX_DN<14> @BASEBOARD_FAB2_LIB.BASEBOARD_FAB2(SCH_1):UPI_CPU0_CPU1_P1P1_DN(14)
 W18 UPI_CPU0_CPU1_P1P1_DP<13> UPI1_RX_DN<13> @BASEBOARD_FAB2_LIB.BASEBOARD_FAB2(SCH_1):UPI_CPU0_CPU1_P1P1_DP(13)
 U16 UPI_CPU0_CPU1_P1P1_DP<12> UPI1_RX_DN<12> @BASEBOARD_FAB2_LIB.BASEBOARD_FAB2(SCH_1):UPI_CPU0_CPU1_P1P1_DP(12)
 P17 UPI_CPU0_CPU1_P1P1_DP<11> UPI1_RX_DN<11> @BASEBOARD_FAB2_LIB.BASEBOARD_FAB2(SCH_1):UPI_CPU0_CPU1_P1P1_DP(11)
 R16 UPI_CPU0_CPU1_P1P1_DN<10> UPI1_RX_DN<10> @BASEBOARD_FAB2_LIB.BASEBOARD_FAB2(SCH_1):UPI_CPU0_CPU1_P1P1_DN(10)
 R12 UPI_CPU0_CPU1_P1P1_DN<9> UPI1_RX_DN<9> @BASEBOARD_FAB2_LIB.BASEBOARD_FAB2(SCH_1):UPI_CPU0_CPU1_P1P1_DN(9)
 N14 UPI_CPU0_CPU1_P1P1_DP<8> UPI1_RX_DN<8> @BASEBOARD_FAB2_LIB.BASEBOARD_FAB2(SCH_1):UPI_CPU0_CPU1_P1P1_DP(8)
 L12 UPI_CPU0_CPU1_P1P1_DN<7> UPI1_RX_DN<7> @BASEBOARD_FAB2_LIB.BASEBOARD_FAB2(SCH_1):UPI_CPU0_CPU1_P1P1_DN(7)
 U12 UPI_CPU0_CPU1_P1P1_DN<6> UPI1_RX_DN<6> @BASEBOARD_FAB2_LIB.BASEBOARD_FAB2(SCH_1):UPI_CPU0_CPU1_P1P1_DN(6)
 R10 UPI_CPU0_CPU1_P1P1_DN<5> UPI1_RX_DN<5> @BASEBOARD_FAB2_LIB.BASEBOARD_FAB2(SCH_1):UPI_CPU0_CPU1_P1P1_DN(5)
  P9 UPI_CPU0_CPU1_P1P1_DN<4> UPI1_RX_DN<4> @BASEBOARD_FAB2_LIB.BASEBOARD_FAB2(SCH_1):UPI_CPU0_CPU1_P1P1_DN(4)
  T9 UPI_CPU0_CPU1_P1P1_DN<3> UPI1_RX_DN<3> @BASEBOARD_FAB2_LIB.BASEBOARD_FAB2(SCH_1):UPI_CPU0_CPU1_P1P1_DN(3)
  V7 UPI_CPU0_CPU1_P1P1_DN<2> UPI1_RX_DN<2> @BASEBOARD_FAB2_LIB.BASEBOARD_FAB2(SCH_1):UPI_CPU0_CPU1_P1P1_DN(2)
  P7 UPI_CPU0_CPU1_P1P1_DN<1> UPI1_RX_DN<1> @BASEBOARD_FAB2_LIB.BASEBOARD_FAB2(SCH_1):UPI_CPU0_CPU1_P1P1_DN(1)
  T5 UPI_CPU0_CPU1_P1P1_DP<0> UPI1_RX_DN<0> @BASEBOARD_FAB2_LIB.BASEBOARD_FAB2(SCH_1):UPI_CPU0_CPU1_P1P1_DP(0)
AA20 UPI_CPU0_CPU1_P1P1_DN<19> UPI1_RX_DP<19> @BASEBOARD_FAB2_LIB.BASEBOARD_FAB2(SCH_1):UPI_CPU0_CPU1_P1P1_DN(19)
 W20 UPI_CPU0_CPU1_P1P1_DN<18> UPI1_RX_DP<18> @BASEBOARD_FAB2_LIB.BASEBOARD_FAB2(SCH_1):UPI_CPU0_CPU1_P1P1_DN(18)
 Y19 UPI_CPU0_CPU1_P1P1_DP<17> UPI1_RX_DP<17> @BASEBOARD_FAB2_LIB.BASEBOARD_FAB2(SCH_1):UPI_CPU0_CPU1_P1P1_DP(17)
 T21 UPI_CPU0_CPU1_P1P1_DP<16> UPI1_RX_DP<16> @BASEBOARD_FAB2_LIB.BASEBOARD_FAB2(SCH_1):UPI_CPU0_CPU1_P1P1_DP(16)
 T19 UPI_CPU0_CPU1_P1P1_DP<15> UPI1_RX_DP<15> @BASEBOARD_FAB2_LIB.BASEBOARD_FAB2(SCH_1):UPI_CPU0_CPU1_P1P1_DP(15)
 P19 UPI_CPU0_CPU1_P1P1_DP<14> UPI1_RX_DP<14> @BASEBOARD_FAB2_LIB.BASEBOARD_FAB2(SCH_1):UPI_CPU0_CPU1_P1P1_DP(14)
 V17 UPI_CPU0_CPU1_P1P1_DN<13> UPI1_RX_DP<13> @BASEBOARD_FAB2_LIB.BASEBOARD_FAB2(SCH_1):UPI_CPU0_CPU1_P1P1_DN(13)
 W16 UPI_CPU0_CPU1_P1P1_DN<12> UPI1_RX_DP<12> @BASEBOARD_FAB2_LIB.BASEBOARD_FAB2(SCH_1):UPI_CPU0_CPU1_P1P1_DN(12)
 N16 UPI_CPU0_CPU1_P1P1_DN<11> UPI1_RX_DP<11> @BASEBOARD_FAB2_LIB.BASEBOARD_FAB2(SCH_1):UPI_CPU0_CPU1_P1P1_DN(11)
 T15 UPI_CPU0_CPU1_P1P1_DP<10> UPI1_RX_DP<10> @BASEBOARD_FAB2_LIB.BASEBOARD_FAB2(SCH_1):UPI_CPU0_CPU1_P1P1_DP(10)
 P13 UPI_CPU0_CPU1_P1P1_DP<9> UPI1_RX_DP<9> @BASEBOARD_FAB2_LIB.BASEBOARD_FAB2(SCH_1):UPI_CPU0_CPU1_P1P1_DP(9)
 M13 UPI_CPU0_CPU1_P1P1_DN<8> UPI1_RX_DP<8> @BASEBOARD_FAB2_LIB.BASEBOARD_FAB2(SCH_1):UPI_CPU0_CPU1_P1P1_DN(8)
 N12 UPI_CPU0_CPU1_P1P1_DP<7> UPI1_RX_DP<7> @BASEBOARD_FAB2_LIB.BASEBOARD_FAB2(SCH_1):UPI_CPU0_CPU1_P1P1_DP(7)
 T11 UPI_CPU0_CPU1_P1P1_DP<6> UPI1_RX_DP<6> @BASEBOARD_FAB2_LIB.BASEBOARD_FAB2(SCH_1):UPI_CPU0_CPU1_P1P1_DP(6)
 U10 UPI_CPU0_CPU1_P1P1_DP<5> UPI1_RX_DP<5> @BASEBOARD_FAB2_LIB.BASEBOARD_FAB2(SCH_1):UPI_CPU0_CPU1_P1P1_DP(5)
 N10 UPI_CPU0_CPU1_P1P1_DP<4> UPI1_RX_DP<4> @BASEBOARD_FAB2_LIB.BASEBOARD_FAB2(SCH_1):UPI_CPU0_CPU1_P1P1_DP(4)
  R8 UPI_CPU0_CPU1_P1P1_DP<3> UPI1_RX_DP<3> @BASEBOARD_FAB2_LIB.BASEBOARD_FAB2(SCH_1):UPI_CPU0_CPU1_P1P1_DP(3)
  U8 UPI_CPU0_CPU1_P1P1_DP<2> UPI1_RX_DP<2> @BASEBOARD_FAB2_LIB.BASEBOARD_FAB2(SCH_1):UPI_CPU0_CPU1_P1P1_DP(2)
  T7 UPI_CPU0_CPU1_P1P1_DP<1> UPI1_RX_DP<1> @BASEBOARD_FAB2_LIB.BASEBOARD_FAB2(SCH_1):UPI_CPU0_CPU1_P1P1_DP(1)
  R6 UPI_CPU0_CPU1_P1P1_DN<0> UPI1_RX_DP<0> @BASEBOARD_FAB2_LIB.BASEBOARD_FAB2(SCH_1):UPI_CPU0_CPU1_P1P1_DN(0)
 H21 UPI_CPU1_CPU0_P1P1_DP<19> UPI1_TX_DN<19> @BASEBOARD_FAB2_LIB.BASEBOARD_FAB2(SCH_1):UPI_CPU1_CPU0_P1P1_DP(19)
 F21 UPI_CPU1_CPU0_P1P1_DP<18> UPI1_TX_DN<18> @BASEBOARD_FAB2_LIB.BASEBOARD_FAB2(SCH_1):UPI_CPU1_CPU0_P1P1_DP(18)
 J20 UPI_CPU1_CPU0_P1P1_DN<17> UPI1_TX_DN<17> @BASEBOARD_FAB2_LIB.BASEBOARD_FAB2(SCH_1):UPI_CPU1_CPU0_P1P1_DN(17)
 G18 UPI_CPU1_CPU0_P1P1_DN<16> UPI1_TX_DN<16> @BASEBOARD_FAB2_LIB.BASEBOARD_FAB2(SCH_1):UPI_CPU1_CPU0_P1P1_DN(16)
 K19 UPI_CPU1_CPU0_P1P1_DN<15> UPI1_TX_DN<15> @BASEBOARD_FAB2_LIB.BASEBOARD_FAB2(SCH_1):UPI_CPU1_CPU0_P1P1_DN(15)
 H17 UPI_CPU1_CPU0_P1P1_DN<14> UPI1_TX_DN<14> @BASEBOARD_FAB2_LIB.BASEBOARD_FAB2(SCH_1):UPI_CPU1_CPU0_P1P1_DN(14)
 F15 UPI_CPU1_CPU0_P1P1_DN<13> UPI1_TX_DN<13> @BASEBOARD_FAB2_LIB.BASEBOARD_FAB2(SCH_1):UPI_CPU1_CPU0_P1P1_DN(13)
 D15 UPI_CPU1_CPU0_P1P1_DN<12> UPI1_TX_DN<12> @BASEBOARD_FAB2_LIB.BASEBOARD_FAB2(SCH_1):UPI_CPU1_CPU0_P1P1_DN(12)
 G14 UPI_CPU1_CPU0_P1P1_DP<11> UPI1_TX_DN<11> @BASEBOARD_FAB2_LIB.BASEBOARD_FAB2(SCH_1):UPI_CPU1_CPU0_P1P1_DP(11)
 E12 UPI_CPU1_CPU0_P1P1_DN<10> UPI1_TX_DN<10> @BASEBOARD_FAB2_LIB.BASEBOARD_FAB2(SCH_1):UPI_CPU1_CPU0_P1P1_DN(10)
 G10 UPI_CPU1_CPU0_P1P1_DN<9> UPI1_TX_DN<9> @BASEBOARD_FAB2_LIB.BASEBOARD_FAB2(SCH_1):UPI_CPU1_CPU0_P1P1_DN(9)
 F11 UPI_CPU1_CPU0_P1P1_DP<8> UPI1_TX_DN<8> @BASEBOARD_FAB2_LIB.BASEBOARD_FAB2(SCH_1):UPI_CPU1_CPU0_P1P1_DP(8)
  D9 UPI_CPU1_CPU0_P1P1_DP<7> UPI1_TX_DN<7> @BASEBOARD_FAB2_LIB.BASEBOARD_FAB2(SCH_1):UPI_CPU1_CPU0_P1P1_DP(7)
  K9 UPI_CPU1_CPU0_P1P1_DP<6> UPI1_TX_DN<6> @BASEBOARD_FAB2_LIB.BASEBOARD_FAB2(SCH_1):UPI_CPU1_CPU0_P1P1_DP(6)
  H7 UPI_CPU1_CPU0_P1P1_DN<5> UPI1_TX_DN<5> @BASEBOARD_FAB2_LIB.BASEBOARD_FAB2(SCH_1):UPI_CPU1_CPU0_P1P1_DN(5)
  G6 UPI_CPU1_CPU0_P1P1_DN<4> UPI1_TX_DN<4> @BASEBOARD_FAB2_LIB.BASEBOARD_FAB2(SCH_1):UPI_CPU1_CPU0_P1P1_DN(4)
  J6 UPI_CPU1_CPU0_P1P1_DN<3> UPI1_TX_DN<3> @BASEBOARD_FAB2_LIB.BASEBOARD_FAB2(SCH_1):UPI_CPU1_CPU0_P1P1_DN(3)
  K5 UPI_CPU1_CPU0_P1P1_DN<2> UPI1_TX_DN<2> @BASEBOARD_FAB2_LIB.BASEBOARD_FAB2(SCH_1):UPI_CPU1_CPU0_P1P1_DN(2)
  L4 UPI_CPU1_CPU0_P1P1_DP<1> UPI1_TX_DN<1> @BASEBOARD_FAB2_LIB.BASEBOARD_FAB2(SCH_1):UPI_CPU1_CPU0_P1P1_DP(1)
  M3 UPI_CPU1_CPU0_P1P1_DP<0> UPI1_TX_DN<0> @BASEBOARD_FAB2_LIB.BASEBOARD_FAB2(SCH_1):UPI_CPU1_CPU0_P1P1_DP(0)
 K21 UPI_CPU1_CPU0_P1P1_DN<19> UPI1_TX_DP<19> @BASEBOARD_FAB2_LIB.BASEBOARD_FAB2(SCH_1):UPI_CPU1_CPU0_P1P1_DN(19)
 G20 UPI_CPU1_CPU0_P1P1_DN<18> UPI1_TX_DP<18> @BASEBOARD_FAB2_LIB.BASEBOARD_FAB2(SCH_1):UPI_CPU1_CPU0_P1P1_DN(18)
 H19 UPI_CPU1_CPU0_P1P1_DP<17> UPI1_TX_DP<17> @BASEBOARD_FAB2_LIB.BASEBOARD_FAB2(SCH_1):UPI_CPU1_CPU0_P1P1_DP(17)
 J18 UPI_CPU1_CPU0_P1P1_DP<16> UPI1_TX_DP<16> @BASEBOARD_FAB2_LIB.BASEBOARD_FAB2(SCH_1):UPI_CPU1_CPU0_P1P1_DP(16)
 L18 UPI_CPU1_CPU0_P1P1_DP<15> UPI1_TX_DP<15> @BASEBOARD_FAB2_LIB.BASEBOARD_FAB2(SCH_1):UPI_CPU1_CPU0_P1P1_DP(15)
 G16 UPI_CPU1_CPU0_P1P1_DP<14> UPI1_TX_DP<14> @BASEBOARD_FAB2_LIB.BASEBOARD_FAB2(SCH_1):UPI_CPU1_CPU0_P1P1_DP(14)
 H15 UPI_CPU1_CPU0_P1P1_DP<13> UPI1_TX_DP<13> @BASEBOARD_FAB2_LIB.BASEBOARD_FAB2(SCH_1):UPI_CPU1_CPU0_P1P1_DP(13)
 E14 UPI_CPU1_CPU0_P1P1_DP<12> UPI1_TX_DP<12> @BASEBOARD_FAB2_LIB.BASEBOARD_FAB2(SCH_1):UPI_CPU1_CPU0_P1P1_DP(12)
 F13 UPI_CPU1_CPU0_P1P1_DN<11> UPI1_TX_DP<11> @BASEBOARD_FAB2_LIB.BASEBOARD_FAB2(SCH_1):UPI_CPU1_CPU0_P1P1_DN(11)
 G12 UPI_CPU1_CPU0_P1P1_DP<10> UPI1_TX_DP<10> @BASEBOARD_FAB2_LIB.BASEBOARD_FAB2(SCH_1):UPI_CPU1_CPU0_P1P1_DP(10)
  H9 UPI_CPU1_CPU0_P1P1_DP<9> UPI1_TX_DP<9> @BASEBOARD_FAB2_LIB.BASEBOARD_FAB2(SCH_1):UPI_CPU1_CPU0_P1P1_DP(9)
 E10 UPI_CPU1_CPU0_P1P1_DN<8> UPI1_TX_DP<8> @BASEBOARD_FAB2_LIB.BASEBOARD_FAB2(SCH_1):UPI_CPU1_CPU0_P1P1_DN(8)
  F9 UPI_CPU1_CPU0_P1P1_DN<7> UPI1_TX_DP<7> @BASEBOARD_FAB2_LIB.BASEBOARD_FAB2(SCH_1):UPI_CPU1_CPU0_P1P1_DN(7)
  J8 UPI_CPU1_CPU0_P1P1_DN<6> UPI1_TX_DP<6> @BASEBOARD_FAB2_LIB.BASEBOARD_FAB2(SCH_1):UPI_CPU1_CPU0_P1P1_DN(6)
  K7 UPI_CPU1_CPU0_P1P1_DP<5> UPI1_TX_DP<5> @BASEBOARD_FAB2_LIB.BASEBOARD_FAB2(SCH_1):UPI_CPU1_CPU0_P1P1_DP(5)
  F7 UPI_CPU1_CPU0_P1P1_DP<4> UPI1_TX_DP<4> @BASEBOARD_FAB2_LIB.BASEBOARD_FAB2(SCH_1):UPI_CPU1_CPU0_P1P1_DP(4)
  H5 UPI_CPU1_CPU0_P1P1_DP<3> UPI1_TX_DP<3> @BASEBOARD_FAB2_LIB.BASEBOARD_FAB2(SCH_1):UPI_CPU1_CPU0_P1P1_DP(3)
  M5 UPI_CPU1_CPU0_P1P1_DP<2> UPI1_TX_DP<2> @BASEBOARD_FAB2_LIB.BASEBOARD_FAB2(SCH_1):UPI_CPU1_CPU0_P1P1_DP(2)
  K3 UPI_CPU1_CPU0_P1P1_DN<1> UPI1_TX_DP<1> @BASEBOARD_FAB2_LIB.BASEBOARD_FAB2(SCH_1):UPI_CPU1_CPU0_P1P1_DN(1)
  P3 UPI_CPU1_CPU0_P1P1_DN<0> UPI1_TX_DP<0> @BASEBOARD_FAB2_LIB.BASEBOARD_FAB2(SCH_1):UPI_CPU1_CPU0_P1P1_DN(0)


DRAWING: @BASEBOARD_FAB2_LIB.BASEBOARD_FAB2(SCH_1):PAGE69 

SKX_EXT_B_BGA1-IC,TBD  I1  U2D1
BY17    GND UPI2_RX_DN<19> @BASEBOARD_FAB2_LIB.BASEBOARD_FAB2(SCH_1):GND
CB15    GND UPI2_RX_DN<18> @BASEBOARD_FAB2_LIB.BASEBOARD_FAB2(SCH_1):GND
CF17    GND UPI2_RX_DN<17> @BASEBOARD_FAB2_LIB.BASEBOARD_FAB2(SCH_1):GND
CD15    GND UPI2_RX_DN<16> @BASEBOARD_FAB2_LIB.BASEBOARD_FAB2(SCH_1):GND
CE16    GND UPI2_RX_DN<15> @BASEBOARD_FAB2_LIB.BASEBOARD_FAB2(SCH_1):GND
CH17    GND UPI2_RX_DN<14> @BASEBOARD_FAB2_LIB.BASEBOARD_FAB2(SCH_1):GND
CJ18    GND UPI2_RX_DN<13> @BASEBOARD_FAB2_LIB.BASEBOARD_FAB2(SCH_1):GND
CL16    GND UPI2_RX_DN<12> @BASEBOARD_FAB2_LIB.BASEBOARD_FAB2(SCH_1):GND
CP21    GND UPI2_RX_DN<11> @BASEBOARD_FAB2_LIB.BASEBOARD_FAB2(SCH_1):GND
CN20    GND UPI2_RX_DN<10> @BASEBOARD_FAB2_LIB.BASEBOARD_FAB2(SCH_1):GND
CR18    GND UPI2_RX_DN<9> @BASEBOARD_FAB2_LIB.BASEBOARD_FAB2(SCH_1):GND
CT21    GND UPI2_RX_DN<8> @BASEBOARD_FAB2_LIB.BASEBOARD_FAB2(SCH_1):GND
CV19    GND UPI2_RX_DN<7> @BASEBOARD_FAB2_LIB.BASEBOARD_FAB2(SCH_1):GND
CW20    GND UPI2_RX_DN<6> @BASEBOARD_FAB2_LIB.BASEBOARD_FAB2(SCH_1):GND
DA20    GND UPI2_RX_DN<5> @BASEBOARD_FAB2_LIB.BASEBOARD_FAB2(SCH_1):GND
DD19    GND UPI2_RX_DN<4> @BASEBOARD_FAB2_LIB.BASEBOARD_FAB2(SCH_1):GND
DB21    GND UPI2_RX_DN<3> @BASEBOARD_FAB2_LIB.BASEBOARD_FAB2(SCH_1):GND
DC22    GND UPI2_RX_DN<2> @BASEBOARD_FAB2_LIB.BASEBOARD_FAB2(SCH_1):GND
DE22    GND UPI2_RX_DN<1> @BASEBOARD_FAB2_LIB.BASEBOARD_FAB2(SCH_1):GND
DF23    GND UPI2_RX_DN<0> @BASEBOARD_FAB2_LIB.BASEBOARD_FAB2(SCH_1):GND
CA16    GND UPI2_RX_DP<19> @BASEBOARD_FAB2_LIB.BASEBOARD_FAB2(SCH_1):GND
BY15    GND UPI2_RX_DP<18> @BASEBOARD_FAB2_LIB.BASEBOARD_FAB2(SCH_1):GND
CD17    GND UPI2_RX_DP<17> @BASEBOARD_FAB2_LIB.BASEBOARD_FAB2(SCH_1):GND
CC14    GND UPI2_RX_DP<16> @BASEBOARD_FAB2_LIB.BASEBOARD_FAB2(SCH_1):GND
CF15    GND UPI2_RX_DP<15> @BASEBOARD_FAB2_LIB.BASEBOARD_FAB2(SCH_1):GND
CG16    GND UPI2_RX_DP<14> @BASEBOARD_FAB2_LIB.BASEBOARD_FAB2(SCH_1):GND
CK17    GND UPI2_RX_DP<13> @BASEBOARD_FAB2_LIB.BASEBOARD_FAB2(SCH_1):GND
CJ16    GND UPI2_RX_DP<12> @BASEBOARD_FAB2_LIB.BASEBOARD_FAB2(SCH_1):GND
CM21    GND UPI2_RX_DP<11> @BASEBOARD_FAB2_LIB.BASEBOARD_FAB2(SCH_1):GND
CP19    GND UPI2_RX_DP<10> @BASEBOARD_FAB2_LIB.BASEBOARD_FAB2(SCH_1):GND
CN18    GND UPI2_RX_DP<9> @BASEBOARD_FAB2_LIB.BASEBOARD_FAB2(SCH_1):GND
CR20    GND UPI2_RX_DP<8> @BASEBOARD_FAB2_LIB.BASEBOARD_FAB2(SCH_1):GND
CW18    GND UPI2_RX_DP<7> @BASEBOARD_FAB2_LIB.BASEBOARD_FAB2(SCH_1):GND
CU20    GND UPI2_RX_DP<6> @BASEBOARD_FAB2_LIB.BASEBOARD_FAB2(SCH_1):GND
CY19    GND UPI2_RX_DP<5> @BASEBOARD_FAB2_LIB.BASEBOARD_FAB2(SCH_1):GND
DB19    GND UPI2_RX_DP<4> @BASEBOARD_FAB2_LIB.BASEBOARD_FAB2(SCH_1):GND
DC20    GND UPI2_RX_DP<3> @BASEBOARD_FAB2_LIB.BASEBOARD_FAB2(SCH_1):GND
DA22    GND UPI2_RX_DP<2> @BASEBOARD_FAB2_LIB.BASEBOARD_FAB2(SCH_1):GND
DD21    GND UPI2_RX_DP<1> @BASEBOARD_FAB2_LIB.BASEBOARD_FAB2(SCH_1):GND
DG22    GND UPI2_RX_DP<0> @BASEBOARD_FAB2_LIB.BASEBOARD_FAB2(SCH_1):GND
CC12 TP_CPU1_UPI2_RSVD_DT21 UPI2_TX_DN<19> @BASEBOARD_FAB2_LIB.BASEBOARD_FAB2(SCH_1):TP_CPU1_UPI2_RSVD_DT21
CC10 TP_CPU1_UPI2_RSVD_DM21 UPI2_TX_DN<18> @BASEBOARD_FAB2_LIB.BASEBOARD_FAB2(SCH_1):TP_CPU1_UPI2_RSVD_DM21
CE12 TP_CPU1_UPI2_RSVD_DL20 UPI2_TX_DN<17> @BASEBOARD_FAB2_LIB.BASEBOARD_FAB2(SCH_1):TP_CPU1_UPI2_RSVD_DL20
CH11 TP_CPU1_UPI2_RSVD_DG20 UPI2_TX_DN<16> @BASEBOARD_FAB2_LIB.BASEBOARD_FAB2(SCH_1):TP_CPU1_UPI2_RSVD_DG20
CF13 TP_CPU1_UPI2_RSVD_DH19 UPI2_TX_DN<15> @BASEBOARD_FAB2_LIB.BASEBOARD_FAB2(SCH_1):TP_CPU1_UPI2_RSVD_DH19
CJ14 TP_CPU1_UPI2_RSVD_DK17 UPI2_TX_DN<14> @BASEBOARD_FAB2_LIB.BASEBOARD_FAB2(SCH_1):TP_CPU1_UPI2_RSVD_DK17
CM13 TP_CPU1_UPI2_RSVD_DG18 UPI2_TX_DN<13> @BASEBOARD_FAB2_LIB.BASEBOARD_FAB2(SCH_1):TP_CPU1_UPI2_RSVD_DG18
CU14 TP_CPU1_UPI2_RSVD_DD17 UPI2_TX_DN<12> @BASEBOARD_FAB2_LIB.BASEBOARD_FAB2(SCH_1):TP_CPU1_UPI2_RSVD_DD17
CW14 TP_CPU1_UPI2_RSVD_DF15 UPI2_TX_DN<11> @BASEBOARD_FAB2_LIB.BASEBOARD_FAB2(SCH_1):TP_CPU1_UPI2_RSVD_DF15
DA16 TP_CPU1_UPI2_RSVD_DC16 UPI2_TX_DN<10> @BASEBOARD_FAB2_LIB.BASEBOARD_FAB2(SCH_1):TP_CPU1_UPI2_RSVD_DC16
DC16 TP_CPU1_UPI2_RSVD_DA16 UPI2_TX_DN<9> @BASEBOARD_FAB2_LIB.BASEBOARD_FAB2(SCH_1):TP_CPU1_UPI2_RSVD_DA16
DF15 TP_CPU1_UPI2_RSVD_CW14 UPI2_TX_DN<8> @BASEBOARD_FAB2_LIB.BASEBOARD_FAB2(SCH_1):TP_CPU1_UPI2_RSVD_CW14
DD17 TP_CPU1_UPI2_RSVD_CU14 UPI2_TX_DN<7> @BASEBOARD_FAB2_LIB.BASEBOARD_FAB2(SCH_1):TP_CPU1_UPI2_RSVD_CU14
DG18 TP_CPU1_UPI2_RSVD_CM13 UPI2_TX_DN<6> @BASEBOARD_FAB2_LIB.BASEBOARD_FAB2(SCH_1):TP_CPU1_UPI2_RSVD_CM13
DK17 TP_CPU1_UPI2_RSVD_CJ14 UPI2_TX_DN<5> @BASEBOARD_FAB2_LIB.BASEBOARD_FAB2(SCH_1):TP_CPU1_UPI2_RSVD_CJ14
DH19 TP_CPU1_UPI2_RSVD_CF13 UPI2_TX_DN<4> @BASEBOARD_FAB2_LIB.BASEBOARD_FAB2(SCH_1):TP_CPU1_UPI2_RSVD_CF13
DG20 TP_CPU1_UPI2_RSVD_CH11 UPI2_TX_DN<3> @BASEBOARD_FAB2_LIB.BASEBOARD_FAB2(SCH_1):TP_CPU1_UPI2_RSVD_CH11
DL20 TP_CPU1_UPI2_RSVD_CE12 UPI2_TX_DN<2> @BASEBOARD_FAB2_LIB.BASEBOARD_FAB2(SCH_1):TP_CPU1_UPI2_RSVD_CE12
DM21 TP_CPU1_UPI2_RSVD_CC10 UPI2_TX_DN<1> @BASEBOARD_FAB2_LIB.BASEBOARD_FAB2(SCH_1):TP_CPU1_UPI2_RSVD_CC10
DT21 TP_CPU1_UPI2_RSVD_CC12 UPI2_TX_DN<0> @BASEBOARD_FAB2_LIB.BASEBOARD_FAB2(SCH_1):TP_CPU1_UPI2_RSVD_CC12
CA12 TP_CPU1_UPI2_RSVD_DP21 UPI2_TX_DP<19> @BASEBOARD_FAB2_LIB.BASEBOARD_FAB2(SCH_1):TP_CPU1_UPI2_RSVD_DP21
CB11 TP_CPU1_UPI2_RSVD_DN20 UPI2_TX_DP<18> @BASEBOARD_FAB2_LIB.BASEBOARD_FAB2(SCH_1):TP_CPU1_UPI2_RSVD_DN20
CD11 TP_CPU1_UPI2_RSVD_DK19 UPI2_TX_DP<17> @BASEBOARD_FAB2_LIB.BASEBOARD_FAB2(SCH_1):TP_CPU1_UPI2_RSVD_DK19
CF11 TP_CPU1_UPI2_RSVD_DJ20 UPI2_TX_DP<16> @BASEBOARD_FAB2_LIB.BASEBOARD_FAB2(SCH_1):TP_CPU1_UPI2_RSVD_DJ20
CG12 TP_CPU1_UPI2_RSVD_DJ18 UPI2_TX_DP<15> @BASEBOARD_FAB2_LIB.BASEBOARD_FAB2(SCH_1):TP_CPU1_UPI2_RSVD_DJ18
CH13 TP_CPU1_UPI2_RSVD_DH17 UPI2_TX_DP<14> @BASEBOARD_FAB2_LIB.BASEBOARD_FAB2(SCH_1):TP_CPU1_UPI2_RSVD_DH17
CK13 TP_CPU1_UPI2_RSVD_DF17 UPI2_TX_DP<13> @BASEBOARD_FAB2_LIB.BASEBOARD_FAB2(SCH_1):TP_CPU1_UPI2_RSVD_DF17
CR14 TP_CPU1_UPI2_RSVD_DE16 UPI2_TX_DP<12> @BASEBOARD_FAB2_LIB.BASEBOARD_FAB2(SCH_1):TP_CPU1_UPI2_RSVD_DE16
CV13 TP_CPU1_UPI2_RSVD_DD15 UPI2_TX_DP<11> @BASEBOARD_FAB2_LIB.BASEBOARD_FAB2(SCH_1):TP_CPU1_UPI2_RSVD_DD15
CW16 TP_CPU1_UPI2_RSVD_DB15 UPI2_TX_DP<10> @BASEBOARD_FAB2_LIB.BASEBOARD_FAB2(SCH_1):TP_CPU1_UPI2_RSVD_DB15
DB15 TP_CPU1_UPI2_RSVD_CW16 UPI2_TX_DP<9> @BASEBOARD_FAB2_LIB.BASEBOARD_FAB2(SCH_1):TP_CPU1_UPI2_RSVD_CW16
DD15 TP_CPU1_UPI2_RSVD_CV13 UPI2_TX_DP<8> @BASEBOARD_FAB2_LIB.BASEBOARD_FAB2(SCH_1):TP_CPU1_UPI2_RSVD_CV13
DE16 TP_CPU1_UPI2_RSVD_CR14 UPI2_TX_DP<7> @BASEBOARD_FAB2_LIB.BASEBOARD_FAB2(SCH_1):TP_CPU1_UPI2_RSVD_CR14
DF17 TP_CPU1_UPI2_RSVD_CK13 UPI2_TX_DP<6> @BASEBOARD_FAB2_LIB.BASEBOARD_FAB2(SCH_1):TP_CPU1_UPI2_RSVD_CK13
DH17 TP_CPU1_UPI2_RSVD_CH13 UPI2_TX_DP<5> @BASEBOARD_FAB2_LIB.BASEBOARD_FAB2(SCH_1):TP_CPU1_UPI2_RSVD_CH13
DJ18 TP_CPU1_UPI2_RSVD_CG12 UPI2_TX_DP<4> @BASEBOARD_FAB2_LIB.BASEBOARD_FAB2(SCH_1):TP_CPU1_UPI2_RSVD_CG12
DJ20 TP_CPU1_UPI2_RSVD_CF11 UPI2_TX_DP<3> @BASEBOARD_FAB2_LIB.BASEBOARD_FAB2(SCH_1):TP_CPU1_UPI2_RSVD_CF11
DK19 TP_CPU1_UPI2_RSVD_CD11 UPI2_TX_DP<2> @BASEBOARD_FAB2_LIB.BASEBOARD_FAB2(SCH_1):TP_CPU1_UPI2_RSVD_CD11
DN20 TP_CPU1_UPI2_RSVD_CB11 UPI2_TX_DP<1> @BASEBOARD_FAB2_LIB.BASEBOARD_FAB2(SCH_1):TP_CPU1_UPI2_RSVD_CB11
DP21 TP_CPU1_UPI2_RSVD_CA12 UPI2_TX_DP<0> @BASEBOARD_FAB2_LIB.BASEBOARD_FAB2(SCH_1):TP_CPU1_UPI2_RSVD_CA12


DRAWING: @BASEBOARD_FAB2_LIB.BASEBOARD_FAB2(SCH_1):PAGE70 

SKX_EXT_B_BGA1-IC,TBD  I9  U2D1
AY83 TP_CPU1_RSVD_255 RSVD<255> @BASEBOARD_FAB2_LIB.BASEBOARD_FAB2(SCH_1):TP_CPU1_RSVD_255
BA78 TP_CPU1_RSVD_171 RSVD<171> @BASEBOARD_FAB2_LIB.BASEBOARD_FAB2(SCH_1):TP_CPU1_RSVD_171
BA82 TP_CPU1_RSVD_170 RSVD<170> @BASEBOARD_FAB2_LIB.BASEBOARD_FAB2(SCH_1):TP_CPU1_RSVD_170
BB13 TP_CPU1_RSVD_169 RSVD<169> @BASEBOARD_FAB2_LIB.BASEBOARD_FAB2(SCH_1):TP_CPU1_RSVD_169
BB15 TP_CPU1_RSVD_168 RSVD<168> @BASEBOARD_FAB2_LIB.BASEBOARD_FAB2(SCH_1):TP_CPU1_RSVD_168
BB17 TP_CPU1_RSVD_167 RSVD<167> @BASEBOARD_FAB2_LIB.BASEBOARD_FAB2(SCH_1):TP_CPU1_RSVD_167
BB21 TP_CPU1_RSVD_166 RSVD<166> @BASEBOARD_FAB2_LIB.BASEBOARD_FAB2(SCH_1):TP_CPU1_RSVD_166
BB25 CLK_100M_CPU1_RC_REFCLK1_DN RSVD<165> @BASEBOARD_FAB2_LIB.BASEBOARD_FAB2(SCH_1):CLK_100M_CPU1_RC_REFCLK1_DN
BB65 TP_CPU1_RSVD_164 RSVD<164> @BASEBOARD_FAB2_LIB.BASEBOARD_FAB2(SCH_1):TP_CPU1_RSVD_164
BB67 TP_CPU1_RSVD_163 RSVD<163> @BASEBOARD_FAB2_LIB.BASEBOARD_FAB2(SCH_1):TP_CPU1_RSVD_163
BC14 TP_CPU1_RSVD_162 RSVD<162> @BASEBOARD_FAB2_LIB.BASEBOARD_FAB2(SCH_1):TP_CPU1_RSVD_162
BC18 TP_CPU1_RSVD_161 RSVD<161> @BASEBOARD_FAB2_LIB.BASEBOARD_FAB2(SCH_1):TP_CPU1_RSVD_161
BC20 TP_CPU1_RSVD_160 RSVD<160> @BASEBOARD_FAB2_LIB.BASEBOARD_FAB2(SCH_1):TP_CPU1_RSVD_160
BC22 TP_CPU1_RSVD_159 RSVD<159> @BASEBOARD_FAB2_LIB.BASEBOARD_FAB2(SCH_1):TP_CPU1_RSVD_159
BC64 TP_CPU1_RSVD_158 RSVD<158> @BASEBOARD_FAB2_LIB.BASEBOARD_FAB2(SCH_1):TP_CPU1_RSVD_158
BC66 TP_CPU1_RSVD_157 RSVD<157> @BASEBOARD_FAB2_LIB.BASEBOARD_FAB2(SCH_1):TP_CPU1_RSVD_157
BC68 TP_CPU1_RSVD_156 RSVD<156> @BASEBOARD_FAB2_LIB.BASEBOARD_FAB2(SCH_1):TP_CPU1_RSVD_156
BD17 TP_CPU1_RSVD_155 RSVD<155> @BASEBOARD_FAB2_LIB.BASEBOARD_FAB2(SCH_1):TP_CPU1_RSVD_155
BD19 TP_CPU1_RSVD_154 RSVD<154> @BASEBOARD_FAB2_LIB.BASEBOARD_FAB2(SCH_1):TP_CPU1_RSVD_154
BD25 CLK_100M_CPU1_RC_REFCLK1_DP RSVD<153> @BASEBOARD_FAB2_LIB.BASEBOARD_FAB2(SCH_1):CLK_100M_CPU1_RC_REFCLK1_DP
BD65 TP_CPU1_RSVD_152 RSVD<152> @BASEBOARD_FAB2_LIB.BASEBOARD_FAB2(SCH_1):TP_CPU1_RSVD_152
BD67 TP_CPU1_RSVD_151 RSVD<151> @BASEBOARD_FAB2_LIB.BASEBOARD_FAB2(SCH_1):TP_CPU1_RSVD_151
BD69 TP_CPU1_RSVD_150 RSVD<150> @BASEBOARD_FAB2_LIB.BASEBOARD_FAB2(SCH_1):TP_CPU1_RSVD_150
BE18 TP_CPU1_RSVD_149 RSVD<149> @BASEBOARD_FAB2_LIB.BASEBOARD_FAB2(SCH_1):TP_CPU1_RSVD_149
BE20 TP_CPU1_RSVD_148 RSVD<148> @BASEBOARD_FAB2_LIB.BASEBOARD_FAB2(SCH_1):TP_CPU1_RSVD_148
BE22 TP_CPU1_RSVD_147 RSVD<147> @BASEBOARD_FAB2_LIB.BASEBOARD_FAB2(SCH_1):TP_CPU1_RSVD_147
BF21 TP_CPU1_RSVD_146 RSVD<146> @BASEBOARD_FAB2_LIB.BASEBOARD_FAB2(SCH_1):TP_CPU1_RSVD_146
BG18 TP_CPU1_RSVD_145 RSVD<145> @BASEBOARD_FAB2_LIB.BASEBOARD_FAB2(SCH_1):TP_CPU1_RSVD_145
BG20 TP_CPU1_RSVD_144 RSVD<144> @BASEBOARD_FAB2_LIB.BASEBOARD_FAB2(SCH_1):TP_CPU1_RSVD_144
BH19 PVCCMCP_CPU1 RSVD<143> @BASEBOARD_FAB2_LIB.BASEBOARD_FAB2(SCH_1):PVCCMCP_CPU1
BJ16 PVCCMCP_CPU1 RSVD<142> @BASEBOARD_FAB2_LIB.BASEBOARD_FAB2(SCH_1):PVCCMCP_CPU1
BJ18 PVCCMCP_CPU1 RSVD<141> @BASEBOARD_FAB2_LIB.BASEBOARD_FAB2(SCH_1):PVCCMCP_CPU1
BJ20 PVCCMCP_CPU1 RSVD<140> @BASEBOARD_FAB2_LIB.BASEBOARD_FAB2(SCH_1):PVCCMCP_CPU1
BK17 PVCCMCP_CPU1 RSVD<139> @BASEBOARD_FAB2_LIB.BASEBOARD_FAB2(SCH_1):PVCCMCP_CPU1
BL18 PVCCMCP_CPU1 RSVD<138> @BASEBOARD_FAB2_LIB.BASEBOARD_FAB2(SCH_1):PVCCMCP_CPU1
BL20 PVCCMCP_CPU1 RSVD<137> @BASEBOARD_FAB2_LIB.BASEBOARD_FAB2(SCH_1):PVCCMCP_CPU1
BM17 PVCCMCP_CPU1 RSVD<136> @BASEBOARD_FAB2_LIB.BASEBOARD_FAB2(SCH_1):PVCCMCP_CPU1
BM19 PVCCMCP_CPU1 RSVD<135> @BASEBOARD_FAB2_LIB.BASEBOARD_FAB2(SCH_1):PVCCMCP_CPU1
BN18 PVCCMCP_CPU1 RSVD<134> @BASEBOARD_FAB2_LIB.BASEBOARD_FAB2(SCH_1):PVCCMCP_CPU1
BP17 PVCCMCP_CPU1 RSVD<133> @BASEBOARD_FAB2_LIB.BASEBOARD_FAB2(SCH_1):PVCCMCP_CPU1
BP21 PVCCMCP_CPU1 RSVD<132> @BASEBOARD_FAB2_LIB.BASEBOARD_FAB2(SCH_1):PVCCMCP_CPU1
BR22 PVCCMCP_CPU1 RSVD<131> @BASEBOARD_FAB2_LIB.BASEBOARD_FAB2(SCH_1):PVCCMCP_CPU1
BR24 PVCCMCP_CPU1 RSVD<130> @BASEBOARD_FAB2_LIB.BASEBOARD_FAB2(SCH_1):PVCCMCP_CPU1
BU18 PVCCMCP_CPU1 RSVD<129> @BASEBOARD_FAB2_LIB.BASEBOARD_FAB2(SCH_1):PVCCMCP_CPU1
BU20 PVCCMCP_CPU1 RSVD<128> @BASEBOARD_FAB2_LIB.BASEBOARD_FAB2(SCH_1):PVCCMCP_CPU1
BU22 PVCCMCP_CPU1 RSVD<127> @BASEBOARD_FAB2_LIB.BASEBOARD_FAB2(SCH_1):PVCCMCP_CPU1
BV19 PVCCMCP_CPU1 RSVD<126> @BASEBOARD_FAB2_LIB.BASEBOARD_FAB2(SCH_1):PVCCMCP_CPU1
BV21 PVCCMCP_CPU1 RSVD<125> @BASEBOARD_FAB2_LIB.BASEBOARD_FAB2(SCH_1):PVCCMCP_CPU1
BV23 TP_CPU1_RSVD_124 RSVD<124> @BASEBOARD_FAB2_LIB.BASEBOARD_FAB2(SCH_1):TP_CPU1_RSVD_124
BW10 TP_CPU1_RSVD_123 RSVD<123> @BASEBOARD_FAB2_LIB.BASEBOARD_FAB2(SCH_1):TP_CPU1_RSVD_123
BW20 PVCCMCP_CPU1 RSVD<122> @BASEBOARD_FAB2_LIB.BASEBOARD_FAB2(SCH_1):PVCCMCP_CPU1
BW22 TP_CPU1_RSVD_121 RSVD<121> @BASEBOARD_FAB2_LIB.BASEBOARD_FAB2(SCH_1):TP_CPU1_RSVD_121
BY19 PVCCMCP_CPU1 RSVD<120> @BASEBOARD_FAB2_LIB.BASEBOARD_FAB2(SCH_1):PVCCMCP_CPU1
BY25 TP_CPU1_RSVD_119 RSVD<119> @BASEBOARD_FAB2_LIB.BASEBOARD_FAB2(SCH_1):TP_CPU1_RSVD_119
CA22 PVCCMCP_CPU1 RSVD<118> @BASEBOARD_FAB2_LIB.BASEBOARD_FAB2(SCH_1):PVCCMCP_CPU1
CA24 TP_CPU1_RSVD_117 RSVD<117> @BASEBOARD_FAB2_LIB.BASEBOARD_FAB2(SCH_1):TP_CPU1_RSVD_117
CB19 PVCCMCP_CPU1 RSVD<116> @BASEBOARD_FAB2_LIB.BASEBOARD_FAB2(SCH_1):PVCCMCP_CPU1
CB21 PVCCMCP_CPU1 RSVD<115> @BASEBOARD_FAB2_LIB.BASEBOARD_FAB2(SCH_1):PVCCMCP_CPU1
CB25 TP_CPU1_RSVD_114 RSVD<114> @BASEBOARD_FAB2_LIB.BASEBOARD_FAB2(SCH_1):TP_CPU1_RSVD_114
 CB5 TP_CPU1_RSVD_113 RSVD<113> @BASEBOARD_FAB2_LIB.BASEBOARD_FAB2(SCH_1):TP_CPU1_RSVD_113
CC20 PVCCMCP_CPU1 RSVD<112> @BASEBOARD_FAB2_LIB.BASEBOARD_FAB2(SCH_1):PVCCMCP_CPU1
 CC6 TP_CPU1_RSVD_111 RSVD<111> @BASEBOARD_FAB2_LIB.BASEBOARD_FAB2(SCH_1):TP_CPU1_RSVD_111
CD19 PVCCMCP_CPU1 RSVD<110> @BASEBOARD_FAB2_LIB.BASEBOARD_FAB2(SCH_1):PVCCMCP_CPU1
CD21 PVCCMCP_CPU1 RSVD<109> @BASEBOARD_FAB2_LIB.BASEBOARD_FAB2(SCH_1):PVCCMCP_CPU1
CD25 TP_CPU1_RSVD_108 RSVD<108> @BASEBOARD_FAB2_LIB.BASEBOARD_FAB2(SCH_1):TP_CPU1_RSVD_108
CE22 PVCCMCP_CPU1 RSVD<107> @BASEBOARD_FAB2_LIB.BASEBOARD_FAB2(SCH_1):PVCCMCP_CPU1
CE78 TP_CPU1_RSVD_106 RSVD<106> @BASEBOARD_FAB2_LIB.BASEBOARD_FAB2(SCH_1):TP_CPU1_RSVD_106
CE80 TP_CPU1_RSVD_105 RSVD<105> @BASEBOARD_FAB2_LIB.BASEBOARD_FAB2(SCH_1):TP_CPU1_RSVD_105
CF19 PVCCMCP_CPU1 RSVD<104> @BASEBOARD_FAB2_LIB.BASEBOARD_FAB2(SCH_1):PVCCMCP_CPU1
CF21 PVCCMCP_CPU1 RSVD<103> @BASEBOARD_FAB2_LIB.BASEBOARD_FAB2(SCH_1):PVCCMCP_CPU1
CF23 PVCCMCP_CPU1 RSVD<102> @BASEBOARD_FAB2_LIB.BASEBOARD_FAB2(SCH_1):PVCCMCP_CPU1
CF79 TP_CPU1_RSVD_101 RSVD<101> @BASEBOARD_FAB2_LIB.BASEBOARD_FAB2(SCH_1):TP_CPU1_RSVD_101
CF81 TP_CPU1_RSVD_100 RSVD<100> @BASEBOARD_FAB2_LIB.BASEBOARD_FAB2(SCH_1):TP_CPU1_RSVD_100
CG10 TP_CPU1_RSVD_99 RSVD<99> @BASEBOARD_FAB2_LIB.BASEBOARD_FAB2(SCH_1):TP_CPU1_RSVD_99
CG20 PVCCMCP_CPU1 RSVD<98> @BASEBOARD_FAB2_LIB.BASEBOARD_FAB2(SCH_1):PVCCMCP_CPU1
CG24 TP_CPU1_RSVD_97 RSVD<97> @BASEBOARD_FAB2_LIB.BASEBOARD_FAB2(SCH_1):TP_CPU1_RSVD_97
CG26 PVCCMCP_CPU1 RSVD<96> @BASEBOARD_FAB2_LIB.BASEBOARD_FAB2(SCH_1):PVCCMCP_CPU1
CG78 TP_CPU1_RSVD_95 RSVD<95> @BASEBOARD_FAB2_LIB.BASEBOARD_FAB2(SCH_1):TP_CPU1_RSVD_95
CG82 TP_CPU1_RSVD_94 RSVD<94> @BASEBOARD_FAB2_LIB.BASEBOARD_FAB2(SCH_1):TP_CPU1_RSVD_94
CH21 PVCCMCP_CPU1 RSVD<93> @BASEBOARD_FAB2_LIB.BASEBOARD_FAB2(SCH_1):PVCCMCP_CPU1
CH23 PVCCMCP_CPU1 RSVD<92> @BASEBOARD_FAB2_LIB.BASEBOARD_FAB2(SCH_1):PVCCMCP_CPU1

SKX_EXT_B_BGA1-IC,TBD  I10  U2D1
CH25 TP_CPU1_RSVD_91 RSVD<91> @BASEBOARD_FAB2_LIB.BASEBOARD_FAB2(SCH_1):TP_CPU1_RSVD_91
CH77 TP_CPU1_RSVD_90 RSVD<90> @BASEBOARD_FAB2_LIB.BASEBOARD_FAB2(SCH_1):TP_CPU1_RSVD_90
CJ20 PVCCMCP_CPU1 RSVD<89> @BASEBOARD_FAB2_LIB.BASEBOARD_FAB2(SCH_1):PVCCMCP_CPU1
CJ22 PVCCMCP_CPU1 RSVD<88> @BASEBOARD_FAB2_LIB.BASEBOARD_FAB2(SCH_1):PVCCMCP_CPU1
CJ24 PVCCMCP_CPU1 RSVD<87> @BASEBOARD_FAB2_LIB.BASEBOARD_FAB2(SCH_1):PVCCMCP_CPU1
CJ26 PVCCMCP_CPU1 RSVD<86> @BASEBOARD_FAB2_LIB.BASEBOARD_FAB2(SCH_1):PVCCMCP_CPU1
CK19 TP_CPU1_RSVD_85 RSVD<85> @BASEBOARD_FAB2_LIB.BASEBOARD_FAB2(SCH_1):TP_CPU1_RSVD_85
CK23 PVCCMCP_CPU1 RSVD<84> @BASEBOARD_FAB2_LIB.BASEBOARD_FAB2(SCH_1):PVCCMCP_CPU1
CK25 PVCCMCP_CPU1 RSVD<83> @BASEBOARD_FAB2_LIB.BASEBOARD_FAB2(SCH_1):PVCCMCP_CPU1
CK77 TP_CPU1_RSVD_82 RSVD<82> @BASEBOARD_FAB2_LIB.BASEBOARD_FAB2(SCH_1):TP_CPU1_RSVD_82
CL24 PVCCMCP_CPU1 RSVD<81> @BASEBOARD_FAB2_LIB.BASEBOARD_FAB2(SCH_1):PVCCMCP_CPU1
AW22 TP_CPU1_TEST_10 TEST_10 @BASEBOARD_FAB2_LIB.BASEBOARD_FAB2(SCH_1):TP_CPU1_TEST_10
AR16 TP_CPU1_TEST_6 TEST_6 @BASEBOARD_FAB2_LIB.BASEBOARD_FAB2(SCH_1):TP_CPU1_TEST_6
AU18 TP_CPU1_TEST_7 TEST_7 @BASEBOARD_FAB2_LIB.BASEBOARD_FAB2(SCH_1):TP_CPU1_TEST_7
AW16 TP_CPU1_TEST_8 TEST_8 @BASEBOARD_FAB2_LIB.BASEBOARD_FAB2(SCH_1):TP_CPU1_TEST_8
AW20 TP_CPU1_TEST_9 TEST_9 @BASEBOARD_FAB2_LIB.BASEBOARD_FAB2(SCH_1):TP_CPU1_TEST_9


DRAWING: @BASEBOARD_FAB2_LIB.BASEBOARD_FAB2(SCH_1):PAGE71 

RES_0402-249,0.1%,1/16W,CHIP,GA  I43  R3D27
   1 VSENSE_PMAX_CPU1      A @BASEBOARD_FAB2_LIB.BASEBOARD_FAB2(SCH_1):VSENSE_PMAX_CPU1
   2    GND      B @BASEBOARD_FAB2_LIB.BASEBOARD_FAB2(SCH_1):GND

RES_0603-100.0K,1%,1/10W,CHIP,A  I49  RT8P1
   1 PVCCIN_CPU1      A @BASEBOARD_FAB2_LIB.BASEBOARD_FAB2(SCH_1):PVCCIN_CPU1
   2 VSENSE_VCCINR2PMAX_CPU1      B @BASEBOARD_FAB2_LIB.BASEBOARD_FAB2(SCH_1):VSENSE_VCCINR2PMAX_CPU1

SKX_EXT_B_BGA1-IC,TBD  I50  U2D1
AF43 PVCCIN_CPU1 VCCIN<267> @BASEBOARD_FAB2_LIB.BASEBOARD_FAB2(SCH_1):PVCCIN_CPU1
AG38 PVCCIN_CPU1 VCCIN<266> @BASEBOARD_FAB2_LIB.BASEBOARD_FAB2(SCH_1):PVCCIN_CPU1
AG40 PVCCIN_CPU1 VCCIN<265> @BASEBOARD_FAB2_LIB.BASEBOARD_FAB2(SCH_1):PVCCIN_CPU1
AG42 PVCCIN_CPU1 VCCIN<264> @BASEBOARD_FAB2_LIB.BASEBOARD_FAB2(SCH_1):PVCCIN_CPU1
AH37 PVCCIN_CPU1 VCCIN<263> @BASEBOARD_FAB2_LIB.BASEBOARD_FAB2(SCH_1):PVCCIN_CPU1
AH39 PVCCIN_CPU1 VCCIN<262> @BASEBOARD_FAB2_LIB.BASEBOARD_FAB2(SCH_1):PVCCIN_CPU1
AH41 PVCCIN_CPU1 VCCIN<261> @BASEBOARD_FAB2_LIB.BASEBOARD_FAB2(SCH_1):PVCCIN_CPU1
AJ36 PVCCIN_CPU1 VCCIN<260> @BASEBOARD_FAB2_LIB.BASEBOARD_FAB2(SCH_1):PVCCIN_CPU1
AK35 PVCCIN_CPU1 VCCIN<259> @BASEBOARD_FAB2_LIB.BASEBOARD_FAB2(SCH_1):PVCCIN_CPU1
AK45 PVCCIN_CPU1 VCCIN<258> @BASEBOARD_FAB2_LIB.BASEBOARD_FAB2(SCH_1):PVCCIN_CPU1
AK47 PVCCIN_CPU1 VCCIN<257> @BASEBOARD_FAB2_LIB.BASEBOARD_FAB2(SCH_1):PVCCIN_CPU1
AK49 PVCCIN_CPU1 VCCIN<256> @BASEBOARD_FAB2_LIB.BASEBOARD_FAB2(SCH_1):PVCCIN_CPU1
AK51 PVCCIN_CPU1 VCCIN<255> @BASEBOARD_FAB2_LIB.BASEBOARD_FAB2(SCH_1):PVCCIN_CPU1
AK53 PVCCIN_CPU1 VCCIN<254> @BASEBOARD_FAB2_LIB.BASEBOARD_FAB2(SCH_1):PVCCIN_CPU1
AL34 PVCCIN_CPU1 VCCIN<253> @BASEBOARD_FAB2_LIB.BASEBOARD_FAB2(SCH_1):PVCCIN_CPU1
AL46 PVCCIN_CPU1 VCCIN<252> @BASEBOARD_FAB2_LIB.BASEBOARD_FAB2(SCH_1):PVCCIN_CPU1
AL48 PVCCIN_CPU1 VCCIN<251> @BASEBOARD_FAB2_LIB.BASEBOARD_FAB2(SCH_1):PVCCIN_CPU1
AL50 PVCCIN_CPU1 VCCIN<250> @BASEBOARD_FAB2_LIB.BASEBOARD_FAB2(SCH_1):PVCCIN_CPU1
AL52 PVCCIN_CPU1 VCCIN<249> @BASEBOARD_FAB2_LIB.BASEBOARD_FAB2(SCH_1):PVCCIN_CPU1
AL54 PVCCIN_CPU1 VCCIN<248> @BASEBOARD_FAB2_LIB.BASEBOARD_FAB2(SCH_1):PVCCIN_CPU1
AM33 PVCCIN_CPU1 VCCIN<247> @BASEBOARD_FAB2_LIB.BASEBOARD_FAB2(SCH_1):PVCCIN_CPU1
AM53 PVCCIN_CPU1 VCCIN<246> @BASEBOARD_FAB2_LIB.BASEBOARD_FAB2(SCH_1):PVCCIN_CPU1
AM55 PVCCIN_CPU1 VCCIN<245> @BASEBOARD_FAB2_LIB.BASEBOARD_FAB2(SCH_1):PVCCIN_CPU1
AN32 PVCCIN_CPU1 VCCIN<244> @BASEBOARD_FAB2_LIB.BASEBOARD_FAB2(SCH_1):PVCCIN_CPU1
AN54 PVCCIN_CPU1 VCCIN<243> @BASEBOARD_FAB2_LIB.BASEBOARD_FAB2(SCH_1):PVCCIN_CPU1
AN56 PVCCIN_CPU1 VCCIN<242> @BASEBOARD_FAB2_LIB.BASEBOARD_FAB2(SCH_1):PVCCIN_CPU1
AP55 PVCCIN_CPU1 VCCIN<241> @BASEBOARD_FAB2_LIB.BASEBOARD_FAB2(SCH_1):PVCCIN_CPU1
AP57 PVCCIN_CPU1 VCCIN<240> @BASEBOARD_FAB2_LIB.BASEBOARD_FAB2(SCH_1):PVCCIN_CPU1
AR56 PVCCIN_CPU1 VCCIN<239> @BASEBOARD_FAB2_LIB.BASEBOARD_FAB2(SCH_1):PVCCIN_CPU1
AR58 PVCCIN_CPU1 VCCIN<238> @BASEBOARD_FAB2_LIB.BASEBOARD_FAB2(SCH_1):PVCCIN_CPU1
AT57 PVCCIN_CPU1 VCCIN<237> @BASEBOARD_FAB2_LIB.BASEBOARD_FAB2(SCH_1):PVCCIN_CPU1
AT59 PVCCIN_CPU1 VCCIN<236> @BASEBOARD_FAB2_LIB.BASEBOARD_FAB2(SCH_1):PVCCIN_CPU1
AU58 PVCCIN_CPU1 VCCIN<235> @BASEBOARD_FAB2_LIB.BASEBOARD_FAB2(SCH_1):PVCCIN_CPU1
AU60 PVCCIN_CPU1 VCCIN<234> @BASEBOARD_FAB2_LIB.BASEBOARD_FAB2(SCH_1):PVCCIN_CPU1
AV59 PVCCIN_CPU1 VCCIN<233> @BASEBOARD_FAB2_LIB.BASEBOARD_FAB2(SCH_1):PVCCIN_CPU1
AV61 PVCCIN_CPU1 VCCIN<232> @BASEBOARD_FAB2_LIB.BASEBOARD_FAB2(SCH_1):PVCCIN_CPU1
AW60 PVCCIN_CPU1 VCCIN<231> @BASEBOARD_FAB2_LIB.BASEBOARD_FAB2(SCH_1):PVCCIN_CPU1
AY61 PVCCIN_CPU1 VCCIN<230> @BASEBOARD_FAB2_LIB.BASEBOARD_FAB2(SCH_1):PVCCIN_CPU1
BA60 PVCCIN_CPU1 VCCIN<229> @BASEBOARD_FAB2_LIB.BASEBOARD_FAB2(SCH_1):PVCCIN_CPU1
BB61 PVCCIN_CPU1 VCCIN<228> @BASEBOARD_FAB2_LIB.BASEBOARD_FAB2(SCH_1):PVCCIN_CPU1
BB85 PVCCIN_CPU1 VCCIN<227> @BASEBOARD_FAB2_LIB.BASEBOARD_FAB2(SCH_1):PVCCIN_CPU1
BC60 PVCCIN_CPU1 VCCIN<226> @BASEBOARD_FAB2_LIB.BASEBOARD_FAB2(SCH_1):PVCCIN_CPU1
BC62 PVCCIN_CPU1 VCCIN<225> @BASEBOARD_FAB2_LIB.BASEBOARD_FAB2(SCH_1):PVCCIN_CPU1
BC84 PVCCIN_CPU1 VCCIN<224> @BASEBOARD_FAB2_LIB.BASEBOARD_FAB2(SCH_1):PVCCIN_CPU1
BD61 PVCCIN_CPU1 VCCIN<223> @BASEBOARD_FAB2_LIB.BASEBOARD_FAB2(SCH_1):PVCCIN_CPU1
BD73 PVCCIN_CPU1 VCCIN<222> @BASEBOARD_FAB2_LIB.BASEBOARD_FAB2(SCH_1):PVCCIN_CPU1
BD75 PVCCIN_CPU1 VCCIN<221> @BASEBOARD_FAB2_LIB.BASEBOARD_FAB2(SCH_1):PVCCIN_CPU1
BD77 PVCCIN_CPU1 VCCIN<220> @BASEBOARD_FAB2_LIB.BASEBOARD_FAB2(SCH_1):PVCCIN_CPU1
BD79 PVCCIN_CPU1 VCCIN<219> @BASEBOARD_FAB2_LIB.BASEBOARD_FAB2(SCH_1):PVCCIN_CPU1
BD81 PVCCIN_CPU1 VCCIN<218> @BASEBOARD_FAB2_LIB.BASEBOARD_FAB2(SCH_1):PVCCIN_CPU1
BD83 PVCCIN_CPU1 VCCIN<217> @BASEBOARD_FAB2_LIB.BASEBOARD_FAB2(SCH_1):PVCCIN_CPU1
BD85 PVCCIN_CPU1 VCCIN<216> @BASEBOARD_FAB2_LIB.BASEBOARD_FAB2(SCH_1):PVCCIN_CPU1
BE60 PVCCIN_CPU1 VCCIN<215> @BASEBOARD_FAB2_LIB.BASEBOARD_FAB2(SCH_1):PVCCIN_CPU1
BE62 PVCCIN_CPU1 VCCIN<214> @BASEBOARD_FAB2_LIB.BASEBOARD_FAB2(SCH_1):PVCCIN_CPU1
BE72 PVCCIN_CPU1 VCCIN<213> @BASEBOARD_FAB2_LIB.BASEBOARD_FAB2(SCH_1):PVCCIN_CPU1
BE74 PVCCIN_CPU1 VCCIN<212> @BASEBOARD_FAB2_LIB.BASEBOARD_FAB2(SCH_1):PVCCIN_CPU1
BE76 PVCCIN_CPU1 VCCIN<211> @BASEBOARD_FAB2_LIB.BASEBOARD_FAB2(SCH_1):PVCCIN_CPU1
BE78 PVCCIN_CPU1 VCCIN<210> @BASEBOARD_FAB2_LIB.BASEBOARD_FAB2(SCH_1):PVCCIN_CPU1
BE80 PVCCIN_CPU1 VCCIN<209> @BASEBOARD_FAB2_LIB.BASEBOARD_FAB2(SCH_1):PVCCIN_CPU1
BE82 PVCCIN_CPU1 VCCIN<208> @BASEBOARD_FAB2_LIB.BASEBOARD_FAB2(SCH_1):PVCCIN_CPU1
BE84 PVCCIN_CPU1 VCCIN<207> @BASEBOARD_FAB2_LIB.BASEBOARD_FAB2(SCH_1):PVCCIN_CPU1
BF61 PVCCIN_CPU1 VCCIN<206> @BASEBOARD_FAB2_LIB.BASEBOARD_FAB2(SCH_1):PVCCIN_CPU1
BF73 PVCCIN_CPU1 VCCIN<205> @BASEBOARD_FAB2_LIB.BASEBOARD_FAB2(SCH_1):PVCCIN_CPU1
BF75 PVCCIN_CPU1 VCCIN<204> @BASEBOARD_FAB2_LIB.BASEBOARD_FAB2(SCH_1):PVCCIN_CPU1
BF77 PVCCIN_CPU1 VCCIN<203> @BASEBOARD_FAB2_LIB.BASEBOARD_FAB2(SCH_1):PVCCIN_CPU1
BF79 PVCCIN_CPU1 VCCIN<202> @BASEBOARD_FAB2_LIB.BASEBOARD_FAB2(SCH_1):PVCCIN_CPU1
BF81 PVCCIN_CPU1 VCCIN<201> @BASEBOARD_FAB2_LIB.BASEBOARD_FAB2(SCH_1):PVCCIN_CPU1
BF83 PVCCIN_CPU1 VCCIN<200> @BASEBOARD_FAB2_LIB.BASEBOARD_FAB2(SCH_1):PVCCIN_CPU1
BF85 PVCCIN_CPU1 VCCIN<199> @BASEBOARD_FAB2_LIB.BASEBOARD_FAB2(SCH_1):PVCCIN_CPU1
BG60 PVCCIN_CPU1 VCCIN<198> @BASEBOARD_FAB2_LIB.BASEBOARD_FAB2(SCH_1):PVCCIN_CPU1
BG62 PVCCIN_CPU1 VCCIN<197> @BASEBOARD_FAB2_LIB.BASEBOARD_FAB2(SCH_1):PVCCIN_CPU1
BG64 PVCCIN_CPU1 VCCIN<196> @BASEBOARD_FAB2_LIB.BASEBOARD_FAB2(SCH_1):PVCCIN_CPU1
BG66 PVCCIN_CPU1 VCCIN<195> @BASEBOARD_FAB2_LIB.BASEBOARD_FAB2(SCH_1):PVCCIN_CPU1
BG68 PVCCIN_CPU1 VCCIN<194> @BASEBOARD_FAB2_LIB.BASEBOARD_FAB2(SCH_1):PVCCIN_CPU1
BG70 PVCCIN_CPU1 VCCIN<193> @BASEBOARD_FAB2_LIB.BASEBOARD_FAB2(SCH_1):PVCCIN_CPU1
BG84 PVCCIN_CPU1 VCCIN<192> @BASEBOARD_FAB2_LIB.BASEBOARD_FAB2(SCH_1):PVCCIN_CPU1
BH61 PVCCIN_CPU1 VCCIN<191> @BASEBOARD_FAB2_LIB.BASEBOARD_FAB2(SCH_1):PVCCIN_CPU1
BH63 PVCCIN_CPU1 VCCIN<190> @BASEBOARD_FAB2_LIB.BASEBOARD_FAB2(SCH_1):PVCCIN_CPU1
BH65 PVCCIN_CPU1 VCCIN<189> @BASEBOARD_FAB2_LIB.BASEBOARD_FAB2(SCH_1):PVCCIN_CPU1
BH67 PVCCIN_CPU1 VCCIN<188> @BASEBOARD_FAB2_LIB.BASEBOARD_FAB2(SCH_1):PVCCIN_CPU1
BH69 PVCCIN_CPU1 VCCIN<187> @BASEBOARD_FAB2_LIB.BASEBOARD_FAB2(SCH_1):PVCCIN_CPU1
BH71 PVCCIN_CPU1 VCCIN<186> @BASEBOARD_FAB2_LIB.BASEBOARD_FAB2(SCH_1):PVCCIN_CPU1
BH73 PVCCIN_CPU1 VCCIN<185> @BASEBOARD_FAB2_LIB.BASEBOARD_FAB2(SCH_1):PVCCIN_CPU1
BH75 PVCCIN_CPU1 VCCIN<184> @BASEBOARD_FAB2_LIB.BASEBOARD_FAB2(SCH_1):PVCCIN_CPU1
BH77 PVCCIN_CPU1 VCCIN<183> @BASEBOARD_FAB2_LIB.BASEBOARD_FAB2(SCH_1):PVCCIN_CPU1
BH79 PVCCIN_CPU1 VCCIN<182> @BASEBOARD_FAB2_LIB.BASEBOARD_FAB2(SCH_1):PVCCIN_CPU1
BH81 PVCCIN_CPU1 VCCIN<181> @BASEBOARD_FAB2_LIB.BASEBOARD_FAB2(SCH_1):PVCCIN_CPU1
BH83 PVCCIN_CPU1 VCCIN<180> @BASEBOARD_FAB2_LIB.BASEBOARD_FAB2(SCH_1):PVCCIN_CPU1
BJ60 PVCCIN_CPU1 VCCIN<179> @BASEBOARD_FAB2_LIB.BASEBOARD_FAB2(SCH_1):PVCCIN_CPU1
BJ62 PVCCIN_CPU1 VCCIN<178> @BASEBOARD_FAB2_LIB.BASEBOARD_FAB2(SCH_1):PVCCIN_CPU1
BJ64 PVCCIN_CPU1 VCCIN<177> @BASEBOARD_FAB2_LIB.BASEBOARD_FAB2(SCH_1):PVCCIN_CPU1
BJ66 PVCCIN_CPU1 VCCIN<176> @BASEBOARD_FAB2_LIB.BASEBOARD_FAB2(SCH_1):PVCCIN_CPU1
BJ68 PVCCIN_CPU1 VCCIN<175> @BASEBOARD_FAB2_LIB.BASEBOARD_FAB2(SCH_1):PVCCIN_CPU1
BJ70 PVCCIN_CPU1 VCCIN<174> @BASEBOARD_FAB2_LIB.BASEBOARD_FAB2(SCH_1):PVCCIN_CPU1
BJ72 PVCCIN_CPU1 VCCIN<173> @BASEBOARD_FAB2_LIB.BASEBOARD_FAB2(SCH_1):PVCCIN_CPU1
BJ74 PVCCIN_CPU1 VCCIN<172> @BASEBOARD_FAB2_LIB.BASEBOARD_FAB2(SCH_1):PVCCIN_CPU1
BJ76 PVCCIN_CPU1 VCCIN<171> @BASEBOARD_FAB2_LIB.BASEBOARD_FAB2(SCH_1):PVCCIN_CPU1
BJ78 PVCCIN_CPU1 VCCIN<170> @BASEBOARD_FAB2_LIB.BASEBOARD_FAB2(SCH_1):PVCCIN_CPU1
BJ80 PVCCIN_CPU1 VCCIN<169> @BASEBOARD_FAB2_LIB.BASEBOARD_FAB2(SCH_1):PVCCIN_CPU1
BJ82 PVCCIN_CPU1 VCCIN<168> @BASEBOARD_FAB2_LIB.BASEBOARD_FAB2(SCH_1):PVCCIN_CPU1
BJ84 PVCCIN_CPU1 VCCIN<167> @BASEBOARD_FAB2_LIB.BASEBOARD_FAB2(SCH_1):PVCCIN_CPU1
BK61 PVCCIN_CPU1 VCCIN<166> @BASEBOARD_FAB2_LIB.BASEBOARD_FAB2(SCH_1):PVCCIN_CPU1
BK63 PVCCIN_CPU1 VCCIN<165> @BASEBOARD_FAB2_LIB.BASEBOARD_FAB2(SCH_1):PVCCIN_CPU1
BK65 PVCCIN_CPU1 VCCIN<164> @BASEBOARD_FAB2_LIB.BASEBOARD_FAB2(SCH_1):PVCCIN_CPU1
BK67 PVCCIN_CPU1 VCCIN<163> @BASEBOARD_FAB2_LIB.BASEBOARD_FAB2(SCH_1):PVCCIN_CPU1
BK69 PVCCIN_CPU1 VCCIN<162> @BASEBOARD_FAB2_LIB.BASEBOARD_FAB2(SCH_1):PVCCIN_CPU1
BK71 PVCCIN_CPU1 VCCIN<161> @BASEBOARD_FAB2_LIB.BASEBOARD_FAB2(SCH_1):PVCCIN_CPU1
BK73 PVCCIN_CPU1 VCCIN<160> @BASEBOARD_FAB2_LIB.BASEBOARD_FAB2(SCH_1):PVCCIN_CPU1
BK75 PVCCIN_CPU1 VCCIN<159> @BASEBOARD_FAB2_LIB.BASEBOARD_FAB2(SCH_1):PVCCIN_CPU1
BK77 PVCCIN_CPU1 VCCIN<158> @BASEBOARD_FAB2_LIB.BASEBOARD_FAB2(SCH_1):PVCCIN_CPU1
BK79 PVCCIN_CPU1 VCCIN<157> @BASEBOARD_FAB2_LIB.BASEBOARD_FAB2(SCH_1):PVCCIN_CPU1
BK81 PVCCIN_CPU1 VCCIN<156> @BASEBOARD_FAB2_LIB.BASEBOARD_FAB2(SCH_1):PVCCIN_CPU1
BK83 PVCCIN_CPU1 VCCIN<155> @BASEBOARD_FAB2_LIB.BASEBOARD_FAB2(SCH_1):PVCCIN_CPU1
BL60 PVCCIN_CPU1 VCCIN<154> @BASEBOARD_FAB2_LIB.BASEBOARD_FAB2(SCH_1):PVCCIN_CPU1
BL62 PVCCIN_CPU1 VCCIN<153> @BASEBOARD_FAB2_LIB.BASEBOARD_FAB2(SCH_1):PVCCIN_CPU1
BL84 PVCCIN_CPU1 VCCIN<152> @BASEBOARD_FAB2_LIB.BASEBOARD_FAB2(SCH_1):PVCCIN_CPU1
BM61 PVCCIN_CPU1 VCCIN<151> @BASEBOARD_FAB2_LIB.BASEBOARD_FAB2(SCH_1):PVCCIN_CPU1
BM63 PVCCIN_CPU1 VCCIN<150> @BASEBOARD_FAB2_LIB.BASEBOARD_FAB2(SCH_1):PVCCIN_CPU1
BM65 PVCCIN_CPU1 VCCIN<149> @BASEBOARD_FAB2_LIB.BASEBOARD_FAB2(SCH_1):PVCCIN_CPU1
BM67 PVCCIN_CPU1 VCCIN<148> @BASEBOARD_FAB2_LIB.BASEBOARD_FAB2(SCH_1):PVCCIN_CPU1
BM69 PVCCIN_CPU1 VCCIN<147> @BASEBOARD_FAB2_LIB.BASEBOARD_FAB2(SCH_1):PVCCIN_CPU1
BM71 PVCCIN_CPU1 VCCIN<146> @BASEBOARD_FAB2_LIB.BASEBOARD_FAB2(SCH_1):PVCCIN_CPU1
BM73 PVCCIN_CPU1 VCCIN<145> @BASEBOARD_FAB2_LIB.BASEBOARD_FAB2(SCH_1):PVCCIN_CPU1
BM75 PVCCIN_CPU1 VCCIN<144> @BASEBOARD_FAB2_LIB.BASEBOARD_FAB2(SCH_1):PVCCIN_CPU1
BM77 PVCCIN_CPU1 VCCIN<143> @BASEBOARD_FAB2_LIB.BASEBOARD_FAB2(SCH_1):PVCCIN_CPU1
BM79 PVCCIN_CPU1 VCCIN<142> @BASEBOARD_FAB2_LIB.BASEBOARD_FAB2(SCH_1):PVCCIN_CPU1
BM81 PVCCIN_CPU1 VCCIN<141> @BASEBOARD_FAB2_LIB.BASEBOARD_FAB2(SCH_1):PVCCIN_CPU1
BM83 PVCCIN_CPU1 VCCIN<140> @BASEBOARD_FAB2_LIB.BASEBOARD_FAB2(SCH_1):PVCCIN_CPU1
BN60 PVCCIN_CPU1 VCCIN<139> @BASEBOARD_FAB2_LIB.BASEBOARD_FAB2(SCH_1):PVCCIN_CPU1
BN62 PVCCIN_CPU1 VCCIN<138> @BASEBOARD_FAB2_LIB.BASEBOARD_FAB2(SCH_1):PVCCIN_CPU1
BN64 PVCCIN_CPU1 VCCIN<137> @BASEBOARD_FAB2_LIB.BASEBOARD_FAB2(SCH_1):PVCCIN_CPU1
BN66 PVCCIN_CPU1 VCCIN<136> @BASEBOARD_FAB2_LIB.BASEBOARD_FAB2(SCH_1):PVCCIN_CPU1
BN68 PVCCIN_CPU1 VCCIN<135> @BASEBOARD_FAB2_LIB.BASEBOARD_FAB2(SCH_1):PVCCIN_CPU1
BN70 PVCCIN_CPU1 VCCIN<134> @BASEBOARD_FAB2_LIB.BASEBOARD_FAB2(SCH_1):PVCCIN_CPU1
BN72 PVCCIN_CPU1 VCCIN<133> @BASEBOARD_FAB2_LIB.BASEBOARD_FAB2(SCH_1):PVCCIN_CPU1
BN74 PVCCIN_CPU1 VCCIN<132> @BASEBOARD_FAB2_LIB.BASEBOARD_FAB2(SCH_1):PVCCIN_CPU1
BN76 PVCCIN_CPU1 VCCIN<131> @BASEBOARD_FAB2_LIB.BASEBOARD_FAB2(SCH_1):PVCCIN_CPU1
BN78 PVCCIN_CPU1 VCCIN<130> @BASEBOARD_FAB2_LIB.BASEBOARD_FAB2(SCH_1):PVCCIN_CPU1

SKX_EXT_B_BGA1-IC,TBD  I51  U2D1
BN80 PVCCIN_CPU1 VCCIN<129> @BASEBOARD_FAB2_LIB.BASEBOARD_FAB2(SCH_1):PVCCIN_CPU1
BN82 PVCCIN_CPU1 VCCIN<128> @BASEBOARD_FAB2_LIB.BASEBOARD_FAB2(SCH_1):PVCCIN_CPU1
BN84 PVCCIN_CPU1 VCCIN<127> @BASEBOARD_FAB2_LIB.BASEBOARD_FAB2(SCH_1):PVCCIN_CPU1
BP61 PVCCIN_CPU1 VCCIN<126> @BASEBOARD_FAB2_LIB.BASEBOARD_FAB2(SCH_1):PVCCIN_CPU1
BP63 PVCCIN_CPU1 VCCIN<125> @BASEBOARD_FAB2_LIB.BASEBOARD_FAB2(SCH_1):PVCCIN_CPU1
BP65 PVCCIN_CPU1 VCCIN<124> @BASEBOARD_FAB2_LIB.BASEBOARD_FAB2(SCH_1):PVCCIN_CPU1
BP67 PVCCIN_CPU1 VCCIN<123> @BASEBOARD_FAB2_LIB.BASEBOARD_FAB2(SCH_1):PVCCIN_CPU1
BP69 PVCCIN_CPU1 VCCIN<122> @BASEBOARD_FAB2_LIB.BASEBOARD_FAB2(SCH_1):PVCCIN_CPU1
BP71 PVCCIN_CPU1 VCCIN<121> @BASEBOARD_FAB2_LIB.BASEBOARD_FAB2(SCH_1):PVCCIN_CPU1
BP73 PVCCIN_CPU1 VCCIN<120> @BASEBOARD_FAB2_LIB.BASEBOARD_FAB2(SCH_1):PVCCIN_CPU1
BP75 PVCCIN_CPU1 VCCIN<119> @BASEBOARD_FAB2_LIB.BASEBOARD_FAB2(SCH_1):PVCCIN_CPU1
BP77 PVCCIN_CPU1 VCCIN<118> @BASEBOARD_FAB2_LIB.BASEBOARD_FAB2(SCH_1):PVCCIN_CPU1
BP79 PVCCIN_CPU1 VCCIN<117> @BASEBOARD_FAB2_LIB.BASEBOARD_FAB2(SCH_1):PVCCIN_CPU1
BP81 PVCCIN_CPU1 VCCIN<116> @BASEBOARD_FAB2_LIB.BASEBOARD_FAB2(SCH_1):PVCCIN_CPU1
BP83 PVCCIN_CPU1 VCCIN<115> @BASEBOARD_FAB2_LIB.BASEBOARD_FAB2(SCH_1):PVCCIN_CPU1
BR60 PVCCIN_CPU1 VCCIN<114> @BASEBOARD_FAB2_LIB.BASEBOARD_FAB2(SCH_1):PVCCIN_CPU1
BR62 PVCCIN_CPU1 VCCIN<113> @BASEBOARD_FAB2_LIB.BASEBOARD_FAB2(SCH_1):PVCCIN_CPU1
BR84 PVCCIN_CPU1 VCCIN<112> @BASEBOARD_FAB2_LIB.BASEBOARD_FAB2(SCH_1):PVCCIN_CPU1
BT61 PVCCIN_CPU1 VCCIN<111> @BASEBOARD_FAB2_LIB.BASEBOARD_FAB2(SCH_1):PVCCIN_CPU1
BT63 PVCCIN_CPU1 VCCIN<110> @BASEBOARD_FAB2_LIB.BASEBOARD_FAB2(SCH_1):PVCCIN_CPU1
BT65 PVCCIN_CPU1 VCCIN<109> @BASEBOARD_FAB2_LIB.BASEBOARD_FAB2(SCH_1):PVCCIN_CPU1
BT67 PVCCIN_CPU1 VCCIN<108> @BASEBOARD_FAB2_LIB.BASEBOARD_FAB2(SCH_1):PVCCIN_CPU1
BT69 PVCCIN_CPU1 VCCIN<107> @BASEBOARD_FAB2_LIB.BASEBOARD_FAB2(SCH_1):PVCCIN_CPU1
BT71 PVCCIN_CPU1 VCCIN<106> @BASEBOARD_FAB2_LIB.BASEBOARD_FAB2(SCH_1):PVCCIN_CPU1
BT73 PVCCIN_CPU1 VCCIN<105> @BASEBOARD_FAB2_LIB.BASEBOARD_FAB2(SCH_1):PVCCIN_CPU1
BT75 PVCCIN_CPU1 VCCIN<104> @BASEBOARD_FAB2_LIB.BASEBOARD_FAB2(SCH_1):PVCCIN_CPU1
BT77 PVCCIN_CPU1 VCCIN<103> @BASEBOARD_FAB2_LIB.BASEBOARD_FAB2(SCH_1):PVCCIN_CPU1
BT79 PVCCIN_CPU1 VCCIN<102> @BASEBOARD_FAB2_LIB.BASEBOARD_FAB2(SCH_1):PVCCIN_CPU1
BT81 PVCCIN_CPU1 VCCIN<101> @BASEBOARD_FAB2_LIB.BASEBOARD_FAB2(SCH_1):PVCCIN_CPU1
BT83 PVCCIN_CPU1 VCCIN<100> @BASEBOARD_FAB2_LIB.BASEBOARD_FAB2(SCH_1):PVCCIN_CPU1
BU60 PVCCIN_CPU1 VCCIN<99> @BASEBOARD_FAB2_LIB.BASEBOARD_FAB2(SCH_1):PVCCIN_CPU1
BU62 PVCCIN_CPU1 VCCIN<98> @BASEBOARD_FAB2_LIB.BASEBOARD_FAB2(SCH_1):PVCCIN_CPU1
BU64 PVCCIN_CPU1 VCCIN<97> @BASEBOARD_FAB2_LIB.BASEBOARD_FAB2(SCH_1):PVCCIN_CPU1
BU66 PVCCIN_CPU1 VCCIN<96> @BASEBOARD_FAB2_LIB.BASEBOARD_FAB2(SCH_1):PVCCIN_CPU1
BU68 PVCCIN_CPU1 VCCIN<95> @BASEBOARD_FAB2_LIB.BASEBOARD_FAB2(SCH_1):PVCCIN_CPU1
BU70 PVCCIN_CPU1 VCCIN<94> @BASEBOARD_FAB2_LIB.BASEBOARD_FAB2(SCH_1):PVCCIN_CPU1
BU72 PVCCIN_CPU1 VCCIN<93> @BASEBOARD_FAB2_LIB.BASEBOARD_FAB2(SCH_1):PVCCIN_CPU1
BU74 PVCCIN_CPU1 VCCIN<92> @BASEBOARD_FAB2_LIB.BASEBOARD_FAB2(SCH_1):PVCCIN_CPU1
BU76 PVCCIN_CPU1 VCCIN<91> @BASEBOARD_FAB2_LIB.BASEBOARD_FAB2(SCH_1):PVCCIN_CPU1
BU78 PVCCIN_CPU1 VCCIN<90> @BASEBOARD_FAB2_LIB.BASEBOARD_FAB2(SCH_1):PVCCIN_CPU1
BU80 PVCCIN_CPU1 VCCIN<89> @BASEBOARD_FAB2_LIB.BASEBOARD_FAB2(SCH_1):PVCCIN_CPU1
BU82 PVCCIN_CPU1 VCCIN<88> @BASEBOARD_FAB2_LIB.BASEBOARD_FAB2(SCH_1):PVCCIN_CPU1
BU84 PVCCIN_CPU1 VCCIN<87> @BASEBOARD_FAB2_LIB.BASEBOARD_FAB2(SCH_1):PVCCIN_CPU1
BV61 PVCCIN_CPU1 VCCIN<86> @BASEBOARD_FAB2_LIB.BASEBOARD_FAB2(SCH_1):PVCCIN_CPU1
BV63 PVCCIN_CPU1 VCCIN<85> @BASEBOARD_FAB2_LIB.BASEBOARD_FAB2(SCH_1):PVCCIN_CPU1
BV65 PVCCIN_CPU1 VCCIN<84> @BASEBOARD_FAB2_LIB.BASEBOARD_FAB2(SCH_1):PVCCIN_CPU1
BV67 PVCCIN_CPU1 VCCIN<83> @BASEBOARD_FAB2_LIB.BASEBOARD_FAB2(SCH_1):PVCCIN_CPU1
BV69 PVCCIN_CPU1 VCCIN<82> @BASEBOARD_FAB2_LIB.BASEBOARD_FAB2(SCH_1):PVCCIN_CPU1
BV71 PVCCIN_CPU1 VCCIN<81> @BASEBOARD_FAB2_LIB.BASEBOARD_FAB2(SCH_1):PVCCIN_CPU1
BV73 PVCCIN_CPU1 VCCIN<80> @BASEBOARD_FAB2_LIB.BASEBOARD_FAB2(SCH_1):PVCCIN_CPU1
BV75 PVCCIN_CPU1 VCCIN<79> @BASEBOARD_FAB2_LIB.BASEBOARD_FAB2(SCH_1):PVCCIN_CPU1
BV77 PVCCIN_CPU1 VCCIN<78> @BASEBOARD_FAB2_LIB.BASEBOARD_FAB2(SCH_1):PVCCIN_CPU1
BV79 PVCCIN_CPU1 VCCIN<77> @BASEBOARD_FAB2_LIB.BASEBOARD_FAB2(SCH_1):PVCCIN_CPU1
BV81 PVCCIN_CPU1 VCCIN<76> @BASEBOARD_FAB2_LIB.BASEBOARD_FAB2(SCH_1):PVCCIN_CPU1
BV83 PVCCIN_CPU1 VCCIN<75> @BASEBOARD_FAB2_LIB.BASEBOARD_FAB2(SCH_1):PVCCIN_CPU1
BW60 PVCCIN_CPU1 VCCIN<74> @BASEBOARD_FAB2_LIB.BASEBOARD_FAB2(SCH_1):PVCCIN_CPU1
BW62 PVCCIN_CPU1 VCCIN<73> @BASEBOARD_FAB2_LIB.BASEBOARD_FAB2(SCH_1):PVCCIN_CPU1
BW64 PVCCIN_CPU1 VCCIN<72> @BASEBOARD_FAB2_LIB.BASEBOARD_FAB2(SCH_1):PVCCIN_CPU1
BW66 PVCCIN_CPU1 VCCIN<71> @BASEBOARD_FAB2_LIB.BASEBOARD_FAB2(SCH_1):PVCCIN_CPU1
BW68 PVCCIN_CPU1 VCCIN<70> @BASEBOARD_FAB2_LIB.BASEBOARD_FAB2(SCH_1):PVCCIN_CPU1
BW70 PVCCIN_CPU1 VCCIN<69> @BASEBOARD_FAB2_LIB.BASEBOARD_FAB2(SCH_1):PVCCIN_CPU1
BW84 PVCCIN_CPU1 VCCIN<68> @BASEBOARD_FAB2_LIB.BASEBOARD_FAB2(SCH_1):PVCCIN_CPU1
BY61 PVCCIN_CPU1 VCCIN<67> @BASEBOARD_FAB2_LIB.BASEBOARD_FAB2(SCH_1):PVCCIN_CPU1
BY73 PVCCIN_CPU1 VCCIN<66> @BASEBOARD_FAB2_LIB.BASEBOARD_FAB2(SCH_1):PVCCIN_CPU1
BY75 PVCCIN_CPU1 VCCIN<65> @BASEBOARD_FAB2_LIB.BASEBOARD_FAB2(SCH_1):PVCCIN_CPU1
BY77 PVCCIN_CPU1 VCCIN<64> @BASEBOARD_FAB2_LIB.BASEBOARD_FAB2(SCH_1):PVCCIN_CPU1
BY79 PVCCIN_CPU1 VCCIN<63> @BASEBOARD_FAB2_LIB.BASEBOARD_FAB2(SCH_1):PVCCIN_CPU1
BY81 PVCCIN_CPU1 VCCIN<62> @BASEBOARD_FAB2_LIB.BASEBOARD_FAB2(SCH_1):PVCCIN_CPU1
BY83 PVCCIN_CPU1 VCCIN<61> @BASEBOARD_FAB2_LIB.BASEBOARD_FAB2(SCH_1):PVCCIN_CPU1
CA60 PVCCIN_CPU1 VCCIN<60> @BASEBOARD_FAB2_LIB.BASEBOARD_FAB2(SCH_1):PVCCIN_CPU1
CA62 PVCCIN_CPU1 VCCIN<59> @BASEBOARD_FAB2_LIB.BASEBOARD_FAB2(SCH_1):PVCCIN_CPU1
CA72 PVCCIN_CPU1 VCCIN<58> @BASEBOARD_FAB2_LIB.BASEBOARD_FAB2(SCH_1):PVCCIN_CPU1
CA74 PVCCIN_CPU1 VCCIN<57> @BASEBOARD_FAB2_LIB.BASEBOARD_FAB2(SCH_1):PVCCIN_CPU1
CA76 PVCCIN_CPU1 VCCIN<56> @BASEBOARD_FAB2_LIB.BASEBOARD_FAB2(SCH_1):PVCCIN_CPU1
CA78 PVCCIN_CPU1 VCCIN<55> @BASEBOARD_FAB2_LIB.BASEBOARD_FAB2(SCH_1):PVCCIN_CPU1
CA80 PVCCIN_CPU1 VCCIN<54> @BASEBOARD_FAB2_LIB.BASEBOARD_FAB2(SCH_1):PVCCIN_CPU1
CA82 PVCCIN_CPU1 VCCIN<53> @BASEBOARD_FAB2_LIB.BASEBOARD_FAB2(SCH_1):PVCCIN_CPU1
CA84 PVCCIN_CPU1 VCCIN<52> @BASEBOARD_FAB2_LIB.BASEBOARD_FAB2(SCH_1):PVCCIN_CPU1
CB61 PVCCIN_CPU1 VCCIN<51> @BASEBOARD_FAB2_LIB.BASEBOARD_FAB2(SCH_1):PVCCIN_CPU1
CB73 PVCCIN_CPU1 VCCIN<50> @BASEBOARD_FAB2_LIB.BASEBOARD_FAB2(SCH_1):PVCCIN_CPU1
CB75 PVCCIN_CPU1 VCCIN<49> @BASEBOARD_FAB2_LIB.BASEBOARD_FAB2(SCH_1):PVCCIN_CPU1
CB77 PVCCIN_CPU1 VCCIN<48> @BASEBOARD_FAB2_LIB.BASEBOARD_FAB2(SCH_1):PVCCIN_CPU1
CB79 PVCCIN_CPU1 VCCIN<47> @BASEBOARD_FAB2_LIB.BASEBOARD_FAB2(SCH_1):PVCCIN_CPU1
CB81 PVCCIN_CPU1 VCCIN<46> @BASEBOARD_FAB2_LIB.BASEBOARD_FAB2(SCH_1):PVCCIN_CPU1
CB83 PVCCIN_CPU1 VCCIN<45> @BASEBOARD_FAB2_LIB.BASEBOARD_FAB2(SCH_1):PVCCIN_CPU1
CC60 PVCCIN_CPU1 VCCIN<44> @BASEBOARD_FAB2_LIB.BASEBOARD_FAB2(SCH_1):PVCCIN_CPU1
CC62 PVCCIN_CPU1 VCCIN<43> @BASEBOARD_FAB2_LIB.BASEBOARD_FAB2(SCH_1):PVCCIN_CPU1
CC84 PVCCIN_CPU1 VCCIN<42> @BASEBOARD_FAB2_LIB.BASEBOARD_FAB2(SCH_1):PVCCIN_CPU1
CD61 PVCCIN_CPU1 VCCIN<41> @BASEBOARD_FAB2_LIB.BASEBOARD_FAB2(SCH_1):PVCCIN_CPU1
CD83 PVCCIN_CPU1 VCCIN<40> @BASEBOARD_FAB2_LIB.BASEBOARD_FAB2(SCH_1):PVCCIN_CPU1
CD85 PVCCIN_CPU1 VCCIN<39> @BASEBOARD_FAB2_LIB.BASEBOARD_FAB2(SCH_1):PVCCIN_CPU1
CE60 PVCCIN_CPU1 VCCIN<38> @BASEBOARD_FAB2_LIB.BASEBOARD_FAB2(SCH_1):PVCCIN_CPU1
CE84 PVCCIN_CPU1 VCCIN<37> @BASEBOARD_FAB2_LIB.BASEBOARD_FAB2(SCH_1):PVCCIN_CPU1
CF61 PVCCIN_CPU1 VCCIN<36> @BASEBOARD_FAB2_LIB.BASEBOARD_FAB2(SCH_1):PVCCIN_CPU1
CF85 PVCCIN_CPU1 VCCIN<35> @BASEBOARD_FAB2_LIB.BASEBOARD_FAB2(SCH_1):PVCCIN_CPU1
CG60 PVCCIN_CPU1 VCCIN<34> @BASEBOARD_FAB2_LIB.BASEBOARD_FAB2(SCH_1):PVCCIN_CPU1
CG84 PVCCIN_CPU1 VCCIN<33> @BASEBOARD_FAB2_LIB.BASEBOARD_FAB2(SCH_1):PVCCIN_CPU1
CH61 PVCCIN_CPU1 VCCIN<32> @BASEBOARD_FAB2_LIB.BASEBOARD_FAB2(SCH_1):PVCCIN_CPU1
CH85 PVCCIN_CPU1 VCCIN<31> @BASEBOARD_FAB2_LIB.BASEBOARD_FAB2(SCH_1):PVCCIN_CPU1
CJ60 PVCCIN_CPU1 VCCIN<30> @BASEBOARD_FAB2_LIB.BASEBOARD_FAB2(SCH_1):PVCCIN_CPU1
CK59 PVCCIN_CPU1 VCCIN<29> @BASEBOARD_FAB2_LIB.BASEBOARD_FAB2(SCH_1):PVCCIN_CPU1
CK61 PVCCIN_CPU1 VCCIN<28> @BASEBOARD_FAB2_LIB.BASEBOARD_FAB2(SCH_1):PVCCIN_CPU1
CL58 PVCCIN_CPU1 VCCIN<27> @BASEBOARD_FAB2_LIB.BASEBOARD_FAB2(SCH_1):PVCCIN_CPU1
CL60 PVCCIN_CPU1 VCCIN<26> @BASEBOARD_FAB2_LIB.BASEBOARD_FAB2(SCH_1):PVCCIN_CPU1
CM57 PVCCIN_CPU1 VCCIN<25> @BASEBOARD_FAB2_LIB.BASEBOARD_FAB2(SCH_1):PVCCIN_CPU1
CM59 PVCCIN_CPU1 VCCIN<24> @BASEBOARD_FAB2_LIB.BASEBOARD_FAB2(SCH_1):PVCCIN_CPU1
CN56 PVCCIN_CPU1 VCCIN<23> @BASEBOARD_FAB2_LIB.BASEBOARD_FAB2(SCH_1):PVCCIN_CPU1
CN58 PVCCIN_CPU1 VCCIN<22> @BASEBOARD_FAB2_LIB.BASEBOARD_FAB2(SCH_1):PVCCIN_CPU1
CP33 PVCCIN_CPU1 VCCIN<21> @BASEBOARD_FAB2_LIB.BASEBOARD_FAB2(SCH_1):PVCCIN_CPU1
CP55 PVCCIN_CPU1 VCCIN<20> @BASEBOARD_FAB2_LIB.BASEBOARD_FAB2(SCH_1):PVCCIN_CPU1
CP57 PVCCIN_CPU1 VCCIN<19> @BASEBOARD_FAB2_LIB.BASEBOARD_FAB2(SCH_1):PVCCIN_CPU1
CR34 PVCCIN_CPU1 VCCIN<18> @BASEBOARD_FAB2_LIB.BASEBOARD_FAB2(SCH_1):PVCCIN_CPU1
CR54 PVCCIN_CPU1 VCCIN<17> @BASEBOARD_FAB2_LIB.BASEBOARD_FAB2(SCH_1):PVCCIN_CPU1
CR56 PVCCIN_CPU1 VCCIN<16> @BASEBOARD_FAB2_LIB.BASEBOARD_FAB2(SCH_1):PVCCIN_CPU1
CT37 PVCCIN_CPU1 VCCIN<15> @BASEBOARD_FAB2_LIB.BASEBOARD_FAB2(SCH_1):PVCCIN_CPU1
CT39 PVCCIN_CPU1 VCCIN<14> @BASEBOARD_FAB2_LIB.BASEBOARD_FAB2(SCH_1):PVCCIN_CPU1
CT41 PVCCIN_CPU1 VCCIN<13> @BASEBOARD_FAB2_LIB.BASEBOARD_FAB2(SCH_1):PVCCIN_CPU1
CT53 PVCCIN_CPU1 VCCIN<12> @BASEBOARD_FAB2_LIB.BASEBOARD_FAB2(SCH_1):PVCCIN_CPU1
CT55 PVCCIN_CPU1 VCCIN<11> @BASEBOARD_FAB2_LIB.BASEBOARD_FAB2(SCH_1):PVCCIN_CPU1
CU38 PVCCIN_CPU1 VCCIN<10> @BASEBOARD_FAB2_LIB.BASEBOARD_FAB2(SCH_1):PVCCIN_CPU1
CU40 PVCCIN_CPU1 VCCIN<9> @BASEBOARD_FAB2_LIB.BASEBOARD_FAB2(SCH_1):PVCCIN_CPU1
CU42 PVCCIN_CPU1 VCCIN<8> @BASEBOARD_FAB2_LIB.BASEBOARD_FAB2(SCH_1):PVCCIN_CPU1
CU52 PVCCIN_CPU1 VCCIN<7> @BASEBOARD_FAB2_LIB.BASEBOARD_FAB2(SCH_1):PVCCIN_CPU1
CU54 PVCCIN_CPU1 VCCIN<6> @BASEBOARD_FAB2_LIB.BASEBOARD_FAB2(SCH_1):PVCCIN_CPU1
CV51 PVCCIN_CPU1 VCCIN<5> @BASEBOARD_FAB2_LIB.BASEBOARD_FAB2(SCH_1):PVCCIN_CPU1
CW46 PVCCIN_CPU1 VCCIN<4> @BASEBOARD_FAB2_LIB.BASEBOARD_FAB2(SCH_1):PVCCIN_CPU1
CW48 PVCCIN_CPU1 VCCIN<3> @BASEBOARD_FAB2_LIB.BASEBOARD_FAB2(SCH_1):PVCCIN_CPU1
CW50 PVCCIN_CPU1 VCCIN<2> @BASEBOARD_FAB2_LIB.BASEBOARD_FAB2(SCH_1):PVCCIN_CPU1
CY47 PVCCIN_CPU1 VCCIN<1> @BASEBOARD_FAB2_LIB.BASEBOARD_FAB2(SCH_1):PVCCIN_CPU1
CY49 PVCCIN_CPU1 VCCIN<0> @BASEBOARD_FAB2_LIB.BASEBOARD_FAB2(SCH_1):PVCCIN_CPU1
AV85 VSENSE_VCCINR2PMAX_CPU1 VCCINPMAX<1> @BASEBOARD_FAB2_LIB.BASEBOARD_FAB2(SCH_1):VSENSE_VCCINR2PMAX_CPU1
AW86 VSENSE_VCCINR2PMAX_CPU1 VCCINPMAX<0> @BASEBOARD_FAB2_LIB.BASEBOARD_FAB2(SCH_1):VSENSE_VCCINR2PMAX_CPU1
BA86 VSENSE_PVCCIN_CPU1_SKT_VSEN VCCIN_SENSE @BASEBOARD_FAB2_LIB.BASEBOARD_FAB2(SCH_1):VSENSE_PVCCIN_CPU1_SKT_VSEN
AD41 VSENSE_PMAX_CPU1 VSENSEPMAX @BASEBOARD_FAB2_LIB.BASEBOARD_FAB2(SCH_1):VSENSE_PMAX_CPU1
AY85 VSENSE_PVCCIN_CPU1_SKT_VRTN VSS_VCCIN_SENSE @BASEBOARD_FAB2_LIB.BASEBOARD_FAB2(SCH_1):VSENSE_PVCCIN_CPU1_SKT_VRTN

RES_0402-10.0,1%,1/16W,EMPTY,GA  I53  R3D32
   1 PVCCIO_CPU1      A @BASEBOARD_FAB2_LIB.BASEBOARD_FAB2(SCH_1):PVCCIO_CPU1
   2 VSENSE_PMAX_CPU1      B @BASEBOARD_FAB2_LIB.BASEBOARD_FAB2(SCH_1):VSENSE_PMAX_CPU1


DRAWING: @BASEBOARD_FAB2_LIB.BASEBOARD_FAB2(SCH_1):PAGE72 

CAP_0603LF-10UF,4V,20%,X6S,E15A  I25  C3D3
   1 P1V8_MCP_CPU1      A @BASEBOARD_FAB2_LIB.BASEBOARD_FAB2(SCH_1):P1V8_MCP_CPU1
   2    GND      B @BASEBOARD_FAB2_LIB.BASEBOARD_FAB2(SCH_1):GND

SKX_EXT_B_BGA1-IC,TBD  I32  U2D1
 B47 PVDDQ_GHJ VCCD012<51> @BASEBOARD_FAB2_LIB.BASEBOARD_FAB2(SCH_1):PVDDQ_GHJ
 C46 PVDDQ_GHJ VCCD012<50> @BASEBOARD_FAB2_LIB.BASEBOARD_FAB2(SCH_1):PVDDQ_GHJ
 D45 PVDDQ_GHJ VCCD012<49> @BASEBOARD_FAB2_LIB.BASEBOARD_FAB2(SCH_1):PVDDQ_GHJ
AF63 PVDDQ_GHJ VCCD012<48> @BASEBOARD_FAB2_LIB.BASEBOARD_FAB2(SCH_1):PVDDQ_GHJ
AF61 PVDDQ_GHJ VCCD012<47> @BASEBOARD_FAB2_LIB.BASEBOARD_FAB2(SCH_1):PVDDQ_GHJ
AF59 PVDDQ_GHJ VCCD012<46> @BASEBOARD_FAB2_LIB.BASEBOARD_FAB2(SCH_1):PVDDQ_GHJ
AF57 PVDDQ_GHJ VCCD012<45> @BASEBOARD_FAB2_LIB.BASEBOARD_FAB2(SCH_1):PVDDQ_GHJ
AF55 PVDDQ_GHJ VCCD012<44> @BASEBOARD_FAB2_LIB.BASEBOARD_FAB2(SCH_1):PVDDQ_GHJ
AD45 PVDDQ_GHJ VCCD012<43> @BASEBOARD_FAB2_LIB.BASEBOARD_FAB2(SCH_1):PVDDQ_GHJ
 Y63 PVDDQ_GHJ VCCD012<42> @BASEBOARD_FAB2_LIB.BASEBOARD_FAB2(SCH_1):PVDDQ_GHJ
 Y61 PVDDQ_GHJ VCCD012<41> @BASEBOARD_FAB2_LIB.BASEBOARD_FAB2(SCH_1):PVDDQ_GHJ
 Y59 PVDDQ_GHJ VCCD012<40> @BASEBOARD_FAB2_LIB.BASEBOARD_FAB2(SCH_1):PVDDQ_GHJ
 Y57 PVDDQ_GHJ VCCD012<39> @BASEBOARD_FAB2_LIB.BASEBOARD_FAB2(SCH_1):PVDDQ_GHJ
 Y55 PVDDQ_GHJ VCCD012<38> @BASEBOARD_FAB2_LIB.BASEBOARD_FAB2(SCH_1):PVDDQ_GHJ
 Y53 PVDDQ_GHJ VCCD012<37> @BASEBOARD_FAB2_LIB.BASEBOARD_FAB2(SCH_1):PVDDQ_GHJ
 Y51 PVDDQ_GHJ VCCD012<36> @BASEBOARD_FAB2_LIB.BASEBOARD_FAB2(SCH_1):PVDDQ_GHJ
 Y49 PVDDQ_GHJ VCCD012<35> @BASEBOARD_FAB2_LIB.BASEBOARD_FAB2(SCH_1):PVDDQ_GHJ
 Y47 PVDDQ_GHJ VCCD012<34> @BASEBOARD_FAB2_LIB.BASEBOARD_FAB2(SCH_1):PVDDQ_GHJ
 Y45 PVDDQ_GHJ VCCD012<33> @BASEBOARD_FAB2_LIB.BASEBOARD_FAB2(SCH_1):PVDDQ_GHJ
 W64 PVDDQ_GHJ VCCD012<32> @BASEBOARD_FAB2_LIB.BASEBOARD_FAB2(SCH_1):PVDDQ_GHJ
 U62 PVDDQ_GHJ VCCD012<31> @BASEBOARD_FAB2_LIB.BASEBOARD_FAB2(SCH_1):PVDDQ_GHJ
 U60 PVDDQ_GHJ VCCD012<30> @BASEBOARD_FAB2_LIB.BASEBOARD_FAB2(SCH_1):PVDDQ_GHJ
 U58 PVDDQ_GHJ VCCD012<29> @BASEBOARD_FAB2_LIB.BASEBOARD_FAB2(SCH_1):PVDDQ_GHJ
 U56 PVDDQ_GHJ VCCD012<28> @BASEBOARD_FAB2_LIB.BASEBOARD_FAB2(SCH_1):PVDDQ_GHJ
 U54 PVDDQ_GHJ VCCD012<27> @BASEBOARD_FAB2_LIB.BASEBOARD_FAB2(SCH_1):PVDDQ_GHJ
 U52 PVDDQ_GHJ VCCD012<26> @BASEBOARD_FAB2_LIB.BASEBOARD_FAB2(SCH_1):PVDDQ_GHJ
 U50 PVDDQ_GHJ VCCD012<25> @BASEBOARD_FAB2_LIB.BASEBOARD_FAB2(SCH_1):PVDDQ_GHJ
 U48 PVDDQ_GHJ VCCD012<24> @BASEBOARD_FAB2_LIB.BASEBOARD_FAB2(SCH_1):PVDDQ_GHJ
 U46 PVDDQ_GHJ VCCD012<23> @BASEBOARD_FAB2_LIB.BASEBOARD_FAB2(SCH_1):PVDDQ_GHJ
 N64 PVDDQ_GHJ VCCD012<22> @BASEBOARD_FAB2_LIB.BASEBOARD_FAB2(SCH_1):PVDDQ_GHJ
 L62 PVDDQ_GHJ VCCD012<21> @BASEBOARD_FAB2_LIB.BASEBOARD_FAB2(SCH_1):PVDDQ_GHJ
 L60 PVDDQ_GHJ VCCD012<20> @BASEBOARD_FAB2_LIB.BASEBOARD_FAB2(SCH_1):PVDDQ_GHJ
 L58 PVDDQ_GHJ VCCD012<19> @BASEBOARD_FAB2_LIB.BASEBOARD_FAB2(SCH_1):PVDDQ_GHJ
 L56 PVDDQ_GHJ VCCD012<18> @BASEBOARD_FAB2_LIB.BASEBOARD_FAB2(SCH_1):PVDDQ_GHJ
 L54 PVDDQ_GHJ VCCD012<17> @BASEBOARD_FAB2_LIB.BASEBOARD_FAB2(SCH_1):PVDDQ_GHJ
 L52 PVDDQ_GHJ VCCD012<16> @BASEBOARD_FAB2_LIB.BASEBOARD_FAB2(SCH_1):PVDDQ_GHJ
 L50 PVDDQ_GHJ VCCD012<15> @BASEBOARD_FAB2_LIB.BASEBOARD_FAB2(SCH_1):PVDDQ_GHJ
 L48 PVDDQ_GHJ VCCD012<14> @BASEBOARD_FAB2_LIB.BASEBOARD_FAB2(SCH_1):PVDDQ_GHJ
 L46 PVDDQ_GHJ VCCD012<13> @BASEBOARD_FAB2_LIB.BASEBOARD_FAB2(SCH_1):PVDDQ_GHJ
 E64 PVDDQ_GHJ VCCD012<12> @BASEBOARD_FAB2_LIB.BASEBOARD_FAB2(SCH_1):PVDDQ_GHJ
 E62 PVDDQ_GHJ VCCD012<11> @BASEBOARD_FAB2_LIB.BASEBOARD_FAB2(SCH_1):PVDDQ_GHJ
 E60 PVDDQ_GHJ VCCD012<10> @BASEBOARD_FAB2_LIB.BASEBOARD_FAB2(SCH_1):PVDDQ_GHJ
 E58 PVDDQ_GHJ VCCD012<9> @BASEBOARD_FAB2_LIB.BASEBOARD_FAB2(SCH_1):PVDDQ_GHJ
 E56 PVDDQ_GHJ VCCD012<8> @BASEBOARD_FAB2_LIB.BASEBOARD_FAB2(SCH_1):PVDDQ_GHJ
 E54 PVDDQ_GHJ VCCD012<7> @BASEBOARD_FAB2_LIB.BASEBOARD_FAB2(SCH_1):PVDDQ_GHJ
 E52 PVDDQ_GHJ VCCD012<6> @BASEBOARD_FAB2_LIB.BASEBOARD_FAB2(SCH_1):PVDDQ_GHJ
 E50 PVDDQ_GHJ VCCD012<5> @BASEBOARD_FAB2_LIB.BASEBOARD_FAB2(SCH_1):PVDDQ_GHJ
 E48 PVDDQ_GHJ VCCD012<4> @BASEBOARD_FAB2_LIB.BASEBOARD_FAB2(SCH_1):PVDDQ_GHJ
 E46 PVDDQ_GHJ VCCD012<3> @BASEBOARD_FAB2_LIB.BASEBOARD_FAB2(SCH_1):PVDDQ_GHJ
 B59 PVDDQ_GHJ VCCD012<2> @BASEBOARD_FAB2_LIB.BASEBOARD_FAB2(SCH_1):PVDDQ_GHJ
 B53 PVDDQ_GHJ VCCD012<1> @BASEBOARD_FAB2_LIB.BASEBOARD_FAB2(SCH_1):PVDDQ_GHJ
 B49 PVDDQ_GHJ VCCD012<0> @BASEBOARD_FAB2_LIB.BASEBOARD_FAB2(SCH_1):PVDDQ_GHJ
EE44 PVDDQ_KLM VCCD345<50> @BASEBOARD_FAB2_LIB.BASEBOARD_FAB2(SCH_1):PVDDQ_KLM
EF45 PVDDQ_KLM VCCD345<49> @BASEBOARD_FAB2_LIB.BASEBOARD_FAB2(SCH_1):PVDDQ_KLM
DB53 PVDDQ_KLM VCCD345<48> @BASEBOARD_FAB2_LIB.BASEBOARD_FAB2(SCH_1):PVDDQ_KLM
DB55 PVDDQ_KLM VCCD345<47> @BASEBOARD_FAB2_LIB.BASEBOARD_FAB2(SCH_1):PVDDQ_KLM
DB57 PVDDQ_KLM VCCD345<46> @BASEBOARD_FAB2_LIB.BASEBOARD_FAB2(SCH_1):PVDDQ_KLM
DB59 PVDDQ_KLM VCCD345<45> @BASEBOARD_FAB2_LIB.BASEBOARD_FAB2(SCH_1):PVDDQ_KLM
DB61 PVDDQ_KLM VCCD345<44> @BASEBOARD_FAB2_LIB.BASEBOARD_FAB2(SCH_1):PVDDQ_KLM
DB63 PVDDQ_KLM VCCD345<43> @BASEBOARD_FAB2_LIB.BASEBOARD_FAB2(SCH_1):PVDDQ_KLM
DD45 PVDDQ_KLM VCCD345<42> @BASEBOARD_FAB2_LIB.BASEBOARD_FAB2(SCH_1):PVDDQ_KLM
DH45 PVDDQ_KLM VCCD345<41> @BASEBOARD_FAB2_LIB.BASEBOARD_FAB2(SCH_1):PVDDQ_KLM
DH47 PVDDQ_KLM VCCD345<40> @BASEBOARD_FAB2_LIB.BASEBOARD_FAB2(SCH_1):PVDDQ_KLM
DH49 PVDDQ_KLM VCCD345<39> @BASEBOARD_FAB2_LIB.BASEBOARD_FAB2(SCH_1):PVDDQ_KLM
DH51 PVDDQ_KLM VCCD345<38> @BASEBOARD_FAB2_LIB.BASEBOARD_FAB2(SCH_1):PVDDQ_KLM
DH53 PVDDQ_KLM VCCD345<37> @BASEBOARD_FAB2_LIB.BASEBOARD_FAB2(SCH_1):PVDDQ_KLM
DH55 PVDDQ_KLM VCCD345<36> @BASEBOARD_FAB2_LIB.BASEBOARD_FAB2(SCH_1):PVDDQ_KLM
DH57 PVDDQ_KLM VCCD345<35> @BASEBOARD_FAB2_LIB.BASEBOARD_FAB2(SCH_1):PVDDQ_KLM
DH59 PVDDQ_KLM VCCD345<34> @BASEBOARD_FAB2_LIB.BASEBOARD_FAB2(SCH_1):PVDDQ_KLM
DH61 PVDDQ_KLM VCCD345<33> @BASEBOARD_FAB2_LIB.BASEBOARD_FAB2(SCH_1):PVDDQ_KLM
DH63 PVDDQ_KLM VCCD345<32> @BASEBOARD_FAB2_LIB.BASEBOARD_FAB2(SCH_1):PVDDQ_KLM
DJ64 PVDDQ_KLM VCCD345<31> @BASEBOARD_FAB2_LIB.BASEBOARD_FAB2(SCH_1):PVDDQ_KLM
DL46 PVDDQ_KLM VCCD345<30> @BASEBOARD_FAB2_LIB.BASEBOARD_FAB2(SCH_1):PVDDQ_KLM
DL48 PVDDQ_KLM VCCD345<29> @BASEBOARD_FAB2_LIB.BASEBOARD_FAB2(SCH_1):PVDDQ_KLM
DL50 PVDDQ_KLM VCCD345<28> @BASEBOARD_FAB2_LIB.BASEBOARD_FAB2(SCH_1):PVDDQ_KLM
DL52 PVDDQ_KLM VCCD345<27> @BASEBOARD_FAB2_LIB.BASEBOARD_FAB2(SCH_1):PVDDQ_KLM
DL54 PVDDQ_KLM VCCD345<26> @BASEBOARD_FAB2_LIB.BASEBOARD_FAB2(SCH_1):PVDDQ_KLM
DL56 PVDDQ_KLM VCCD345<25> @BASEBOARD_FAB2_LIB.BASEBOARD_FAB2(SCH_1):PVDDQ_KLM
DL58 PVDDQ_KLM VCCD345<24> @BASEBOARD_FAB2_LIB.BASEBOARD_FAB2(SCH_1):PVDDQ_KLM
DL60 PVDDQ_KLM VCCD345<23> @BASEBOARD_FAB2_LIB.BASEBOARD_FAB2(SCH_1):PVDDQ_KLM
DL62 PVDDQ_KLM VCCD345<22> @BASEBOARD_FAB2_LIB.BASEBOARD_FAB2(SCH_1):PVDDQ_KLM
DU46 PVDDQ_KLM VCCD345<21> @BASEBOARD_FAB2_LIB.BASEBOARD_FAB2(SCH_1):PVDDQ_KLM
DU48 PVDDQ_KLM VCCD345<20> @BASEBOARD_FAB2_LIB.BASEBOARD_FAB2(SCH_1):PVDDQ_KLM
DU50 PVDDQ_KLM VCCD345<19> @BASEBOARD_FAB2_LIB.BASEBOARD_FAB2(SCH_1):PVDDQ_KLM
DU52 PVDDQ_KLM VCCD345<18> @BASEBOARD_FAB2_LIB.BASEBOARD_FAB2(SCH_1):PVDDQ_KLM
DU54 PVDDQ_KLM VCCD345<17> @BASEBOARD_FAB2_LIB.BASEBOARD_FAB2(SCH_1):PVDDQ_KLM
DU56 PVDDQ_KLM VCCD345<16> @BASEBOARD_FAB2_LIB.BASEBOARD_FAB2(SCH_1):PVDDQ_KLM
DU58 PVDDQ_KLM VCCD345<15> @BASEBOARD_FAB2_LIB.BASEBOARD_FAB2(SCH_1):PVDDQ_KLM
DU60 PVDDQ_KLM VCCD345<14> @BASEBOARD_FAB2_LIB.BASEBOARD_FAB2(SCH_1):PVDDQ_KLM
DU62 PVDDQ_KLM VCCD345<13> @BASEBOARD_FAB2_LIB.BASEBOARD_FAB2(SCH_1):PVDDQ_KLM
DU64 PVDDQ_KLM VCCD345<12> @BASEBOARD_FAB2_LIB.BASEBOARD_FAB2(SCH_1):PVDDQ_KLM
EC46 PVDDQ_KLM VCCD345<11> @BASEBOARD_FAB2_LIB.BASEBOARD_FAB2(SCH_1):PVDDQ_KLM
EC48 PVDDQ_KLM VCCD345<10> @BASEBOARD_FAB2_LIB.BASEBOARD_FAB2(SCH_1):PVDDQ_KLM
EC50 PVDDQ_KLM VCCD345<9> @BASEBOARD_FAB2_LIB.BASEBOARD_FAB2(SCH_1):PVDDQ_KLM
EC52 PVDDQ_KLM VCCD345<8> @BASEBOARD_FAB2_LIB.BASEBOARD_FAB2(SCH_1):PVDDQ_KLM
EC54 PVDDQ_KLM VCCD345<7> @BASEBOARD_FAB2_LIB.BASEBOARD_FAB2(SCH_1):PVDDQ_KLM
EC56 PVDDQ_KLM VCCD345<6> @BASEBOARD_FAB2_LIB.BASEBOARD_FAB2(SCH_1):PVDDQ_KLM
EC58 PVDDQ_KLM VCCD345<5> @BASEBOARD_FAB2_LIB.BASEBOARD_FAB2(SCH_1):PVDDQ_KLM
EC60 PVDDQ_KLM VCCD345<4> @BASEBOARD_FAB2_LIB.BASEBOARD_FAB2(SCH_1):PVDDQ_KLM
EC62 PVDDQ_KLM VCCD345<3> @BASEBOARD_FAB2_LIB.BASEBOARD_FAB2(SCH_1):PVDDQ_KLM
EF49 PVDDQ_KLM VCCD345<2> @BASEBOARD_FAB2_LIB.BASEBOARD_FAB2(SCH_1):PVDDQ_KLM
EF53 PVDDQ_KLM VCCD345<1> @BASEBOARD_FAB2_LIB.BASEBOARD_FAB2(SCH_1):PVDDQ_KLM
EF59 PVDDQ_KLM VCCD345<0> @BASEBOARD_FAB2_LIB.BASEBOARD_FAB2(SCH_1):PVDDQ_KLM

SKX_EXT_B_BGA1-IC,TBD  I33  U2D1
BY27 P1V8_MCP_CPU1 CD_VCCIN<3> @BASEBOARD_FAB2_LIB.BASEBOARD_FAB2(SCH_1):P1V8_MCP_CPU1
BV27 P1V8_MCP_CPU1 CD_VCCIN<2> @BASEBOARD_FAB2_LIB.BASEBOARD_FAB2(SCH_1):P1V8_MCP_CPU1
BU26 P1V8_MCP_CPU1 CD_VCCIN<1> @BASEBOARD_FAB2_LIB.BASEBOARD_FAB2(SCH_1):P1V8_MCP_CPU1
BT27 P1V8_MCP_CPU1 CD_VCCIN<0> @BASEBOARD_FAB2_LIB.BASEBOARD_FAB2(SCH_1):P1V8_MCP_CPU1
BM11 PVCCIOMCP_CPU1 CD_VCCP<15> @BASEBOARD_FAB2_LIB.BASEBOARD_FAB2(SCH_1):PVCCIOMCP_CPU1
BN12 PVCCIOMCP_CPU1 CD_VCCP<14> @BASEBOARD_FAB2_LIB.BASEBOARD_FAB2(SCH_1):PVCCIOMCP_CPU1
BN14 PVCCIOMCP_CPU1 CD_VCCP<13> @BASEBOARD_FAB2_LIB.BASEBOARD_FAB2(SCH_1):PVCCIOMCP_CPU1
BP11 PVCCIOMCP_CPU1 CD_VCCP<12> @BASEBOARD_FAB2_LIB.BASEBOARD_FAB2(SCH_1):PVCCIOMCP_CPU1
BP13 PVCCIOMCP_CPU1 CD_VCCP<11> @BASEBOARD_FAB2_LIB.BASEBOARD_FAB2(SCH_1):PVCCIOMCP_CPU1
BP15 PVCCIOMCP_CPU1 CD_VCCP<10> @BASEBOARD_FAB2_LIB.BASEBOARD_FAB2(SCH_1):PVCCIOMCP_CPU1
BR12 PVCCIOMCP_CPU1 CD_VCCP<9> @BASEBOARD_FAB2_LIB.BASEBOARD_FAB2(SCH_1):PVCCIOMCP_CPU1
BR14 PVCCIOMCP_CPU1 CD_VCCP<8> @BASEBOARD_FAB2_LIB.BASEBOARD_FAB2(SCH_1):PVCCIOMCP_CPU1
BT11 PVCCIOMCP_CPU1 CD_VCCP<7> @BASEBOARD_FAB2_LIB.BASEBOARD_FAB2(SCH_1):PVCCIOMCP_CPU1
BT13 PVCCIOMCP_CPU1 CD_VCCP<6> @BASEBOARD_FAB2_LIB.BASEBOARD_FAB2(SCH_1):PVCCIOMCP_CPU1
BT15 PVCCIOMCP_CPU1 CD_VCCP<5> @BASEBOARD_FAB2_LIB.BASEBOARD_FAB2(SCH_1):PVCCIOMCP_CPU1
BU12 PVCCIOMCP_CPU1 CD_VCCP<4> @BASEBOARD_FAB2_LIB.BASEBOARD_FAB2(SCH_1):PVCCIOMCP_CPU1
BU14 PVCCIOMCP_CPU1 CD_VCCP<3> @BASEBOARD_FAB2_LIB.BASEBOARD_FAB2(SCH_1):PVCCIOMCP_CPU1
BV11 PVCCIOMCP_CPU1 CD_VCCP<2> @BASEBOARD_FAB2_LIB.BASEBOARD_FAB2(SCH_1):PVCCIOMCP_CPU1
BV13 PVCCIOMCP_CPU1 CD_VCCP<1> @BASEBOARD_FAB2_LIB.BASEBOARD_FAB2(SCH_1):PVCCIOMCP_CPU1
BV15 PVCCIOMCP_CPU1 CD_VCCP<0> @BASEBOARD_FAB2_LIB.BASEBOARD_FAB2(SCH_1):PVCCIOMCP_CPU1
BD13 PVCCMCP_CPU1 CD_VCC_CORE<12> @BASEBOARD_FAB2_LIB.BASEBOARD_FAB2(SCH_1):PVCCMCP_CPU1
BE12 PVCCMCP_CPU1 CD_VCC_CORE<11> @BASEBOARD_FAB2_LIB.BASEBOARD_FAB2(SCH_1):PVCCMCP_CPU1
BE14 PVCCMCP_CPU1 CD_VCC_CORE<10> @BASEBOARD_FAB2_LIB.BASEBOARD_FAB2(SCH_1):PVCCMCP_CPU1
BF11 PVCCMCP_CPU1 CD_VCC_CORE<9> @BASEBOARD_FAB2_LIB.BASEBOARD_FAB2(SCH_1):PVCCMCP_CPU1
BF13 PVCCMCP_CPU1 CD_VCC_CORE<8> @BASEBOARD_FAB2_LIB.BASEBOARD_FAB2(SCH_1):PVCCMCP_CPU1
BG12 PVCCMCP_CPU1 CD_VCC_CORE<7> @BASEBOARD_FAB2_LIB.BASEBOARD_FAB2(SCH_1):PVCCMCP_CPU1
BG14 PVCCMCP_CPU1 CD_VCC_CORE<6> @BASEBOARD_FAB2_LIB.BASEBOARD_FAB2(SCH_1):PVCCMCP_CPU1
BH13 PVCCMCP_CPU1 CD_VCC_CORE<5> @BASEBOARD_FAB2_LIB.BASEBOARD_FAB2(SCH_1):PVCCMCP_CPU1
BJ12 PVCCMCP_CPU1 CD_VCC_CORE<4> @BASEBOARD_FAB2_LIB.BASEBOARD_FAB2(SCH_1):PVCCMCP_CPU1
BJ14 PVCCMCP_CPU1 CD_VCC_CORE<3> @BASEBOARD_FAB2_LIB.BASEBOARD_FAB2(SCH_1):PVCCMCP_CPU1
BK13 PVCCMCP_CPU1 CD_VCC_CORE<2> @BASEBOARD_FAB2_LIB.BASEBOARD_FAB2(SCH_1):PVCCMCP_CPU1
BK15 PVCCMCP_CPU1 CD_VCC_CORE<1> @BASEBOARD_FAB2_LIB.BASEBOARD_FAB2(SCH_1):PVCCMCP_CPU1
BL14 PVCCMCP_CPU1 CD_VCC_CORE<0> @BASEBOARD_FAB2_LIB.BASEBOARD_FAB2(SCH_1):PVCCMCP_CPU1
  A8 PVPP_GHJ CD_VPP<3> @BASEBOARD_FAB2_LIB.BASEBOARD_FAB2(SCH_1):PVPP_GHJ
 A10 PVPP_GHJ CD_VPP<2> @BASEBOARD_FAB2_LIB.BASEBOARD_FAB2(SCH_1):PVPP_GHJ
 A12 PVPP_GHJ CD_VPP<1> @BASEBOARD_FAB2_LIB.BASEBOARD_FAB2(SCH_1):PVPP_GHJ
 B11 PVPP_GHJ CD_VPP<0> @BASEBOARD_FAB2_LIB.BASEBOARD_FAB2(SCH_1):PVPP_GHJ
CY55 P3V3_STBY  VCC33 @BASEBOARD_FAB2_LIB.BASEBOARD_FAB2(SCH_1):P3V3_STBY
AR28 PVCCIO_CPU1 VCCIO<104> @BASEBOARD_FAB2_LIB.BASEBOARD_FAB2(SCH_1):PVCCIO_CPU1
AL28 PVCCIO_CPU1 VCCIO<103> @BASEBOARD_FAB2_LIB.BASEBOARD_FAB2(SCH_1):PVCCIO_CPU1
AM29 PVCCIO_CPU1 VCCIO<102> @BASEBOARD_FAB2_LIB.BASEBOARD_FAB2(SCH_1):PVCCIO_CPU1
AG34 PVCCIO_CPU1 VCCIO<101> @BASEBOARD_FAB2_LIB.BASEBOARD_FAB2(SCH_1):PVCCIO_CPU1
AE34 PVCCIO_CPU1 VCCIO<100> @BASEBOARD_FAB2_LIB.BASEBOARD_FAB2(SCH_1):PVCCIO_CPU1
AD35 PVCCIO_CPU1 VCCIO<99> @BASEBOARD_FAB2_LIB.BASEBOARD_FAB2(SCH_1):PVCCIO_CPU1
AF35 PVCCIO_CPU1 VCCIO<98> @BASEBOARD_FAB2_LIB.BASEBOARD_FAB2(SCH_1):PVCCIO_CPU1
AC36 PVCCIO_CPU1 VCCIO<97> @BASEBOARD_FAB2_LIB.BASEBOARD_FAB2(SCH_1):PVCCIO_CPU1
AD37 PVCCIO_CPU1 VCCIO<96> @BASEBOARD_FAB2_LIB.BASEBOARD_FAB2(SCH_1):PVCCIO_CPU1
AE36 PVCCIO_CPU1 VCCIO<95> @BASEBOARD_FAB2_LIB.BASEBOARD_FAB2(SCH_1):PVCCIO_CPU1
BF27 PVCCIO_CPU1 VCCIO<94> @BASEBOARD_FAB2_LIB.BASEBOARD_FAB2(SCH_1):PVCCIO_CPU1
BG26 PVCCIO_CPU1 VCCIO<93> @BASEBOARD_FAB2_LIB.BASEBOARD_FAB2(SCH_1):PVCCIO_CPU1
BH25 PVCCIO_CPU1 VCCIO<92> @BASEBOARD_FAB2_LIB.BASEBOARD_FAB2(SCH_1):PVCCIO_CPU1
BH27 PVCCIO_CPU1 VCCIO<91> @BASEBOARD_FAB2_LIB.BASEBOARD_FAB2(SCH_1):PVCCIO_CPU1
BJ26 PVCCIO_CPU1 VCCIO<90> @BASEBOARD_FAB2_LIB.BASEBOARD_FAB2(SCH_1):PVCCIO_CPU1
BK25 PVCCIO_CPU1 VCCIO<89> @BASEBOARD_FAB2_LIB.BASEBOARD_FAB2(SCH_1):PVCCIO_CPU1
BK27 PVCCIO_CPU1 VCCIO<88> @BASEBOARD_FAB2_LIB.BASEBOARD_FAB2(SCH_1):PVCCIO_CPU1
BL26 PVCCIO_CPU1 VCCIO<87> @BASEBOARD_FAB2_LIB.BASEBOARD_FAB2(SCH_1):PVCCIO_CPU1
BM27 PVCCIO_CPU1 VCCIO<86> @BASEBOARD_FAB2_LIB.BASEBOARD_FAB2(SCH_1):PVCCIO_CPU1
CH27 PVCCIO_CPU1 VCCIO<85> @BASEBOARD_FAB2_LIB.BASEBOARD_FAB2(SCH_1):PVCCIO_CPU1
CJ28 PVCCIO_CPU1 VCCIO<84> @BASEBOARD_FAB2_LIB.BASEBOARD_FAB2(SCH_1):PVCCIO_CPU1
CC26 PVCCIO_CPU1 VCCIO<83> @BASEBOARD_FAB2_LIB.BASEBOARD_FAB2(SCH_1):PVCCIO_CPU1
CD27 PVCCIO_CPU1 VCCIO<82> @BASEBOARD_FAB2_LIB.BASEBOARD_FAB2(SCH_1):PVCCIO_CPU1
CF27 PVCCIO_CPU1 VCCIO<81> @BASEBOARD_FAB2_LIB.BASEBOARD_FAB2(SCH_1):PVCCIO_CPU1
AV27 PVCCIO_CPU1 VCCIO<80> @BASEBOARD_FAB2_LIB.BASEBOARD_FAB2(SCH_1):PVCCIO_CPU1
AW26 PVCCIO_CPU1 VCCIO<79> @BASEBOARD_FAB2_LIB.BASEBOARD_FAB2(SCH_1):PVCCIO_CPU1
AY27 PVCCIO_CPU1 VCCIO<78> @BASEBOARD_FAB2_LIB.BASEBOARD_FAB2(SCH_1):PVCCIO_CPU1
BA26 PVCCIO_CPU1 VCCIO<77> @BASEBOARD_FAB2_LIB.BASEBOARD_FAB2(SCH_1):PVCCIO_CPU1
BB27 PVCCIO_CPU1 VCCIO<76> @BASEBOARD_FAB2_LIB.BASEBOARD_FAB2(SCH_1):PVCCIO_CPU1
BC26 PVCCIO_CPU1 VCCIO<75> @BASEBOARD_FAB2_LIB.BASEBOARD_FAB2(SCH_1):PVCCIO_CPU1
 W10 PVCCIO_CPU1 VCCIO<74> @BASEBOARD_FAB2_LIB.BASEBOARD_FAB2(SCH_1):PVCCIO_CPU1
 N18 PVCCIO_CPU1 VCCIO<73> @BASEBOARD_FAB2_LIB.BASEBOARD_FAB2(SCH_1):PVCCIO_CPU1
  M9 PVCCIO_CPU1 VCCIO<72> @BASEBOARD_FAB2_LIB.BASEBOARD_FAB2(SCH_1):PVCCIO_CPU1
  M7 PVCCIO_CPU1 VCCIO<71> @BASEBOARD_FAB2_LIB.BASEBOARD_FAB2(SCH_1):PVCCIO_CPU1
 K15 PVCCIO_CPU1 VCCIO<70> @BASEBOARD_FAB2_LIB.BASEBOARD_FAB2(SCH_1):PVCCIO_CPU1
  J2 PVCCIO_CPU1 VCCIO<69> @BASEBOARD_FAB2_LIB.BASEBOARD_FAB2(SCH_1):PVCCIO_CPU1
EB15 PVCCIO_CPU1 VCCIO<68> @BASEBOARD_FAB2_LIB.BASEBOARD_FAB2(SCH_1):PVCCIO_CPU1
EA12 PVCCIO_CPU1 VCCIO<67> @BASEBOARD_FAB2_LIB.BASEBOARD_FAB2(SCH_1):PVCCIO_CPU1
DU20 PVCCIO_CPU1 VCCIO<66> @BASEBOARD_FAB2_LIB.BASEBOARD_FAB2(SCH_1):PVCCIO_CPU1
 DR2 PVCCIO_CPU1 VCCIO<65> @BASEBOARD_FAB2_LIB.BASEBOARD_FAB2(SCH_1):PVCCIO_CPU1
DR10 PVCCIO_CPU1 VCCIO<64> @BASEBOARD_FAB2_LIB.BASEBOARD_FAB2(SCH_1):PVCCIO_CPU1
DP19 PVCCIO_CPU1 VCCIO<63> @BASEBOARD_FAB2_LIB.BASEBOARD_FAB2(SCH_1):PVCCIO_CPU1
 DN8 PVCCIO_CPU1 VCCIO<62> @BASEBOARD_FAB2_LIB.BASEBOARD_FAB2(SCH_1):PVCCIO_CPU1
DM17 PVCCIO_CPU1 VCCIO<61> @BASEBOARD_FAB2_LIB.BASEBOARD_FAB2(SCH_1):PVCCIO_CPU1
DJ16 PVCCIO_CPU1 VCCIO<60> @BASEBOARD_FAB2_LIB.BASEBOARD_FAB2(SCH_1):PVCCIO_CPU1
 H13 PVCCIO_CPU1 VCCIO<59> @BASEBOARD_FAB2_LIB.BASEBOARD_FAB2(SCH_1):PVCCIO_CPU1
 J10 PVCCIO_CPU1 VCCIO<58> @BASEBOARD_FAB2_LIB.BASEBOARD_FAB2(SCH_1):PVCCIO_CPU1
 L14 PVCCIO_CPU1 VCCIO<57> @BASEBOARD_FAB2_LIB.BASEBOARD_FAB2(SCH_1):PVCCIO_CPU1
 L16 PVCCIO_CPU1 VCCIO<56> @BASEBOARD_FAB2_LIB.BASEBOARD_FAB2(SCH_1):PVCCIO_CPU1
 DH7 PVCCIO_CPU1 VCCIO<55> @BASEBOARD_FAB2_LIB.BASEBOARD_FAB2(SCH_1):PVCCIO_CPU1
 DG8 PVCCIO_CPU1 VCCIO<54> @BASEBOARD_FAB2_LIB.BASEBOARD_FAB2(SCH_1):PVCCIO_CPU1
 M11 PVCCIO_CPU1 VCCIO<53> @BASEBOARD_FAB2_LIB.BASEBOARD_FAB2(SCH_1):PVCCIO_CPU1
 M21 PVCCIO_CPU1 VCCIO<52> @BASEBOARD_FAB2_LIB.BASEBOARD_FAB2(SCH_1):PVCCIO_CPU1
  P5 PVCCIO_CPU1 VCCIO<51> @BASEBOARD_FAB2_LIB.BASEBOARD_FAB2(SCH_1):PVCCIO_CPU1
  T3 PVCCIO_CPU1 VCCIO<50> @BASEBOARD_FAB2_LIB.BASEBOARD_FAB2(SCH_1):PVCCIO_CPU1
 U14 PVCCIO_CPU1 VCCIO<49> @BASEBOARD_FAB2_LIB.BASEBOARD_FAB2(SCH_1):PVCCIO_CPU1
DF21 PVCCIO_CPU1 VCCIO<48> @BASEBOARD_FAB2_LIB.BASEBOARD_FAB2(SCH_1):PVCCIO_CPU1
  W4 PVCCIO_CPU1 VCCIO<47> @BASEBOARD_FAB2_LIB.BASEBOARD_FAB2(SCH_1):PVCCIO_CPU1
  W6 PVCCIO_CPU1 VCCIO<46> @BASEBOARD_FAB2_LIB.BASEBOARD_FAB2(SCH_1):PVCCIO_CPU1
AA10 PVCCIO_CPU1 VCCIO<45> @BASEBOARD_FAB2_LIB.BASEBOARD_FAB2(SCH_1):PVCCIO_CPU1
AC20 PVCCIO_CPU1 VCCIO<44> @BASEBOARD_FAB2_LIB.BASEBOARD_FAB2(SCH_1):PVCCIO_CPU1
 AC4 PVCCIO_CPU1 VCCIO<43> @BASEBOARD_FAB2_LIB.BASEBOARD_FAB2(SCH_1):PVCCIO_CPU1
 AH9 PVCCIO_CPU1 VCCIO<42> @BASEBOARD_FAB2_LIB.BASEBOARD_FAB2(SCH_1):PVCCIO_CPU1
DF13 PVCCIO_CPU1 VCCIO<41> @BASEBOARD_FAB2_LIB.BASEBOARD_FAB2(SCH_1):PVCCIO_CPU1
AN10 PVCCIO_CPU1 VCCIO<40> @BASEBOARD_FAB2_LIB.BASEBOARD_FAB2(SCH_1):PVCCIO_CPU1
 DD7 PVCCIO_CPU1 VCCIO<39> @BASEBOARD_FAB2_LIB.BASEBOARD_FAB2(SCH_1):PVCCIO_CPU1
AT11 PVCCIO_CPU1 VCCIO<38> @BASEBOARD_FAB2_LIB.BASEBOARD_FAB2(SCH_1):PVCCIO_CPU1
 AW6 PVCCIO_CPU1 VCCIO<37> @BASEBOARD_FAB2_LIB.BASEBOARD_FAB2(SCH_1):PVCCIO_CPU1
AY11 PVCCIO_CPU1 VCCIO<36> @BASEBOARD_FAB2_LIB.BASEBOARD_FAB2(SCH_1):PVCCIO_CPU1
BA24 PVCCIO_CPU1 VCCIO<35> @BASEBOARD_FAB2_LIB.BASEBOARD_FAB2(SCH_1):PVCCIO_CPU1
 BB5 PVCCIO_CPU1 VCCIO<34> @BASEBOARD_FAB2_LIB.BASEBOARD_FAB2(SCH_1):PVCCIO_CPU1
DA14 PVCCIO_CPU1 VCCIO<33> @BASEBOARD_FAB2_LIB.BASEBOARD_FAB2(SCH_1):PVCCIO_CPU1
BF23 PVCCIO_CPU1 VCCIO<32> @BASEBOARD_FAB2_LIB.BASEBOARD_FAB2(SCH_1):PVCCIO_CPU1
BJ24 PVCCIO_CPU1 VCCIO<31> @BASEBOARD_FAB2_LIB.BASEBOARD_FAB2(SCH_1):PVCCIO_CPU1
BP25 PVCCIO_CPU1 VCCIO<30> @BASEBOARD_FAB2_LIB.BASEBOARD_FAB2(SCH_1):PVCCIO_CPU1
CB13 PVCCIO_CPU1 VCCIO<29> @BASEBOARD_FAB2_LIB.BASEBOARD_FAB2(SCH_1):PVCCIO_CPU1
CB17 PVCCIO_CPU1 VCCIO<28> @BASEBOARD_FAB2_LIB.BASEBOARD_FAB2(SCH_1):PVCCIO_CPU1
 CD9 PVCCIO_CPU1 VCCIO<27> @BASEBOARD_FAB2_LIB.BASEBOARD_FAB2(SCH_1):PVCCIO_CPU1
CE18 PVCCIO_CPU1 VCCIO<26> @BASEBOARD_FAB2_LIB.BASEBOARD_FAB2(SCH_1):PVCCIO_CPU1
  D7 PVCCIO_CPU1 VCCIO<25> @BASEBOARD_FAB2_LIB.BASEBOARD_FAB2(SCH_1):PVCCIO_CPU1
 CH9 PVCCIO_CPU1 VCCIO<24> @BASEBOARD_FAB2_LIB.BASEBOARD_FAB2(SCH_1):PVCCIO_CPU1
 CV7 PVCCIO_CPU1 VCCIO<23> @BASEBOARD_FAB2_LIB.BASEBOARD_FAB2(SCH_1):PVCCIO_CPU1
 CK5 PVCCIO_CPU1 VCCIO<22> @BASEBOARD_FAB2_LIB.BASEBOARD_FAB2(SCH_1):PVCCIO_CPU1
CL12 PVCCIO_CPU1 VCCIO<21> @BASEBOARD_FAB2_LIB.BASEBOARD_FAB2(SCH_1):PVCCIO_CPU1
CM15 PVCCIO_CPU1 VCCIO<20> @BASEBOARD_FAB2_LIB.BASEBOARD_FAB2(SCH_1):PVCCIO_CPU1
CB65 PVSA_CPU1 VCCSA<25> @BASEBOARD_FAB2_LIB.BASEBOARD_FAB2(SCH_1):PVSA_CPU1
CB67 PVSA_CPU1 VCCSA<24> @BASEBOARD_FAB2_LIB.BASEBOARD_FAB2(SCH_1):PVSA_CPU1
CB69 PVSA_CPU1 VCCSA<23> @BASEBOARD_FAB2_LIB.BASEBOARD_FAB2(SCH_1):PVSA_CPU1
CC66 PVSA_CPU1 VCCSA<22> @BASEBOARD_FAB2_LIB.BASEBOARD_FAB2(SCH_1):PVSA_CPU1
CC68 PVSA_CPU1 VCCSA<21> @BASEBOARD_FAB2_LIB.BASEBOARD_FAB2(SCH_1):PVSA_CPU1
CC70 PVSA_CPU1 VCCSA<20> @BASEBOARD_FAB2_LIB.BASEBOARD_FAB2(SCH_1):PVSA_CPU1
CD65 PVSA_CPU1 VCCSA<19> @BASEBOARD_FAB2_LIB.BASEBOARD_FAB2(SCH_1):PVSA_CPU1
CD67 PVSA_CPU1 VCCSA<18> @BASEBOARD_FAB2_LIB.BASEBOARD_FAB2(SCH_1):PVSA_CPU1
CD69 PVSA_CPU1 VCCSA<17> @BASEBOARD_FAB2_LIB.BASEBOARD_FAB2(SCH_1):PVSA_CPU1
CD71 PVSA_CPU1 VCCSA<16> @BASEBOARD_FAB2_LIB.BASEBOARD_FAB2(SCH_1):PVSA_CPU1
CE64 PVSA_CPU1 VCCSA<15> @BASEBOARD_FAB2_LIB.BASEBOARD_FAB2(SCH_1):PVSA_CPU1
CE66 PVSA_CPU1 VCCSA<14> @BASEBOARD_FAB2_LIB.BASEBOARD_FAB2(SCH_1):PVSA_CPU1
CE68 PVSA_CPU1 VCCSA<13> @BASEBOARD_FAB2_LIB.BASEBOARD_FAB2(SCH_1):PVSA_CPU1
CE72 PVSA_CPU1 VCCSA<12> @BASEBOARD_FAB2_LIB.BASEBOARD_FAB2(SCH_1):PVSA_CPU1
CE74 PVSA_CPU1 VCCSA<11> @BASEBOARD_FAB2_LIB.BASEBOARD_FAB2(SCH_1):PVSA_CPU1
CF65 PVSA_CPU1 VCCSA<10> @BASEBOARD_FAB2_LIB.BASEBOARD_FAB2(SCH_1):PVSA_CPU1
CF67 PVSA_CPU1 VCCSA<9> @BASEBOARD_FAB2_LIB.BASEBOARD_FAB2(SCH_1):PVSA_CPU1
CF73 PVSA_CPU1 VCCSA<8> @BASEBOARD_FAB2_LIB.BASEBOARD_FAB2(SCH_1):PVSA_CPU1
CF75 PVSA_CPU1 VCCSA<7> @BASEBOARD_FAB2_LIB.BASEBOARD_FAB2(SCH_1):PVSA_CPU1
CG64 PVSA_CPU1 VCCSA<6> @BASEBOARD_FAB2_LIB.BASEBOARD_FAB2(SCH_1):PVSA_CPU1
CG66 PVSA_CPU1 VCCSA<5> @BASEBOARD_FAB2_LIB.BASEBOARD_FAB2(SCH_1):PVSA_CPU1
CG74 PVSA_CPU1 VCCSA<4> @BASEBOARD_FAB2_LIB.BASEBOARD_FAB2(SCH_1):PVSA_CPU1
CH65 PVSA_CPU1 VCCSA<3> @BASEBOARD_FAB2_LIB.BASEBOARD_FAB2(SCH_1):PVSA_CPU1
CH75 PVSA_CPU1 VCCSA<2> @BASEBOARD_FAB2_LIB.BASEBOARD_FAB2(SCH_1):PVSA_CPU1
CJ64 PVSA_CPU1 VCCSA<1> @BASEBOARD_FAB2_LIB.BASEBOARD_FAB2(SCH_1):PVSA_CPU1
CJ66 PVSA_CPU1 VCCSA<0> @BASEBOARD_FAB2_LIB.BASEBOARD_FAB2(SCH_1):PVSA_CPU1


DRAWING: @BASEBOARD_FAB2_LIB.BASEBOARD_FAB2(SCH_1):PAGE73 

SKX_EXT_B_BGA1-IC,TBD  I107  U2D1
BT17 VSENSE_PVCCIOMCP_CPU1_SKT_VSEN CD_VCCP_SENSE<1> @BASEBOARD_FAB2_LIB.BASEBOARD_FAB2(SCH_1):VSENSE_PVCCIOMCP_CPU1_SKT_VSEN
BU16 VSENSE_PVCCIOMCP_CPU1_SKT_VRTN CD_VCCP_SENSE<0> @BASEBOARD_FAB2_LIB.BASEBOARD_FAB2(SCH_1):VSENSE_PVCCIOMCP_CPU1_SKT_VRTN
BN16 VSENSE_PVCCMCP_CPU1_SKT_VSEN CD_VCC_CORE_SENSE @BASEBOARD_FAB2_LIB.BASEBOARD_FAB2(SCH_1):VSENSE_PVCCMCP_CPU1_SKT_VSEN
BL16 VSENSE_PVCCMCP_CPU1_SKT_VRTN CD_VSS_VCC_CORE_SENSE @BASEBOARD_FAB2_LIB.BASEBOARD_FAB2(SCH_1):VSENSE_PVCCMCP_CPU1_SKT_VRTN
CL26 PVCCMCP_CPU1 RSVD<80> @BASEBOARD_FAB2_LIB.BASEBOARD_FAB2(SCH_1):PVCCMCP_CPU1
CM23 PVCCMCP_CPU1 RSVD<79> @BASEBOARD_FAB2_LIB.BASEBOARD_FAB2(SCH_1):PVCCMCP_CPU1
CM25 PVCCMCP_CPU1 RSVD<78> @BASEBOARD_FAB2_LIB.BASEBOARD_FAB2(SCH_1):PVCCMCP_CPU1
CN22 TP_CPU1_KTI2_AMONV RSVD<77> @BASEBOARD_FAB2_LIB.BASEBOARD_FAB2(SCH_1):TP_CPU1_KTI2_AMONV
CN24 PVCCMCP_CPU1 RSVD<76> @BASEBOARD_FAB2_LIB.BASEBOARD_FAB2(SCH_1):PVCCMCP_CPU1
CN28 PD_CPU1_MCP01_DMON RSVD<75> @BASEBOARD_FAB2_LIB.BASEBOARD_FAB2(SCH_1):PD_CPU1_MCP01_DMON
CP23 PVCCMCP_CPU1 RSVD<74> @BASEBOARD_FAB2_LIB.BASEBOARD_FAB2(SCH_1):PVCCMCP_CPU1
CP31 TP_CPU1_RSVD_73 RSVD<73> @BASEBOARD_FAB2_LIB.BASEBOARD_FAB2(SCH_1):TP_CPU1_RSVD_73
CR60 TP_CPU1_RSVD_72 RSVD<72> @BASEBOARD_FAB2_LIB.BASEBOARD_FAB2(SCH_1):TP_CPU1_RSVD_72
CT23 PVCCMCP_CPU1 RSVD<71> @BASEBOARD_FAB2_LIB.BASEBOARD_FAB2(SCH_1):PVCCMCP_CPU1
 CT5 TP_CPU1_RSVD_70 RSVD<70> @BASEBOARD_FAB2_LIB.BASEBOARD_FAB2(SCH_1):TP_CPU1_RSVD_70
CT69 TP_CPU1_RSVD_69 RSVD<69> @BASEBOARD_FAB2_LIB.BASEBOARD_FAB2(SCH_1):TP_CPU1_RSVD_69
CU24 PVCCMCP_CPU1 RSVD<68> @BASEBOARD_FAB2_LIB.BASEBOARD_FAB2(SCH_1):PVCCMCP_CPU1
 CU6 TP_CPU1_RSVD_67 RSVD<67> @BASEBOARD_FAB2_LIB.BASEBOARD_FAB2(SCH_1):TP_CPU1_RSVD_67
CU60 TP_CPU1_RSVD_66 RSVD<66> @BASEBOARD_FAB2_LIB.BASEBOARD_FAB2(SCH_1):TP_CPU1_RSVD_66
CV23 PVCCMCP_CPU1 RSVD<65> @BASEBOARD_FAB2_LIB.BASEBOARD_FAB2(SCH_1):PVCCMCP_CPU1
CV69 TP_CPU1_RSVD_64 RSVD<64> @BASEBOARD_FAB2_LIB.BASEBOARD_FAB2(SCH_1):TP_CPU1_RSVD_64
CW22 TP_CPU1_KTI2_DFX_DN RSVD<63> @BASEBOARD_FAB2_LIB.BASEBOARD_FAB2(SCH_1):TP_CPU1_KTI2_DFX_DN
CW24 PVCCMCP_CPU1 RSVD<62> @BASEBOARD_FAB2_LIB.BASEBOARD_FAB2(SCH_1):PVCCMCP_CPU1
CW60 TP_CPU1_RSVD_61 RSVD<61> @BASEBOARD_FAB2_LIB.BASEBOARD_FAB2(SCH_1):TP_CPU1_RSVD_61
CW62 TP_CPU1_RSVD_60 RSVD<60> @BASEBOARD_FAB2_LIB.BASEBOARD_FAB2(SCH_1):TP_CPU1_RSVD_60
CY23 TP_CPU1_RSVD_59 RSVD<59> @BASEBOARD_FAB2_LIB.BASEBOARD_FAB2(SCH_1):TP_CPU1_RSVD_59
CY25 PVCCMCP_CPU1 RSVD<58> @BASEBOARD_FAB2_LIB.BASEBOARD_FAB2(SCH_1):PVCCMCP_CPU1
CY39 TP_CPU1_RSVD_57 RSVD<57> @BASEBOARD_FAB2_LIB.BASEBOARD_FAB2(SCH_1):TP_CPU1_RSVD_57
CY53 TP_CPU1_RSVD_56 RSVD<56> @BASEBOARD_FAB2_LIB.BASEBOARD_FAB2(SCH_1):TP_CPU1_RSVD_56
CY57 TP_CPU1_RSVD_55 RSVD<55> @BASEBOARD_FAB2_LIB.BASEBOARD_FAB2(SCH_1):TP_CPU1_RSVD_55
CY63 TP_CPU1_RSVD_54 RSVD<54> @BASEBOARD_FAB2_LIB.BASEBOARD_FAB2(SCH_1):TP_CPU1_RSVD_54
CY73 TP_CPU1_RSVD_53 RSVD<53> @BASEBOARD_FAB2_LIB.BASEBOARD_FAB2(SCH_1):TP_CPU1_RSVD_53
DA24 PVCCMCP_CPU1 RSVD<52> @BASEBOARD_FAB2_LIB.BASEBOARD_FAB2(SCH_1):PVCCMCP_CPU1
DA40 TP_CPU1_RSVD_51 RSVD<51> @BASEBOARD_FAB2_LIB.BASEBOARD_FAB2(SCH_1):TP_CPU1_RSVD_51
DA52 TP_CPU1_RSVD_50 RSVD<50> @BASEBOARD_FAB2_LIB.BASEBOARD_FAB2(SCH_1):TP_CPU1_RSVD_50
DA54 TP_CPU1_RSVD_49 RSVD<49> @BASEBOARD_FAB2_LIB.BASEBOARD_FAB2(SCH_1):TP_CPU1_RSVD_49
DA56 TP_CPU1_RSVD_48 RSVD<48> @BASEBOARD_FAB2_LIB.BASEBOARD_FAB2(SCH_1):TP_CPU1_RSVD_48
DC46 TP_CPU1_RSVD_47 RSVD<47> @BASEBOARD_FAB2_LIB.BASEBOARD_FAB2(SCH_1):TP_CPU1_RSVD_47
DC52 TP_CPU1_RSVD_46 RSVD<46> @BASEBOARD_FAB2_LIB.BASEBOARD_FAB2(SCH_1):TP_CPU1_RSVD_46
DD51 TP_CPU1_RSVD_45 RSVD<45> @BASEBOARD_FAB2_LIB.BASEBOARD_FAB2(SCH_1):TP_CPU1_RSVD_45
DG36 TP_CPU1_RSVD_44 RSVD<44> @BASEBOARD_FAB2_LIB.BASEBOARD_FAB2(SCH_1):TP_CPU1_RSVD_44
DG64 TP_CPU1_RSVD_43 RSVD<43> @BASEBOARD_FAB2_LIB.BASEBOARD_FAB2(SCH_1):TP_CPU1_RSVD_43
DH65 TP_CPU1_RSVD_42 RSVD<42> @BASEBOARD_FAB2_LIB.BASEBOARD_FAB2(SCH_1):TP_CPU1_RSVD_42
DJ36 TP_CPU1_RSVD_41 RSVD<41> @BASEBOARD_FAB2_LIB.BASEBOARD_FAB2(SCH_1):TP_CPU1_RSVD_41
DJ66 TP_CPU1_RSVD_40 RSVD<40> @BASEBOARD_FAB2_LIB.BASEBOARD_FAB2(SCH_1):TP_CPU1_RSVD_40
DK15 TP_CPU1_RSVD_39 RSVD<39> @BASEBOARD_FAB2_LIB.BASEBOARD_FAB2(SCH_1):TP_CPU1_RSVD_39
DK37 TP_CPU1_RSVD_38 RSVD<38> @BASEBOARD_FAB2_LIB.BASEBOARD_FAB2(SCH_1):TP_CPU1_RSVD_38
DK65 TP_CPU1_RSVD_37 RSVD<37> @BASEBOARD_FAB2_LIB.BASEBOARD_FAB2(SCH_1):TP_CPU1_RSVD_37
DK67 TP_CPU1_RSVD_36 RSVD<36> @BASEBOARD_FAB2_LIB.BASEBOARD_FAB2(SCH_1):TP_CPU1_RSVD_36
DL38 TP_CPU1_RSVD_35 RSVD<35> @BASEBOARD_FAB2_LIB.BASEBOARD_FAB2(SCH_1):TP_CPU1_RSVD_35
DL66 TP_CPU1_RSVD_34 RSVD<34> @BASEBOARD_FAB2_LIB.BASEBOARD_FAB2(SCH_1):TP_CPU1_RSVD_34
DM67 TP_CPU1_RSVD_33 RSVD<33> @BASEBOARD_FAB2_LIB.BASEBOARD_FAB2(SCH_1):TP_CPU1_RSVD_33
DN62 TP_CPU1_RSVD_32 RSVD<32> @BASEBOARD_FAB2_LIB.BASEBOARD_FAB2(SCH_1):TP_CPU1_RSVD_32
DN66 TP_CPU1_RSVD_31 RSVD<31> @BASEBOARD_FAB2_LIB.BASEBOARD_FAB2(SCH_1):TP_CPU1_RSVD_31
DP17 TP_CPU1_RSVD_30 RSVD<30> @BASEBOARD_FAB2_LIB.BASEBOARD_FAB2(SCH_1):TP_CPU1_RSVD_30
DP65 TP_CPU1_RSVD_29 RSVD<29> @BASEBOARD_FAB2_LIB.BASEBOARD_FAB2(SCH_1):TP_CPU1_RSVD_29
DR44 TP_CPU1_RSVD_28 RSVD<28> @BASEBOARD_FAB2_LIB.BASEBOARD_FAB2(SCH_1):TP_CPU1_RSVD_28
DT71 TP_CPU1_RSVD_27 RSVD<27> @BASEBOARD_FAB2_LIB.BASEBOARD_FAB2(SCH_1):TP_CPU1_RSVD_27
DU44 TP_CPU1_RSVD_26 RSVD<26> @BASEBOARD_FAB2_LIB.BASEBOARD_FAB2(SCH_1):TP_CPU1_RSVD_26
DV61 TP_CPU1_RSVD_25 RSVD<25> @BASEBOARD_FAB2_LIB.BASEBOARD_FAB2(SCH_1):TP_CPU1_RSVD_25
DV71 TP_CPU1_RSVD_24 RSVD<24> @BASEBOARD_FAB2_LIB.BASEBOARD_FAB2(SCH_1):TP_CPU1_RSVD_24
DW44 TP_CPU1_RSVD_23 RSVD<23> @BASEBOARD_FAB2_LIB.BASEBOARD_FAB2(SCH_1):TP_CPU1_RSVD_23
DW46 TP_CPU1_RSVD_22 RSVD<22> @BASEBOARD_FAB2_LIB.BASEBOARD_FAB2(SCH_1):TP_CPU1_RSVD_22
 DY3 TP_CPU1_RSVD_21 RSVD<21> @BASEBOARD_FAB2_LIB.BASEBOARD_FAB2(SCH_1):TP_CPU1_RSVD_21
 EA4 TP_CPU1_RSVD_20 RSVD<20> @BASEBOARD_FAB2_LIB.BASEBOARD_FAB2(SCH_1):TP_CPU1_RSVD_20
EA44 TP_CPU1_RSVD_19 RSVD<19> @BASEBOARD_FAB2_LIB.BASEBOARD_FAB2(SCH_1):TP_CPU1_RSVD_19
 EB3 TP_CPU1_RSVD_18 RSVD<18> @BASEBOARD_FAB2_LIB.BASEBOARD_FAB2(SCH_1):TP_CPU1_RSVD_18
 EB5 TP_CPU1_RSVD_17 RSVD<17> @BASEBOARD_FAB2_LIB.BASEBOARD_FAB2(SCH_1):TP_CPU1_RSVD_17
EB85 TP_CPU1_RSVD_16 RSVD<16> @BASEBOARD_FAB2_LIB.BASEBOARD_FAB2(SCH_1):TP_CPU1_RSVD_16
EC16 TP_CPU1_RSVD_15 RSVD<15> @BASEBOARD_FAB2_LIB.BASEBOARD_FAB2(SCH_1):TP_CPU1_RSVD_15
 EC4 TP_CPU1_RSVD_14 RSVD<14> @BASEBOARD_FAB2_LIB.BASEBOARD_FAB2(SCH_1):TP_CPU1_RSVD_14
EC44 TP_CPU1_RSVD_13 RSVD<13> @BASEBOARD_FAB2_LIB.BASEBOARD_FAB2(SCH_1):TP_CPU1_RSVD_13
EC84 TP_CPU1_RSVD_12 RSVD<12> @BASEBOARD_FAB2_LIB.BASEBOARD_FAB2(SCH_1):TP_CPU1_RSVD_12
ED45 TP_CPU1_RSVD_11 RSVD<11> @BASEBOARD_FAB2_LIB.BASEBOARD_FAB2(SCH_1):TP_CPU1_RSVD_11
 ED5 TP_CPU1_RSVD_10 RSVD<10> @BASEBOARD_FAB2_LIB.BASEBOARD_FAB2(SCH_1):TP_CPU1_RSVD_10
ED83 TP_CPU1_RSVD_9 RSVD<9> @BASEBOARD_FAB2_LIB.BASEBOARD_FAB2(SCH_1):TP_CPU1_RSVD_9
EE16 TP_CPU1_RSVD_8 RSVD<8> @BASEBOARD_FAB2_LIB.BASEBOARD_FAB2(SCH_1):TP_CPU1_RSVD_8
EE46 TP_CPU1_RSVD_7 RSVD<7> @BASEBOARD_FAB2_LIB.BASEBOARD_FAB2(SCH_1):TP_CPU1_RSVD_7
 EE6 TP_CPU1_RSVD_6 RSVD<6> @BASEBOARD_FAB2_LIB.BASEBOARD_FAB2(SCH_1):TP_CPU1_RSVD_6
EE82 TP_CPU1_RSVD_5 RSVD<5> @BASEBOARD_FAB2_LIB.BASEBOARD_FAB2(SCH_1):TP_CPU1_RSVD_5
EE84 TP_CPU1_RSVD_4 RSVD<4> @BASEBOARD_FAB2_LIB.BASEBOARD_FAB2(SCH_1):TP_CPU1_RSVD_4
EF47 TP_CPU1_RSVD_3 RSVD<3> @BASEBOARD_FAB2_LIB.BASEBOARD_FAB2(SCH_1):TP_CPU1_RSVD_3
EF77 TP_CPU1_RSVD_2 RSVD<2> @BASEBOARD_FAB2_LIB.BASEBOARD_FAB2(SCH_1):TP_CPU1_RSVD_2
EF81 TP_CPU1_RSVD_1 RSVD<1> @BASEBOARD_FAB2_LIB.BASEBOARD_FAB2(SCH_1):TP_CPU1_RSVD_1
EF83 TP_CPU1_RSVD_0 RSVD<0> @BASEBOARD_FAB2_LIB.BASEBOARD_FAB2(SCH_1):TP_CPU1_RSVD_0
 CN6 PVCCIO_CPU1 VCCIO<19> @BASEBOARD_FAB2_LIB.BASEBOARD_FAB2(SCH_1):PVCCIO_CPU1
CU12 PVCCIO_CPU1 VCCIO<18> @BASEBOARD_FAB2_LIB.BASEBOARD_FAB2(SCH_1):PVCCIO_CPU1
CV21 PVCCIO_CPU1 VCCIO<17> @BASEBOARD_FAB2_LIB.BASEBOARD_FAB2(SCH_1):PVCCIO_CPU1
CU18 PVCCIO_CPU1 VCCIO<16> @BASEBOARD_FAB2_LIB.BASEBOARD_FAB2(SCH_1):PVCCIO_CPU1
CY17 PVCCIO_CPU1 VCCIO<15> @BASEBOARD_FAB2_LIB.BASEBOARD_FAB2(SCH_1):PVCCIO_CPU1
DC18 PVCCIO_CPU1 VCCIO<14> @BASEBOARD_FAB2_LIB.BASEBOARD_FAB2(SCH_1):PVCCIO_CPU1
DE14 PVCCIO_CPU1 VCCIO<13> @BASEBOARD_FAB2_LIB.BASEBOARD_FAB2(SCH_1):PVCCIO_CPU1
CP13 PVCCIO_CPU1 VCCIO<12> @BASEBOARD_FAB2_LIB.BASEBOARD_FAB2(SCH_1):PVCCIO_CPU1
CL20 PVCCIO_CPU1 VCCIO<11> @BASEBOARD_FAB2_LIB.BASEBOARD_FAB2(SCH_1):PVCCIO_CPU1
CG14 PVCCIO_CPU1 VCCIO<10> @BASEBOARD_FAB2_LIB.BASEBOARD_FAB2(SCH_1):PVCCIO_CPU1
 CF5 PVCCIO_CPU1 VCCIO<9> @BASEBOARD_FAB2_LIB.BASEBOARD_FAB2(SCH_1):PVCCIO_CPU1
DK21 PVCCIO_CPU1 VCCIO<8> @BASEBOARD_FAB2_LIB.BASEBOARD_FAB2(SCH_1):PVCCIO_CPU1
BE24 PVCCIO_CPU1 VCCIO<7> @BASEBOARD_FAB2_LIB.BASEBOARD_FAB2(SCH_1):PVCCIO_CPU1
 AT7 PVCCIO_CPU1 VCCIO<6> @BASEBOARD_FAB2_LIB.BASEBOARD_FAB2(SCH_1):PVCCIO_CPU1
 AT5 PVCCIO_CPU1 VCCIO<5> @BASEBOARD_FAB2_LIB.BASEBOARD_FAB2(SCH_1):PVCCIO_CPU1
 AM5 PVCCIO_CPU1 VCCIO<4> @BASEBOARD_FAB2_LIB.BASEBOARD_FAB2(SCH_1):PVCCIO_CPU1
DV11 PVCCIO_CPU1 VCCIO<3> @BASEBOARD_FAB2_LIB.BASEBOARD_FAB2(SCH_1):PVCCIO_CPU1
 AF5 PVCCIO_CPU1 VCCIO<2> @BASEBOARD_FAB2_LIB.BASEBOARD_FAB2(SCH_1):PVCCIO_CPU1
AE10 PVCCIO_CPU1 VCCIO<1> @BASEBOARD_FAB2_LIB.BASEBOARD_FAB2(SCH_1):PVCCIO_CPU1
EE10 PVCCIO_CPU1 VCCIO<0> @BASEBOARD_FAB2_LIB.BASEBOARD_FAB2(SCH_1):PVCCIO_CPU1
 BH5 VSENSE_PVCCIO_CPU1_SKT_VSEN VCCIO_SENSE @BASEBOARD_FAB2_LIB.BASEBOARD_FAB2(SCH_1):VSENSE_PVCCIO_CPU1_SKT_VSEN
CE76 VSENSE_PVSA_CPU1_SKT_VSEN VCCSA_SENSE @BASEBOARD_FAB2_LIB.BASEBOARD_FAB2(SCH_1):VSENSE_PVSA_CPU1_SKT_VSEN
 BF5 VSENSE_PVCCIO_CPU1_SKT_VRTN VSS_VCCIO_SENSE @BASEBOARD_FAB2_LIB.BASEBOARD_FAB2(SCH_1):VSENSE_PVCCIO_CPU1_SKT_VRTN
CG76 VSENSE_PVSA_CPU1_SKT_VRTN VSS_VCCSA_SENSE @BASEBOARD_FAB2_LIB.BASEBOARD_FAB2(SCH_1):VSENSE_PVSA_CPU1_SKT_VRTN


DRAWING: @BASEBOARD_FAB2_LIB.BASEBOARD_FAB2(SCH_1):PAGE74 

SKX_EXT_B_BGA1-IC,TBD  I20  U2D1
  B9    GND VSS<1253> @BASEBOARD_FAB2_LIB.BASEBOARD_FAB2(SCH_1):GND
 A42    GND VSS<1252> @BASEBOARD_FAB2_LIB.BASEBOARD_FAB2(SCH_1):GND
 B43    GND VSS<1251> @BASEBOARD_FAB2_LIB.BASEBOARD_FAB2(SCH_1):GND
  B5    GND VSS<1250> @BASEBOARD_FAB2_LIB.BASEBOARD_FAB2(SCH_1):GND
 B79    GND VSS<1249> @BASEBOARD_FAB2_LIB.BASEBOARD_FAB2(SCH_1):GND
  C4    GND VSS<1248> @BASEBOARD_FAB2_LIB.BASEBOARD_FAB2(SCH_1):GND
 C80    GND VSS<1247> @BASEBOARD_FAB2_LIB.BASEBOARD_FAB2(SCH_1):GND
  D3    GND VSS<1246> @BASEBOARD_FAB2_LIB.BASEBOARD_FAB2(SCH_1):GND
 D81    GND VSS<1245> @BASEBOARD_FAB2_LIB.BASEBOARD_FAB2(SCH_1):GND
 E82    GND VSS<1244> @BASEBOARD_FAB2_LIB.BASEBOARD_FAB2(SCH_1):GND
 J86    GND VSS<1243> @BASEBOARD_FAB2_LIB.BASEBOARD_FAB2(SCH_1):GND
DY85    GND VSS<1242> @BASEBOARD_FAB2_LIB.BASEBOARD_FAB2(SCH_1):GND
EA84    GND VSS<1241> @BASEBOARD_FAB2_LIB.BASEBOARD_FAB2(SCH_1):GND
EB83    GND VSS<1240> @BASEBOARD_FAB2_LIB.BASEBOARD_FAB2(SCH_1):GND
 DW2    GND VSS<1239> @BASEBOARD_FAB2_LIB.BASEBOARD_FAB2(SCH_1):GND
EC42    GND VSS<1238> @BASEBOARD_FAB2_LIB.BASEBOARD_FAB2(SCH_1):GND
 EC6    GND VSS<1237> @BASEBOARD_FAB2_LIB.BASEBOARD_FAB2(SCH_1):GND
EC82    GND VSS<1236> @BASEBOARD_FAB2_LIB.BASEBOARD_FAB2(SCH_1):GND
ED41    GND VSS<1235> @BASEBOARD_FAB2_LIB.BASEBOARD_FAB2(SCH_1):GND
 ED7    GND VSS<1234> @BASEBOARD_FAB2_LIB.BASEBOARD_FAB2(SCH_1):GND
ED81    GND VSS<1233> @BASEBOARD_FAB2_LIB.BASEBOARD_FAB2(SCH_1):GND
EE40    GND VSS<1232> @BASEBOARD_FAB2_LIB.BASEBOARD_FAB2(SCH_1):GND
 EE8    GND VSS<1231> @BASEBOARD_FAB2_LIB.BASEBOARD_FAB2(SCH_1):GND
EE80    GND VSS<1230> @BASEBOARD_FAB2_LIB.BASEBOARD_FAB2(SCH_1):GND
ED69    GND VSS<1229> @BASEBOARD_FAB2_LIB.BASEBOARD_FAB2(SCH_1):GND
 E66    GND VSS<1228> @BASEBOARD_FAB2_LIB.BASEBOARD_FAB2(SCH_1):GND
 V11    GND VSS<1227> @BASEBOARD_FAB2_LIB.BASEBOARD_FAB2(SCH_1):GND
  L8    GND VSS<1226> @BASEBOARD_FAB2_LIB.BASEBOARD_FAB2(SCH_1):GND
EA14    GND VSS<1225> @BASEBOARD_FAB2_LIB.BASEBOARD_FAB2(SCH_1):GND
DY63    GND VSS<1224> @BASEBOARD_FAB2_LIB.BASEBOARD_FAB2(SCH_1):GND
DY61    GND VSS<1223> @BASEBOARD_FAB2_LIB.BASEBOARD_FAB2(SCH_1):GND
DY59    GND VSS<1222> @BASEBOARD_FAB2_LIB.BASEBOARD_FAB2(SCH_1):GND
DY57    GND VSS<1221> @BASEBOARD_FAB2_LIB.BASEBOARD_FAB2(SCH_1):GND
DY55    GND VSS<1220> @BASEBOARD_FAB2_LIB.BASEBOARD_FAB2(SCH_1):GND
DY53    GND VSS<1219> @BASEBOARD_FAB2_LIB.BASEBOARD_FAB2(SCH_1):GND
DY51    GND VSS<1218> @BASEBOARD_FAB2_LIB.BASEBOARD_FAB2(SCH_1):GND
DY49    GND VSS<1217> @BASEBOARD_FAB2_LIB.BASEBOARD_FAB2(SCH_1):GND
DY47    GND VSS<1216> @BASEBOARD_FAB2_LIB.BASEBOARD_FAB2(SCH_1):GND
DY45    GND VSS<1215> @BASEBOARD_FAB2_LIB.BASEBOARD_FAB2(SCH_1):GND
DV19    GND VSS<1214> @BASEBOARD_FAB2_LIB.BASEBOARD_FAB2(SCH_1):GND
 DP9    GND VSS<1213> @BASEBOARD_FAB2_LIB.BASEBOARD_FAB2(SCH_1):GND
DP63    GND VSS<1212> @BASEBOARD_FAB2_LIB.BASEBOARD_FAB2(SCH_1):GND
DP61    GND VSS<1211> @BASEBOARD_FAB2_LIB.BASEBOARD_FAB2(SCH_1):GND
DP59    GND VSS<1210> @BASEBOARD_FAB2_LIB.BASEBOARD_FAB2(SCH_1):GND
DP57    GND VSS<1209> @BASEBOARD_FAB2_LIB.BASEBOARD_FAB2(SCH_1):GND
DP55    GND VSS<1208> @BASEBOARD_FAB2_LIB.BASEBOARD_FAB2(SCH_1):GND
DP53    GND VSS<1207> @BASEBOARD_FAB2_LIB.BASEBOARD_FAB2(SCH_1):GND
DP51    GND VSS<1206> @BASEBOARD_FAB2_LIB.BASEBOARD_FAB2(SCH_1):GND
DP49    GND VSS<1205> @BASEBOARD_FAB2_LIB.BASEBOARD_FAB2(SCH_1):GND
DP47    GND VSS<1204> @BASEBOARD_FAB2_LIB.BASEBOARD_FAB2(SCH_1):GND
DP45    GND VSS<1203> @BASEBOARD_FAB2_LIB.BASEBOARD_FAB2(SCH_1):GND
DN18    GND VSS<1202> @BASEBOARD_FAB2_LIB.BASEBOARD_FAB2(SCH_1):GND
 DL8    GND VSS<1201> @BASEBOARD_FAB2_LIB.BASEBOARD_FAB2(SCH_1):GND
DE62    GND VSS<1200> @BASEBOARD_FAB2_LIB.BASEBOARD_FAB2(SCH_1):GND
DE60    GND VSS<1199> @BASEBOARD_FAB2_LIB.BASEBOARD_FAB2(SCH_1):GND
DE58    GND VSS<1198> @BASEBOARD_FAB2_LIB.BASEBOARD_FAB2(SCH_1):GND
DE56    GND VSS<1197> @BASEBOARD_FAB2_LIB.BASEBOARD_FAB2(SCH_1):GND
DE54    GND VSS<1196> @BASEBOARD_FAB2_LIB.BASEBOARD_FAB2(SCH_1):GND
DE52    GND VSS<1195> @BASEBOARD_FAB2_LIB.BASEBOARD_FAB2(SCH_1):GND
DE50    GND VSS<1194> @BASEBOARD_FAB2_LIB.BASEBOARD_FAB2(SCH_1):GND
DE48    GND VSS<1193> @BASEBOARD_FAB2_LIB.BASEBOARD_FAB2(SCH_1):GND
 CW6    GND VSS<1192> @BASEBOARD_FAB2_LIB.BASEBOARD_FAB2(SCH_1):GND
 CG6    GND VSS<1191> @BASEBOARD_FAB2_LIB.BASEBOARD_FAB2(SCH_1):GND
 AR6    GND VSS<1190> @BASEBOARD_FAB2_LIB.BASEBOARD_FAB2(SCH_1):GND
 AJ4    GND VSS<1189> @BASEBOARD_FAB2_LIB.BASEBOARD_FAB2(SCH_1):GND
AC62    GND VSS<1188> @BASEBOARD_FAB2_LIB.BASEBOARD_FAB2(SCH_1):GND
AC60    GND VSS<1187> @BASEBOARD_FAB2_LIB.BASEBOARD_FAB2(SCH_1):GND
AC58    GND VSS<1186> @BASEBOARD_FAB2_LIB.BASEBOARD_FAB2(SCH_1):GND
 A26    GND VSS<1185> @BASEBOARD_FAB2_LIB.BASEBOARD_FAB2(SCH_1):GND
 A30    GND VSS<1184> @BASEBOARD_FAB2_LIB.BASEBOARD_FAB2(SCH_1):GND
 A32    GND VSS<1183> @BASEBOARD_FAB2_LIB.BASEBOARD_FAB2(SCH_1):GND
 A36    GND VSS<1182> @BASEBOARD_FAB2_LIB.BASEBOARD_FAB2(SCH_1):GND
 A38    GND VSS<1181> @BASEBOARD_FAB2_LIB.BASEBOARD_FAB2(SCH_1):GND
 B25    GND VSS<1180> @BASEBOARD_FAB2_LIB.BASEBOARD_FAB2(SCH_1):GND
 B31    GND VSS<1179> @BASEBOARD_FAB2_LIB.BASEBOARD_FAB2(SCH_1):GND
 B37    GND VSS<1178> @BASEBOARD_FAB2_LIB.BASEBOARD_FAB2(SCH_1):GND
 B71    GND VSS<1177> @BASEBOARD_FAB2_LIB.BASEBOARD_FAB2(SCH_1):GND
 B75    GND VSS<1176> @BASEBOARD_FAB2_LIB.BASEBOARD_FAB2(SCH_1):GND
  C8    GND VSS<1175> @BASEBOARD_FAB2_LIB.BASEBOARD_FAB2(SCH_1):GND
 C10    GND VSS<1174> @BASEBOARD_FAB2_LIB.BASEBOARD_FAB2(SCH_1):GND
 C12    GND VSS<1173> @BASEBOARD_FAB2_LIB.BASEBOARD_FAB2(SCH_1):GND
 C14    GND VSS<1172> @BASEBOARD_FAB2_LIB.BASEBOARD_FAB2(SCH_1):GND
 C16    GND VSS<1171> @BASEBOARD_FAB2_LIB.BASEBOARD_FAB2(SCH_1):GND
 C76    GND VSS<1170> @BASEBOARD_FAB2_LIB.BASEBOARD_FAB2(SCH_1):GND
 C78    GND VSS<1169> @BASEBOARD_FAB2_LIB.BASEBOARD_FAB2(SCH_1):GND
CM27    GND VSS<1168> @BASEBOARD_FAB2_LIB.BASEBOARD_FAB2(SCH_1):GND
 D11    GND VSS<1167> @BASEBOARD_FAB2_LIB.BASEBOARD_FAB2(SCH_1):GND
 D13    GND VSS<1166> @BASEBOARD_FAB2_LIB.BASEBOARD_FAB2(SCH_1):GND
 D25    GND VSS<1165> @BASEBOARD_FAB2_LIB.BASEBOARD_FAB2(SCH_1):GND
 D27    GND VSS<1164> @BASEBOARD_FAB2_LIB.BASEBOARD_FAB2(SCH_1):GND
 D29    GND VSS<1163> @BASEBOARD_FAB2_LIB.BASEBOARD_FAB2(SCH_1):GND
 D31    GND VSS<1162> @BASEBOARD_FAB2_LIB.BASEBOARD_FAB2(SCH_1):GND
 D33    GND VSS<1161> @BASEBOARD_FAB2_LIB.BASEBOARD_FAB2(SCH_1):GND
 D35    GND VSS<1160> @BASEBOARD_FAB2_LIB.BASEBOARD_FAB2(SCH_1):GND
 D37    GND VSS<1159> @BASEBOARD_FAB2_LIB.BASEBOARD_FAB2(SCH_1):GND
 D39    GND VSS<1158> @BASEBOARD_FAB2_LIB.BASEBOARD_FAB2(SCH_1):GND
 D41    GND VSS<1157> @BASEBOARD_FAB2_LIB.BASEBOARD_FAB2(SCH_1):GND
 D43    GND VSS<1156> @BASEBOARD_FAB2_LIB.BASEBOARD_FAB2(SCH_1):GND
 D77    GND VSS<1155> @BASEBOARD_FAB2_LIB.BASEBOARD_FAB2(SCH_1):GND
  E6    GND VSS<1154> @BASEBOARD_FAB2_LIB.BASEBOARD_FAB2(SCH_1):GND
  E8    GND VSS<1153> @BASEBOARD_FAB2_LIB.BASEBOARD_FAB2(SCH_1):GND
 E16    GND VSS<1152> @BASEBOARD_FAB2_LIB.BASEBOARD_FAB2(SCH_1):GND
 E18    GND VSS<1151> @BASEBOARD_FAB2_LIB.BASEBOARD_FAB2(SCH_1):GND
 E20    GND VSS<1150> @BASEBOARD_FAB2_LIB.BASEBOARD_FAB2(SCH_1):GND
 E22    GND VSS<1149> @BASEBOARD_FAB2_LIB.BASEBOARD_FAB2(SCH_1):GND
 E72    GND VSS<1148> @BASEBOARD_FAB2_LIB.BASEBOARD_FAB2(SCH_1):GND
 E74    GND VSS<1147> @BASEBOARD_FAB2_LIB.BASEBOARD_FAB2(SCH_1):GND
 E76    GND VSS<1146> @BASEBOARD_FAB2_LIB.BASEBOARD_FAB2(SCH_1):GND
  F5    GND VSS<1145> @BASEBOARD_FAB2_LIB.BASEBOARD_FAB2(SCH_1):GND
 F17    GND VSS<1144> @BASEBOARD_FAB2_LIB.BASEBOARD_FAB2(SCH_1):GND
 F19    GND VSS<1143> @BASEBOARD_FAB2_LIB.BASEBOARD_FAB2(SCH_1):GND
 F25    GND VSS<1142> @BASEBOARD_FAB2_LIB.BASEBOARD_FAB2(SCH_1):GND
 F31    GND VSS<1141> @BASEBOARD_FAB2_LIB.BASEBOARD_FAB2(SCH_1):GND
 F37    GND VSS<1140> @BASEBOARD_FAB2_LIB.BASEBOARD_FAB2(SCH_1):GND
 F43    GND VSS<1139> @BASEBOARD_FAB2_LIB.BASEBOARD_FAB2(SCH_1):GND
 F67    GND VSS<1138> @BASEBOARD_FAB2_LIB.BASEBOARD_FAB2(SCH_1):GND
 F69    GND VSS<1137> @BASEBOARD_FAB2_LIB.BASEBOARD_FAB2(SCH_1):GND
  G4    GND VSS<1136> @BASEBOARD_FAB2_LIB.BASEBOARD_FAB2(SCH_1):GND
  G8    GND VSS<1135> @BASEBOARD_FAB2_LIB.BASEBOARD_FAB2(SCH_1):GND
 G22    GND VSS<1134> @BASEBOARD_FAB2_LIB.BASEBOARD_FAB2(SCH_1):GND
 G24    GND VSS<1133> @BASEBOARD_FAB2_LIB.BASEBOARD_FAB2(SCH_1):GND
 G26    GND VSS<1132> @BASEBOARD_FAB2_LIB.BASEBOARD_FAB2(SCH_1):GND
 G30    GND VSS<1131> @BASEBOARD_FAB2_LIB.BASEBOARD_FAB2(SCH_1):GND
 G32    GND VSS<1130> @BASEBOARD_FAB2_LIB.BASEBOARD_FAB2(SCH_1):GND
 G36    GND VSS<1129> @BASEBOARD_FAB2_LIB.BASEBOARD_FAB2(SCH_1):GND
 G38    GND VSS<1128> @BASEBOARD_FAB2_LIB.BASEBOARD_FAB2(SCH_1):GND
 G42    GND VSS<1127> @BASEBOARD_FAB2_LIB.BASEBOARD_FAB2(SCH_1):GND
 G66    GND VSS<1126> @BASEBOARD_FAB2_LIB.BASEBOARD_FAB2(SCH_1):GND
 G70    GND VSS<1125> @BASEBOARD_FAB2_LIB.BASEBOARD_FAB2(SCH_1):GND
 G76    GND VSS<1124> @BASEBOARD_FAB2_LIB.BASEBOARD_FAB2(SCH_1):GND
 G78    GND VSS<1123> @BASEBOARD_FAB2_LIB.BASEBOARD_FAB2(SCH_1):GND
 G80    GND VSS<1122> @BASEBOARD_FAB2_LIB.BASEBOARD_FAB2(SCH_1):GND
 G82    GND VSS<1121> @BASEBOARD_FAB2_LIB.BASEBOARD_FAB2(SCH_1):GND
  H3    GND VSS<1120> @BASEBOARD_FAB2_LIB.BASEBOARD_FAB2(SCH_1):GND
 H11    GND VSS<1119> @BASEBOARD_FAB2_LIB.BASEBOARD_FAB2(SCH_1):GND
 H25    GND VSS<1118> @BASEBOARD_FAB2_LIB.BASEBOARD_FAB2(SCH_1):GND
 H27    GND VSS<1117> @BASEBOARD_FAB2_LIB.BASEBOARD_FAB2(SCH_1):GND
 H29    GND VSS<1116> @BASEBOARD_FAB2_LIB.BASEBOARD_FAB2(SCH_1):GND
 H31    GND VSS<1115> @BASEBOARD_FAB2_LIB.BASEBOARD_FAB2(SCH_1):GND
 H33    GND VSS<1114> @BASEBOARD_FAB2_LIB.BASEBOARD_FAB2(SCH_1):GND
 H35    GND VSS<1113> @BASEBOARD_FAB2_LIB.BASEBOARD_FAB2(SCH_1):GND
 H37    GND VSS<1112> @BASEBOARD_FAB2_LIB.BASEBOARD_FAB2(SCH_1):GND
 H39    GND VSS<1111> @BASEBOARD_FAB2_LIB.BASEBOARD_FAB2(SCH_1):GND
 H41    GND VSS<1110> @BASEBOARD_FAB2_LIB.BASEBOARD_FAB2(SCH_1):GND
 H65    GND VSS<1109> @BASEBOARD_FAB2_LIB.BASEBOARD_FAB2(SCH_1):GND
 H71    GND VSS<1108> @BASEBOARD_FAB2_LIB.BASEBOARD_FAB2(SCH_1):GND
 H75    GND VSS<1107> @BASEBOARD_FAB2_LIB.BASEBOARD_FAB2(SCH_1):GND
DN44    GND VSS<1106> @BASEBOARD_FAB2_LIB.BASEBOARD_FAB2(SCH_1):GND
  J4    GND VSS<1105> @BASEBOARD_FAB2_LIB.BASEBOARD_FAB2(SCH_1):GND
 J12    GND VSS<1104> @BASEBOARD_FAB2_LIB.BASEBOARD_FAB2(SCH_1):GND
 J14    GND VSS<1103> @BASEBOARD_FAB2_LIB.BASEBOARD_FAB2(SCH_1):GND
 J22    GND VSS<1102> @BASEBOARD_FAB2_LIB.BASEBOARD_FAB2(SCH_1):GND
 J26    GND VSS<1101> @BASEBOARD_FAB2_LIB.BASEBOARD_FAB2(SCH_1):GND
 J28    GND VSS<1100> @BASEBOARD_FAB2_LIB.BASEBOARD_FAB2(SCH_1):GND
 J32    GND VSS<1099> @BASEBOARD_FAB2_LIB.BASEBOARD_FAB2(SCH_1):GND
 J34    GND VSS<1098> @BASEBOARD_FAB2_LIB.BASEBOARD_FAB2(SCH_1):GND
 J38    GND VSS<1097> @BASEBOARD_FAB2_LIB.BASEBOARD_FAB2(SCH_1):GND
 J40    GND VSS<1096> @BASEBOARD_FAB2_LIB.BASEBOARD_FAB2(SCH_1):GND
 J72    GND VSS<1095> @BASEBOARD_FAB2_LIB.BASEBOARD_FAB2(SCH_1):GND
 J74    GND VSS<1094> @BASEBOARD_FAB2_LIB.BASEBOARD_FAB2(SCH_1):GND

SKX_EXT_B_BGA1-IC,TBD  I21  U2D1
 J76    GND VSS<1093> @BASEBOARD_FAB2_LIB.BASEBOARD_FAB2(SCH_1):GND
 J82    GND VSS<1092> @BASEBOARD_FAB2_LIB.BASEBOARD_FAB2(SCH_1):GND
 J84    GND VSS<1091> @BASEBOARD_FAB2_LIB.BASEBOARD_FAB2(SCH_1):GND
  K1    GND VSS<1090> @BASEBOARD_FAB2_LIB.BASEBOARD_FAB2(SCH_1):GND
 K11    GND VSS<1089> @BASEBOARD_FAB2_LIB.BASEBOARD_FAB2(SCH_1):GND
 K13    GND VSS<1088> @BASEBOARD_FAB2_LIB.BASEBOARD_FAB2(SCH_1):GND
 K17    GND VSS<1087> @BASEBOARD_FAB2_LIB.BASEBOARD_FAB2(SCH_1):GND
 DB7    GND VSS<1086> @BASEBOARD_FAB2_LIB.BASEBOARD_FAB2(SCH_1):GND
 K27    GND VSS<1085> @BASEBOARD_FAB2_LIB.BASEBOARD_FAB2(SCH_1):GND
 K33    GND VSS<1084> @BASEBOARD_FAB2_LIB.BASEBOARD_FAB2(SCH_1):GND
 K39    GND VSS<1083> @BASEBOARD_FAB2_LIB.BASEBOARD_FAB2(SCH_1):GND
 K65    GND VSS<1082> @BASEBOARD_FAB2_LIB.BASEBOARD_FAB2(SCH_1):GND
 K67    GND VSS<1081> @BASEBOARD_FAB2_LIB.BASEBOARD_FAB2(SCH_1):GND
 K69    GND VSS<1080> @BASEBOARD_FAB2_LIB.BASEBOARD_FAB2(SCH_1):GND
 K71    GND VSS<1079> @BASEBOARD_FAB2_LIB.BASEBOARD_FAB2(SCH_1):GND
 K73    GND VSS<1078> @BASEBOARD_FAB2_LIB.BASEBOARD_FAB2(SCH_1):GND
 K77    GND VSS<1077> @BASEBOARD_FAB2_LIB.BASEBOARD_FAB2(SCH_1):GND
 K81    GND VSS<1076> @BASEBOARD_FAB2_LIB.BASEBOARD_FAB2(SCH_1):GND
 K83    GND VSS<1075> @BASEBOARD_FAB2_LIB.BASEBOARD_FAB2(SCH_1):GND
 K85    GND VSS<1074> @BASEBOARD_FAB2_LIB.BASEBOARD_FAB2(SCH_1):GND
 L10    GND VSS<1073> @BASEBOARD_FAB2_LIB.BASEBOARD_FAB2(SCH_1):GND
  L2    GND VSS<1072> @BASEBOARD_FAB2_LIB.BASEBOARD_FAB2(SCH_1):GND
  L6    GND VSS<1071> @BASEBOARD_FAB2_LIB.BASEBOARD_FAB2(SCH_1):GND
 L20    GND VSS<1070> @BASEBOARD_FAB2_LIB.BASEBOARD_FAB2(SCH_1):GND
 L22    GND VSS<1069> @BASEBOARD_FAB2_LIB.BASEBOARD_FAB2(SCH_1):GND
 L72    GND VSS<1068> @BASEBOARD_FAB2_LIB.BASEBOARD_FAB2(SCH_1):GND
 L78    GND VSS<1067> @BASEBOARD_FAB2_LIB.BASEBOARD_FAB2(SCH_1):GND
 L80    GND VSS<1066> @BASEBOARD_FAB2_LIB.BASEBOARD_FAB2(SCH_1):GND
 L82    GND VSS<1065> @BASEBOARD_FAB2_LIB.BASEBOARD_FAB2(SCH_1):GND
 BT9    GND VSS<1064> @BASEBOARD_FAB2_LIB.BASEBOARD_FAB2(SCH_1):GND
 CT7    GND VSS<1063> @BASEBOARD_FAB2_LIB.BASEBOARD_FAB2(SCH_1):GND
 M15    GND VSS<1062> @BASEBOARD_FAB2_LIB.BASEBOARD_FAB2(SCH_1):GND
 M17    GND VSS<1061> @BASEBOARD_FAB2_LIB.BASEBOARD_FAB2(SCH_1):GND
 M19    GND VSS<1060> @BASEBOARD_FAB2_LIB.BASEBOARD_FAB2(SCH_1):GND
 M23    GND VSS<1059> @BASEBOARD_FAB2_LIB.BASEBOARD_FAB2(SCH_1):GND
 M25    GND VSS<1058> @BASEBOARD_FAB2_LIB.BASEBOARD_FAB2(SCH_1):GND
 M27    GND VSS<1057> @BASEBOARD_FAB2_LIB.BASEBOARD_FAB2(SCH_1):GND
 M29    GND VSS<1056> @BASEBOARD_FAB2_LIB.BASEBOARD_FAB2(SCH_1):GND
 M31    GND VSS<1055> @BASEBOARD_FAB2_LIB.BASEBOARD_FAB2(SCH_1):GND
 M33    GND VSS<1054> @BASEBOARD_FAB2_LIB.BASEBOARD_FAB2(SCH_1):GND
 M35    GND VSS<1053> @BASEBOARD_FAB2_LIB.BASEBOARD_FAB2(SCH_1):GND
 M37    GND VSS<1052> @BASEBOARD_FAB2_LIB.BASEBOARD_FAB2(SCH_1):GND
 M39    GND VSS<1051> @BASEBOARD_FAB2_LIB.BASEBOARD_FAB2(SCH_1):GND
 M41    GND VSS<1050> @BASEBOARD_FAB2_LIB.BASEBOARD_FAB2(SCH_1):GND
 M43    GND VSS<1049> @BASEBOARD_FAB2_LIB.BASEBOARD_FAB2(SCH_1):GND
 M65    GND VSS<1048> @BASEBOARD_FAB2_LIB.BASEBOARD_FAB2(SCH_1):GND
 M71    GND VSS<1047> @BASEBOARD_FAB2_LIB.BASEBOARD_FAB2(SCH_1):GND
 M79    GND VSS<1046> @BASEBOARD_FAB2_LIB.BASEBOARD_FAB2(SCH_1):GND
 M83    GND VSS<1045> @BASEBOARD_FAB2_LIB.BASEBOARD_FAB2(SCH_1):GND
 M85    GND VSS<1044> @BASEBOARD_FAB2_LIB.BASEBOARD_FAB2(SCH_1):GND
DM19    GND VSS<1043> @BASEBOARD_FAB2_LIB.BASEBOARD_FAB2(SCH_1):GND
 N20    GND VSS<1042> @BASEBOARD_FAB2_LIB.BASEBOARD_FAB2(SCH_1):GND
 N22    GND VSS<1041> @BASEBOARD_FAB2_LIB.BASEBOARD_FAB2(SCH_1):GND
  N6    GND VSS<1040> @BASEBOARD_FAB2_LIB.BASEBOARD_FAB2(SCH_1):GND
 N66    GND VSS<1039> @BASEBOARD_FAB2_LIB.BASEBOARD_FAB2(SCH_1):GND
 N70    GND VSS<1038> @BASEBOARD_FAB2_LIB.BASEBOARD_FAB2(SCH_1):GND
 N72    GND VSS<1037> @BASEBOARD_FAB2_LIB.BASEBOARD_FAB2(SCH_1):GND
 N74    GND VSS<1036> @BASEBOARD_FAB2_LIB.BASEBOARD_FAB2(SCH_1):GND
 N76    GND VSS<1035> @BASEBOARD_FAB2_LIB.BASEBOARD_FAB2(SCH_1):GND
 N78    GND VSS<1034> @BASEBOARD_FAB2_LIB.BASEBOARD_FAB2(SCH_1):GND
  N4    GND VSS<1033> @BASEBOARD_FAB2_LIB.BASEBOARD_FAB2(SCH_1):GND
  N8    GND VSS<1032> @BASEBOARD_FAB2_LIB.BASEBOARD_FAB2(SCH_1):GND
 P11    GND VSS<1031> @BASEBOARD_FAB2_LIB.BASEBOARD_FAB2(SCH_1):GND
 P15    GND VSS<1030> @BASEBOARD_FAB2_LIB.BASEBOARD_FAB2(SCH_1):GND
 P27    GND VSS<1029> @BASEBOARD_FAB2_LIB.BASEBOARD_FAB2(SCH_1):GND
 P33    GND VSS<1028> @BASEBOARD_FAB2_LIB.BASEBOARD_FAB2(SCH_1):GND
 P39    GND VSS<1027> @BASEBOARD_FAB2_LIB.BASEBOARD_FAB2(SCH_1):GND
 P67    GND VSS<1026> @BASEBOARD_FAB2_LIB.BASEBOARD_FAB2(SCH_1):GND
 P69    GND VSS<1025> @BASEBOARD_FAB2_LIB.BASEBOARD_FAB2(SCH_1):GND
 P71    GND VSS<1024> @BASEBOARD_FAB2_LIB.BASEBOARD_FAB2(SCH_1):GND
 P81    GND VSS<1023> @BASEBOARD_FAB2_LIB.BASEBOARD_FAB2(SCH_1):GND
 P83    GND VSS<1022> @BASEBOARD_FAB2_LIB.BASEBOARD_FAB2(SCH_1):GND
 R14    GND VSS<1021> @BASEBOARD_FAB2_LIB.BASEBOARD_FAB2(SCH_1):GND
 R18    GND VSS<1020> @BASEBOARD_FAB2_LIB.BASEBOARD_FAB2(SCH_1):GND
  R2    GND VSS<1019> @BASEBOARD_FAB2_LIB.BASEBOARD_FAB2(SCH_1):GND
  R4    GND VSS<1018> @BASEBOARD_FAB2_LIB.BASEBOARD_FAB2(SCH_1):GND
 R22    GND VSS<1017> @BASEBOARD_FAB2_LIB.BASEBOARD_FAB2(SCH_1):GND
 R26    GND VSS<1016> @BASEBOARD_FAB2_LIB.BASEBOARD_FAB2(SCH_1):GND
 R28    GND VSS<1015> @BASEBOARD_FAB2_LIB.BASEBOARD_FAB2(SCH_1):GND
 R32    GND VSS<1014> @BASEBOARD_FAB2_LIB.BASEBOARD_FAB2(SCH_1):GND
 R34    GND VSS<1013> @BASEBOARD_FAB2_LIB.BASEBOARD_FAB2(SCH_1):GND
 R38    GND VSS<1012> @BASEBOARD_FAB2_LIB.BASEBOARD_FAB2(SCH_1):GND
 R40    GND VSS<1011> @BASEBOARD_FAB2_LIB.BASEBOARD_FAB2(SCH_1):GND
 R68    GND VSS<1010> @BASEBOARD_FAB2_LIB.BASEBOARD_FAB2(SCH_1):GND
 R72    GND VSS<1009> @BASEBOARD_FAB2_LIB.BASEBOARD_FAB2(SCH_1):GND
 R78    GND VSS<1008> @BASEBOARD_FAB2_LIB.BASEBOARD_FAB2(SCH_1):GND
 R86    GND VSS<1007> @BASEBOARD_FAB2_LIB.BASEBOARD_FAB2(SCH_1):GND
 T13    GND VSS<1006> @BASEBOARD_FAB2_LIB.BASEBOARD_FAB2(SCH_1):GND
 T17    GND VSS<1005> @BASEBOARD_FAB2_LIB.BASEBOARD_FAB2(SCH_1):GND
 T25    GND VSS<1004> @BASEBOARD_FAB2_LIB.BASEBOARD_FAB2(SCH_1):GND
 T29    GND VSS<1003> @BASEBOARD_FAB2_LIB.BASEBOARD_FAB2(SCH_1):GND
 T31    GND VSS<1002> @BASEBOARD_FAB2_LIB.BASEBOARD_FAB2(SCH_1):GND
 T35    GND VSS<1001> @BASEBOARD_FAB2_LIB.BASEBOARD_FAB2(SCH_1):GND
 T37    GND VSS<1000> @BASEBOARD_FAB2_LIB.BASEBOARD_FAB2(SCH_1):GND
 T41    GND VSS<999> @BASEBOARD_FAB2_LIB.BASEBOARD_FAB2(SCH_1):GND
 T65    GND VSS<998> @BASEBOARD_FAB2_LIB.BASEBOARD_FAB2(SCH_1):GND
 T73    GND VSS<997> @BASEBOARD_FAB2_LIB.BASEBOARD_FAB2(SCH_1):GND
 T77    GND VSS<996> @BASEBOARD_FAB2_LIB.BASEBOARD_FAB2(SCH_1):GND
 T83    GND VSS<995> @BASEBOARD_FAB2_LIB.BASEBOARD_FAB2(SCH_1):GND
 T85    GND VSS<994> @BASEBOARD_FAB2_LIB.BASEBOARD_FAB2(SCH_1):GND
  U2    GND VSS<993> @BASEBOARD_FAB2_LIB.BASEBOARD_FAB2(SCH_1):GND
  U4    GND VSS<992> @BASEBOARD_FAB2_LIB.BASEBOARD_FAB2(SCH_1):GND
  U6    GND VSS<991> @BASEBOARD_FAB2_LIB.BASEBOARD_FAB2(SCH_1):GND
 U20    GND VSS<990> @BASEBOARD_FAB2_LIB.BASEBOARD_FAB2(SCH_1):GND
 U22    GND VSS<989> @BASEBOARD_FAB2_LIB.BASEBOARD_FAB2(SCH_1):GND
 U24    GND VSS<988> @BASEBOARD_FAB2_LIB.BASEBOARD_FAB2(SCH_1):GND
 U30    GND VSS<987> @BASEBOARD_FAB2_LIB.BASEBOARD_FAB2(SCH_1):GND
 U36    GND VSS<986> @BASEBOARD_FAB2_LIB.BASEBOARD_FAB2(SCH_1):GND
 U42    GND VSS<985> @BASEBOARD_FAB2_LIB.BASEBOARD_FAB2(SCH_1):GND
 U68    GND VSS<984> @BASEBOARD_FAB2_LIB.BASEBOARD_FAB2(SCH_1):GND
 U70    GND VSS<983> @BASEBOARD_FAB2_LIB.BASEBOARD_FAB2(SCH_1):GND
 U74    GND VSS<982> @BASEBOARD_FAB2_LIB.BASEBOARD_FAB2(SCH_1):GND
 U76    GND VSS<981> @BASEBOARD_FAB2_LIB.BASEBOARD_FAB2(SCH_1):GND
 U78    GND VSS<980> @BASEBOARD_FAB2_LIB.BASEBOARD_FAB2(SCH_1):GND
 U80    GND VSS<979> @BASEBOARD_FAB2_LIB.BASEBOARD_FAB2(SCH_1):GND
 U86    GND VSS<978> @BASEBOARD_FAB2_LIB.BASEBOARD_FAB2(SCH_1):GND
  V1    GND VSS<977> @BASEBOARD_FAB2_LIB.BASEBOARD_FAB2(SCH_1):GND
  V5    GND VSS<976> @BASEBOARD_FAB2_LIB.BASEBOARD_FAB2(SCH_1):GND
  V9    GND VSS<975> @BASEBOARD_FAB2_LIB.BASEBOARD_FAB2(SCH_1):GND
 V13    GND VSS<974> @BASEBOARD_FAB2_LIB.BASEBOARD_FAB2(SCH_1):GND
 V15    GND VSS<973> @BASEBOARD_FAB2_LIB.BASEBOARD_FAB2(SCH_1):GND
 V21    GND VSS<972> @BASEBOARD_FAB2_LIB.BASEBOARD_FAB2(SCH_1):GND
 V23    GND VSS<971> @BASEBOARD_FAB2_LIB.BASEBOARD_FAB2(SCH_1):GND
 V43    GND VSS<970> @BASEBOARD_FAB2_LIB.BASEBOARD_FAB2(SCH_1):GND
 V73    GND VSS<969> @BASEBOARD_FAB2_LIB.BASEBOARD_FAB2(SCH_1):GND
 V75    GND VSS<968> @BASEBOARD_FAB2_LIB.BASEBOARD_FAB2(SCH_1):GND
 V77    GND VSS<967> @BASEBOARD_FAB2_LIB.BASEBOARD_FAB2(SCH_1):GND
 V83    GND VSS<966> @BASEBOARD_FAB2_LIB.BASEBOARD_FAB2(SCH_1):GND
  W8    GND VSS<965> @BASEBOARD_FAB2_LIB.BASEBOARD_FAB2(SCH_1):GND
AC56    GND VSS<964> @BASEBOARD_FAB2_LIB.BASEBOARD_FAB2(SCH_1):GND
 W12    GND VSS<963> @BASEBOARD_FAB2_LIB.BASEBOARD_FAB2(SCH_1):GND
 W22    GND VSS<962> @BASEBOARD_FAB2_LIB.BASEBOARD_FAB2(SCH_1):GND
 W24    GND VSS<961> @BASEBOARD_FAB2_LIB.BASEBOARD_FAB2(SCH_1):GND
 W26    GND VSS<960> @BASEBOARD_FAB2_LIB.BASEBOARD_FAB2(SCH_1):GND
 W28    GND VSS<959> @BASEBOARD_FAB2_LIB.BASEBOARD_FAB2(SCH_1):GND
 W30    GND VSS<958> @BASEBOARD_FAB2_LIB.BASEBOARD_FAB2(SCH_1):GND
 W32    GND VSS<957> @BASEBOARD_FAB2_LIB.BASEBOARD_FAB2(SCH_1):GND
 W34    GND VSS<956> @BASEBOARD_FAB2_LIB.BASEBOARD_FAB2(SCH_1):GND
 W36    GND VSS<955> @BASEBOARD_FAB2_LIB.BASEBOARD_FAB2(SCH_1):GND
 W38    GND VSS<954> @BASEBOARD_FAB2_LIB.BASEBOARD_FAB2(SCH_1):GND
 W40    GND VSS<953> @BASEBOARD_FAB2_LIB.BASEBOARD_FAB2(SCH_1):GND
 W42    GND VSS<952> @BASEBOARD_FAB2_LIB.BASEBOARD_FAB2(SCH_1):GND
 W68    GND VSS<951> @BASEBOARD_FAB2_LIB.BASEBOARD_FAB2(SCH_1):GND
 W74    GND VSS<950> @BASEBOARD_FAB2_LIB.BASEBOARD_FAB2(SCH_1):GND
 W78    GND VSS<949> @BASEBOARD_FAB2_LIB.BASEBOARD_FAB2(SCH_1):GND
 W82    GND VSS<948> @BASEBOARD_FAB2_LIB.BASEBOARD_FAB2(SCH_1):GND
 Y15    GND VSS<947> @BASEBOARD_FAB2_LIB.BASEBOARD_FAB2(SCH_1):GND
 Y17    GND VSS<946> @BASEBOARD_FAB2_LIB.BASEBOARD_FAB2(SCH_1):GND
  Y5    GND VSS<945> @BASEBOARD_FAB2_LIB.BASEBOARD_FAB2(SCH_1):GND
 Y67    GND VSS<944> @BASEBOARD_FAB2_LIB.BASEBOARD_FAB2(SCH_1):GND
  Y7    GND VSS<943> @BASEBOARD_FAB2_LIB.BASEBOARD_FAB2(SCH_1):GND
  Y9    GND VSS<942> @BASEBOARD_FAB2_LIB.BASEBOARD_FAB2(SCH_1):GND
 Y71    GND VSS<941> @BASEBOARD_FAB2_LIB.BASEBOARD_FAB2(SCH_1):GND
 Y73    GND VSS<940> @BASEBOARD_FAB2_LIB.BASEBOARD_FAB2(SCH_1):GND
 Y79    GND VSS<939> @BASEBOARD_FAB2_LIB.BASEBOARD_FAB2(SCH_1):GND
 Y81    GND VSS<938> @BASEBOARD_FAB2_LIB.BASEBOARD_FAB2(SCH_1):GND
 Y83    GND VSS<937> @BASEBOARD_FAB2_LIB.BASEBOARD_FAB2(SCH_1):GND
 Y85    GND VSS<936> @BASEBOARD_FAB2_LIB.BASEBOARD_FAB2(SCH_1):GND
 AA4    GND VSS<935> @BASEBOARD_FAB2_LIB.BASEBOARD_FAB2(SCH_1):GND
AA16    GND VSS<934> @BASEBOARD_FAB2_LIB.BASEBOARD_FAB2(SCH_1):GND

SKX_EXT_B_BGA1-IC,TBD  I22  U2D1
AA18    GND VSS<933> @BASEBOARD_FAB2_LIB.BASEBOARD_FAB2(SCH_1):GND
AA22    GND VSS<932> @BASEBOARD_FAB2_LIB.BASEBOARD_FAB2(SCH_1):GND
AA24    GND VSS<931> @BASEBOARD_FAB2_LIB.BASEBOARD_FAB2(SCH_1):GND
AA30    GND VSS<930> @BASEBOARD_FAB2_LIB.BASEBOARD_FAB2(SCH_1):GND
AA36    GND VSS<929> @BASEBOARD_FAB2_LIB.BASEBOARD_FAB2(SCH_1):GND
AA42    GND VSS<928> @BASEBOARD_FAB2_LIB.BASEBOARD_FAB2(SCH_1):GND
AA64    GND VSS<927> @BASEBOARD_FAB2_LIB.BASEBOARD_FAB2(SCH_1):GND
AA66    GND VSS<926> @BASEBOARD_FAB2_LIB.BASEBOARD_FAB2(SCH_1):GND
AA68    GND VSS<925> @BASEBOARD_FAB2_LIB.BASEBOARD_FAB2(SCH_1):GND
AA76    GND VSS<924> @BASEBOARD_FAB2_LIB.BASEBOARD_FAB2(SCH_1):GND
AA78    GND VSS<923> @BASEBOARD_FAB2_LIB.BASEBOARD_FAB2(SCH_1):GND
AA80    GND VSS<922> @BASEBOARD_FAB2_LIB.BASEBOARD_FAB2(SCH_1):GND
AA82    GND VSS<921> @BASEBOARD_FAB2_LIB.BASEBOARD_FAB2(SCH_1):GND
 AB1    GND VSS<920> @BASEBOARD_FAB2_LIB.BASEBOARD_FAB2(SCH_1):GND
 AB5    GND VSS<919> @BASEBOARD_FAB2_LIB.BASEBOARD_FAB2(SCH_1):GND
AB11    GND VSS<918> @BASEBOARD_FAB2_LIB.BASEBOARD_FAB2(SCH_1):GND
AB21    GND VSS<917> @BASEBOARD_FAB2_LIB.BASEBOARD_FAB2(SCH_1):GND
AB23    GND VSS<916> @BASEBOARD_FAB2_LIB.BASEBOARD_FAB2(SCH_1):GND
AB25    GND VSS<915> @BASEBOARD_FAB2_LIB.BASEBOARD_FAB2(SCH_1):GND
AB29    GND VSS<914> @BASEBOARD_FAB2_LIB.BASEBOARD_FAB2(SCH_1):GND
AB31    GND VSS<913> @BASEBOARD_FAB2_LIB.BASEBOARD_FAB2(SCH_1):GND
AB35    GND VSS<912> @BASEBOARD_FAB2_LIB.BASEBOARD_FAB2(SCH_1):GND
AB37    GND VSS<911> @BASEBOARD_FAB2_LIB.BASEBOARD_FAB2(SCH_1):GND
AB41    GND VSS<910> @BASEBOARD_FAB2_LIB.BASEBOARD_FAB2(SCH_1):GND
AB65    GND VSS<909> @BASEBOARD_FAB2_LIB.BASEBOARD_FAB2(SCH_1):GND
AB69    GND VSS<908> @BASEBOARD_FAB2_LIB.BASEBOARD_FAB2(SCH_1):GND
AB73    GND VSS<907> @BASEBOARD_FAB2_LIB.BASEBOARD_FAB2(SCH_1):GND
AB79    GND VSS<906> @BASEBOARD_FAB2_LIB.BASEBOARD_FAB2(SCH_1):GND
AB83    GND VSS<905> @BASEBOARD_FAB2_LIB.BASEBOARD_FAB2(SCH_1):GND
AB85    GND VSS<904> @BASEBOARD_FAB2_LIB.BASEBOARD_FAB2(SCH_1):GND
AC18    GND VSS<903> @BASEBOARD_FAB2_LIB.BASEBOARD_FAB2(SCH_1):GND
AC22    GND VSS<902> @BASEBOARD_FAB2_LIB.BASEBOARD_FAB2(SCH_1):GND
AC26    GND VSS<901> @BASEBOARD_FAB2_LIB.BASEBOARD_FAB2(SCH_1):GND
AC28    GND VSS<900> @BASEBOARD_FAB2_LIB.BASEBOARD_FAB2(SCH_1):GND
AC32    GND VSS<899> @BASEBOARD_FAB2_LIB.BASEBOARD_FAB2(SCH_1):GND
AC34    GND VSS<898> @BASEBOARD_FAB2_LIB.BASEBOARD_FAB2(SCH_1):GND
AC38    GND VSS<897> @BASEBOARD_FAB2_LIB.BASEBOARD_FAB2(SCH_1):GND
AC40    GND VSS<896> @BASEBOARD_FAB2_LIB.BASEBOARD_FAB2(SCH_1):GND
AC64    GND VSS<895> @BASEBOARD_FAB2_LIB.BASEBOARD_FAB2(SCH_1):GND
AC70    GND VSS<894> @BASEBOARD_FAB2_LIB.BASEBOARD_FAB2(SCH_1):GND
AC72    GND VSS<893> @BASEBOARD_FAB2_LIB.BASEBOARD_FAB2(SCH_1):GND
AC78    GND VSS<892> @BASEBOARD_FAB2_LIB.BASEBOARD_FAB2(SCH_1):GND
AC84    GND VSS<891> @BASEBOARD_FAB2_LIB.BASEBOARD_FAB2(SCH_1):GND
AC86    GND VSS<890> @BASEBOARD_FAB2_LIB.BASEBOARD_FAB2(SCH_1):GND
 AD3    GND VSS<889> @BASEBOARD_FAB2_LIB.BASEBOARD_FAB2(SCH_1):GND
 AD7    GND VSS<888> @BASEBOARD_FAB2_LIB.BASEBOARD_FAB2(SCH_1):GND
 AD9    GND VSS<887> @BASEBOARD_FAB2_LIB.BASEBOARD_FAB2(SCH_1):GND
AD11    GND VSS<886> @BASEBOARD_FAB2_LIB.BASEBOARD_FAB2(SCH_1):GND
AD13    GND VSS<885> @BASEBOARD_FAB2_LIB.BASEBOARD_FAB2(SCH_1):GND
AD15    GND VSS<884> @BASEBOARD_FAB2_LIB.BASEBOARD_FAB2(SCH_1):GND
AD19    GND VSS<883> @BASEBOARD_FAB2_LIB.BASEBOARD_FAB2(SCH_1):GND
AD21    GND VSS<882> @BASEBOARD_FAB2_LIB.BASEBOARD_FAB2(SCH_1):GND
AD27    GND VSS<881> @BASEBOARD_FAB2_LIB.BASEBOARD_FAB2(SCH_1):GND
AD33    GND VSS<880> @BASEBOARD_FAB2_LIB.BASEBOARD_FAB2(SCH_1):GND
AD39    GND VSS<879> @BASEBOARD_FAB2_LIB.BASEBOARD_FAB2(SCH_1):GND
AD43    GND VSS<878> @BASEBOARD_FAB2_LIB.BASEBOARD_FAB2(SCH_1):GND
AD71    GND VSS<877> @BASEBOARD_FAB2_LIB.BASEBOARD_FAB2(SCH_1):GND
AD73    GND VSS<876> @BASEBOARD_FAB2_LIB.BASEBOARD_FAB2(SCH_1):GND
AD75    GND VSS<875> @BASEBOARD_FAB2_LIB.BASEBOARD_FAB2(SCH_1):GND
AD81    GND VSS<874> @BASEBOARD_FAB2_LIB.BASEBOARD_FAB2(SCH_1):GND
AD83    GND VSS<873> @BASEBOARD_FAB2_LIB.BASEBOARD_FAB2(SCH_1):GND
AD85    GND VSS<872> @BASEBOARD_FAB2_LIB.BASEBOARD_FAB2(SCH_1):GND
 AE4    GND VSS<871> @BASEBOARD_FAB2_LIB.BASEBOARD_FAB2(SCH_1):GND
 AE8    GND VSS<870> @BASEBOARD_FAB2_LIB.BASEBOARD_FAB2(SCH_1):GND
AC54    GND VSS<869> @BASEBOARD_FAB2_LIB.BASEBOARD_FAB2(SCH_1):GND
AE16    GND VSS<868> @BASEBOARD_FAB2_LIB.BASEBOARD_FAB2(SCH_1):GND
AE38    GND VSS<867> @BASEBOARD_FAB2_LIB.BASEBOARD_FAB2(SCH_1):GND
AE40    GND VSS<866> @BASEBOARD_FAB2_LIB.BASEBOARD_FAB2(SCH_1):GND
AE42    GND VSS<865> @BASEBOARD_FAB2_LIB.BASEBOARD_FAB2(SCH_1):GND
AE64    GND VSS<864> @BASEBOARD_FAB2_LIB.BASEBOARD_FAB2(SCH_1):GND
AE66    GND VSS<863> @BASEBOARD_FAB2_LIB.BASEBOARD_FAB2(SCH_1):GND
AE68    GND VSS<862> @BASEBOARD_FAB2_LIB.BASEBOARD_FAB2(SCH_1):GND
AE70    GND VSS<861> @BASEBOARD_FAB2_LIB.BASEBOARD_FAB2(SCH_1):GND
AE78    GND VSS<860> @BASEBOARD_FAB2_LIB.BASEBOARD_FAB2(SCH_1):GND
 AF1    GND VSS<859> @BASEBOARD_FAB2_LIB.BASEBOARD_FAB2(SCH_1):GND
AC52    GND VSS<858> @BASEBOARD_FAB2_LIB.BASEBOARD_FAB2(SCH_1):GND
 AF9    GND VSS<857> @BASEBOARD_FAB2_LIB.BASEBOARD_FAB2(SCH_1):GND
AF21    GND VSS<856> @BASEBOARD_FAB2_LIB.BASEBOARD_FAB2(SCH_1):GND
AF23    GND VSS<855> @BASEBOARD_FAB2_LIB.BASEBOARD_FAB2(SCH_1):GND
AF25    GND VSS<854> @BASEBOARD_FAB2_LIB.BASEBOARD_FAB2(SCH_1):GND
AF27    GND VSS<853> @BASEBOARD_FAB2_LIB.BASEBOARD_FAB2(SCH_1):GND
AF29    GND VSS<852> @BASEBOARD_FAB2_LIB.BASEBOARD_FAB2(SCH_1):GND
AF31    GND VSS<851> @BASEBOARD_FAB2_LIB.BASEBOARD_FAB2(SCH_1):GND
AF33    GND VSS<850> @BASEBOARD_FAB2_LIB.BASEBOARD_FAB2(SCH_1):GND
AF37    GND VSS<849> @BASEBOARD_FAB2_LIB.BASEBOARD_FAB2(SCH_1):GND
AF39    GND VSS<848> @BASEBOARD_FAB2_LIB.BASEBOARD_FAB2(SCH_1):GND
AF41    GND VSS<847> @BASEBOARD_FAB2_LIB.BASEBOARD_FAB2(SCH_1):GND
AF73    GND VSS<846> @BASEBOARD_FAB2_LIB.BASEBOARD_FAB2(SCH_1):GND
AF77    GND VSS<845> @BASEBOARD_FAB2_LIB.BASEBOARD_FAB2(SCH_1):GND
AF83    GND VSS<844> @BASEBOARD_FAB2_LIB.BASEBOARD_FAB2(SCH_1):GND
AF85    GND VSS<843> @BASEBOARD_FAB2_LIB.BASEBOARD_FAB2(SCH_1):GND
AG12    GND VSS<842> @BASEBOARD_FAB2_LIB.BASEBOARD_FAB2(SCH_1):GND
AG14    GND VSS<841> @BASEBOARD_FAB2_LIB.BASEBOARD_FAB2(SCH_1):GND
AG18    GND VSS<840> @BASEBOARD_FAB2_LIB.BASEBOARD_FAB2(SCH_1):GND
AG36    GND VSS<839> @BASEBOARD_FAB2_LIB.BASEBOARD_FAB2(SCH_1):GND
AG64    GND VSS<838> @BASEBOARD_FAB2_LIB.BASEBOARD_FAB2(SCH_1):GND
AG70    GND VSS<837> @BASEBOARD_FAB2_LIB.BASEBOARD_FAB2(SCH_1):GND
AG74    GND VSS<836> @BASEBOARD_FAB2_LIB.BASEBOARD_FAB2(SCH_1):GND
AG76    GND VSS<835> @BASEBOARD_FAB2_LIB.BASEBOARD_FAB2(SCH_1):GND
AG78    GND VSS<834> @BASEBOARD_FAB2_LIB.BASEBOARD_FAB2(SCH_1):GND
AG80    GND VSS<833> @BASEBOARD_FAB2_LIB.BASEBOARD_FAB2(SCH_1):GND
 AH1    GND VSS<832> @BASEBOARD_FAB2_LIB.BASEBOARD_FAB2(SCH_1):GND
 AH5    GND VSS<831> @BASEBOARD_FAB2_LIB.BASEBOARD_FAB2(SCH_1):GND
AH21    GND VSS<830> @BASEBOARD_FAB2_LIB.BASEBOARD_FAB2(SCH_1):GND
AH27    GND VSS<829> @BASEBOARD_FAB2_LIB.BASEBOARD_FAB2(SCH_1):GND
AH33    GND VSS<828> @BASEBOARD_FAB2_LIB.BASEBOARD_FAB2(SCH_1):GND
AH35    GND VSS<827> @BASEBOARD_FAB2_LIB.BASEBOARD_FAB2(SCH_1):GND
AH45    GND VSS<826> @BASEBOARD_FAB2_LIB.BASEBOARD_FAB2(SCH_1):GND
AH47    GND VSS<825> @BASEBOARD_FAB2_LIB.BASEBOARD_FAB2(SCH_1):GND
AH49    GND VSS<824> @BASEBOARD_FAB2_LIB.BASEBOARD_FAB2(SCH_1):GND
AH51    GND VSS<823> @BASEBOARD_FAB2_LIB.BASEBOARD_FAB2(SCH_1):GND
AH53    GND VSS<822> @BASEBOARD_FAB2_LIB.BASEBOARD_FAB2(SCH_1):GND
AH59    GND VSS<821> @BASEBOARD_FAB2_LIB.BASEBOARD_FAB2(SCH_1):GND
AH61    GND VSS<820> @BASEBOARD_FAB2_LIB.BASEBOARD_FAB2(SCH_1):GND
AH65    GND VSS<819> @BASEBOARD_FAB2_LIB.BASEBOARD_FAB2(SCH_1):GND
AH69    GND VSS<818> @BASEBOARD_FAB2_LIB.BASEBOARD_FAB2(SCH_1):GND
AH75    GND VSS<817> @BASEBOARD_FAB2_LIB.BASEBOARD_FAB2(SCH_1):GND
AH77    GND VSS<816> @BASEBOARD_FAB2_LIB.BASEBOARD_FAB2(SCH_1):GND
AH83    GND VSS<815> @BASEBOARD_FAB2_LIB.BASEBOARD_FAB2(SCH_1):GND
 AJ8    GND VSS<814> @BASEBOARD_FAB2_LIB.BASEBOARD_FAB2(SCH_1):GND
AJ22    GND VSS<813> @BASEBOARD_FAB2_LIB.BASEBOARD_FAB2(SCH_1):GND
AJ26    GND VSS<812> @BASEBOARD_FAB2_LIB.BASEBOARD_FAB2(SCH_1):GND
AJ28    GND VSS<811> @BASEBOARD_FAB2_LIB.BASEBOARD_FAB2(SCH_1):GND
AJ32    GND VSS<810> @BASEBOARD_FAB2_LIB.BASEBOARD_FAB2(SCH_1):GND
AJ34    GND VSS<809> @BASEBOARD_FAB2_LIB.BASEBOARD_FAB2(SCH_1):GND
AJ46    GND VSS<808> @BASEBOARD_FAB2_LIB.BASEBOARD_FAB2(SCH_1):GND
AJ48    GND VSS<807> @BASEBOARD_FAB2_LIB.BASEBOARD_FAB2(SCH_1):GND
AJ50    GND VSS<806> @BASEBOARD_FAB2_LIB.BASEBOARD_FAB2(SCH_1):GND
AJ52    GND VSS<805> @BASEBOARD_FAB2_LIB.BASEBOARD_FAB2(SCH_1):GND
AJ54    GND VSS<804> @BASEBOARD_FAB2_LIB.BASEBOARD_FAB2(SCH_1):GND
AJ66    GND VSS<803> @BASEBOARD_FAB2_LIB.BASEBOARD_FAB2(SCH_1):GND
AJ68    GND VSS<802> @BASEBOARD_FAB2_LIB.BASEBOARD_FAB2(SCH_1):GND
AJ74    GND VSS<801> @BASEBOARD_FAB2_LIB.BASEBOARD_FAB2(SCH_1):GND
AJ78    GND VSS<800> @BASEBOARD_FAB2_LIB.BASEBOARD_FAB2(SCH_1):GND
AJ82    GND VSS<799> @BASEBOARD_FAB2_LIB.BASEBOARD_FAB2(SCH_1):GND
AJ86    GND VSS<798> @BASEBOARD_FAB2_LIB.BASEBOARD_FAB2(SCH_1):GND
 AK9    GND VSS<797> @BASEBOARD_FAB2_LIB.BASEBOARD_FAB2(SCH_1):GND
AK13    GND VSS<796> @BASEBOARD_FAB2_LIB.BASEBOARD_FAB2(SCH_1):GND
AK19    GND VSS<795> @BASEBOARD_FAB2_LIB.BASEBOARD_FAB2(SCH_1):GND
AK23    GND VSS<794> @BASEBOARD_FAB2_LIB.BASEBOARD_FAB2(SCH_1):GND
AK25    GND VSS<793> @BASEBOARD_FAB2_LIB.BASEBOARD_FAB2(SCH_1):GND
AK29    GND VSS<792> @BASEBOARD_FAB2_LIB.BASEBOARD_FAB2(SCH_1):GND
AK31    GND VSS<791> @BASEBOARD_FAB2_LIB.BASEBOARD_FAB2(SCH_1):GND
AK33    GND VSS<790> @BASEBOARD_FAB2_LIB.BASEBOARD_FAB2(SCH_1):GND
AK55    GND VSS<789> @BASEBOARD_FAB2_LIB.BASEBOARD_FAB2(SCH_1):GND
AK65    GND VSS<788> @BASEBOARD_FAB2_LIB.BASEBOARD_FAB2(SCH_1):GND
AK67    GND VSS<787> @BASEBOARD_FAB2_LIB.BASEBOARD_FAB2(SCH_1):GND
AK73    GND VSS<786> @BASEBOARD_FAB2_LIB.BASEBOARD_FAB2(SCH_1):GND
AK79    GND VSS<785> @BASEBOARD_FAB2_LIB.BASEBOARD_FAB2(SCH_1):GND
AK81    GND VSS<784> @BASEBOARD_FAB2_LIB.BASEBOARD_FAB2(SCH_1):GND
AK83    GND VSS<783> @BASEBOARD_FAB2_LIB.BASEBOARD_FAB2(SCH_1):GND
AK85    GND VSS<782> @BASEBOARD_FAB2_LIB.BASEBOARD_FAB2(SCH_1):GND
 AL4    GND VSS<781> @BASEBOARD_FAB2_LIB.BASEBOARD_FAB2(SCH_1):GND
AL10    GND VSS<780> @BASEBOARD_FAB2_LIB.BASEBOARD_FAB2(SCH_1):GND
AL24    GND VSS<779> @BASEBOARD_FAB2_LIB.BASEBOARD_FAB2(SCH_1):GND
AL30    GND VSS<778> @BASEBOARD_FAB2_LIB.BASEBOARD_FAB2(SCH_1):GND
AL32    GND VSS<777> @BASEBOARD_FAB2_LIB.BASEBOARD_FAB2(SCH_1):GND
AL56    GND VSS<776> @BASEBOARD_FAB2_LIB.BASEBOARD_FAB2(SCH_1):GND
AL64    GND VSS<775> @BASEBOARD_FAB2_LIB.BASEBOARD_FAB2(SCH_1):GND
AL68    GND VSS<774> @BASEBOARD_FAB2_LIB.BASEBOARD_FAB2(SCH_1):GND

SKX_EXT_B_BGA1-IC,TBD  I23  U2D1
AL76    GND VSS<773> @BASEBOARD_FAB2_LIB.BASEBOARD_FAB2(SCH_1):GND
AL78    GND VSS<772> @BASEBOARD_FAB2_LIB.BASEBOARD_FAB2(SCH_1):GND
AL80    GND VSS<771> @BASEBOARD_FAB2_LIB.BASEBOARD_FAB2(SCH_1):GND
AL82    GND VSS<770> @BASEBOARD_FAB2_LIB.BASEBOARD_FAB2(SCH_1):GND
AL86    GND VSS<769> @BASEBOARD_FAB2_LIB.BASEBOARD_FAB2(SCH_1):GND
 AM1    GND VSS<768> @BASEBOARD_FAB2_LIB.BASEBOARD_FAB2(SCH_1):GND
AC50    GND VSS<767> @BASEBOARD_FAB2_LIB.BASEBOARD_FAB2(SCH_1):GND
AM31    GND VSS<766> @BASEBOARD_FAB2_LIB.BASEBOARD_FAB2(SCH_1):GND
AM57    GND VSS<765> @BASEBOARD_FAB2_LIB.BASEBOARD_FAB2(SCH_1):GND
AM63    GND VSS<764> @BASEBOARD_FAB2_LIB.BASEBOARD_FAB2(SCH_1):GND
AM69    GND VSS<763> @BASEBOARD_FAB2_LIB.BASEBOARD_FAB2(SCH_1):GND
AM73    GND VSS<762> @BASEBOARD_FAB2_LIB.BASEBOARD_FAB2(SCH_1):GND
AM79    GND VSS<761> @BASEBOARD_FAB2_LIB.BASEBOARD_FAB2(SCH_1):GND
AM83    GND VSS<760> @BASEBOARD_FAB2_LIB.BASEBOARD_FAB2(SCH_1):GND
 AN2    GND VSS<759> @BASEBOARD_FAB2_LIB.BASEBOARD_FAB2(SCH_1):GND
 AN6    GND VSS<758> @BASEBOARD_FAB2_LIB.BASEBOARD_FAB2(SCH_1):GND
AN28    GND VSS<757> @BASEBOARD_FAB2_LIB.BASEBOARD_FAB2(SCH_1):GND
AN58    GND VSS<756> @BASEBOARD_FAB2_LIB.BASEBOARD_FAB2(SCH_1):GND
AN78    GND VSS<755> @BASEBOARD_FAB2_LIB.BASEBOARD_FAB2(SCH_1):GND
 AP5    GND VSS<754> @BASEBOARD_FAB2_LIB.BASEBOARD_FAB2(SCH_1):GND
 AP9    GND VSS<753> @BASEBOARD_FAB2_LIB.BASEBOARD_FAB2(SCH_1):GND
AP13    GND VSS<752> @BASEBOARD_FAB2_LIB.BASEBOARD_FAB2(SCH_1):GND
AP19    GND VSS<751> @BASEBOARD_FAB2_LIB.BASEBOARD_FAB2(SCH_1):GND
AP31    GND VSS<750> @BASEBOARD_FAB2_LIB.BASEBOARD_FAB2(SCH_1):GND
AP59    GND VSS<749> @BASEBOARD_FAB2_LIB.BASEBOARD_FAB2(SCH_1):GND
AP63    GND VSS<748> @BASEBOARD_FAB2_LIB.BASEBOARD_FAB2(SCH_1):GND
AP65    GND VSS<747> @BASEBOARD_FAB2_LIB.BASEBOARD_FAB2(SCH_1):GND
AP67    GND VSS<746> @BASEBOARD_FAB2_LIB.BASEBOARD_FAB2(SCH_1):GND
AP69    GND VSS<745> @BASEBOARD_FAB2_LIB.BASEBOARD_FAB2(SCH_1):GND
AP73    GND VSS<744> @BASEBOARD_FAB2_LIB.BASEBOARD_FAB2(SCH_1):GND
AP75    GND VSS<743> @BASEBOARD_FAB2_LIB.BASEBOARD_FAB2(SCH_1):GND
AP81    GND VSS<742> @BASEBOARD_FAB2_LIB.BASEBOARD_FAB2(SCH_1):GND
AP83    GND VSS<741> @BASEBOARD_FAB2_LIB.BASEBOARD_FAB2(SCH_1):GND
AP85    GND VSS<740> @BASEBOARD_FAB2_LIB.BASEBOARD_FAB2(SCH_1):GND
AR10    GND VSS<739> @BASEBOARD_FAB2_LIB.BASEBOARD_FAB2(SCH_1):GND
AR24    GND VSS<738> @BASEBOARD_FAB2_LIB.BASEBOARD_FAB2(SCH_1):GND
AR30    GND VSS<737> @BASEBOARD_FAB2_LIB.BASEBOARD_FAB2(SCH_1):GND
AR60    GND VSS<736> @BASEBOARD_FAB2_LIB.BASEBOARD_FAB2(SCH_1):GND
AR72    GND VSS<735> @BASEBOARD_FAB2_LIB.BASEBOARD_FAB2(SCH_1):GND
AR78    GND VSS<734> @BASEBOARD_FAB2_LIB.BASEBOARD_FAB2(SCH_1):GND
AC48    GND VSS<733> @BASEBOARD_FAB2_LIB.BASEBOARD_FAB2(SCH_1):GND
 P63    GND VSS<732> @BASEBOARD_FAB2_LIB.BASEBOARD_FAB2(SCH_1):GND
AT15    GND VSS<731> @BASEBOARD_FAB2_LIB.BASEBOARD_FAB2(SCH_1):GND
AT17    GND VSS<730> @BASEBOARD_FAB2_LIB.BASEBOARD_FAB2(SCH_1):GND
AT21    GND VSS<729> @BASEBOARD_FAB2_LIB.BASEBOARD_FAB2(SCH_1):GND
AT27    GND VSS<728> @BASEBOARD_FAB2_LIB.BASEBOARD_FAB2(SCH_1):GND
AT61    GND VSS<727> @BASEBOARD_FAB2_LIB.BASEBOARD_FAB2(SCH_1):GND
AT63    GND VSS<726> @BASEBOARD_FAB2_LIB.BASEBOARD_FAB2(SCH_1):GND
AT69    GND VSS<725> @BASEBOARD_FAB2_LIB.BASEBOARD_FAB2(SCH_1):GND
AT73    GND VSS<724> @BASEBOARD_FAB2_LIB.BASEBOARD_FAB2(SCH_1):GND
AT77    GND VSS<723> @BASEBOARD_FAB2_LIB.BASEBOARD_FAB2(SCH_1):GND
AT83    GND VSS<722> @BASEBOARD_FAB2_LIB.BASEBOARD_FAB2(SCH_1):GND
AT85    GND VSS<721> @BASEBOARD_FAB2_LIB.BASEBOARD_FAB2(SCH_1):GND
 AU2    GND VSS<720> @BASEBOARD_FAB2_LIB.BASEBOARD_FAB2(SCH_1):GND
 AU6    GND VSS<719> @BASEBOARD_FAB2_LIB.BASEBOARD_FAB2(SCH_1):GND
AU26    GND VSS<718> @BASEBOARD_FAB2_LIB.BASEBOARD_FAB2(SCH_1):GND
AU28    GND VSS<717> @BASEBOARD_FAB2_LIB.BASEBOARD_FAB2(SCH_1):GND
AU62    GND VSS<716> @BASEBOARD_FAB2_LIB.BASEBOARD_FAB2(SCH_1):GND
AU64    GND VSS<715> @BASEBOARD_FAB2_LIB.BASEBOARD_FAB2(SCH_1):GND
AU68    GND VSS<714> @BASEBOARD_FAB2_LIB.BASEBOARD_FAB2(SCH_1):GND
AU74    GND VSS<713> @BASEBOARD_FAB2_LIB.BASEBOARD_FAB2(SCH_1):GND
AU76    GND VSS<712> @BASEBOARD_FAB2_LIB.BASEBOARD_FAB2(SCH_1):GND
AU78    GND VSS<711> @BASEBOARD_FAB2_LIB.BASEBOARD_FAB2(SCH_1):GND
AU80    GND VSS<710> @BASEBOARD_FAB2_LIB.BASEBOARD_FAB2(SCH_1):GND
AU84    GND VSS<709> @BASEBOARD_FAB2_LIB.BASEBOARD_FAB2(SCH_1):GND
AU86    GND VSS<708> @BASEBOARD_FAB2_LIB.BASEBOARD_FAB2(SCH_1):GND
 AV1    GND VSS<707> @BASEBOARD_FAB2_LIB.BASEBOARD_FAB2(SCH_1):GND
 AV3    GND VSS<706> @BASEBOARD_FAB2_LIB.BASEBOARD_FAB2(SCH_1):GND
 AV7    GND VSS<705> @BASEBOARD_FAB2_LIB.BASEBOARD_FAB2(SCH_1):GND
AV11    GND VSS<704> @BASEBOARD_FAB2_LIB.BASEBOARD_FAB2(SCH_1):GND
AV13    GND VSS<703> @BASEBOARD_FAB2_LIB.BASEBOARD_FAB2(SCH_1):GND
AV19    GND VSS<702> @BASEBOARD_FAB2_LIB.BASEBOARD_FAB2(SCH_1):GND
AV23    GND VSS<701> @BASEBOARD_FAB2_LIB.BASEBOARD_FAB2(SCH_1):GND
AV25    GND VSS<700> @BASEBOARD_FAB2_LIB.BASEBOARD_FAB2(SCH_1):GND
AV63    GND VSS<699> @BASEBOARD_FAB2_LIB.BASEBOARD_FAB2(SCH_1):GND
AV65    GND VSS<698> @BASEBOARD_FAB2_LIB.BASEBOARD_FAB2(SCH_1):GND
AV67    GND VSS<697> @BASEBOARD_FAB2_LIB.BASEBOARD_FAB2(SCH_1):GND
AV75    GND VSS<696> @BASEBOARD_FAB2_LIB.BASEBOARD_FAB2(SCH_1):GND
AV83    GND VSS<695> @BASEBOARD_FAB2_LIB.BASEBOARD_FAB2(SCH_1):GND
 AW2    GND VSS<694> @BASEBOARD_FAB2_LIB.BASEBOARD_FAB2(SCH_1):GND
AW10    GND VSS<693> @BASEBOARD_FAB2_LIB.BASEBOARD_FAB2(SCH_1):GND
AW62    GND VSS<692> @BASEBOARD_FAB2_LIB.BASEBOARD_FAB2(SCH_1):GND
AW66    GND VSS<691> @BASEBOARD_FAB2_LIB.BASEBOARD_FAB2(SCH_1):GND
AW68    GND VSS<690> @BASEBOARD_FAB2_LIB.BASEBOARD_FAB2(SCH_1):GND
AW70    GND VSS<689> @BASEBOARD_FAB2_LIB.BASEBOARD_FAB2(SCH_1):GND
AW72    GND VSS<688> @BASEBOARD_FAB2_LIB.BASEBOARD_FAB2(SCH_1):GND
AW74    GND VSS<687> @BASEBOARD_FAB2_LIB.BASEBOARD_FAB2(SCH_1):GND
AW78    GND VSS<686> @BASEBOARD_FAB2_LIB.BASEBOARD_FAB2(SCH_1):GND
AW82    GND VSS<685> @BASEBOARD_FAB2_LIB.BASEBOARD_FAB2(SCH_1):GND
AW84    GND VSS<684> @BASEBOARD_FAB2_LIB.BASEBOARD_FAB2(SCH_1):GND
 AY5    GND VSS<683> @BASEBOARD_FAB2_LIB.BASEBOARD_FAB2(SCH_1):GND
AY15    GND VSS<682> @BASEBOARD_FAB2_LIB.BASEBOARD_FAB2(SCH_1):GND
AY17    GND VSS<681> @BASEBOARD_FAB2_LIB.BASEBOARD_FAB2(SCH_1):GND
AY21    GND VSS<680> @BASEBOARD_FAB2_LIB.BASEBOARD_FAB2(SCH_1):GND
AY23    GND VSS<679> @BASEBOARD_FAB2_LIB.BASEBOARD_FAB2(SCH_1):GND
AY25    GND VSS<678> @BASEBOARD_FAB2_LIB.BASEBOARD_FAB2(SCH_1):GND
AY63    GND VSS<677> @BASEBOARD_FAB2_LIB.BASEBOARD_FAB2(SCH_1):GND
AY79    GND VSS<676> @BASEBOARD_FAB2_LIB.BASEBOARD_FAB2(SCH_1):GND
AY81    GND VSS<675> @BASEBOARD_FAB2_LIB.BASEBOARD_FAB2(SCH_1):GND
 BA2    GND VSS<674> @BASEBOARD_FAB2_LIB.BASEBOARD_FAB2(SCH_1):GND
 BA6    GND VSS<673> @BASEBOARD_FAB2_LIB.BASEBOARD_FAB2(SCH_1):GND
BA12    GND VSS<672> @BASEBOARD_FAB2_LIB.BASEBOARD_FAB2(SCH_1):GND
BA62    GND VSS<671> @BASEBOARD_FAB2_LIB.BASEBOARD_FAB2(SCH_1):GND
BA68    GND VSS<670> @BASEBOARD_FAB2_LIB.BASEBOARD_FAB2(SCH_1):GND
BA74    GND VSS<669> @BASEBOARD_FAB2_LIB.BASEBOARD_FAB2(SCH_1):GND
BA80    GND VSS<668> @BASEBOARD_FAB2_LIB.BASEBOARD_FAB2(SCH_1):GND
BA84    GND VSS<667> @BASEBOARD_FAB2_LIB.BASEBOARD_FAB2(SCH_1):GND
BB19    GND VSS<666> @BASEBOARD_FAB2_LIB.BASEBOARD_FAB2(SCH_1):GND
BB23    GND VSS<665> @BASEBOARD_FAB2_LIB.BASEBOARD_FAB2(SCH_1):GND
BB63    GND VSS<664> @BASEBOARD_FAB2_LIB.BASEBOARD_FAB2(SCH_1):GND
BB69    GND VSS<663> @BASEBOARD_FAB2_LIB.BASEBOARD_FAB2(SCH_1):GND
BB73    GND VSS<662> @BASEBOARD_FAB2_LIB.BASEBOARD_FAB2(SCH_1):GND
BB75    GND VSS<661> @BASEBOARD_FAB2_LIB.BASEBOARD_FAB2(SCH_1):GND
BB77    GND VSS<660> @BASEBOARD_FAB2_LIB.BASEBOARD_FAB2(SCH_1):GND
BB79    GND VSS<659> @BASEBOARD_FAB2_LIB.BASEBOARD_FAB2(SCH_1):GND
BB81    GND VSS<658> @BASEBOARD_FAB2_LIB.BASEBOARD_FAB2(SCH_1):GND
BB83    GND VSS<657> @BASEBOARD_FAB2_LIB.BASEBOARD_FAB2(SCH_1):GND
 BC4    GND VSS<656> @BASEBOARD_FAB2_LIB.BASEBOARD_FAB2(SCH_1):GND
 BC8    GND VSS<655> @BASEBOARD_FAB2_LIB.BASEBOARD_FAB2(SCH_1):GND
BC12    GND VSS<654> @BASEBOARD_FAB2_LIB.BASEBOARD_FAB2(SCH_1):GND
BC16    GND VSS<653> @BASEBOARD_FAB2_LIB.BASEBOARD_FAB2(SCH_1):GND
BC70    GND VSS<652> @BASEBOARD_FAB2_LIB.BASEBOARD_FAB2(SCH_1):GND
BC72    GND VSS<651> @BASEBOARD_FAB2_LIB.BASEBOARD_FAB2(SCH_1):GND
BC74    GND VSS<650> @BASEBOARD_FAB2_LIB.BASEBOARD_FAB2(SCH_1):GND
BC76    GND VSS<649> @BASEBOARD_FAB2_LIB.BASEBOARD_FAB2(SCH_1):GND
BC78    GND VSS<648> @BASEBOARD_FAB2_LIB.BASEBOARD_FAB2(SCH_1):GND
BC80    GND VSS<647> @BASEBOARD_FAB2_LIB.BASEBOARD_FAB2(SCH_1):GND
BC82    GND VSS<646> @BASEBOARD_FAB2_LIB.BASEBOARD_FAB2(SCH_1):GND
 BD5    GND VSS<645> @BASEBOARD_FAB2_LIB.BASEBOARD_FAB2(SCH_1):GND
BD11    GND VSS<644> @BASEBOARD_FAB2_LIB.BASEBOARD_FAB2(SCH_1):GND
BD15    GND VSS<643> @BASEBOARD_FAB2_LIB.BASEBOARD_FAB2(SCH_1):GND
BD21    GND VSS<642> @BASEBOARD_FAB2_LIB.BASEBOARD_FAB2(SCH_1):GND
BD27    GND VSS<641> @BASEBOARD_FAB2_LIB.BASEBOARD_FAB2(SCH_1):GND
BD63    GND VSS<640> @BASEBOARD_FAB2_LIB.BASEBOARD_FAB2(SCH_1):GND
BD71    GND VSS<639> @BASEBOARD_FAB2_LIB.BASEBOARD_FAB2(SCH_1):GND
 BE4    GND VSS<638> @BASEBOARD_FAB2_LIB.BASEBOARD_FAB2(SCH_1):GND
 BE6    GND VSS<637> @BASEBOARD_FAB2_LIB.BASEBOARD_FAB2(SCH_1):GND
 BE8    GND VSS<636> @BASEBOARD_FAB2_LIB.BASEBOARD_FAB2(SCH_1):GND
BE10    GND VSS<635> @BASEBOARD_FAB2_LIB.BASEBOARD_FAB2(SCH_1):GND
BE26    GND VSS<634> @BASEBOARD_FAB2_LIB.BASEBOARD_FAB2(SCH_1):GND
BE64    GND VSS<633> @BASEBOARD_FAB2_LIB.BASEBOARD_FAB2(SCH_1):GND
BE66    GND VSS<632> @BASEBOARD_FAB2_LIB.BASEBOARD_FAB2(SCH_1):GND
BE68    GND VSS<631> @BASEBOARD_FAB2_LIB.BASEBOARD_FAB2(SCH_1):GND
BE70    GND VSS<630> @BASEBOARD_FAB2_LIB.BASEBOARD_FAB2(SCH_1):GND
 BF9    GND VSS<629> @BASEBOARD_FAB2_LIB.BASEBOARD_FAB2(SCH_1):GND
BF15    GND VSS<628> @BASEBOARD_FAB2_LIB.BASEBOARD_FAB2(SCH_1):GND
BF17    GND VSS<627> @BASEBOARD_FAB2_LIB.BASEBOARD_FAB2(SCH_1):GND
BF19    GND VSS<626> @BASEBOARD_FAB2_LIB.BASEBOARD_FAB2(SCH_1):GND
BF25    GND VSS<625> @BASEBOARD_FAB2_LIB.BASEBOARD_FAB2(SCH_1):GND
BF63    GND VSS<624> @BASEBOARD_FAB2_LIB.BASEBOARD_FAB2(SCH_1):GND
BF65    GND VSS<623> @BASEBOARD_FAB2_LIB.BASEBOARD_FAB2(SCH_1):GND
BF67    GND VSS<622> @BASEBOARD_FAB2_LIB.BASEBOARD_FAB2(SCH_1):GND
BF69    GND VSS<621> @BASEBOARD_FAB2_LIB.BASEBOARD_FAB2(SCH_1):GND
BF71    GND VSS<620> @BASEBOARD_FAB2_LIB.BASEBOARD_FAB2(SCH_1):GND
 BG6    GND VSS<619> @BASEBOARD_FAB2_LIB.BASEBOARD_FAB2(SCH_1):GND
 BG8    GND VSS<618> @BASEBOARD_FAB2_LIB.BASEBOARD_FAB2(SCH_1):GND
BG10    GND VSS<617> @BASEBOARD_FAB2_LIB.BASEBOARD_FAB2(SCH_1):GND
BG22    GND VSS<616> @BASEBOARD_FAB2_LIB.BASEBOARD_FAB2(SCH_1):GND
BG24    GND VSS<615> @BASEBOARD_FAB2_LIB.BASEBOARD_FAB2(SCH_1):GND
BG72    GND VSS<614> @BASEBOARD_FAB2_LIB.BASEBOARD_FAB2(SCH_1):GND


DRAWING: @BASEBOARD_FAB2_LIB.BASEBOARD_FAB2(SCH_1):PAGE75 

SKX_EXT_B_BGA1-IC,TBD  I17  U2D1
BG74    GND VSS<613> @BASEBOARD_FAB2_LIB.BASEBOARD_FAB2(SCH_1):GND
BG76    GND VSS<612> @BASEBOARD_FAB2_LIB.BASEBOARD_FAB2(SCH_1):GND
BG78    GND VSS<611> @BASEBOARD_FAB2_LIB.BASEBOARD_FAB2(SCH_1):GND
BG80    GND VSS<610> @BASEBOARD_FAB2_LIB.BASEBOARD_FAB2(SCH_1):GND
BG82    GND VSS<609> @BASEBOARD_FAB2_LIB.BASEBOARD_FAB2(SCH_1):GND
 BH7    GND VSS<608> @BASEBOARD_FAB2_LIB.BASEBOARD_FAB2(SCH_1):GND
 BH9    GND VSS<607> @BASEBOARD_FAB2_LIB.BASEBOARD_FAB2(SCH_1):GND
BH11    GND VSS<606> @BASEBOARD_FAB2_LIB.BASEBOARD_FAB2(SCH_1):GND
BH15    GND VSS<605> @BASEBOARD_FAB2_LIB.BASEBOARD_FAB2(SCH_1):GND
BH21    GND VSS<604> @BASEBOARD_FAB2_LIB.BASEBOARD_FAB2(SCH_1):GND
 BJ4    GND VSS<603> @BASEBOARD_FAB2_LIB.BASEBOARD_FAB2(SCH_1):GND
 BJ6    GND VSS<602> @BASEBOARD_FAB2_LIB.BASEBOARD_FAB2(SCH_1):GND
 BK3    GND VSS<601> @BASEBOARD_FAB2_LIB.BASEBOARD_FAB2(SCH_1):GND
 BK7    GND VSS<600> @BASEBOARD_FAB2_LIB.BASEBOARD_FAB2(SCH_1):GND
BK11    GND VSS<599> @BASEBOARD_FAB2_LIB.BASEBOARD_FAB2(SCH_1):GND
BK19    GND VSS<598> @BASEBOARD_FAB2_LIB.BASEBOARD_FAB2(SCH_1):GND
 BL6    GND VSS<597> @BASEBOARD_FAB2_LIB.BASEBOARD_FAB2(SCH_1):GND
BL10    GND VSS<596> @BASEBOARD_FAB2_LIB.BASEBOARD_FAB2(SCH_1):GND
BL12    GND VSS<595> @BASEBOARD_FAB2_LIB.BASEBOARD_FAB2(SCH_1):GND
 P61    GND VSS<594> @BASEBOARD_FAB2_LIB.BASEBOARD_FAB2(SCH_1):GND
BL22    GND VSS<593> @BASEBOARD_FAB2_LIB.BASEBOARD_FAB2(SCH_1):GND
BL24    GND VSS<592> @BASEBOARD_FAB2_LIB.BASEBOARD_FAB2(SCH_1):GND
BL64    GND VSS<591> @BASEBOARD_FAB2_LIB.BASEBOARD_FAB2(SCH_1):GND
BL66    GND VSS<590> @BASEBOARD_FAB2_LIB.BASEBOARD_FAB2(SCH_1):GND
BL68    GND VSS<589> @BASEBOARD_FAB2_LIB.BASEBOARD_FAB2(SCH_1):GND
BL70    GND VSS<588> @BASEBOARD_FAB2_LIB.BASEBOARD_FAB2(SCH_1):GND
BL72    GND VSS<587> @BASEBOARD_FAB2_LIB.BASEBOARD_FAB2(SCH_1):GND
BL74    GND VSS<586> @BASEBOARD_FAB2_LIB.BASEBOARD_FAB2(SCH_1):GND
BL76    GND VSS<585> @BASEBOARD_FAB2_LIB.BASEBOARD_FAB2(SCH_1):GND
BL78    GND VSS<584> @BASEBOARD_FAB2_LIB.BASEBOARD_FAB2(SCH_1):GND
BL80    GND VSS<583> @BASEBOARD_FAB2_LIB.BASEBOARD_FAB2(SCH_1):GND
BL82    GND VSS<582> @BASEBOARD_FAB2_LIB.BASEBOARD_FAB2(SCH_1):GND
 BM9    GND VSS<581> @BASEBOARD_FAB2_LIB.BASEBOARD_FAB2(SCH_1):GND
BM13    GND VSS<580> @BASEBOARD_FAB2_LIB.BASEBOARD_FAB2(SCH_1):GND
BM15    GND VSS<579> @BASEBOARD_FAB2_LIB.BASEBOARD_FAB2(SCH_1):GND
 P59    GND VSS<578> @BASEBOARD_FAB2_LIB.BASEBOARD_FAB2(SCH_1):GND
BM25    GND VSS<577> @BASEBOARD_FAB2_LIB.BASEBOARD_FAB2(SCH_1):GND
 BN6    GND VSS<576> @BASEBOARD_FAB2_LIB.BASEBOARD_FAB2(SCH_1):GND
BN10    GND VSS<575> @BASEBOARD_FAB2_LIB.BASEBOARD_FAB2(SCH_1):GND
BN20    GND VSS<574> @BASEBOARD_FAB2_LIB.BASEBOARD_FAB2(SCH_1):GND
BN26    GND VSS<573> @BASEBOARD_FAB2_LIB.BASEBOARD_FAB2(SCH_1):GND
 BP3    GND VSS<572> @BASEBOARD_FAB2_LIB.BASEBOARD_FAB2(SCH_1):GND
BP27    GND VSS<571> @BASEBOARD_FAB2_LIB.BASEBOARD_FAB2(SCH_1):GND
 BR6    GND VSS<570> @BASEBOARD_FAB2_LIB.BASEBOARD_FAB2(SCH_1):GND
BR10    GND VSS<569> @BASEBOARD_FAB2_LIB.BASEBOARD_FAB2(SCH_1):GND
BR16    GND VSS<568> @BASEBOARD_FAB2_LIB.BASEBOARD_FAB2(SCH_1):GND
 P57    GND VSS<567> @BASEBOARD_FAB2_LIB.BASEBOARD_FAB2(SCH_1):GND
BR64    GND VSS<566> @BASEBOARD_FAB2_LIB.BASEBOARD_FAB2(SCH_1):GND
BR66    GND VSS<565> @BASEBOARD_FAB2_LIB.BASEBOARD_FAB2(SCH_1):GND
BR68    GND VSS<564> @BASEBOARD_FAB2_LIB.BASEBOARD_FAB2(SCH_1):GND
BR70    GND VSS<563> @BASEBOARD_FAB2_LIB.BASEBOARD_FAB2(SCH_1):GND
BR72    GND VSS<562> @BASEBOARD_FAB2_LIB.BASEBOARD_FAB2(SCH_1):GND
BR74    GND VSS<561> @BASEBOARD_FAB2_LIB.BASEBOARD_FAB2(SCH_1):GND
BR76    GND VSS<560> @BASEBOARD_FAB2_LIB.BASEBOARD_FAB2(SCH_1):GND
BR78    GND VSS<559> @BASEBOARD_FAB2_LIB.BASEBOARD_FAB2(SCH_1):GND
BR80    GND VSS<558> @BASEBOARD_FAB2_LIB.BASEBOARD_FAB2(SCH_1):GND
BR82    GND VSS<557> @BASEBOARD_FAB2_LIB.BASEBOARD_FAB2(SCH_1):GND
 BT3    GND VSS<556> @BASEBOARD_FAB2_LIB.BASEBOARD_FAB2(SCH_1):GND
 BT5    GND VSS<555> @BASEBOARD_FAB2_LIB.BASEBOARD_FAB2(SCH_1):GND
BT21    GND VSS<554> @BASEBOARD_FAB2_LIB.BASEBOARD_FAB2(SCH_1):GND
BT23    GND VSS<553> @BASEBOARD_FAB2_LIB.BASEBOARD_FAB2(SCH_1):GND
BT25    GND VSS<552> @BASEBOARD_FAB2_LIB.BASEBOARD_FAB2(SCH_1):GND
 BU8    GND VSS<551> @BASEBOARD_FAB2_LIB.BASEBOARD_FAB2(SCH_1):GND
 BV5    GND VSS<550> @BASEBOARD_FAB2_LIB.BASEBOARD_FAB2(SCH_1):GND
BU10    GND VSS<549> @BASEBOARD_FAB2_LIB.BASEBOARD_FAB2(SCH_1):GND
BV17    GND VSS<548> @BASEBOARD_FAB2_LIB.BASEBOARD_FAB2(SCH_1):GND
BV25    GND VSS<547> @BASEBOARD_FAB2_LIB.BASEBOARD_FAB2(SCH_1):GND
 BW6    GND VSS<546> @BASEBOARD_FAB2_LIB.BASEBOARD_FAB2(SCH_1):GND
 P55    GND VSS<545> @BASEBOARD_FAB2_LIB.BASEBOARD_FAB2(SCH_1):GND
BW12    GND VSS<544> @BASEBOARD_FAB2_LIB.BASEBOARD_FAB2(SCH_1):GND
BW14    GND VSS<543> @BASEBOARD_FAB2_LIB.BASEBOARD_FAB2(SCH_1):GND
BW16    GND VSS<542> @BASEBOARD_FAB2_LIB.BASEBOARD_FAB2(SCH_1):GND
BW18    GND VSS<541> @BASEBOARD_FAB2_LIB.BASEBOARD_FAB2(SCH_1):GND
BW26    GND VSS<540> @BASEBOARD_FAB2_LIB.BASEBOARD_FAB2(SCH_1):GND
BW72    GND VSS<539> @BASEBOARD_FAB2_LIB.BASEBOARD_FAB2(SCH_1):GND
BW74    GND VSS<538> @BASEBOARD_FAB2_LIB.BASEBOARD_FAB2(SCH_1):GND
BW76    GND VSS<537> @BASEBOARD_FAB2_LIB.BASEBOARD_FAB2(SCH_1):GND
BW78    GND VSS<536> @BASEBOARD_FAB2_LIB.BASEBOARD_FAB2(SCH_1):GND
BW80    GND VSS<535> @BASEBOARD_FAB2_LIB.BASEBOARD_FAB2(SCH_1):GND
BW82    GND VSS<534> @BASEBOARD_FAB2_LIB.BASEBOARD_FAB2(SCH_1):GND
BY11    GND VSS<533> @BASEBOARD_FAB2_LIB.BASEBOARD_FAB2(SCH_1):GND
BY13    GND VSS<532> @BASEBOARD_FAB2_LIB.BASEBOARD_FAB2(SCH_1):GND
BY23    GND VSS<531> @BASEBOARD_FAB2_LIB.BASEBOARD_FAB2(SCH_1):GND
BY63    GND VSS<530> @BASEBOARD_FAB2_LIB.BASEBOARD_FAB2(SCH_1):GND
BY65    GND VSS<529> @BASEBOARD_FAB2_LIB.BASEBOARD_FAB2(SCH_1):GND
BY67    GND VSS<528> @BASEBOARD_FAB2_LIB.BASEBOARD_FAB2(SCH_1):GND
BY69    GND VSS<527> @BASEBOARD_FAB2_LIB.BASEBOARD_FAB2(SCH_1):GND
BY71    GND VSS<526> @BASEBOARD_FAB2_LIB.BASEBOARD_FAB2(SCH_1):GND
 CA2    GND VSS<525> @BASEBOARD_FAB2_LIB.BASEBOARD_FAB2(SCH_1):GND
 CA6    GND VSS<524> @BASEBOARD_FAB2_LIB.BASEBOARD_FAB2(SCH_1):GND
 CA8    GND VSS<523> @BASEBOARD_FAB2_LIB.BASEBOARD_FAB2(SCH_1):GND
CA10    GND VSS<522> @BASEBOARD_FAB2_LIB.BASEBOARD_FAB2(SCH_1):GND
CA14    GND VSS<521> @BASEBOARD_FAB2_LIB.BASEBOARD_FAB2(SCH_1):GND
CA18    GND VSS<520> @BASEBOARD_FAB2_LIB.BASEBOARD_FAB2(SCH_1):GND
CA26    GND VSS<519> @BASEBOARD_FAB2_LIB.BASEBOARD_FAB2(SCH_1):GND
CA64    GND VSS<518> @BASEBOARD_FAB2_LIB.BASEBOARD_FAB2(SCH_1):GND
CA66    GND VSS<517> @BASEBOARD_FAB2_LIB.BASEBOARD_FAB2(SCH_1):GND
CA68    GND VSS<516> @BASEBOARD_FAB2_LIB.BASEBOARD_FAB2(SCH_1):GND
CA70    GND VSS<515> @BASEBOARD_FAB2_LIB.BASEBOARD_FAB2(SCH_1):GND
 CB7    GND VSS<514> @BASEBOARD_FAB2_LIB.BASEBOARD_FAB2(SCH_1):GND
 CB9    GND VSS<513> @BASEBOARD_FAB2_LIB.BASEBOARD_FAB2(SCH_1):GND
CB27    GND VSS<512> @BASEBOARD_FAB2_LIB.BASEBOARD_FAB2(SCH_1):GND
CB63    GND VSS<511> @BASEBOARD_FAB2_LIB.BASEBOARD_FAB2(SCH_1):GND
CB71    GND VSS<510> @BASEBOARD_FAB2_LIB.BASEBOARD_FAB2(SCH_1):GND
 CC4    GND VSS<509> @BASEBOARD_FAB2_LIB.BASEBOARD_FAB2(SCH_1):GND
CC16    GND VSS<508> @BASEBOARD_FAB2_LIB.BASEBOARD_FAB2(SCH_1):GND
CC18    GND VSS<507> @BASEBOARD_FAB2_LIB.BASEBOARD_FAB2(SCH_1):GND
CC24    GND VSS<506> @BASEBOARD_FAB2_LIB.BASEBOARD_FAB2(SCH_1):GND
CC64    GND VSS<505> @BASEBOARD_FAB2_LIB.BASEBOARD_FAB2(SCH_1):GND
CC72    GND VSS<504> @BASEBOARD_FAB2_LIB.BASEBOARD_FAB2(SCH_1):GND
CC74    GND VSS<503> @BASEBOARD_FAB2_LIB.BASEBOARD_FAB2(SCH_1):GND
CC76    GND VSS<502> @BASEBOARD_FAB2_LIB.BASEBOARD_FAB2(SCH_1):GND
CC78    GND VSS<501> @BASEBOARD_FAB2_LIB.BASEBOARD_FAB2(SCH_1):GND
CC80    GND VSS<500> @BASEBOARD_FAB2_LIB.BASEBOARD_FAB2(SCH_1):GND
CC82    GND VSS<499> @BASEBOARD_FAB2_LIB.BASEBOARD_FAB2(SCH_1):GND
 CD5    GND VSS<498> @BASEBOARD_FAB2_LIB.BASEBOARD_FAB2(SCH_1):GND
CD13    GND VSS<497> @BASEBOARD_FAB2_LIB.BASEBOARD_FAB2(SCH_1):GND
CD63    GND VSS<496> @BASEBOARD_FAB2_LIB.BASEBOARD_FAB2(SCH_1):GND
CD73    GND VSS<495> @BASEBOARD_FAB2_LIB.BASEBOARD_FAB2(SCH_1):GND
CD75    GND VSS<494> @BASEBOARD_FAB2_LIB.BASEBOARD_FAB2(SCH_1):GND
CD77    GND VSS<493> @BASEBOARD_FAB2_LIB.BASEBOARD_FAB2(SCH_1):GND
CD79    GND VSS<492> @BASEBOARD_FAB2_LIB.BASEBOARD_FAB2(SCH_1):GND
CD81    GND VSS<491> @BASEBOARD_FAB2_LIB.BASEBOARD_FAB2(SCH_1):GND
CE10    GND VSS<490> @BASEBOARD_FAB2_LIB.BASEBOARD_FAB2(SCH_1):GND
CE14    GND VSS<489> @BASEBOARD_FAB2_LIB.BASEBOARD_FAB2(SCH_1):GND
CE20    GND VSS<488> @BASEBOARD_FAB2_LIB.BASEBOARD_FAB2(SCH_1):GND
CE26    GND VSS<487> @BASEBOARD_FAB2_LIB.BASEBOARD_FAB2(SCH_1):GND
CE62    GND VSS<486> @BASEBOARD_FAB2_LIB.BASEBOARD_FAB2(SCH_1):GND
CE70    GND VSS<485> @BASEBOARD_FAB2_LIB.BASEBOARD_FAB2(SCH_1):GND
CE82    GND VSS<484> @BASEBOARD_FAB2_LIB.BASEBOARD_FAB2(SCH_1):GND
 P53    GND VSS<483> @BASEBOARD_FAB2_LIB.BASEBOARD_FAB2(SCH_1):GND
 CF9    GND VSS<482> @BASEBOARD_FAB2_LIB.BASEBOARD_FAB2(SCH_1):GND
CF63    GND VSS<481> @BASEBOARD_FAB2_LIB.BASEBOARD_FAB2(SCH_1):GND
CF69    GND VSS<480> @BASEBOARD_FAB2_LIB.BASEBOARD_FAB2(SCH_1):GND
CF71    GND VSS<479> @BASEBOARD_FAB2_LIB.BASEBOARD_FAB2(SCH_1):GND
CF77    GND VSS<478> @BASEBOARD_FAB2_LIB.BASEBOARD_FAB2(SCH_1):GND
CF83    GND VSS<477> @BASEBOARD_FAB2_LIB.BASEBOARD_FAB2(SCH_1):GND
 P51    GND VSS<476> @BASEBOARD_FAB2_LIB.BASEBOARD_FAB2(SCH_1):GND
CG18    GND VSS<475> @BASEBOARD_FAB2_LIB.BASEBOARD_FAB2(SCH_1):GND
CG22    GND VSS<474> @BASEBOARD_FAB2_LIB.BASEBOARD_FAB2(SCH_1):GND
CG62    GND VSS<473> @BASEBOARD_FAB2_LIB.BASEBOARD_FAB2(SCH_1):GND
CG68    GND VSS<472> @BASEBOARD_FAB2_LIB.BASEBOARD_FAB2(SCH_1):GND
CG72    GND VSS<471> @BASEBOARD_FAB2_LIB.BASEBOARD_FAB2(SCH_1):GND
CG80    GND VSS<470> @BASEBOARD_FAB2_LIB.BASEBOARD_FAB2(SCH_1):GND
 CH1    GND VSS<469> @BASEBOARD_FAB2_LIB.BASEBOARD_FAB2(SCH_1):GND
 CH3    GND VSS<468> @BASEBOARD_FAB2_LIB.BASEBOARD_FAB2(SCH_1):GND
CH15    GND VSS<467> @BASEBOARD_FAB2_LIB.BASEBOARD_FAB2(SCH_1):GND
CH19    GND VSS<466> @BASEBOARD_FAB2_LIB.BASEBOARD_FAB2(SCH_1):GND
CH63    GND VSS<465> @BASEBOARD_FAB2_LIB.BASEBOARD_FAB2(SCH_1):GND
CH67    GND VSS<464> @BASEBOARD_FAB2_LIB.BASEBOARD_FAB2(SCH_1):GND
CH73    GND VSS<463> @BASEBOARD_FAB2_LIB.BASEBOARD_FAB2(SCH_1):GND
CH79    GND VSS<462> @BASEBOARD_FAB2_LIB.BASEBOARD_FAB2(SCH_1):GND
CH81    GND VSS<461> @BASEBOARD_FAB2_LIB.BASEBOARD_FAB2(SCH_1):GND
CH83    GND VSS<460> @BASEBOARD_FAB2_LIB.BASEBOARD_FAB2(SCH_1):GND
 CJ2    GND VSS<459> @BASEBOARD_FAB2_LIB.BASEBOARD_FAB2(SCH_1):GND
 CJ6    GND VSS<458> @BASEBOARD_FAB2_LIB.BASEBOARD_FAB2(SCH_1):GND
 CJ8    GND VSS<457> @BASEBOARD_FAB2_LIB.BASEBOARD_FAB2(SCH_1):GND
CJ10    GND VSS<456> @BASEBOARD_FAB2_LIB.BASEBOARD_FAB2(SCH_1):GND
CJ12    GND VSS<455> @BASEBOARD_FAB2_LIB.BASEBOARD_FAB2(SCH_1):GND
 P49    GND VSS<454> @BASEBOARD_FAB2_LIB.BASEBOARD_FAB2(SCH_1):GND

SKX_EXT_B_BGA1-IC,TBD  I18  U2D1
 P47    GND VSS<453> @BASEBOARD_FAB2_LIB.BASEBOARD_FAB2(SCH_1):GND
CJ62    GND VSS<452> @BASEBOARD_FAB2_LIB.BASEBOARD_FAB2(SCH_1):GND
CJ74    GND VSS<451> @BASEBOARD_FAB2_LIB.BASEBOARD_FAB2(SCH_1):GND
CJ76    GND VSS<450> @BASEBOARD_FAB2_LIB.BASEBOARD_FAB2(SCH_1):GND
CJ78    GND VSS<449> @BASEBOARD_FAB2_LIB.BASEBOARD_FAB2(SCH_1):GND
CJ82    GND VSS<448> @BASEBOARD_FAB2_LIB.BASEBOARD_FAB2(SCH_1):GND
CJ84    GND VSS<447> @BASEBOARD_FAB2_LIB.BASEBOARD_FAB2(SCH_1):GND
CJ86    GND VSS<446> @BASEBOARD_FAB2_LIB.BASEBOARD_FAB2(SCH_1):GND
CK11    GND VSS<445> @BASEBOARD_FAB2_LIB.BASEBOARD_FAB2(SCH_1):GND
CK15    GND VSS<444> @BASEBOARD_FAB2_LIB.BASEBOARD_FAB2(SCH_1):GND
CK21    GND VSS<443> @BASEBOARD_FAB2_LIB.BASEBOARD_FAB2(SCH_1):GND
CK27    GND VSS<442> @BASEBOARD_FAB2_LIB.BASEBOARD_FAB2(SCH_1):GND
CK63    GND VSS<441> @BASEBOARD_FAB2_LIB.BASEBOARD_FAB2(SCH_1):GND
CK65    GND VSS<440> @BASEBOARD_FAB2_LIB.BASEBOARD_FAB2(SCH_1):GND
CK67    GND VSS<439> @BASEBOARD_FAB2_LIB.BASEBOARD_FAB2(SCH_1):GND
CK69    GND VSS<438> @BASEBOARD_FAB2_LIB.BASEBOARD_FAB2(SCH_1):GND
CK71    GND VSS<437> @BASEBOARD_FAB2_LIB.BASEBOARD_FAB2(SCH_1):GND
CK73    GND VSS<436> @BASEBOARD_FAB2_LIB.BASEBOARD_FAB2(SCH_1):GND
CK75    GND VSS<435> @BASEBOARD_FAB2_LIB.BASEBOARD_FAB2(SCH_1):GND
CK83    GND VSS<434> @BASEBOARD_FAB2_LIB.BASEBOARD_FAB2(SCH_1):GND
CK85    GND VSS<433> @BASEBOARD_FAB2_LIB.BASEBOARD_FAB2(SCH_1):GND
 CL8    GND VSS<432> @BASEBOARD_FAB2_LIB.BASEBOARD_FAB2(SCH_1):GND
CL14    GND VSS<431> @BASEBOARD_FAB2_LIB.BASEBOARD_FAB2(SCH_1):GND
CL18    GND VSS<430> @BASEBOARD_FAB2_LIB.BASEBOARD_FAB2(SCH_1):GND
 P45    GND VSS<429> @BASEBOARD_FAB2_LIB.BASEBOARD_FAB2(SCH_1):GND
 H63    GND VSS<428> @BASEBOARD_FAB2_LIB.BASEBOARD_FAB2(SCH_1):GND
CL62    GND VSS<427> @BASEBOARD_FAB2_LIB.BASEBOARD_FAB2(SCH_1):GND
CL64    GND VSS<426> @BASEBOARD_FAB2_LIB.BASEBOARD_FAB2(SCH_1):GND
CL66    GND VSS<425> @BASEBOARD_FAB2_LIB.BASEBOARD_FAB2(SCH_1):GND
CL74    GND VSS<424> @BASEBOARD_FAB2_LIB.BASEBOARD_FAB2(SCH_1):GND
CL76    GND VSS<423> @BASEBOARD_FAB2_LIB.BASEBOARD_FAB2(SCH_1):GND
CL78    GND VSS<422> @BASEBOARD_FAB2_LIB.BASEBOARD_FAB2(SCH_1):GND
CL80    GND VSS<421> @BASEBOARD_FAB2_LIB.BASEBOARD_FAB2(SCH_1):GND
CM19    GND VSS<420> @BASEBOARD_FAB2_LIB.BASEBOARD_FAB2(SCH_1):GND
CM29    GND VSS<419> @BASEBOARD_FAB2_LIB.BASEBOARD_FAB2(SCH_1):GND
 CM5    GND VSS<418> @BASEBOARD_FAB2_LIB.BASEBOARD_FAB2(SCH_1):GND
CM31    GND VSS<417> @BASEBOARD_FAB2_LIB.BASEBOARD_FAB2(SCH_1):GND
CM61    GND VSS<416> @BASEBOARD_FAB2_LIB.BASEBOARD_FAB2(SCH_1):GND
CM63    GND VSS<415> @BASEBOARD_FAB2_LIB.BASEBOARD_FAB2(SCH_1):GND
CM67    GND VSS<414> @BASEBOARD_FAB2_LIB.BASEBOARD_FAB2(SCH_1):GND
CM73    GND VSS<413> @BASEBOARD_FAB2_LIB.BASEBOARD_FAB2(SCH_1):GND
CM77    GND VSS<412> @BASEBOARD_FAB2_LIB.BASEBOARD_FAB2(SCH_1):GND
CM83    GND VSS<411> @BASEBOARD_FAB2_LIB.BASEBOARD_FAB2(SCH_1):GND
CM85    GND VSS<410> @BASEBOARD_FAB2_LIB.BASEBOARD_FAB2(SCH_1):GND
 CN2    GND VSS<409> @BASEBOARD_FAB2_LIB.BASEBOARD_FAB2(SCH_1):GND
CN12    GND VSS<408> @BASEBOARD_FAB2_LIB.BASEBOARD_FAB2(SCH_1):GND
 H61    GND VSS<407> @BASEBOARD_FAB2_LIB.BASEBOARD_FAB2(SCH_1):GND
CN26    GND VSS<406> @BASEBOARD_FAB2_LIB.BASEBOARD_FAB2(SCH_1):GND
CN32    GND VSS<405> @BASEBOARD_FAB2_LIB.BASEBOARD_FAB2(SCH_1):GND
CN60    GND VSS<404> @BASEBOARD_FAB2_LIB.BASEBOARD_FAB2(SCH_1):GND
CN62    GND VSS<403> @BASEBOARD_FAB2_LIB.BASEBOARD_FAB2(SCH_1):GND
CN68    GND VSS<402> @BASEBOARD_FAB2_LIB.BASEBOARD_FAB2(SCH_1):GND
CN78    GND VSS<401> @BASEBOARD_FAB2_LIB.BASEBOARD_FAB2(SCH_1):GND
 CP1    GND VSS<400> @BASEBOARD_FAB2_LIB.BASEBOARD_FAB2(SCH_1):GND
 H59    GND VSS<399> @BASEBOARD_FAB2_LIB.BASEBOARD_FAB2(SCH_1):GND
CP25    GND VSS<398> @BASEBOARD_FAB2_LIB.BASEBOARD_FAB2(SCH_1):GND
CP59    GND VSS<397> @BASEBOARD_FAB2_LIB.BASEBOARD_FAB2(SCH_1):GND
CP69    GND VSS<396> @BASEBOARD_FAB2_LIB.BASEBOARD_FAB2(SCH_1):GND
CP73    GND VSS<395> @BASEBOARD_FAB2_LIB.BASEBOARD_FAB2(SCH_1):GND
CP75    GND VSS<394> @BASEBOARD_FAB2_LIB.BASEBOARD_FAB2(SCH_1):GND
CP81    GND VSS<393> @BASEBOARD_FAB2_LIB.BASEBOARD_FAB2(SCH_1):GND
CP83    GND VSS<392> @BASEBOARD_FAB2_LIB.BASEBOARD_FAB2(SCH_1):GND
 CR6    GND VSS<391> @BASEBOARD_FAB2_LIB.BASEBOARD_FAB2(SCH_1):GND
CR10    GND VSS<390> @BASEBOARD_FAB2_LIB.BASEBOARD_FAB2(SCH_1):GND
CR22    GND VSS<389> @BASEBOARD_FAB2_LIB.BASEBOARD_FAB2(SCH_1):GND
CR24    GND VSS<388> @BASEBOARD_FAB2_LIB.BASEBOARD_FAB2(SCH_1):GND
CR32    GND VSS<387> @BASEBOARD_FAB2_LIB.BASEBOARD_FAB2(SCH_1):GND
CR58    GND VSS<386> @BASEBOARD_FAB2_LIB.BASEBOARD_FAB2(SCH_1):GND
CR62    GND VSS<385> @BASEBOARD_FAB2_LIB.BASEBOARD_FAB2(SCH_1):GND
CR64    GND VSS<384> @BASEBOARD_FAB2_LIB.BASEBOARD_FAB2(SCH_1):GND
CR66    GND VSS<383> @BASEBOARD_FAB2_LIB.BASEBOARD_FAB2(SCH_1):GND
CR68    GND VSS<382> @BASEBOARD_FAB2_LIB.BASEBOARD_FAB2(SCH_1):GND
CR78    GND VSS<381> @BASEBOARD_FAB2_LIB.BASEBOARD_FAB2(SCH_1):GND
CR86    GND VSS<380> @BASEBOARD_FAB2_LIB.BASEBOARD_FAB2(SCH_1):GND
 H57    GND VSS<379> @BASEBOARD_FAB2_LIB.BASEBOARD_FAB2(SCH_1):GND
CT13    GND VSS<378> @BASEBOARD_FAB2_LIB.BASEBOARD_FAB2(SCH_1):GND
CT19    GND VSS<377> @BASEBOARD_FAB2_LIB.BASEBOARD_FAB2(SCH_1):GND
CT27    GND VSS<376> @BASEBOARD_FAB2_LIB.BASEBOARD_FAB2(SCH_1):GND
CT29    GND VSS<375> @BASEBOARD_FAB2_LIB.BASEBOARD_FAB2(SCH_1):GND
CT33    GND VSS<374> @BASEBOARD_FAB2_LIB.BASEBOARD_FAB2(SCH_1):GND
CT35    GND VSS<373> @BASEBOARD_FAB2_LIB.BASEBOARD_FAB2(SCH_1):GND
CT57    GND VSS<372> @BASEBOARD_FAB2_LIB.BASEBOARD_FAB2(SCH_1):GND
CT73    GND VSS<371> @BASEBOARD_FAB2_LIB.BASEBOARD_FAB2(SCH_1):GND
CT79    GND VSS<370> @BASEBOARD_FAB2_LIB.BASEBOARD_FAB2(SCH_1):GND
CT83    GND VSS<369> @BASEBOARD_FAB2_LIB.BASEBOARD_FAB2(SCH_1):GND
CT85    GND VSS<368> @BASEBOARD_FAB2_LIB.BASEBOARD_FAB2(SCH_1):GND
 CU4    GND VSS<367> @BASEBOARD_FAB2_LIB.BASEBOARD_FAB2(SCH_1):GND
CU22    GND VSS<366> @BASEBOARD_FAB2_LIB.BASEBOARD_FAB2(SCH_1):GND
CU28    GND VSS<365> @BASEBOARD_FAB2_LIB.BASEBOARD_FAB2(SCH_1):GND
CU30    GND VSS<364> @BASEBOARD_FAB2_LIB.BASEBOARD_FAB2(SCH_1):GND
CU34    GND VSS<363> @BASEBOARD_FAB2_LIB.BASEBOARD_FAB2(SCH_1):GND
CU36    GND VSS<362> @BASEBOARD_FAB2_LIB.BASEBOARD_FAB2(SCH_1):GND
CU56    GND VSS<361> @BASEBOARD_FAB2_LIB.BASEBOARD_FAB2(SCH_1):GND
CU62    GND VSS<360> @BASEBOARD_FAB2_LIB.BASEBOARD_FAB2(SCH_1):GND
CU68    GND VSS<359> @BASEBOARD_FAB2_LIB.BASEBOARD_FAB2(SCH_1):GND
CU76    GND VSS<358> @BASEBOARD_FAB2_LIB.BASEBOARD_FAB2(SCH_1):GND
CU78    GND VSS<357> @BASEBOARD_FAB2_LIB.BASEBOARD_FAB2(SCH_1):GND
CU80    GND VSS<356> @BASEBOARD_FAB2_LIB.BASEBOARD_FAB2(SCH_1):GND
CU82    GND VSS<355> @BASEBOARD_FAB2_LIB.BASEBOARD_FAB2(SCH_1):GND
CU86    GND VSS<354> @BASEBOARD_FAB2_LIB.BASEBOARD_FAB2(SCH_1):GND
 CV1    GND VSS<353> @BASEBOARD_FAB2_LIB.BASEBOARD_FAB2(SCH_1):GND
 H55    GND VSS<352> @BASEBOARD_FAB2_LIB.BASEBOARD_FAB2(SCH_1):GND
CV17    GND VSS<351> @BASEBOARD_FAB2_LIB.BASEBOARD_FAB2(SCH_1):GND
CV25    GND VSS<350> @BASEBOARD_FAB2_LIB.BASEBOARD_FAB2(SCH_1):GND
CV27    GND VSS<349> @BASEBOARD_FAB2_LIB.BASEBOARD_FAB2(SCH_1):GND
CV31    GND VSS<348> @BASEBOARD_FAB2_LIB.BASEBOARD_FAB2(SCH_1):GND
CV33    GND VSS<347> @BASEBOARD_FAB2_LIB.BASEBOARD_FAB2(SCH_1):GND
CV37    GND VSS<346> @BASEBOARD_FAB2_LIB.BASEBOARD_FAB2(SCH_1):GND
CV39    GND VSS<345> @BASEBOARD_FAB2_LIB.BASEBOARD_FAB2(SCH_1):GND
CV41    GND VSS<344> @BASEBOARD_FAB2_LIB.BASEBOARD_FAB2(SCH_1):GND
CV53    GND VSS<343> @BASEBOARD_FAB2_LIB.BASEBOARD_FAB2(SCH_1):GND
CV55    GND VSS<342> @BASEBOARD_FAB2_LIB.BASEBOARD_FAB2(SCH_1):GND
CV63    GND VSS<341> @BASEBOARD_FAB2_LIB.BASEBOARD_FAB2(SCH_1):GND
CV67    GND VSS<340> @BASEBOARD_FAB2_LIB.BASEBOARD_FAB2(SCH_1):GND
CV73    GND VSS<339> @BASEBOARD_FAB2_LIB.BASEBOARD_FAB2(SCH_1):GND
CV79    GND VSS<338> @BASEBOARD_FAB2_LIB.BASEBOARD_FAB2(SCH_1):GND
CV81    GND VSS<337> @BASEBOARD_FAB2_LIB.BASEBOARD_FAB2(SCH_1):GND
CV83    GND VSS<336> @BASEBOARD_FAB2_LIB.BASEBOARD_FAB2(SCH_1):GND
CW12    GND VSS<335> @BASEBOARD_FAB2_LIB.BASEBOARD_FAB2(SCH_1):GND
CW26    GND VSS<334> @BASEBOARD_FAB2_LIB.BASEBOARD_FAB2(SCH_1):GND
CW32    GND VSS<333> @BASEBOARD_FAB2_LIB.BASEBOARD_FAB2(SCH_1):GND
CW38    GND VSS<332> @BASEBOARD_FAB2_LIB.BASEBOARD_FAB2(SCH_1):GND
CW40    GND VSS<331> @BASEBOARD_FAB2_LIB.BASEBOARD_FAB2(SCH_1):GND
CW42    GND VSS<330> @BASEBOARD_FAB2_LIB.BASEBOARD_FAB2(SCH_1):GND
CW52    GND VSS<329> @BASEBOARD_FAB2_LIB.BASEBOARD_FAB2(SCH_1):GND
CW54    GND VSS<328> @BASEBOARD_FAB2_LIB.BASEBOARD_FAB2(SCH_1):GND
CW64    GND VSS<327> @BASEBOARD_FAB2_LIB.BASEBOARD_FAB2(SCH_1):GND
CW66    GND VSS<326> @BASEBOARD_FAB2_LIB.BASEBOARD_FAB2(SCH_1):GND
CW68    GND VSS<325> @BASEBOARD_FAB2_LIB.BASEBOARD_FAB2(SCH_1):GND
CW74    GND VSS<324> @BASEBOARD_FAB2_LIB.BASEBOARD_FAB2(SCH_1):GND
CW78    GND VSS<323> @BASEBOARD_FAB2_LIB.BASEBOARD_FAB2(SCH_1):GND
CW82    GND VSS<322> @BASEBOARD_FAB2_LIB.BASEBOARD_FAB2(SCH_1):GND
 CY1    GND VSS<321> @BASEBOARD_FAB2_LIB.BASEBOARD_FAB2(SCH_1):GND
 CY9    GND VSS<320> @BASEBOARD_FAB2_LIB.BASEBOARD_FAB2(SCH_1):GND
CY13    GND VSS<319> @BASEBOARD_FAB2_LIB.BASEBOARD_FAB2(SCH_1):GND
CY15    GND VSS<318> @BASEBOARD_FAB2_LIB.BASEBOARD_FAB2(SCH_1):GND
CY21    GND VSS<317> @BASEBOARD_FAB2_LIB.BASEBOARD_FAB2(SCH_1):GND
CY41    GND VSS<316> @BASEBOARD_FAB2_LIB.BASEBOARD_FAB2(SCH_1):GND
CY45    GND VSS<315> @BASEBOARD_FAB2_LIB.BASEBOARD_FAB2(SCH_1):GND
CY51    GND VSS<314> @BASEBOARD_FAB2_LIB.BASEBOARD_FAB2(SCH_1):GND
CY59    GND VSS<313> @BASEBOARD_FAB2_LIB.BASEBOARD_FAB2(SCH_1):GND
CY61    GND VSS<312> @BASEBOARD_FAB2_LIB.BASEBOARD_FAB2(SCH_1):GND
CY65    GND VSS<311> @BASEBOARD_FAB2_LIB.BASEBOARD_FAB2(SCH_1):GND
CY69    GND VSS<310> @BASEBOARD_FAB2_LIB.BASEBOARD_FAB2(SCH_1):GND
CY75    GND VSS<309> @BASEBOARD_FAB2_LIB.BASEBOARD_FAB2(SCH_1):GND
CY77    GND VSS<308> @BASEBOARD_FAB2_LIB.BASEBOARD_FAB2(SCH_1):GND
CY83    GND VSS<307> @BASEBOARD_FAB2_LIB.BASEBOARD_FAB2(SCH_1):GND
CY85    GND VSS<306> @BASEBOARD_FAB2_LIB.BASEBOARD_FAB2(SCH_1):GND
 DA6    GND VSS<305> @BASEBOARD_FAB2_LIB.BASEBOARD_FAB2(SCH_1):GND
 H53    GND VSS<304> @BASEBOARD_FAB2_LIB.BASEBOARD_FAB2(SCH_1):GND
DA18    GND VSS<303> @BASEBOARD_FAB2_LIB.BASEBOARD_FAB2(SCH_1):GND
DA26    GND VSS<302> @BASEBOARD_FAB2_LIB.BASEBOARD_FAB2(SCH_1):GND
DA28    GND VSS<301> @BASEBOARD_FAB2_LIB.BASEBOARD_FAB2(SCH_1):GND
DA30    GND VSS<300> @BASEBOARD_FAB2_LIB.BASEBOARD_FAB2(SCH_1):GND
DA32    GND VSS<299> @BASEBOARD_FAB2_LIB.BASEBOARD_FAB2(SCH_1):GND
DA34    GND VSS<298> @BASEBOARD_FAB2_LIB.BASEBOARD_FAB2(SCH_1):GND
DA36    GND VSS<297> @BASEBOARD_FAB2_LIB.BASEBOARD_FAB2(SCH_1):GND
DA38    GND VSS<296> @BASEBOARD_FAB2_LIB.BASEBOARD_FAB2(SCH_1):GND
DA44    GND VSS<295> @BASEBOARD_FAB2_LIB.BASEBOARD_FAB2(SCH_1):GND
DA46    GND VSS<294> @BASEBOARD_FAB2_LIB.BASEBOARD_FAB2(SCH_1):GND

SKX_EXT_B_BGA1-IC,TBD  I19  U2D1
DA48    GND VSS<293> @BASEBOARD_FAB2_LIB.BASEBOARD_FAB2(SCH_1):GND
DA50    GND VSS<292> @BASEBOARD_FAB2_LIB.BASEBOARD_FAB2(SCH_1):GND
DA64    GND VSS<291> @BASEBOARD_FAB2_LIB.BASEBOARD_FAB2(SCH_1):GND
DA70    GND VSS<290> @BASEBOARD_FAB2_LIB.BASEBOARD_FAB2(SCH_1):GND
DA74    GND VSS<289> @BASEBOARD_FAB2_LIB.BASEBOARD_FAB2(SCH_1):GND
DA76    GND VSS<288> @BASEBOARD_FAB2_LIB.BASEBOARD_FAB2(SCH_1):GND
DA78    GND VSS<287> @BASEBOARD_FAB2_LIB.BASEBOARD_FAB2(SCH_1):GND
DA80    GND VSS<286> @BASEBOARD_FAB2_LIB.BASEBOARD_FAB2(SCH_1):GND
 DB3    GND VSS<285> @BASEBOARD_FAB2_LIB.BASEBOARD_FAB2(SCH_1):GND
DB13    GND VSS<284> @BASEBOARD_FAB2_LIB.BASEBOARD_FAB2(SCH_1):GND
DB17    GND VSS<283> @BASEBOARD_FAB2_LIB.BASEBOARD_FAB2(SCH_1):GND
DB23    GND VSS<282> @BASEBOARD_FAB2_LIB.BASEBOARD_FAB2(SCH_1):GND
DB25    GND VSS<281> @BASEBOARD_FAB2_LIB.BASEBOARD_FAB2(SCH_1):GND
DB39    GND VSS<280> @BASEBOARD_FAB2_LIB.BASEBOARD_FAB2(SCH_1):GND
DB41    GND VSS<279> @BASEBOARD_FAB2_LIB.BASEBOARD_FAB2(SCH_1):GND
DB47    GND VSS<278> @BASEBOARD_FAB2_LIB.BASEBOARD_FAB2(SCH_1):GND
DB49    GND VSS<277> @BASEBOARD_FAB2_LIB.BASEBOARD_FAB2(SCH_1):GND
DB73    GND VSS<276> @BASEBOARD_FAB2_LIB.BASEBOARD_FAB2(SCH_1):GND
DB77    GND VSS<275> @BASEBOARD_FAB2_LIB.BASEBOARD_FAB2(SCH_1):GND
DB83    GND VSS<274> @BASEBOARD_FAB2_LIB.BASEBOARD_FAB2(SCH_1):GND
DB85    GND VSS<273> @BASEBOARD_FAB2_LIB.BASEBOARD_FAB2(SCH_1):GND
DC14    GND VSS<272> @BASEBOARD_FAB2_LIB.BASEBOARD_FAB2(SCH_1):GND
DC24    GND VSS<271> @BASEBOARD_FAB2_LIB.BASEBOARD_FAB2(SCH_1):GND
DC26    GND VSS<270> @BASEBOARD_FAB2_LIB.BASEBOARD_FAB2(SCH_1):GND
DC32    GND VSS<269> @BASEBOARD_FAB2_LIB.BASEBOARD_FAB2(SCH_1):GND
DC38    GND VSS<268> @BASEBOARD_FAB2_LIB.BASEBOARD_FAB2(SCH_1):GND
DC42    GND VSS<267> @BASEBOARD_FAB2_LIB.BASEBOARD_FAB2(SCH_1):GND
DC64    GND VSS<266> @BASEBOARD_FAB2_LIB.BASEBOARD_FAB2(SCH_1):GND
DC66    GND VSS<265> @BASEBOARD_FAB2_LIB.BASEBOARD_FAB2(SCH_1):GND
DC68    GND VSS<264> @BASEBOARD_FAB2_LIB.BASEBOARD_FAB2(SCH_1):GND
DC70    GND VSS<263> @BASEBOARD_FAB2_LIB.BASEBOARD_FAB2(SCH_1):GND
DC78    GND VSS<262> @BASEBOARD_FAB2_LIB.BASEBOARD_FAB2(SCH_1):GND
DC84    GND VSS<261> @BASEBOARD_FAB2_LIB.BASEBOARD_FAB2(SCH_1):GND
DC86    GND VSS<260> @BASEBOARD_FAB2_LIB.BASEBOARD_FAB2(SCH_1):GND
DD11    GND VSS<259> @BASEBOARD_FAB2_LIB.BASEBOARD_FAB2(SCH_1):GND
DD23    GND VSS<258> @BASEBOARD_FAB2_LIB.BASEBOARD_FAB2(SCH_1):GND
DD27    GND VSS<257> @BASEBOARD_FAB2_LIB.BASEBOARD_FAB2(SCH_1):GND
DD31    GND VSS<256> @BASEBOARD_FAB2_LIB.BASEBOARD_FAB2(SCH_1):GND
DD33    GND VSS<255> @BASEBOARD_FAB2_LIB.BASEBOARD_FAB2(SCH_1):GND
DD37    GND VSS<254> @BASEBOARD_FAB2_LIB.BASEBOARD_FAB2(SCH_1):GND
DD71    GND VSS<253> @BASEBOARD_FAB2_LIB.BASEBOARD_FAB2(SCH_1):GND
DD73    GND VSS<252> @BASEBOARD_FAB2_LIB.BASEBOARD_FAB2(SCH_1):GND
DD75    GND VSS<251> @BASEBOARD_FAB2_LIB.BASEBOARD_FAB2(SCH_1):GND
DD81    GND VSS<250> @BASEBOARD_FAB2_LIB.BASEBOARD_FAB2(SCH_1):GND
DD83    GND VSS<249> @BASEBOARD_FAB2_LIB.BASEBOARD_FAB2(SCH_1):GND
 DE6    GND VSS<248> @BASEBOARD_FAB2_LIB.BASEBOARD_FAB2(SCH_1):GND
 DE8    GND VSS<247> @BASEBOARD_FAB2_LIB.BASEBOARD_FAB2(SCH_1):GND
DE18    GND VSS<246> @BASEBOARD_FAB2_LIB.BASEBOARD_FAB2(SCH_1):GND
DE20    GND VSS<245> @BASEBOARD_FAB2_LIB.BASEBOARD_FAB2(SCH_1):GND
DE24    GND VSS<244> @BASEBOARD_FAB2_LIB.BASEBOARD_FAB2(SCH_1):GND
DE28    GND VSS<243> @BASEBOARD_FAB2_LIB.BASEBOARD_FAB2(SCH_1):GND
DE30    GND VSS<242> @BASEBOARD_FAB2_LIB.BASEBOARD_FAB2(SCH_1):GND
DE34    GND VSS<241> @BASEBOARD_FAB2_LIB.BASEBOARD_FAB2(SCH_1):GND
DE36    GND VSS<240> @BASEBOARD_FAB2_LIB.BASEBOARD_FAB2(SCH_1):GND
DE64    GND VSS<239> @BASEBOARD_FAB2_LIB.BASEBOARD_FAB2(SCH_1):GND
DE70    GND VSS<238> @BASEBOARD_FAB2_LIB.BASEBOARD_FAB2(SCH_1):GND
DE72    GND VSS<237> @BASEBOARD_FAB2_LIB.BASEBOARD_FAB2(SCH_1):GND
DE78    GND VSS<236> @BASEBOARD_FAB2_LIB.BASEBOARD_FAB2(SCH_1):GND
 DF5    GND VSS<235> @BASEBOARD_FAB2_LIB.BASEBOARD_FAB2(SCH_1):GND
 DF7    GND VSS<234> @BASEBOARD_FAB2_LIB.BASEBOARD_FAB2(SCH_1):GND
 H51    GND VSS<233> @BASEBOARD_FAB2_LIB.BASEBOARD_FAB2(SCH_1):GND
DF19    GND VSS<232> @BASEBOARD_FAB2_LIB.BASEBOARD_FAB2(SCH_1):GND
DF29    GND VSS<231> @BASEBOARD_FAB2_LIB.BASEBOARD_FAB2(SCH_1):GND
DF35    GND VSS<230> @BASEBOARD_FAB2_LIB.BASEBOARD_FAB2(SCH_1):GND
DF37    GND VSS<229> @BASEBOARD_FAB2_LIB.BASEBOARD_FAB2(SCH_1):GND
DF39    GND VSS<228> @BASEBOARD_FAB2_LIB.BASEBOARD_FAB2(SCH_1):GND
DF41    GND VSS<227> @BASEBOARD_FAB2_LIB.BASEBOARD_FAB2(SCH_1):GND
DF65    GND VSS<226> @BASEBOARD_FAB2_LIB.BASEBOARD_FAB2(SCH_1):GND
DF69    GND VSS<225> @BASEBOARD_FAB2_LIB.BASEBOARD_FAB2(SCH_1):GND
DF73    GND VSS<224> @BASEBOARD_FAB2_LIB.BASEBOARD_FAB2(SCH_1):GND
DF79    GND VSS<223> @BASEBOARD_FAB2_LIB.BASEBOARD_FAB2(SCH_1):GND
DF83    GND VSS<222> @BASEBOARD_FAB2_LIB.BASEBOARD_FAB2(SCH_1):GND
DF85    GND VSS<221> @BASEBOARD_FAB2_LIB.BASEBOARD_FAB2(SCH_1):GND
 DG2    GND VSS<220> @BASEBOARD_FAB2_LIB.BASEBOARD_FAB2(SCH_1):GND
 H49    GND VSS<219> @BASEBOARD_FAB2_LIB.BASEBOARD_FAB2(SCH_1):GND
DG14    GND VSS<218> @BASEBOARD_FAB2_LIB.BASEBOARD_FAB2(SCH_1):GND
DG16    GND VSS<217> @BASEBOARD_FAB2_LIB.BASEBOARD_FAB2(SCH_1):GND
DG24    GND VSS<216> @BASEBOARD_FAB2_LIB.BASEBOARD_FAB2(SCH_1):GND
DG66    GND VSS<215> @BASEBOARD_FAB2_LIB.BASEBOARD_FAB2(SCH_1):GND
DG68    GND VSS<214> @BASEBOARD_FAB2_LIB.BASEBOARD_FAB2(SCH_1):GND
DG76    GND VSS<213> @BASEBOARD_FAB2_LIB.BASEBOARD_FAB2(SCH_1):GND
DG78    GND VSS<212> @BASEBOARD_FAB2_LIB.BASEBOARD_FAB2(SCH_1):GND
DG80    GND VSS<211> @BASEBOARD_FAB2_LIB.BASEBOARD_FAB2(SCH_1):GND
DG82    GND VSS<210> @BASEBOARD_FAB2_LIB.BASEBOARD_FAB2(SCH_1):GND
DH13    GND VSS<209> @BASEBOARD_FAB2_LIB.BASEBOARD_FAB2(SCH_1):GND
DH15    GND VSS<208> @BASEBOARD_FAB2_LIB.BASEBOARD_FAB2(SCH_1):GND
DH23    GND VSS<207> @BASEBOARD_FAB2_LIB.BASEBOARD_FAB2(SCH_1):GND
DH25    GND VSS<206> @BASEBOARD_FAB2_LIB.BASEBOARD_FAB2(SCH_1):GND
DH27    GND VSS<205> @BASEBOARD_FAB2_LIB.BASEBOARD_FAB2(SCH_1):GND
DH29    GND VSS<204> @BASEBOARD_FAB2_LIB.BASEBOARD_FAB2(SCH_1):GND
DH31    GND VSS<203> @BASEBOARD_FAB2_LIB.BASEBOARD_FAB2(SCH_1):GND
DH33    GND VSS<202> @BASEBOARD_FAB2_LIB.BASEBOARD_FAB2(SCH_1):GND
DH35    GND VSS<201> @BASEBOARD_FAB2_LIB.BASEBOARD_FAB2(SCH_1):GND
DH37    GND VSS<200> @BASEBOARD_FAB2_LIB.BASEBOARD_FAB2(SCH_1):GND
DH41    GND VSS<199> @BASEBOARD_FAB2_LIB.BASEBOARD_FAB2(SCH_1):GND
DH67    GND VSS<198> @BASEBOARD_FAB2_LIB.BASEBOARD_FAB2(SCH_1):GND
DH71    GND VSS<197> @BASEBOARD_FAB2_LIB.BASEBOARD_FAB2(SCH_1):GND
DH73    GND VSS<196> @BASEBOARD_FAB2_LIB.BASEBOARD_FAB2(SCH_1):GND
DH79    GND VSS<195> @BASEBOARD_FAB2_LIB.BASEBOARD_FAB2(SCH_1):GND
DH81    GND VSS<194> @BASEBOARD_FAB2_LIB.BASEBOARD_FAB2(SCH_1):GND
DH83    GND VSS<193> @BASEBOARD_FAB2_LIB.BASEBOARD_FAB2(SCH_1):GND
 DJ2    GND VSS<192> @BASEBOARD_FAB2_LIB.BASEBOARD_FAB2(SCH_1):GND
DJ10    GND VSS<191> @BASEBOARD_FAB2_LIB.BASEBOARD_FAB2(SCH_1):GND
 H47    GND VSS<190> @BASEBOARD_FAB2_LIB.BASEBOARD_FAB2(SCH_1):GND
DJ22    GND VSS<189> @BASEBOARD_FAB2_LIB.BASEBOARD_FAB2(SCH_1):GND
DJ38    GND VSS<188> @BASEBOARD_FAB2_LIB.BASEBOARD_FAB2(SCH_1):GND
DJ42    GND VSS<187> @BASEBOARD_FAB2_LIB.BASEBOARD_FAB2(SCH_1):GND
DJ68    GND VSS<186> @BASEBOARD_FAB2_LIB.BASEBOARD_FAB2(SCH_1):GND
DJ74    GND VSS<185> @BASEBOARD_FAB2_LIB.BASEBOARD_FAB2(SCH_1):GND
DJ78    GND VSS<184> @BASEBOARD_FAB2_LIB.BASEBOARD_FAB2(SCH_1):GND
DJ82    GND VSS<183> @BASEBOARD_FAB2_LIB.BASEBOARD_FAB2(SCH_1):GND
DJ84    GND VSS<182> @BASEBOARD_FAB2_LIB.BASEBOARD_FAB2(SCH_1):GND
 DK7    GND VSS<181> @BASEBOARD_FAB2_LIB.BASEBOARD_FAB2(SCH_1):GND
DK23    GND VSS<180> @BASEBOARD_FAB2_LIB.BASEBOARD_FAB2(SCH_1):GND
DK29    GND VSS<179> @BASEBOARD_FAB2_LIB.BASEBOARD_FAB2(SCH_1):GND
DK35    GND VSS<178> @BASEBOARD_FAB2_LIB.BASEBOARD_FAB2(SCH_1):GND
DK39    GND VSS<177> @BASEBOARD_FAB2_LIB.BASEBOARD_FAB2(SCH_1):GND
DK41    GND VSS<176> @BASEBOARD_FAB2_LIB.BASEBOARD_FAB2(SCH_1):GND
DK73    GND VSS<175> @BASEBOARD_FAB2_LIB.BASEBOARD_FAB2(SCH_1):GND
DK75    GND VSS<174> @BASEBOARD_FAB2_LIB.BASEBOARD_FAB2(SCH_1):GND
DK77    GND VSS<173> @BASEBOARD_FAB2_LIB.BASEBOARD_FAB2(SCH_1):GND
DK83    GND VSS<172> @BASEBOARD_FAB2_LIB.BASEBOARD_FAB2(SCH_1):GND
DK85    GND VSS<171> @BASEBOARD_FAB2_LIB.BASEBOARD_FAB2(SCH_1):GND
DL16    GND VSS<170> @BASEBOARD_FAB2_LIB.BASEBOARD_FAB2(SCH_1):GND
DL18    GND VSS<169> @BASEBOARD_FAB2_LIB.BASEBOARD_FAB2(SCH_1):GND
 DL4    GND VSS<168> @BASEBOARD_FAB2_LIB.BASEBOARD_FAB2(SCH_1):GND
DL22    GND VSS<167> @BASEBOARD_FAB2_LIB.BASEBOARD_FAB2(SCH_1):GND
DL24    GND VSS<166> @BASEBOARD_FAB2_LIB.BASEBOARD_FAB2(SCH_1):GND
DL28    GND VSS<165> @BASEBOARD_FAB2_LIB.BASEBOARD_FAB2(SCH_1):GND
DL30    GND VSS<164> @BASEBOARD_FAB2_LIB.BASEBOARD_FAB2(SCH_1):GND
DL34    GND VSS<163> @BASEBOARD_FAB2_LIB.BASEBOARD_FAB2(SCH_1):GND
DL36    GND VSS<162> @BASEBOARD_FAB2_LIB.BASEBOARD_FAB2(SCH_1):GND
DL40    GND VSS<161> @BASEBOARD_FAB2_LIB.BASEBOARD_FAB2(SCH_1):GND
DL68    GND VSS<160> @BASEBOARD_FAB2_LIB.BASEBOARD_FAB2(SCH_1):GND
DL70    GND VSS<159> @BASEBOARD_FAB2_LIB.BASEBOARD_FAB2(SCH_1):GND
DL74    GND VSS<158> @BASEBOARD_FAB2_LIB.BASEBOARD_FAB2(SCH_1):GND
DL76    GND VSS<157> @BASEBOARD_FAB2_LIB.BASEBOARD_FAB2(SCH_1):GND
DL78    GND VSS<156> @BASEBOARD_FAB2_LIB.BASEBOARD_FAB2(SCH_1):GND
DL80    GND VSS<155> @BASEBOARD_FAB2_LIB.BASEBOARD_FAB2(SCH_1):GND
DM15    GND VSS<154> @BASEBOARD_FAB2_LIB.BASEBOARD_FAB2(SCH_1):GND
 H45    GND VSS<153> @BASEBOARD_FAB2_LIB.BASEBOARD_FAB2(SCH_1):GND
DM25    GND VSS<152> @BASEBOARD_FAB2_LIB.BASEBOARD_FAB2(SCH_1):GND
DM27    GND VSS<151> @BASEBOARD_FAB2_LIB.BASEBOARD_FAB2(SCH_1):GND
DM31    GND VSS<150> @BASEBOARD_FAB2_LIB.BASEBOARD_FAB2(SCH_1):GND
DM33    GND VSS<149> @BASEBOARD_FAB2_LIB.BASEBOARD_FAB2(SCH_1):GND
DM37    GND VSS<148> @BASEBOARD_FAB2_LIB.BASEBOARD_FAB2(SCH_1):GND
DM39    GND VSS<147> @BASEBOARD_FAB2_LIB.BASEBOARD_FAB2(SCH_1):GND
DM65    GND VSS<146> @BASEBOARD_FAB2_LIB.BASEBOARD_FAB2(SCH_1):GND
DM73    GND VSS<145> @BASEBOARD_FAB2_LIB.BASEBOARD_FAB2(SCH_1):GND
DM77    GND VSS<144> @BASEBOARD_FAB2_LIB.BASEBOARD_FAB2(SCH_1):GND
DM83    GND VSS<143> @BASEBOARD_FAB2_LIB.BASEBOARD_FAB2(SCH_1):GND
 DN2    GND VSS<142> @BASEBOARD_FAB2_LIB.BASEBOARD_FAB2(SCH_1):GND
BH17    GND VSS<141> @BASEBOARD_FAB2_LIB.BASEBOARD_FAB2(SCH_1):GND
DN12    GND VSS<140> @BASEBOARD_FAB2_LIB.BASEBOARD_FAB2(SCH_1):GND
DN22    GND VSS<139> @BASEBOARD_FAB2_LIB.BASEBOARD_FAB2(SCH_1):GND
DN26    GND VSS<138> @BASEBOARD_FAB2_LIB.BASEBOARD_FAB2(SCH_1):GND
DN32    GND VSS<137> @BASEBOARD_FAB2_LIB.BASEBOARD_FAB2(SCH_1):GND
DN38    GND VSS<136> @BASEBOARD_FAB2_LIB.BASEBOARD_FAB2(SCH_1):GND
DN68    GND VSS<135> @BASEBOARD_FAB2_LIB.BASEBOARD_FAB2(SCH_1):GND
DN72    GND VSS<134> @BASEBOARD_FAB2_LIB.BASEBOARD_FAB2(SCH_1):GND

SKX_EXT_B_BGA1-IC,TBD  I20  U2D1
DN78    GND VSS<133> @BASEBOARD_FAB2_LIB.BASEBOARD_FAB2(SCH_1):GND
DP67    GND VSS<132> @BASEBOARD_FAB2_LIB.BASEBOARD_FAB2(SCH_1):GND
DP69    GND VSS<131> @BASEBOARD_FAB2_LIB.BASEBOARD_FAB2(SCH_1):GND
DP71    GND VSS<130> @BASEBOARD_FAB2_LIB.BASEBOARD_FAB2(SCH_1):GND
DP81    GND VSS<129> @BASEBOARD_FAB2_LIB.BASEBOARD_FAB2(SCH_1):GND
DP83    GND VSS<128> @BASEBOARD_FAB2_LIB.BASEBOARD_FAB2(SCH_1):GND
BR26    GND VSS<127> @BASEBOARD_FAB2_LIB.BASEBOARD_FAB2(SCH_1):GND
 DR6    GND VSS<126> @BASEBOARD_FAB2_LIB.BASEBOARD_FAB2(SCH_1):GND
CA20    GND VSS<125> @BASEBOARD_FAB2_LIB.BASEBOARD_FAB2(SCH_1):GND
CL22    GND VSS<124> @BASEBOARD_FAB2_LIB.BASEBOARD_FAB2(SCH_1):GND
DR20    GND VSS<123> @BASEBOARD_FAB2_LIB.BASEBOARD_FAB2(SCH_1):GND
DR22    GND VSS<122> @BASEBOARD_FAB2_LIB.BASEBOARD_FAB2(SCH_1):GND
DR24    GND VSS<121> @BASEBOARD_FAB2_LIB.BASEBOARD_FAB2(SCH_1):GND
DR26    GND VSS<120> @BASEBOARD_FAB2_LIB.BASEBOARD_FAB2(SCH_1):GND
DR28    GND VSS<119> @BASEBOARD_FAB2_LIB.BASEBOARD_FAB2(SCH_1):GND
DR30    GND VSS<118> @BASEBOARD_FAB2_LIB.BASEBOARD_FAB2(SCH_1):GND
DR32    GND VSS<117> @BASEBOARD_FAB2_LIB.BASEBOARD_FAB2(SCH_1):GND
DR34    GND VSS<116> @BASEBOARD_FAB2_LIB.BASEBOARD_FAB2(SCH_1):GND
DR36    GND VSS<115> @BASEBOARD_FAB2_LIB.BASEBOARD_FAB2(SCH_1):GND
DR38    GND VSS<114> @BASEBOARD_FAB2_LIB.BASEBOARD_FAB2(SCH_1):GND
DR40    GND VSS<113> @BASEBOARD_FAB2_LIB.BASEBOARD_FAB2(SCH_1):GND
DR42    GND VSS<112> @BASEBOARD_FAB2_LIB.BASEBOARD_FAB2(SCH_1):GND
DR66    GND VSS<111> @BASEBOARD_FAB2_LIB.BASEBOARD_FAB2(SCH_1):GND
DR68    GND VSS<110> @BASEBOARD_FAB2_LIB.BASEBOARD_FAB2(SCH_1):GND
DR70    GND VSS<109> @BASEBOARD_FAB2_LIB.BASEBOARD_FAB2(SCH_1):GND
DR72    GND VSS<108> @BASEBOARD_FAB2_LIB.BASEBOARD_FAB2(SCH_1):GND
DR74    GND VSS<107> @BASEBOARD_FAB2_LIB.BASEBOARD_FAB2(SCH_1):GND
DR76    GND VSS<106> @BASEBOARD_FAB2_LIB.BASEBOARD_FAB2(SCH_1):GND
DR78    GND VSS<105> @BASEBOARD_FAB2_LIB.BASEBOARD_FAB2(SCH_1):GND
 DT3    GND VSS<104> @BASEBOARD_FAB2_LIB.BASEBOARD_FAB2(SCH_1):GND
DT17    GND VSS<103> @BASEBOARD_FAB2_LIB.BASEBOARD_FAB2(SCH_1):GND
DH21    GND VSS<102> @BASEBOARD_FAB2_LIB.BASEBOARD_FAB2(SCH_1):GND
DT65    GND VSS<101> @BASEBOARD_FAB2_LIB.BASEBOARD_FAB2(SCH_1):GND
DT69    GND VSS<100> @BASEBOARD_FAB2_LIB.BASEBOARD_FAB2(SCH_1):GND
DT79    GND VSS<99> @BASEBOARD_FAB2_LIB.BASEBOARD_FAB2(SCH_1):GND
DT83    GND VSS<98> @BASEBOARD_FAB2_LIB.BASEBOARD_FAB2(SCH_1):GND
DT85    GND VSS<97> @BASEBOARD_FAB2_LIB.BASEBOARD_FAB2(SCH_1):GND
DU10    GND VSS<96> @BASEBOARD_FAB2_LIB.BASEBOARD_FAB2(SCH_1):GND
DU14    GND VSS<95> @BASEBOARD_FAB2_LIB.BASEBOARD_FAB2(SCH_1):GND
CN14    GND VSS<94> @BASEBOARD_FAB2_LIB.BASEBOARD_FAB2(SCH_1):GND
DU22    GND VSS<93> @BASEBOARD_FAB2_LIB.BASEBOARD_FAB2(SCH_1):GND
DU26    GND VSS<92> @BASEBOARD_FAB2_LIB.BASEBOARD_FAB2(SCH_1):GND
DU32    GND VSS<91> @BASEBOARD_FAB2_LIB.BASEBOARD_FAB2(SCH_1):GND
DU38    GND VSS<90> @BASEBOARD_FAB2_LIB.BASEBOARD_FAB2(SCH_1):GND
DU70    GND VSS<89> @BASEBOARD_FAB2_LIB.BASEBOARD_FAB2(SCH_1):GND
DU72    GND VSS<88> @BASEBOARD_FAB2_LIB.BASEBOARD_FAB2(SCH_1):GND
DU78    GND VSS<87> @BASEBOARD_FAB2_LIB.BASEBOARD_FAB2(SCH_1):GND
DU80    GND VSS<86> @BASEBOARD_FAB2_LIB.BASEBOARD_FAB2(SCH_1):GND
DU82    GND VSS<85> @BASEBOARD_FAB2_LIB.BASEBOARD_FAB2(SCH_1):GND
DU84    GND VSS<84> @BASEBOARD_FAB2_LIB.BASEBOARD_FAB2(SCH_1):GND
DV21    GND VSS<83> @BASEBOARD_FAB2_LIB.BASEBOARD_FAB2(SCH_1):GND
DV25    GND VSS<82> @BASEBOARD_FAB2_LIB.BASEBOARD_FAB2(SCH_1):GND
DV27    GND VSS<81> @BASEBOARD_FAB2_LIB.BASEBOARD_FAB2(SCH_1):GND
DV31    GND VSS<80> @BASEBOARD_FAB2_LIB.BASEBOARD_FAB2(SCH_1):GND
DV33    GND VSS<79> @BASEBOARD_FAB2_LIB.BASEBOARD_FAB2(SCH_1):GND
DV37    GND VSS<78> @BASEBOARD_FAB2_LIB.BASEBOARD_FAB2(SCH_1):GND
DV39    GND VSS<77> @BASEBOARD_FAB2_LIB.BASEBOARD_FAB2(SCH_1):GND
DV73    GND VSS<76> @BASEBOARD_FAB2_LIB.BASEBOARD_FAB2(SCH_1):GND
DV77    GND VSS<75> @BASEBOARD_FAB2_LIB.BASEBOARD_FAB2(SCH_1):GND
DV81    GND VSS<74> @BASEBOARD_FAB2_LIB.BASEBOARD_FAB2(SCH_1):GND
DW12    GND VSS<73> @BASEBOARD_FAB2_LIB.BASEBOARD_FAB2(SCH_1):GND
DW20    GND VSS<72> @BASEBOARD_FAB2_LIB.BASEBOARD_FAB2(SCH_1):GND
DW24    GND VSS<71> @BASEBOARD_FAB2_LIB.BASEBOARD_FAB2(SCH_1):GND
DW28    GND VSS<70> @BASEBOARD_FAB2_LIB.BASEBOARD_FAB2(SCH_1):GND
DW30    GND VSS<69> @BASEBOARD_FAB2_LIB.BASEBOARD_FAB2(SCH_1):GND
DW34    GND VSS<68> @BASEBOARD_FAB2_LIB.BASEBOARD_FAB2(SCH_1):GND
DW36    GND VSS<67> @BASEBOARD_FAB2_LIB.BASEBOARD_FAB2(SCH_1):GND
DW40    GND VSS<66> @BASEBOARD_FAB2_LIB.BASEBOARD_FAB2(SCH_1):GND
DW64    GND VSS<65> @BASEBOARD_FAB2_LIB.BASEBOARD_FAB2(SCH_1):GND
DW66    GND VSS<64> @BASEBOARD_FAB2_LIB.BASEBOARD_FAB2(SCH_1):GND
DW68    GND VSS<63> @BASEBOARD_FAB2_LIB.BASEBOARD_FAB2(SCH_1):GND
DW70    GND VSS<62> @BASEBOARD_FAB2_LIB.BASEBOARD_FAB2(SCH_1):GND
DW72    GND VSS<61> @BASEBOARD_FAB2_LIB.BASEBOARD_FAB2(SCH_1):GND
DW74    GND VSS<60> @BASEBOARD_FAB2_LIB.BASEBOARD_FAB2(SCH_1):GND
DW76    GND VSS<59> @BASEBOARD_FAB2_LIB.BASEBOARD_FAB2(SCH_1):GND
 DW8    GND VSS<58> @BASEBOARD_FAB2_LIB.BASEBOARD_FAB2(SCH_1):GND
DW82    GND VSS<57> @BASEBOARD_FAB2_LIB.BASEBOARD_FAB2(SCH_1):GND
DW84    GND VSS<56> @BASEBOARD_FAB2_LIB.BASEBOARD_FAB2(SCH_1):GND
 DY5    GND VSS<55> @BASEBOARD_FAB2_LIB.BASEBOARD_FAB2(SCH_1):GND
DY19    GND VSS<54> @BASEBOARD_FAB2_LIB.BASEBOARD_FAB2(SCH_1):GND
DY23    GND VSS<53> @BASEBOARD_FAB2_LIB.BASEBOARD_FAB2(SCH_1):GND
DY29    GND VSS<52> @BASEBOARD_FAB2_LIB.BASEBOARD_FAB2(SCH_1):GND
DY35    GND VSS<51> @BASEBOARD_FAB2_LIB.BASEBOARD_FAB2(SCH_1):GND
DY41    GND VSS<50> @BASEBOARD_FAB2_LIB.BASEBOARD_FAB2(SCH_1):GND
DY71    GND VSS<49> @BASEBOARD_FAB2_LIB.BASEBOARD_FAB2(SCH_1):GND
DY75    GND VSS<48> @BASEBOARD_FAB2_LIB.BASEBOARD_FAB2(SCH_1):GND
 EA6    GND VSS<47> @BASEBOARD_FAB2_LIB.BASEBOARD_FAB2(SCH_1):GND
 J16    GND VSS<46> @BASEBOARD_FAB2_LIB.BASEBOARD_FAB2(SCH_1):GND
EA16    GND VSS<45> @BASEBOARD_FAB2_LIB.BASEBOARD_FAB2(SCH_1):GND
EA20    GND VSS<44> @BASEBOARD_FAB2_LIB.BASEBOARD_FAB2(SCH_1):GND
EA22    GND VSS<43> @BASEBOARD_FAB2_LIB.BASEBOARD_FAB2(SCH_1):GND
EA42    GND VSS<42> @BASEBOARD_FAB2_LIB.BASEBOARD_FAB2(SCH_1):GND
EA64    GND VSS<41> @BASEBOARD_FAB2_LIB.BASEBOARD_FAB2(SCH_1):GND
EA70    GND VSS<40> @BASEBOARD_FAB2_LIB.BASEBOARD_FAB2(SCH_1):GND
EA76    GND VSS<39> @BASEBOARD_FAB2_LIB.BASEBOARD_FAB2(SCH_1):GND
EA78    GND VSS<38> @BASEBOARD_FAB2_LIB.BASEBOARD_FAB2(SCH_1):GND
EA80    GND VSS<37> @BASEBOARD_FAB2_LIB.BASEBOARD_FAB2(SCH_1):GND
EA82    GND VSS<36> @BASEBOARD_FAB2_LIB.BASEBOARD_FAB2(SCH_1):GND
EB13    GND VSS<35> @BASEBOARD_FAB2_LIB.BASEBOARD_FAB2(SCH_1):GND
BR18    GND VSS<34> @BASEBOARD_FAB2_LIB.BASEBOARD_FAB2(SCH_1):GND
EB23    GND VSS<33> @BASEBOARD_FAB2_LIB.BASEBOARD_FAB2(SCH_1):GND
EB25    GND VSS<32> @BASEBOARD_FAB2_LIB.BASEBOARD_FAB2(SCH_1):GND
EB27    GND VSS<31> @BASEBOARD_FAB2_LIB.BASEBOARD_FAB2(SCH_1):GND
EB29    GND VSS<30> @BASEBOARD_FAB2_LIB.BASEBOARD_FAB2(SCH_1):GND
EB31    GND VSS<29> @BASEBOARD_FAB2_LIB.BASEBOARD_FAB2(SCH_1):GND
EB33    GND VSS<28> @BASEBOARD_FAB2_LIB.BASEBOARD_FAB2(SCH_1):GND
EB35    GND VSS<27> @BASEBOARD_FAB2_LIB.BASEBOARD_FAB2(SCH_1):GND
EB37    GND VSS<26> @BASEBOARD_FAB2_LIB.BASEBOARD_FAB2(SCH_1):GND
EB39    GND VSS<25> @BASEBOARD_FAB2_LIB.BASEBOARD_FAB2(SCH_1):GND
EB41    GND VSS<24> @BASEBOARD_FAB2_LIB.BASEBOARD_FAB2(SCH_1):GND
EB65    GND VSS<23> @BASEBOARD_FAB2_LIB.BASEBOARD_FAB2(SCH_1):GND
EB69    GND VSS<22> @BASEBOARD_FAB2_LIB.BASEBOARD_FAB2(SCH_1):GND
EC10    GND VSS<21> @BASEBOARD_FAB2_LIB.BASEBOARD_FAB2(SCH_1):GND
EC70    GND VSS<20> @BASEBOARD_FAB2_LIB.BASEBOARD_FAB2(SCH_1):GND
EC72    GND VSS<19> @BASEBOARD_FAB2_LIB.BASEBOARD_FAB2(SCH_1):GND
EC74    GND VSS<18> @BASEBOARD_FAB2_LIB.BASEBOARD_FAB2(SCH_1):GND
EC76    GND VSS<17> @BASEBOARD_FAB2_LIB.BASEBOARD_FAB2(SCH_1):GND
ED11    GND VSS<16> @BASEBOARD_FAB2_LIB.BASEBOARD_FAB2(SCH_1):GND
ED15    GND VSS<15> @BASEBOARD_FAB2_LIB.BASEBOARD_FAB2(SCH_1):GND
ED23    GND VSS<14> @BASEBOARD_FAB2_LIB.BASEBOARD_FAB2(SCH_1):GND
ED29    GND VSS<13> @BASEBOARD_FAB2_LIB.BASEBOARD_FAB2(SCH_1):GND
ED35    GND VSS<12> @BASEBOARD_FAB2_LIB.BASEBOARD_FAB2(SCH_1):GND
ED77    GND VSS<11> @BASEBOARD_FAB2_LIB.BASEBOARD_FAB2(SCH_1):GND
EE24    GND VSS<10> @BASEBOARD_FAB2_LIB.BASEBOARD_FAB2(SCH_1):GND
EE28    GND VSS<9> @BASEBOARD_FAB2_LIB.BASEBOARD_FAB2(SCH_1):GND
EE30    GND VSS<8> @BASEBOARD_FAB2_LIB.BASEBOARD_FAB2(SCH_1):GND
EE34    GND VSS<7> @BASEBOARD_FAB2_LIB.BASEBOARD_FAB2(SCH_1):GND
EE36    GND VSS<6> @BASEBOARD_FAB2_LIB.BASEBOARD_FAB2(SCH_1):GND
EE70    GND VSS<5> @BASEBOARD_FAB2_LIB.BASEBOARD_FAB2(SCH_1):GND
EE76    GND VSS<4> @BASEBOARD_FAB2_LIB.BASEBOARD_FAB2(SCH_1):GND
EE78    GND VSS<3> @BASEBOARD_FAB2_LIB.BASEBOARD_FAB2(SCH_1):GND
EF71    GND VSS<2> @BASEBOARD_FAB2_LIB.BASEBOARD_FAB2(SCH_1):GND
EF75    GND VSS<1> @BASEBOARD_FAB2_LIB.BASEBOARD_FAB2(SCH_1):GND
EF79    GND VSS<0> @BASEBOARD_FAB2_LIB.BASEBOARD_FAB2(SCH_1):GND


DRAWING: @BASEBOARD_FAB2_LIB.BASEBOARD_FAB2(SCH_1):PAGE76 

CAP_A_0603V-22.0UF,4V,20%,X6S,A  I1  C3D21
   1 PVCCMCP_CPU1      A @BASEBOARD_FAB2_LIB.BASEBOARD_FAB2(SCH_1):PVCCMCP_CPU1
   2    GND      B @BASEBOARD_FAB2_LIB.BASEBOARD_FAB2(SCH_1):GND

CAP_A_0603V-22.0UF,4V,20%,X6S,A  I3  C3D5
   1 PVCCMCP_CPU1      A @BASEBOARD_FAB2_LIB.BASEBOARD_FAB2(SCH_1):PVCCMCP_CPU1
   2    GND      B @BASEBOARD_FAB2_LIB.BASEBOARD_FAB2(SCH_1):GND

CAP_A_0603V-22.0UF,4V,20%,X6S,A  I4  C3D12
   1 PVCCMCP_CPU1      A @BASEBOARD_FAB2_LIB.BASEBOARD_FAB2(SCH_1):PVCCMCP_CPU1
   2    GND      B @BASEBOARD_FAB2_LIB.BASEBOARD_FAB2(SCH_1):GND

CAP_A_0603V-22.0UF,4V,20%,X6S,A  I5  C3D4
   1 PVCCMCP_CPU1      A @BASEBOARD_FAB2_LIB.BASEBOARD_FAB2(SCH_1):PVCCMCP_CPU1
   2    GND      B @BASEBOARD_FAB2_LIB.BASEBOARD_FAB2(SCH_1):GND

CAP_A_0603V-22.0UF,4V,20%,X6S,A  I7  C3D11
   1 PVCCMCP_CPU1      A @BASEBOARD_FAB2_LIB.BASEBOARD_FAB2(SCH_1):PVCCMCP_CPU1
   2    GND      B @BASEBOARD_FAB2_LIB.BASEBOARD_FAB2(SCH_1):GND

CAP_A_0603V-22.0UF,4V,20%,X6S,A  I8  C3D13
   1 PVCCMCP_CPU1      A @BASEBOARD_FAB2_LIB.BASEBOARD_FAB2(SCH_1):PVCCMCP_CPU1
   2    GND      B @BASEBOARD_FAB2_LIB.BASEBOARD_FAB2(SCH_1):GND

CAP_A_0603V-22.0UF,4V,20%,X6S,A  I10  C2D40
   1 PVCCMCP_CPU1      A @BASEBOARD_FAB2_LIB.BASEBOARD_FAB2(SCH_1):PVCCMCP_CPU1
   2    GND      B @BASEBOARD_FAB2_LIB.BASEBOARD_FAB2(SCH_1):GND

CAP_A_0603V-22.0UF,4V,20%,X6S,A  I15  C3D9
   1 PVCCIO_CPU1      A @BASEBOARD_FAB2_LIB.BASEBOARD_FAB2(SCH_1):PVCCIO_CPU1
   2    GND      B @BASEBOARD_FAB2_LIB.BASEBOARD_FAB2(SCH_1):GND

CAP_A_0603V-22.0UF,4V,20%,X6S,A  I18  C3D8
   1 PVCCIO_CPU1      A @BASEBOARD_FAB2_LIB.BASEBOARD_FAB2(SCH_1):PVCCIO_CPU1
   2    GND      B @BASEBOARD_FAB2_LIB.BASEBOARD_FAB2(SCH_1):GND

CAP_0805-47UF,4V,20%,X6S,C9533A  I23  C7P6
   1 PVCCMCP_CPU1      A @BASEBOARD_FAB2_LIB.BASEBOARD_FAB2(SCH_1):PVCCMCP_CPU1
   2    GND      B @BASEBOARD_FAB2_LIB.BASEBOARD_FAB2(SCH_1):GND

CAP_0805-47UF,4V,20%,X6S,C9533A  I25  C7P13
   1 PVCCMCP_CPU1      A @BASEBOARD_FAB2_LIB.BASEBOARD_FAB2(SCH_1):PVCCMCP_CPU1
   2    GND      B @BASEBOARD_FAB2_LIB.BASEBOARD_FAB2(SCH_1):GND

CAP_0805-47UF,4V,20%,X6S,C9533A  I26  C7P10
   1 PVCCMCP_CPU1      A @BASEBOARD_FAB2_LIB.BASEBOARD_FAB2(SCH_1):PVCCMCP_CPU1
   2    GND      B @BASEBOARD_FAB2_LIB.BASEBOARD_FAB2(SCH_1):GND

CAP_0805-47UF,4V,20%,X6S,C9533A  I27  C7P7
   1 PVCCMCP_CPU1      A @BASEBOARD_FAB2_LIB.BASEBOARD_FAB2(SCH_1):PVCCMCP_CPU1
   2    GND      B @BASEBOARD_FAB2_LIB.BASEBOARD_FAB2(SCH_1):GND

CAP_0805-47UF,4V,20%,X6S,C9533A  I28  C8P22
   1 PVCCMCP_CPU1      A @BASEBOARD_FAB2_LIB.BASEBOARD_FAB2(SCH_1):PVCCMCP_CPU1
   2    GND      B @BASEBOARD_FAB2_LIB.BASEBOARD_FAB2(SCH_1):GND

CAP_0805-47UF,4V,20%,X6S,C9533A  I29  C7P17
   1 PVCCIO_CPU1      A @BASEBOARD_FAB2_LIB.BASEBOARD_FAB2(SCH_1):PVCCIO_CPU1
   2    GND      B @BASEBOARD_FAB2_LIB.BASEBOARD_FAB2(SCH_1):GND

CAP_0603LF-10UF,4V,20%,X6S,E15A  I33  C2D8
   1 PVSA_CPU1      A @BASEBOARD_FAB2_LIB.BASEBOARD_FAB2(SCH_1):PVSA_CPU1
   2    GND      B @BASEBOARD_FAB2_LIB.BASEBOARD_FAB2(SCH_1):GND

CAP_0603LF-10UF,4V,20%,X6S,E15A  I37  C2D10
   1 PVSA_CPU1      A @BASEBOARD_FAB2_LIB.BASEBOARD_FAB2(SCH_1):PVSA_CPU1
   2    GND      B @BASEBOARD_FAB2_LIB.BASEBOARD_FAB2(SCH_1):GND

CAP_0603LF-10UF,4V,20%,X6S,E15A  I42  C2D11
   1 PVSA_CPU1      A @BASEBOARD_FAB2_LIB.BASEBOARD_FAB2(SCH_1):PVSA_CPU1
   2    GND      B @BASEBOARD_FAB2_LIB.BASEBOARD_FAB2(SCH_1):GND

CAP_0603LF-10UF,4V,20%,X6S,E15A  I43  C2D9
   1 PVSA_CPU1      A @BASEBOARD_FAB2_LIB.BASEBOARD_FAB2(SCH_1):PVSA_CPU1
   2    GND      B @BASEBOARD_FAB2_LIB.BASEBOARD_FAB2(SCH_1):GND

CAP_0805-47UF,4V,20%,X6S,C9533A  I45  C7P15
   1 PVCCMCP_CPU1      A @BASEBOARD_FAB2_LIB.BASEBOARD_FAB2(SCH_1):PVCCMCP_CPU1
   2    GND      B @BASEBOARD_FAB2_LIB.BASEBOARD_FAB2(SCH_1):GND

CAP_0805-47UF,4V,20%,X6S,C9533A  I48  C8P23
   1 PVCCMCP_CPU1      A @BASEBOARD_FAB2_LIB.BASEBOARD_FAB2(SCH_1):PVCCMCP_CPU1
   2    GND      B @BASEBOARD_FAB2_LIB.BASEBOARD_FAB2(SCH_1):GND

CAP_0805-47UF,4V,20%,X6S,C9533A  I49  C7P14
   1 PVCCMCP_CPU1      A @BASEBOARD_FAB2_LIB.BASEBOARD_FAB2(SCH_1):PVCCMCP_CPU1
   2    GND      B @BASEBOARD_FAB2_LIB.BASEBOARD_FAB2(SCH_1):GND

CAP_0805LF-22UF,4V,20%,X6S,C95A  I50  C8P7
   1 PVSA_CPU1      A @BASEBOARD_FAB2_LIB.BASEBOARD_FAB2(SCH_1):PVSA_CPU1
   2    GND      B @BASEBOARD_FAB2_LIB.BASEBOARD_FAB2(SCH_1):GND

CAP_0805-47UF,4V,20%,X6S,C9533A  I51  C7P18
   1 PVCCIO_CPU1      A @BASEBOARD_FAB2_LIB.BASEBOARD_FAB2(SCH_1):PVCCIO_CPU1
   2    GND      B @BASEBOARD_FAB2_LIB.BASEBOARD_FAB2(SCH_1):GND

CAP_0805-47UF,4V,20%,X6S,C9533A  I52  C7P3
   1 PVCCIO_CPU1      A @BASEBOARD_FAB2_LIB.BASEBOARD_FAB2(SCH_1):PVCCIO_CPU1
   2    GND      B @BASEBOARD_FAB2_LIB.BASEBOARD_FAB2(SCH_1):GND

CAP_0805LF-22UF,4V,20%,X6S,C95A  I55  C8P6
   1 PVSA_CPU1      A @BASEBOARD_FAB2_LIB.BASEBOARD_FAB2(SCH_1):PVSA_CPU1
   2    GND      B @BASEBOARD_FAB2_LIB.BASEBOARD_FAB2(SCH_1):GND

CAP_0805LF-22UF,4V,20%,X6S,C95A  I58  C8P5
   1 PVSA_CPU1      A @BASEBOARD_FAB2_LIB.BASEBOARD_FAB2(SCH_1):PVSA_CPU1
   2    GND      B @BASEBOARD_FAB2_LIB.BASEBOARD_FAB2(SCH_1):GND

CAP_A_0603V-22.0UF,4V,20%,X6S,A  I59  C2D12
   1 PVCCIN_CPU1      A @BASEBOARD_FAB2_LIB.BASEBOARD_FAB2(SCH_1):PVCCIN_CPU1
   2    GND      B @BASEBOARD_FAB2_LIB.BASEBOARD_FAB2(SCH_1):GND

CAP_A_0603V-22.0UF,4V,20%,X6S,A  I61  C2D22
   1 PVCCIN_CPU1      A @BASEBOARD_FAB2_LIB.BASEBOARD_FAB2(SCH_1):PVCCIN_CPU1
   2    GND      B @BASEBOARD_FAB2_LIB.BASEBOARD_FAB2(SCH_1):GND

CAP_A_0603V-22.0UF,4V,20%,X6S,A  I63  C2D31
   1 PVCCIN_CPU1      A @BASEBOARD_FAB2_LIB.BASEBOARD_FAB2(SCH_1):PVCCIN_CPU1
   2    GND      B @BASEBOARD_FAB2_LIB.BASEBOARD_FAB2(SCH_1):GND

CAP_A_0603V-22.0UF,4V,20%,X6S,A  I65  C2D21
   1 PVCCIN_CPU1      A @BASEBOARD_FAB2_LIB.BASEBOARD_FAB2(SCH_1):PVCCIN_CPU1
   2    GND      B @BASEBOARD_FAB2_LIB.BASEBOARD_FAB2(SCH_1):GND

CAP_A_0603V-22.0UF,4V,20%,X6S,A  I66  C2D27
   1 PVCCIN_CPU1      A @BASEBOARD_FAB2_LIB.BASEBOARD_FAB2(SCH_1):PVCCIN_CPU1
   2    GND      B @BASEBOARD_FAB2_LIB.BASEBOARD_FAB2(SCH_1):GND

CAP_A_0603V-22.0UF,4V,20%,X6S,A  I69  C3D2
   1 PVCCIN_CPU1      A @BASEBOARD_FAB2_LIB.BASEBOARD_FAB2(SCH_1):PVCCIN_CPU1
   2    GND      B @BASEBOARD_FAB2_LIB.BASEBOARD_FAB2(SCH_1):GND

CAP_A_0603V-22.0UF,4V,20%,X6S,A  I70  C2D36
   1 PVCCIN_CPU1      A @BASEBOARD_FAB2_LIB.BASEBOARD_FAB2(SCH_1):PVCCIN_CPU1
   2    GND      B @BASEBOARD_FAB2_LIB.BASEBOARD_FAB2(SCH_1):GND

CAP_A_0603V-22.0UF,4V,20%,X6S,A  I73  C2D13
   1 PVCCIN_CPU1      A @BASEBOARD_FAB2_LIB.BASEBOARD_FAB2(SCH_1):PVCCIN_CPU1
   2    GND      B @BASEBOARD_FAB2_LIB.BASEBOARD_FAB2(SCH_1):GND

CAP_A_0603V-22.0UF,4V,20%,X6S,A  I75  C2D19
   1 PVCCIN_CPU1      A @BASEBOARD_FAB2_LIB.BASEBOARD_FAB2(SCH_1):PVCCIN_CPU1
   2    GND      B @BASEBOARD_FAB2_LIB.BASEBOARD_FAB2(SCH_1):GND

CAP_A_0603V-22.0UF,4V,20%,X6S,A  I76  C2D14
   1 PVCCIN_CPU1      A @BASEBOARD_FAB2_LIB.BASEBOARD_FAB2(SCH_1):PVCCIN_CPU1
   2    GND      B @BASEBOARD_FAB2_LIB.BASEBOARD_FAB2(SCH_1):GND

CAP_A_0603V-22.0UF,4V,20%,X6S,A  I79  C2D20
   1 PVCCIN_CPU1      A @BASEBOARD_FAB2_LIB.BASEBOARD_FAB2(SCH_1):PVCCIN_CPU1
   2    GND      B @BASEBOARD_FAB2_LIB.BASEBOARD_FAB2(SCH_1):GND

CAP_A_0603V-22.0UF,4V,20%,X6S,A  I80  C2D24
   1 PVCCIN_CPU1      A @BASEBOARD_FAB2_LIB.BASEBOARD_FAB2(SCH_1):PVCCIN_CPU1
   2    GND      B @BASEBOARD_FAB2_LIB.BASEBOARD_FAB2(SCH_1):GND

CAP_A_0603V-22.0UF,4V,20%,X6S,A  I82  C2D25
   1 PVCCIN_CPU1      A @BASEBOARD_FAB2_LIB.BASEBOARD_FAB2(SCH_1):PVCCIN_CPU1
   2    GND      B @BASEBOARD_FAB2_LIB.BASEBOARD_FAB2(SCH_1):GND

CAP_A_0603V-22.0UF,4V,20%,X6S,A  I83  C2D30
   1 PVCCIN_CPU1      A @BASEBOARD_FAB2_LIB.BASEBOARD_FAB2(SCH_1):PVCCIN_CPU1
   2    GND      B @BASEBOARD_FAB2_LIB.BASEBOARD_FAB2(SCH_1):GND

CAP_A_0603V-22.0UF,4V,20%,X6S,A  I85  C2D33
   1 PVCCIN_CPU1      A @BASEBOARD_FAB2_LIB.BASEBOARD_FAB2(SCH_1):PVCCIN_CPU1
   2    GND      B @BASEBOARD_FAB2_LIB.BASEBOARD_FAB2(SCH_1):GND

CAP_0805-47UF,4V,20%,X6S,C9533A  I88  C8P4
   1 PVCCIN_CPU1      A @BASEBOARD_FAB2_LIB.BASEBOARD_FAB2(SCH_1):PVCCIN_CPU1
   2    GND      B @BASEBOARD_FAB2_LIB.BASEBOARD_FAB2(SCH_1):GND

CAP_0805-47UF,4V,20%,X6S,C9533A  I89  C8P20
   1 PVCCIN_CPU1      A @BASEBOARD_FAB2_LIB.BASEBOARD_FAB2(SCH_1):PVCCIN_CPU1
   2    GND      B @BASEBOARD_FAB2_LIB.BASEBOARD_FAB2(SCH_1):GND

CAP_A_0603V-22.0UF,4V,20%,X6S,A  I90  C2D32
   1 PVCCIN_CPU1      A @BASEBOARD_FAB2_LIB.BASEBOARD_FAB2(SCH_1):PVCCIN_CPU1
   2    GND      B @BASEBOARD_FAB2_LIB.BASEBOARD_FAB2(SCH_1):GND

CAP_0805-47UF,4V,20%,X6S,C9533A  I92  C8P18
   1 PVCCIN_CPU1      A @BASEBOARD_FAB2_LIB.BASEBOARD_FAB2(SCH_1):PVCCIN_CPU1
   2    GND      B @BASEBOARD_FAB2_LIB.BASEBOARD_FAB2(SCH_1):GND

CAP_0805-47UF,4V,20%,X6S,C9533A  I100  C7P2
   1 PVCCIN_CPU1      A @BASEBOARD_FAB2_LIB.BASEBOARD_FAB2(SCH_1):PVCCIN_CPU1
   2    GND      B @BASEBOARD_FAB2_LIB.BASEBOARD_FAB2(SCH_1):GND

CAP_0805-47UF,4V,20%,X6S,C9533A  I101  C8P3
   1 PVCCIN_CPU1      A @BASEBOARD_FAB2_LIB.BASEBOARD_FAB2(SCH_1):PVCCIN_CPU1
   2    GND      B @BASEBOARD_FAB2_LIB.BASEBOARD_FAB2(SCH_1):GND

CAP_0805-47UF,4V,20%,X6S,C9533A  I103  C8P19
   1 PVCCIN_CPU1      A @BASEBOARD_FAB2_LIB.BASEBOARD_FAB2(SCH_1):PVCCIN_CPU1
   2    GND      B @BASEBOARD_FAB2_LIB.BASEBOARD_FAB2(SCH_1):GND

CAP_0805-47UF,4V,20%,X6S,C9533A  I105  C7P1
   1 PVCCIN_CPU1      A @BASEBOARD_FAB2_LIB.BASEBOARD_FAB2(SCH_1):PVCCIN_CPU1
   2    GND      B @BASEBOARD_FAB2_LIB.BASEBOARD_FAB2(SCH_1):GND

CAP_0805-47UF,4V,20%,X6S,C9533A  I106  C8P34
   1 PVCCIN_CPU1      A @BASEBOARD_FAB2_LIB.BASEBOARD_FAB2(SCH_1):PVCCIN_CPU1
   2    GND      B @BASEBOARD_FAB2_LIB.BASEBOARD_FAB2(SCH_1):GND

CAP_0805-47UF,4V,20%,X6S,C9533A  I107  C8P12
   1 PVCCIN_CPU1      A @BASEBOARD_FAB2_LIB.BASEBOARD_FAB2(SCH_1):PVCCIN_CPU1
   2    GND      B @BASEBOARD_FAB2_LIB.BASEBOARD_FAB2(SCH_1):GND

CAP_A_0603V-22.0UF,4V,20%,X6S,A  I108  C2D26
   1 PVCCIN_CPU1      A @BASEBOARD_FAB2_LIB.BASEBOARD_FAB2(SCH_1):PVCCIN_CPU1
   2    GND      B @BASEBOARD_FAB2_LIB.BASEBOARD_FAB2(SCH_1):GND

CAP_A_0603V-22.0UF,4V,20%,X6S,A  I111  C3D1
   1 PVCCIN_CPU1      A @BASEBOARD_FAB2_LIB.BASEBOARD_FAB2(SCH_1):PVCCIN_CPU1
   2    GND      B @BASEBOARD_FAB2_LIB.BASEBOARD_FAB2(SCH_1):GND

CAP_A_0603V-22.0UF,4V,20%,X6S,A  I112  C2D23
   1 PVCCIN_CPU1      A @BASEBOARD_FAB2_LIB.BASEBOARD_FAB2(SCH_1):PVCCIN_CPU1
   2    GND      B @BASEBOARD_FAB2_LIB.BASEBOARD_FAB2(SCH_1):GND

CAP_A_0603V-22.0UF,4V,20%,X6S,A  I114  C2D17
   1 PVCCIN_CPU1      A @BASEBOARD_FAB2_LIB.BASEBOARD_FAB2(SCH_1):PVCCIN_CPU1
   2    GND      B @BASEBOARD_FAB2_LIB.BASEBOARD_FAB2(SCH_1):GND

CAP_A_0603V-22.0UF,4V,20%,X6S,A  I116  C2D1
   1 PVCCIN_CPU1      A @BASEBOARD_FAB2_LIB.BASEBOARD_FAB2(SCH_1):PVCCIN_CPU1
   2    GND      B @BASEBOARD_FAB2_LIB.BASEBOARD_FAB2(SCH_1):GND

CAP_0805-47UF,4V,20%,X6S,C9533A  I118  C8P26
   1 PVCCIN_CPU1      A @BASEBOARD_FAB2_LIB.BASEBOARD_FAB2(SCH_1):PVCCIN_CPU1
   2    GND      B @BASEBOARD_FAB2_LIB.BASEBOARD_FAB2(SCH_1):GND

CAP_A_0603V-22.0UF,4V,20%,X6S,A  I119  C2D37
   1 PVCCIN_CPU1      A @BASEBOARD_FAB2_LIB.BASEBOARD_FAB2(SCH_1):PVCCIN_CPU1
   2    GND      B @BASEBOARD_FAB2_LIB.BASEBOARD_FAB2(SCH_1):GND

CAP_A_0603V-22.0UF,4V,20%,X6S,A  I122  C2D34
   1 PVCCIN_CPU1      A @BASEBOARD_FAB2_LIB.BASEBOARD_FAB2(SCH_1):PVCCIN_CPU1
   2    GND      B @BASEBOARD_FAB2_LIB.BASEBOARD_FAB2(SCH_1):GND

CAP_A_0603V-22.0UF,4V,20%,X6S,A  I123  C2D45
   1 PVCCIN_CPU1      A @BASEBOARD_FAB2_LIB.BASEBOARD_FAB2(SCH_1):PVCCIN_CPU1
   2    GND      B @BASEBOARD_FAB2_LIB.BASEBOARD_FAB2(SCH_1):GND

CAP_A_0603V-22.0UF,4V,20%,X6S,A  I124  C2D16
   1 PVCCIN_CPU1      A @BASEBOARD_FAB2_LIB.BASEBOARD_FAB2(SCH_1):PVCCIN_CPU1
   2    GND      B @BASEBOARD_FAB2_LIB.BASEBOARD_FAB2(SCH_1):GND

CAP_0805-47UF,4V,20%,X6S,C9533A  I125  C8P29
   1 PVCCIN_CPU1      A @BASEBOARD_FAB2_LIB.BASEBOARD_FAB2(SCH_1):PVCCIN_CPU1
   2    GND      B @BASEBOARD_FAB2_LIB.BASEBOARD_FAB2(SCH_1):GND

CAP_0805-47UF,4V,20%,X6S,C9533A  I127  C8P10
   1 PVCCIN_CPU1      A @BASEBOARD_FAB2_LIB.BASEBOARD_FAB2(SCH_1):PVCCIN_CPU1
   2    GND      B @BASEBOARD_FAB2_LIB.BASEBOARD_FAB2(SCH_1):GND

CAP_0805-47UF,4V,20%,X6S,C9533A  I129  C8P16
   1 PVCCIN_CPU1      A @BASEBOARD_FAB2_LIB.BASEBOARD_FAB2(SCH_1):PVCCIN_CPU1
   2    GND      B @BASEBOARD_FAB2_LIB.BASEBOARD_FAB2(SCH_1):GND

CAP_0805-47UF,4V,20%,X6S,C9533A  I131  C8P33
   1 PVCCIN_CPU1      A @BASEBOARD_FAB2_LIB.BASEBOARD_FAB2(SCH_1):PVCCIN_CPU1
   2    GND      B @BASEBOARD_FAB2_LIB.BASEBOARD_FAB2(SCH_1):GND

CAP_0805-47UF,4V,20%,X6S,C9533A  I132  C8P13
   1 PVCCIN_CPU1      A @BASEBOARD_FAB2_LIB.BASEBOARD_FAB2(SCH_1):PVCCIN_CPU1
   2    GND      B @BASEBOARD_FAB2_LIB.BASEBOARD_FAB2(SCH_1):GND

CAP_0805-47UF,4V,20%,X6S,C9533A  I133  C8P17
   1 PVCCIN_CPU1      A @BASEBOARD_FAB2_LIB.BASEBOARD_FAB2(SCH_1):PVCCIN_CPU1
   2    GND      B @BASEBOARD_FAB2_LIB.BASEBOARD_FAB2(SCH_1):GND

CAP_0805-47UF,4V,20%,X6S,C9533A  I135  C8P21
   1 PVCCIN_CPU1      A @BASEBOARD_FAB2_LIB.BASEBOARD_FAB2(SCH_1):PVCCIN_CPU1
   2    GND      B @BASEBOARD_FAB2_LIB.BASEBOARD_FAB2(SCH_1):GND

CAP_0805-47UF,4V,20%,X6S,C9533A  I136  C8P25
   1 PVCCIN_CPU1      A @BASEBOARD_FAB2_LIB.BASEBOARD_FAB2(SCH_1):PVCCIN_CPU1
   2    GND      B @BASEBOARD_FAB2_LIB.BASEBOARD_FAB2(SCH_1):GND

CAP_0805-47UF,4V,20%,X6S,C9533A  I137  C8P28
   1 PVCCIN_CPU1      A @BASEBOARD_FAB2_LIB.BASEBOARD_FAB2(SCH_1):PVCCIN_CPU1
   2    GND      B @BASEBOARD_FAB2_LIB.BASEBOARD_FAB2(SCH_1):GND

CAP_0805-47UF,4V,20%,X6S,C9533A  I139  C8P11
   1 PVCCIN_CPU1      A @BASEBOARD_FAB2_LIB.BASEBOARD_FAB2(SCH_1):PVCCIN_CPU1
   2    GND      B @BASEBOARD_FAB2_LIB.BASEBOARD_FAB2(SCH_1):GND

CAP_0805-47UF,4V,20%,X6S,C9533A  I141  C8P27
   1 PVCCIN_CPU1      A @BASEBOARD_FAB2_LIB.BASEBOARD_FAB2(SCH_1):PVCCIN_CPU1
   2    GND      B @BASEBOARD_FAB2_LIB.BASEBOARD_FAB2(SCH_1):GND

CAP_A_0603V-22.0UF,4V,20%,X6S,A  I159  C2D15
   1 PVCCIN_CPU1      A @BASEBOARD_FAB2_LIB.BASEBOARD_FAB2(SCH_1):PVCCIN_CPU1
   2    GND      B @BASEBOARD_FAB2_LIB.BASEBOARD_FAB2(SCH_1):GND

CAP_A_0603V-22.0UF,4V,20%,X6S,A  I160  C2D38
   1 PVCCIN_CPU1      A @BASEBOARD_FAB2_LIB.BASEBOARD_FAB2(SCH_1):PVCCIN_CPU1
   2    GND      B @BASEBOARD_FAB2_LIB.BASEBOARD_FAB2(SCH_1):GND

CAP_A_0603V-22.0UF,4V,20%,X6S,A  I161  C2D35
   1 PVCCIN_CPU1      A @BASEBOARD_FAB2_LIB.BASEBOARD_FAB2(SCH_1):PVCCIN_CPU1
   2    GND      B @BASEBOARD_FAB2_LIB.BASEBOARD_FAB2(SCH_1):GND

CAP_A_0603V-22.0UF,4V,20%,X6S,A  I164  C3D7
   1 PVCCMCP_CPU1      A @BASEBOARD_FAB2_LIB.BASEBOARD_FAB2(SCH_1):PVCCMCP_CPU1
   2    GND      B @BASEBOARD_FAB2_LIB.BASEBOARD_FAB2(SCH_1):GND

CAP_A_0603V-22.0UF,4V,20%,X6S,A  I165  C2D39
   1 PVCCMCP_CPU1      A @BASEBOARD_FAB2_LIB.BASEBOARD_FAB2(SCH_1):PVCCMCP_CPU1
   2    GND      B @BASEBOARD_FAB2_LIB.BASEBOARD_FAB2(SCH_1):GND

CAP_A_0603V-22.0UF,4V,20%,X6S,A  I166  C3D17
   1 PVCCMCP_CPU1      A @BASEBOARD_FAB2_LIB.BASEBOARD_FAB2(SCH_1):PVCCMCP_CPU1
   2    GND      B @BASEBOARD_FAB2_LIB.BASEBOARD_FAB2(SCH_1):GND

CAP_A_0603V-22.0UF,4V,20%,X6S,A  I169  C3D18
   1 PVCCMCP_CPU1      A @BASEBOARD_FAB2_LIB.BASEBOARD_FAB2(SCH_1):PVCCMCP_CPU1
   2    GND      B @BASEBOARD_FAB2_LIB.BASEBOARD_FAB2(SCH_1):GND

CAP_A_0603V-22.0UF,4V,20%,X6S,A  I170  C3D6
   1 PVCCMCP_CPU1      A @BASEBOARD_FAB2_LIB.BASEBOARD_FAB2(SCH_1):PVCCMCP_CPU1
   2    GND      B @BASEBOARD_FAB2_LIB.BASEBOARD_FAB2(SCH_1):GND

CAP_A_0603V-22.0UF,4V,20%,X6S,A  I171  C3D14
   1 PVCCMCP_CPU1      A @BASEBOARD_FAB2_LIB.BASEBOARD_FAB2(SCH_1):PVCCMCP_CPU1
   2    GND      B @BASEBOARD_FAB2_LIB.BASEBOARD_FAB2(SCH_1):GND

CAP_A_0603V-22.0UF,4V,20%,X6S,A  I172  C3D23
   1 PVCCIO_CPU1      A @BASEBOARD_FAB2_LIB.BASEBOARD_FAB2(SCH_1):PVCCIO_CPU1
   2    GND      B @BASEBOARD_FAB2_LIB.BASEBOARD_FAB2(SCH_1):GND

CAP_A_0603V-22.0UF,4V,20%,X6S,A  I174  C3D15
   1 PVCCIO_CPU1      A @BASEBOARD_FAB2_LIB.BASEBOARD_FAB2(SCH_1):PVCCIO_CPU1
   2    GND      B @BASEBOARD_FAB2_LIB.BASEBOARD_FAB2(SCH_1):GND

CAP_A_0603V-22.0UF,4V,20%,X6S,A  I175  C3D24
   1 PVCCIO_CPU1      A @BASEBOARD_FAB2_LIB.BASEBOARD_FAB2(SCH_1):PVCCIO_CPU1
   2    GND      B @BASEBOARD_FAB2_LIB.BASEBOARD_FAB2(SCH_1):GND

CAP_A_0603V-22.0UF,4V,20%,X6S,A  I176  C3D16
   1 PVCCIO_CPU1      A @BASEBOARD_FAB2_LIB.BASEBOARD_FAB2(SCH_1):PVCCIO_CPU1
   2    GND      B @BASEBOARD_FAB2_LIB.BASEBOARD_FAB2(SCH_1):GND

CAP_A_0603V-22.0UF,4V,20%,X6S,A  I179  C7P12
   1 PVCCIO_CPU1      A @BASEBOARD_FAB2_LIB.BASEBOARD_FAB2(SCH_1):PVCCIO_CPU1
   2    GND      B @BASEBOARD_FAB2_LIB.BASEBOARD_FAB2(SCH_1):GND

CAP_0805-47UF,4V,20%,X6S,C9533A  I181  C7P9
   1 PVCCMCP_CPU1      A @BASEBOARD_FAB2_LIB.BASEBOARD_FAB2(SCH_1):PVCCMCP_CPU1
   2    GND      B @BASEBOARD_FAB2_LIB.BASEBOARD_FAB2(SCH_1):GND

CAP_0805-47UF,4V,20%,X6S,C9533A  I182  C7P5
   1 PVCCMCP_CPU1      A @BASEBOARD_FAB2_LIB.BASEBOARD_FAB2(SCH_1):PVCCMCP_CPU1
   2    GND      B @BASEBOARD_FAB2_LIB.BASEBOARD_FAB2(SCH_1):GND

CAP_0805-47UF,4V,20%,X6S,C9533A  I183  C7P11
   1 PVCCMCP_CPU1      A @BASEBOARD_FAB2_LIB.BASEBOARD_FAB2(SCH_1):PVCCMCP_CPU1
   2    GND      B @BASEBOARD_FAB2_LIB.BASEBOARD_FAB2(SCH_1):GND

CAP_0805-47UF,4V,20%,X6S,C9533A  I184  C7P8
   1 PVCCMCP_CPU1      A @BASEBOARD_FAB2_LIB.BASEBOARD_FAB2(SCH_1):PVCCMCP_CPU1
   2    GND      B @BASEBOARD_FAB2_LIB.BASEBOARD_FAB2(SCH_1):GND

CAP_0805-47UF,4V,20%,X6S,C9533A  I195  C7P4
   1 PVCCMCP_CPU1      A @BASEBOARD_FAB2_LIB.BASEBOARD_FAB2(SCH_1):PVCCMCP_CPU1
   2    GND      B @BASEBOARD_FAB2_LIB.BASEBOARD_FAB2(SCH_1):GND

CAP_A_0603V-22.0UF,4V,20%,X6S,A  I196  C3D10
   1 PVCCMCP_CPU1      A @BASEBOARD_FAB2_LIB.BASEBOARD_FAB2(SCH_1):PVCCMCP_CPU1
   2    GND      B @BASEBOARD_FAB2_LIB.BASEBOARD_FAB2(SCH_1):GND

CAP_A_0603V-22.0UF,4V,20%,X6S,A  I197  C2D18
   1 PVCCMCP_CPU1      A @BASEBOARD_FAB2_LIB.BASEBOARD_FAB2(SCH_1):PVCCMCP_CPU1
   2    GND      B @BASEBOARD_FAB2_LIB.BASEBOARD_FAB2(SCH_1):GND

CAP_A_0603V-22.0UF,4V,20%,X6S,A  I198  C2D28
   1 PVCCMCP_CPU1      A @BASEBOARD_FAB2_LIB.BASEBOARD_FAB2(SCH_1):PVCCMCP_CPU1
   2    GND      B @BASEBOARD_FAB2_LIB.BASEBOARD_FAB2(SCH_1):GND

CAP_A_0603V-22.0UF,4V,20%,X6S,A  I199  C2D29
   1 PVCCMCP_CPU1      A @BASEBOARD_FAB2_LIB.BASEBOARD_FAB2(SCH_1):PVCCMCP_CPU1
   2    GND      B @BASEBOARD_FAB2_LIB.BASEBOARD_FAB2(SCH_1):GND

CAP_A_0603V-22.0UF,4V,20%,X6S,A  I201  C2D2
   1 PVCCIN_CPU1      A @BASEBOARD_FAB2_LIB.BASEBOARD_FAB2(SCH_1):PVCCIN_CPU1
   2    GND      B @BASEBOARD_FAB2_LIB.BASEBOARD_FAB2(SCH_1):GND

CAP_A_0603V-22.0UF,4V,20%,X6S,A  I202  C2D3
   1 PVCCIN_CPU1      A @BASEBOARD_FAB2_LIB.BASEBOARD_FAB2(SCH_1):PVCCIN_CPU1
   2    GND      B @BASEBOARD_FAB2_LIB.BASEBOARD_FAB2(SCH_1):GND

CAP_A_0603V-22.0UF,4V,20%,X6S,A  I203  C2D47
   1 PVCCIN_CPU1      A @BASEBOARD_FAB2_LIB.BASEBOARD_FAB2(SCH_1):PVCCIN_CPU1
   2    GND      B @BASEBOARD_FAB2_LIB.BASEBOARD_FAB2(SCH_1):GND

CAP_A_0603V-22.0UF,4V,20%,X6S,A  I204  C2D46
   1 PVCCIN_CPU1      A @BASEBOARD_FAB2_LIB.BASEBOARD_FAB2(SCH_1):PVCCIN_CPU1
   2    GND      B @BASEBOARD_FAB2_LIB.BASEBOARD_FAB2(SCH_1):GND

CAP_A_0603V-22.0UF,4V,20%,X6S,A  I205  C3D25
   1 PVCCIN_CPU1      A @BASEBOARD_FAB2_LIB.BASEBOARD_FAB2(SCH_1):PVCCIN_CPU1
   2    GND      B @BASEBOARD_FAB2_LIB.BASEBOARD_FAB2(SCH_1):GND

CAP_A_0603V-22.0UF,4V,20%,X6S,A  I206  C7P16
   1 PVCCIO_CPU1      A @BASEBOARD_FAB2_LIB.BASEBOARD_FAB2(SCH_1):PVCCIO_CPU1
   2    GND      B @BASEBOARD_FAB2_LIB.BASEBOARD_FAB2(SCH_1):GND

CAP_A_0603V-22.0UF,4V,20%,X6S,A  I207  C3D20
   1 PVCCMCP_CPU1      A @BASEBOARD_FAB2_LIB.BASEBOARD_FAB2(SCH_1):PVCCMCP_CPU1
   2    GND      B @BASEBOARD_FAB2_LIB.BASEBOARD_FAB2(SCH_1):GND

CAP_A_0603V-22.0UF,4V,20%,X6S,A  I208  C3D19
   1 PVCCMCP_CPU1      A @BASEBOARD_FAB2_LIB.BASEBOARD_FAB2(SCH_1):PVCCMCP_CPU1
   2    GND      B @BASEBOARD_FAB2_LIB.BASEBOARD_FAB2(SCH_1):GND

CAP_0805-47UF,4V,20%,X6S,C9533A  I211  C8P14
   1 PVCCMCP_CPU1      A @BASEBOARD_FAB2_LIB.BASEBOARD_FAB2(SCH_1):PVCCMCP_CPU1
   2    GND      B @BASEBOARD_FAB2_LIB.BASEBOARD_FAB2(SCH_1):GND

CAP_0805-47UF,4V,20%,X6S,C9533A  I212  C8P15
   1 PVCCMCP_CPU1      A @BASEBOARD_FAB2_LIB.BASEBOARD_FAB2(SCH_1):PVCCMCP_CPU1
   2    GND      B @BASEBOARD_FAB2_LIB.BASEBOARD_FAB2(SCH_1):GND

CAP_0805-47UF,4V,20%,X6S,C9533A  I213  C8P8
   1 PVCCMCP_CPU1      A @BASEBOARD_FAB2_LIB.BASEBOARD_FAB2(SCH_1):PVCCMCP_CPU1
   2    GND      B @BASEBOARD_FAB2_LIB.BASEBOARD_FAB2(SCH_1):GND

CAP_0805-47UF,4V,20%,X6S,C9533A  I214  C8P9
   1 PVCCMCP_CPU1      A @BASEBOARD_FAB2_LIB.BASEBOARD_FAB2(SCH_1):PVCCMCP_CPU1
   2    GND      B @BASEBOARD_FAB2_LIB.BASEBOARD_FAB2(SCH_1):GND

CAP_0805-47UF,4V,20%,X6S,C9533A  I215  C7P19
   1 PVCCIN_CPU1      A @BASEBOARD_FAB2_LIB.BASEBOARD_FAB2(SCH_1):PVCCIN_CPU1
   2    GND      B @BASEBOARD_FAB2_LIB.BASEBOARD_FAB2(SCH_1):GND

CAP_0805-47UF,4V,20%,X6S,C9533A  I216  C8P32
   1 PVCCIN_CPU1      A @BASEBOARD_FAB2_LIB.BASEBOARD_FAB2(SCH_1):PVCCIN_CPU1
   2    GND      B @BASEBOARD_FAB2_LIB.BASEBOARD_FAB2(SCH_1):GND

CAP_0805-47UF,4V,20%,X6S,C9533A  I217  C8P24
   1 PVCCIN_CPU1      A @BASEBOARD_FAB2_LIB.BASEBOARD_FAB2(SCH_1):PVCCIN_CPU1
   2    GND      B @BASEBOARD_FAB2_LIB.BASEBOARD_FAB2(SCH_1):GND

CAP_0805-47UF,4V,20%,X6S,C9533A  I218  C7P20
   1 PVCCIN_CPU1      A @BASEBOARD_FAB2_LIB.BASEBOARD_FAB2(SCH_1):PVCCIN_CPU1
   2    GND      B @BASEBOARD_FAB2_LIB.BASEBOARD_FAB2(SCH_1):GND


DRAWING: @BASEBOARD_FAB2_LIB.BASEBOARD_FAB2(SCH_1):PAGE77 

SCONN288_H44441004_PIP-SCONN,HA  I43  J1G1
   2    GND VSS<93> @BASEBOARD_FAB2_LIB.BASEBOARD_FAB2(SCH_1):GND
   4    GND VSS<92> @BASEBOARD_FAB2_LIB.BASEBOARD_FAB2(SCH_1):GND
   6    GND VSS<91> @BASEBOARD_FAB2_LIB.BASEBOARD_FAB2(SCH_1):GND
   9    GND VSS<90> @BASEBOARD_FAB2_LIB.BASEBOARD_FAB2(SCH_1):GND
  11    GND VSS<89> @BASEBOARD_FAB2_LIB.BASEBOARD_FAB2(SCH_1):GND
  13    GND VSS<88> @BASEBOARD_FAB2_LIB.BASEBOARD_FAB2(SCH_1):GND
  15    GND VSS<87> @BASEBOARD_FAB2_LIB.BASEBOARD_FAB2(SCH_1):GND
  17    GND VSS<86> @BASEBOARD_FAB2_LIB.BASEBOARD_FAB2(SCH_1):GND
  20    GND VSS<85> @BASEBOARD_FAB2_LIB.BASEBOARD_FAB2(SCH_1):GND
  22    GND VSS<84> @BASEBOARD_FAB2_LIB.BASEBOARD_FAB2(SCH_1):GND
  24    GND VSS<83> @BASEBOARD_FAB2_LIB.BASEBOARD_FAB2(SCH_1):GND
  26    GND VSS<82> @BASEBOARD_FAB2_LIB.BASEBOARD_FAB2(SCH_1):GND
  28    GND VSS<81> @BASEBOARD_FAB2_LIB.BASEBOARD_FAB2(SCH_1):GND
  31    GND VSS<80> @BASEBOARD_FAB2_LIB.BASEBOARD_FAB2(SCH_1):GND
  33    GND VSS<79> @BASEBOARD_FAB2_LIB.BASEBOARD_FAB2(SCH_1):GND
  35    GND VSS<78> @BASEBOARD_FAB2_LIB.BASEBOARD_FAB2(SCH_1):GND
  37    GND VSS<77> @BASEBOARD_FAB2_LIB.BASEBOARD_FAB2(SCH_1):GND
  39    GND VSS<76> @BASEBOARD_FAB2_LIB.BASEBOARD_FAB2(SCH_1):GND
  42    GND VSS<75> @BASEBOARD_FAB2_LIB.BASEBOARD_FAB2(SCH_1):GND
  44    GND VSS<74> @BASEBOARD_FAB2_LIB.BASEBOARD_FAB2(SCH_1):GND
  46    GND VSS<73> @BASEBOARD_FAB2_LIB.BASEBOARD_FAB2(SCH_1):GND
  48    GND VSS<72> @BASEBOARD_FAB2_LIB.BASEBOARD_FAB2(SCH_1):GND
  50    GND VSS<71> @BASEBOARD_FAB2_LIB.BASEBOARD_FAB2(SCH_1):GND
  53    GND VSS<70> @BASEBOARD_FAB2_LIB.BASEBOARD_FAB2(SCH_1):GND
  55    GND VSS<69> @BASEBOARD_FAB2_LIB.BASEBOARD_FAB2(SCH_1):GND
  57    GND VSS<68> @BASEBOARD_FAB2_LIB.BASEBOARD_FAB2(SCH_1):GND
  94    GND VSS<67> @BASEBOARD_FAB2_LIB.BASEBOARD_FAB2(SCH_1):GND
  96    GND VSS<66> @BASEBOARD_FAB2_LIB.BASEBOARD_FAB2(SCH_1):GND
  98    GND VSS<65> @BASEBOARD_FAB2_LIB.BASEBOARD_FAB2(SCH_1):GND
 101    GND VSS<64> @BASEBOARD_FAB2_LIB.BASEBOARD_FAB2(SCH_1):GND
 103    GND VSS<63> @BASEBOARD_FAB2_LIB.BASEBOARD_FAB2(SCH_1):GND
 105    GND VSS<62> @BASEBOARD_FAB2_LIB.BASEBOARD_FAB2(SCH_1):GND
 107    GND VSS<61> @BASEBOARD_FAB2_LIB.BASEBOARD_FAB2(SCH_1):GND
 109    GND VSS<60> @BASEBOARD_FAB2_LIB.BASEBOARD_FAB2(SCH_1):GND
 112    GND VSS<59> @BASEBOARD_FAB2_LIB.BASEBOARD_FAB2(SCH_1):GND
 114    GND VSS<58> @BASEBOARD_FAB2_LIB.BASEBOARD_FAB2(SCH_1):GND
 116    GND VSS<57> @BASEBOARD_FAB2_LIB.BASEBOARD_FAB2(SCH_1):GND
 118    GND VSS<56> @BASEBOARD_FAB2_LIB.BASEBOARD_FAB2(SCH_1):GND
 120    GND VSS<55> @BASEBOARD_FAB2_LIB.BASEBOARD_FAB2(SCH_1):GND
 123    GND VSS<54> @BASEBOARD_FAB2_LIB.BASEBOARD_FAB2(SCH_1):GND
 125    GND VSS<53> @BASEBOARD_FAB2_LIB.BASEBOARD_FAB2(SCH_1):GND
 127    GND VSS<52> @BASEBOARD_FAB2_LIB.BASEBOARD_FAB2(SCH_1):GND
 129    GND VSS<51> @BASEBOARD_FAB2_LIB.BASEBOARD_FAB2(SCH_1):GND
 131    GND VSS<50> @BASEBOARD_FAB2_LIB.BASEBOARD_FAB2(SCH_1):GND
 134    GND VSS<49> @BASEBOARD_FAB2_LIB.BASEBOARD_FAB2(SCH_1):GND
 136    GND VSS<48> @BASEBOARD_FAB2_LIB.BASEBOARD_FAB2(SCH_1):GND
 138    GND VSS<47> @BASEBOARD_FAB2_LIB.BASEBOARD_FAB2(SCH_1):GND
 147    GND VSS<46> @BASEBOARD_FAB2_LIB.BASEBOARD_FAB2(SCH_1):GND
 149    GND VSS<45> @BASEBOARD_FAB2_LIB.BASEBOARD_FAB2(SCH_1):GND
 151    GND VSS<44> @BASEBOARD_FAB2_LIB.BASEBOARD_FAB2(SCH_1):GND
 154    GND VSS<43> @BASEBOARD_FAB2_LIB.BASEBOARD_FAB2(SCH_1):GND
 156    GND VSS<42> @BASEBOARD_FAB2_LIB.BASEBOARD_FAB2(SCH_1):GND
 158    GND VSS<41> @BASEBOARD_FAB2_LIB.BASEBOARD_FAB2(SCH_1):GND
 160    GND VSS<40> @BASEBOARD_FAB2_LIB.BASEBOARD_FAB2(SCH_1):GND
 162    GND VSS<39> @BASEBOARD_FAB2_LIB.BASEBOARD_FAB2(SCH_1):GND
 165    GND VSS<38> @BASEBOARD_FAB2_LIB.BASEBOARD_FAB2(SCH_1):GND
 167    GND VSS<37> @BASEBOARD_FAB2_LIB.BASEBOARD_FAB2(SCH_1):GND
 169    GND VSS<36> @BASEBOARD_FAB2_LIB.BASEBOARD_FAB2(SCH_1):GND
 171    GND VSS<35> @BASEBOARD_FAB2_LIB.BASEBOARD_FAB2(SCH_1):GND
 173    GND VSS<34> @BASEBOARD_FAB2_LIB.BASEBOARD_FAB2(SCH_1):GND
 176    GND VSS<33> @BASEBOARD_FAB2_LIB.BASEBOARD_FAB2(SCH_1):GND
 178    GND VSS<32> @BASEBOARD_FAB2_LIB.BASEBOARD_FAB2(SCH_1):GND
 180    GND VSS<31> @BASEBOARD_FAB2_LIB.BASEBOARD_FAB2(SCH_1):GND
 182    GND VSS<30> @BASEBOARD_FAB2_LIB.BASEBOARD_FAB2(SCH_1):GND
 184    GND VSS<29> @BASEBOARD_FAB2_LIB.BASEBOARD_FAB2(SCH_1):GND
 187    GND VSS<28> @BASEBOARD_FAB2_LIB.BASEBOARD_FAB2(SCH_1):GND
 189    GND VSS<27> @BASEBOARD_FAB2_LIB.BASEBOARD_FAB2(SCH_1):GND
 191    GND VSS<26> @BASEBOARD_FAB2_LIB.BASEBOARD_FAB2(SCH_1):GND
 193    GND VSS<25> @BASEBOARD_FAB2_LIB.BASEBOARD_FAB2(SCH_1):GND
 195    GND VSS<24> @BASEBOARD_FAB2_LIB.BASEBOARD_FAB2(SCH_1):GND
 198    GND VSS<23> @BASEBOARD_FAB2_LIB.BASEBOARD_FAB2(SCH_1):GND
 200    GND VSS<22> @BASEBOARD_FAB2_LIB.BASEBOARD_FAB2(SCH_1):GND
 202    GND VSS<21> @BASEBOARD_FAB2_LIB.BASEBOARD_FAB2(SCH_1):GND
 239    GND VSS<20> @BASEBOARD_FAB2_LIB.BASEBOARD_FAB2(SCH_1):GND
 241    GND VSS<19> @BASEBOARD_FAB2_LIB.BASEBOARD_FAB2(SCH_1):GND
 243    GND VSS<18> @BASEBOARD_FAB2_LIB.BASEBOARD_FAB2(SCH_1):GND
 246    GND VSS<17> @BASEBOARD_FAB2_LIB.BASEBOARD_FAB2(SCH_1):GND
 248    GND VSS<16> @BASEBOARD_FAB2_LIB.BASEBOARD_FAB2(SCH_1):GND
 250    GND VSS<15> @BASEBOARD_FAB2_LIB.BASEBOARD_FAB2(SCH_1):GND
 252    GND VSS<14> @BASEBOARD_FAB2_LIB.BASEBOARD_FAB2(SCH_1):GND
 254    GND VSS<13> @BASEBOARD_FAB2_LIB.BASEBOARD_FAB2(SCH_1):GND
 257    GND VSS<12> @BASEBOARD_FAB2_LIB.BASEBOARD_FAB2(SCH_1):GND
 259    GND VSS<11> @BASEBOARD_FAB2_LIB.BASEBOARD_FAB2(SCH_1):GND
 261    GND VSS<10> @BASEBOARD_FAB2_LIB.BASEBOARD_FAB2(SCH_1):GND
 263    GND VSS<9> @BASEBOARD_FAB2_LIB.BASEBOARD_FAB2(SCH_1):GND
 265    GND VSS<8> @BASEBOARD_FAB2_LIB.BASEBOARD_FAB2(SCH_1):GND
 268    GND VSS<7> @BASEBOARD_FAB2_LIB.BASEBOARD_FAB2(SCH_1):GND
 270    GND VSS<6> @BASEBOARD_FAB2_LIB.BASEBOARD_FAB2(SCH_1):GND
 272    GND VSS<5> @BASEBOARD_FAB2_LIB.BASEBOARD_FAB2(SCH_1):GND
 274    GND VSS<4> @BASEBOARD_FAB2_LIB.BASEBOARD_FAB2(SCH_1):GND
 276    GND VSS<3> @BASEBOARD_FAB2_LIB.BASEBOARD_FAB2(SCH_1):GND
 279    GND VSS<2> @BASEBOARD_FAB2_LIB.BASEBOARD_FAB2(SCH_1):GND
 281    GND VSS<1> @BASEBOARD_FAB2_LIB.BASEBOARD_FAB2(SCH_1):GND
 283    GND VSS<0> @BASEBOARD_FAB2_LIB.BASEBOARD_FAB2(SCH_1):GND

SCONN288_H44441004_PIP-SCONN,HA  I66  J1G1
 152 M_G_DQS_DN<0>  DQS0N @BASEBOARD_FAB2_LIB.BASEBOARD_FAB2(SCH_1):M_G_DQS_DN(0)
 153 M_G_DQS_DP<0>  DQS0P @BASEBOARD_FAB2_LIB.BASEBOARD_FAB2(SCH_1):M_G_DQS_DP(0)
  19 M_G_DQS_DN<10> DQS10N @BASEBOARD_FAB2_LIB.BASEBOARD_FAB2(SCH_1):M_G_DQS_DN(10)
  18 M_G_DQS_DP<10> DQS10P @BASEBOARD_FAB2_LIB.BASEBOARD_FAB2(SCH_1):M_G_DQS_DP(10)
  30 M_G_DQS_DN<11> DQS11N @BASEBOARD_FAB2_LIB.BASEBOARD_FAB2(SCH_1):M_G_DQS_DN(11)
  29 M_G_DQS_DP<11> DQS11P @BASEBOARD_FAB2_LIB.BASEBOARD_FAB2(SCH_1):M_G_DQS_DP(11)
  41 M_G_DQS_DN<12> DQS12N @BASEBOARD_FAB2_LIB.BASEBOARD_FAB2(SCH_1):M_G_DQS_DN(12)
  40 M_G_DQS_DP<12> DQS12P @BASEBOARD_FAB2_LIB.BASEBOARD_FAB2(SCH_1):M_G_DQS_DP(12)
 100 M_G_DQS_DN<13> DQS13N @BASEBOARD_FAB2_LIB.BASEBOARD_FAB2(SCH_1):M_G_DQS_DN(13)
  99 M_G_DQS_DP<13> DQS13P @BASEBOARD_FAB2_LIB.BASEBOARD_FAB2(SCH_1):M_G_DQS_DP(13)
 111 M_G_DQS_DN<14> DQS14N @BASEBOARD_FAB2_LIB.BASEBOARD_FAB2(SCH_1):M_G_DQS_DN(14)
 110 M_G_DQS_DP<14> DQS14P @BASEBOARD_FAB2_LIB.BASEBOARD_FAB2(SCH_1):M_G_DQS_DP(14)
 122 M_G_DQS_DN<15> DQS15N @BASEBOARD_FAB2_LIB.BASEBOARD_FAB2(SCH_1):M_G_DQS_DN(15)
 121 M_G_DQS_DP<15> DQS15P @BASEBOARD_FAB2_LIB.BASEBOARD_FAB2(SCH_1):M_G_DQS_DP(15)
 133 M_G_DQS_DN<16> DQS16N @BASEBOARD_FAB2_LIB.BASEBOARD_FAB2(SCH_1):M_G_DQS_DN(16)
 132 M_G_DQS_DP<16> DQS16P @BASEBOARD_FAB2_LIB.BASEBOARD_FAB2(SCH_1):M_G_DQS_DP(16)
  52 M_G_DQS_DN<17> DQS17N @BASEBOARD_FAB2_LIB.BASEBOARD_FAB2(SCH_1):M_G_DQS_DN(17)
  51 M_G_DQS_DP<17> DQS17P @BASEBOARD_FAB2_LIB.BASEBOARD_FAB2(SCH_1):M_G_DQS_DP(17)
 163 M_G_DQS_DN<1>  DQS1N @BASEBOARD_FAB2_LIB.BASEBOARD_FAB2(SCH_1):M_G_DQS_DN(1)
 164 M_G_DQS_DP<1>  DQS1P @BASEBOARD_FAB2_LIB.BASEBOARD_FAB2(SCH_1):M_G_DQS_DP(1)
 174 M_G_DQS_DN<2>  DQS2N @BASEBOARD_FAB2_LIB.BASEBOARD_FAB2(SCH_1):M_G_DQS_DN(2)
 175 M_G_DQS_DP<2>  DQS2P @BASEBOARD_FAB2_LIB.BASEBOARD_FAB2(SCH_1):M_G_DQS_DP(2)
 185 M_G_DQS_DN<3>  DQS3N @BASEBOARD_FAB2_LIB.BASEBOARD_FAB2(SCH_1):M_G_DQS_DN(3)
 186 M_G_DQS_DP<3>  DQS3P @BASEBOARD_FAB2_LIB.BASEBOARD_FAB2(SCH_1):M_G_DQS_DP(3)
 244 M_G_DQS_DN<4>  DQS4N @BASEBOARD_FAB2_LIB.BASEBOARD_FAB2(SCH_1):M_G_DQS_DN(4)
 245 M_G_DQS_DP<4>  DQS4P @BASEBOARD_FAB2_LIB.BASEBOARD_FAB2(SCH_1):M_G_DQS_DP(4)
 255 M_G_DQS_DN<5>  DQS5N @BASEBOARD_FAB2_LIB.BASEBOARD_FAB2(SCH_1):M_G_DQS_DN(5)
 256 M_G_DQS_DP<5>  DQS5P @BASEBOARD_FAB2_LIB.BASEBOARD_FAB2(SCH_1):M_G_DQS_DP(5)
 266 M_G_DQS_DN<6>  DQS6N @BASEBOARD_FAB2_LIB.BASEBOARD_FAB2(SCH_1):M_G_DQS_DN(6)
 267 M_G_DQS_DP<6>  DQS6P @BASEBOARD_FAB2_LIB.BASEBOARD_FAB2(SCH_1):M_G_DQS_DP(6)
 277 M_G_DQS_DN<7>  DQS7N @BASEBOARD_FAB2_LIB.BASEBOARD_FAB2(SCH_1):M_G_DQS_DN(7)
 278 M_G_DQS_DP<7>  DQS7P @BASEBOARD_FAB2_LIB.BASEBOARD_FAB2(SCH_1):M_G_DQS_DP(7)
 196 M_G_DQS_DN<8>  DQS8N @BASEBOARD_FAB2_LIB.BASEBOARD_FAB2(SCH_1):M_G_DQS_DN(8)
 197 M_G_DQS_DP<8>  DQS8P @BASEBOARD_FAB2_LIB.BASEBOARD_FAB2(SCH_1):M_G_DQS_DP(8)
   8 M_G_DQS_DN<9>  DQS9N @BASEBOARD_FAB2_LIB.BASEBOARD_FAB2(SCH_1):M_G_DQS_DN(9)
   7 M_G_DQS_DP<9>  DQS9P @BASEBOARD_FAB2_LIB.BASEBOARD_FAB2(SCH_1):M_G_DQS_DP(9)

SCONN288_H44441004_PIP-SCONN,HA  I111  J1G1
  79 M_G_MA<0>     A0 @BASEBOARD_FAB2_LIB.BASEBOARD_FAB2(SCH_1):M_G_MA(0)
  72 M_G_MA<1>     A1 @BASEBOARD_FAB2_LIB.BASEBOARD_FAB2(SCH_1):M_G_MA(1)
 225 M_G_MA<10>    A10 @BASEBOARD_FAB2_LIB.BASEBOARD_FAB2(SCH_1):M_G_MA(10)
 210 M_G_MA<11>    A11 @BASEBOARD_FAB2_LIB.BASEBOARD_FAB2(SCH_1):M_G_MA(11)
  65 M_G_MA<12>    A12 @BASEBOARD_FAB2_LIB.BASEBOARD_FAB2(SCH_1):M_G_MA(12)
 232 M_G_MA<13>    A13 @BASEBOARD_FAB2_LIB.BASEBOARD_FAB2(SCH_1):M_G_MA(13)
 228 M_G_MA<14> A14_WE_N @BASEBOARD_FAB2_LIB.BASEBOARD_FAB2(SCH_1):M_G_MA(14)
  86 M_G_MA<15> A15_CAS_N @BASEBOARD_FAB2_LIB.BASEBOARD_FAB2(SCH_1):M_G_MA(15)
  82 M_G_MA<16> A16_RAS_N @BASEBOARD_FAB2_LIB.BASEBOARD_FAB2(SCH_1):M_G_MA(16)
 234 M_G_MA<17>    A17 @BASEBOARD_FAB2_LIB.BASEBOARD_FAB2(SCH_1):M_G_MA(17)
 216 M_G_MA<2>     A2 @BASEBOARD_FAB2_LIB.BASEBOARD_FAB2(SCH_1):M_G_MA(2)
  71 M_G_MA<3>     A3 @BASEBOARD_FAB2_LIB.BASEBOARD_FAB2(SCH_1):M_G_MA(3)
 214 M_G_MA<4>     A4 @BASEBOARD_FAB2_LIB.BASEBOARD_FAB2(SCH_1):M_G_MA(4)
 213 M_G_MA<5>     A5 @BASEBOARD_FAB2_LIB.BASEBOARD_FAB2(SCH_1):M_G_MA(5)
  69 M_G_MA<6>     A6 @BASEBOARD_FAB2_LIB.BASEBOARD_FAB2(SCH_1):M_G_MA(6)
 211 M_G_MA<7>     A7 @BASEBOARD_FAB2_LIB.BASEBOARD_FAB2(SCH_1):M_G_MA(7)
  68 M_G_MA<8>     A8 @BASEBOARD_FAB2_LIB.BASEBOARD_FAB2(SCH_1):M_G_MA(8)
  66 M_G_MA<9>     A9 @BASEBOARD_FAB2_LIB.BASEBOARD_FAB2(SCH_1):M_G_MA(9)
  62 M_G_ACT_N  ACT_N @BASEBOARD_FAB2_LIB.BASEBOARD_FAB2(SCH_1):M_G_ACT_N
 208 M_G_ALERT_N ALERT_N @BASEBOARD_FAB2_LIB.BASEBOARD_FAB2(SCH_1):M_G_ALERT_N
 224 M_G_BA<1>  BA<1> @BASEBOARD_FAB2_LIB.BASEBOARD_FAB2(SCH_1):M_G_BA(1)
  81 M_G_BA<0>  BA<0> @BASEBOARD_FAB2_LIB.BASEBOARD_FAB2(SCH_1):M_G_BA(0)
 207 M_G_BG<1>  BG<1> @BASEBOARD_FAB2_LIB.BASEBOARD_FAB2(SCH_1):M_G_BG(1)
  63 M_G_BG<0>  BG<0> @BASEBOARD_FAB2_LIB.BASEBOARD_FAB2(SCH_1):M_G_BG(0)
 235 M_G_C<2>   C<2> @BASEBOARD_FAB2_LIB.BASEBOARD_FAB2(SCH_1):M_G_C(2)
 199 M_G_ECC<6>  CB<7> @BASEBOARD_FAB2_LIB.BASEBOARD_FAB2(SCH_1):M_G_ECC(6)
  54 M_G_ECC<7>  CB<6> @BASEBOARD_FAB2_LIB.BASEBOARD_FAB2(SCH_1):M_G_ECC(7)
 192 M_G_ECC<4>  CB<5> @BASEBOARD_FAB2_LIB.BASEBOARD_FAB2(SCH_1):M_G_ECC(4)
  47 M_G_ECC<5>  CB<4> @BASEBOARD_FAB2_LIB.BASEBOARD_FAB2(SCH_1):M_G_ECC(5)
 201 M_G_ECC<2>  CB<3> @BASEBOARD_FAB2_LIB.BASEBOARD_FAB2(SCH_1):M_G_ECC(2)
  56 M_G_ECC<3>  CB<2> @BASEBOARD_FAB2_LIB.BASEBOARD_FAB2(SCH_1):M_G_ECC(3)
 194 M_G_ECC<0>  CB<1> @BASEBOARD_FAB2_LIB.BASEBOARD_FAB2(SCH_1):M_G_ECC(0)
  49 M_G_ECC<1>  CB<0> @BASEBOARD_FAB2_LIB.BASEBOARD_FAB2(SCH_1):M_G_ECC(1)
  75 M_G_CLK_DN<0>   CK0N @BASEBOARD_FAB2_LIB.BASEBOARD_FAB2(SCH_1):M_G_CLK_DN(0)
  74 M_G_CLK_DP<0>   CK0P @BASEBOARD_FAB2_LIB.BASEBOARD_FAB2(SCH_1):M_G_CLK_DP(0)
 219 M_G_CLK_DN<1>   CK1N @BASEBOARD_FAB2_LIB.BASEBOARD_FAB2(SCH_1):M_G_CLK_DN(1)
 218 M_G_CLK_DP<1>   CK1P @BASEBOARD_FAB2_LIB.BASEBOARD_FAB2(SCH_1):M_G_CLK_DP(1)
 203 M_G_CKE<1> CKE<1> @BASEBOARD_FAB2_LIB.BASEBOARD_FAB2(SCH_1):M_G_CKE(1)
  60 M_G_CKE<0> CKE<0> @BASEBOARD_FAB2_LIB.BASEBOARD_FAB2(SCH_1):M_G_CKE(0)
 280 M_G_DQ<62> DQ<63> @BASEBOARD_FAB2_LIB.BASEBOARD_FAB2(SCH_1):M_G_DQ(62)
 135 M_G_DQ<63> DQ<62> @BASEBOARD_FAB2_LIB.BASEBOARD_FAB2(SCH_1):M_G_DQ(63)
 273 M_G_DQ<60> DQ<61> @BASEBOARD_FAB2_LIB.BASEBOARD_FAB2(SCH_1):M_G_DQ(60)
 128 M_G_DQ<61> DQ<60> @BASEBOARD_FAB2_LIB.BASEBOARD_FAB2(SCH_1):M_G_DQ(61)
 282 M_G_DQ<58> DQ<59> @BASEBOARD_FAB2_LIB.BASEBOARD_FAB2(SCH_1):M_G_DQ(58)
 137 M_G_DQ<59> DQ<58> @BASEBOARD_FAB2_LIB.BASEBOARD_FAB2(SCH_1):M_G_DQ(59)
 275 M_G_DQ<56> DQ<57> @BASEBOARD_FAB2_LIB.BASEBOARD_FAB2(SCH_1):M_G_DQ(56)
 130 M_G_DQ<57> DQ<56> @BASEBOARD_FAB2_LIB.BASEBOARD_FAB2(SCH_1):M_G_DQ(57)
 269 M_G_DQ<54> DQ<55> @BASEBOARD_FAB2_LIB.BASEBOARD_FAB2(SCH_1):M_G_DQ(54)
 124 M_G_DQ<55> DQ<54> @BASEBOARD_FAB2_LIB.BASEBOARD_FAB2(SCH_1):M_G_DQ(55)
 262 M_G_DQ<52> DQ<53> @BASEBOARD_FAB2_LIB.BASEBOARD_FAB2(SCH_1):M_G_DQ(52)
 117 M_G_DQ<53> DQ<52> @BASEBOARD_FAB2_LIB.BASEBOARD_FAB2(SCH_1):M_G_DQ(53)
 271 M_G_DQ<50> DQ<51> @BASEBOARD_FAB2_LIB.BASEBOARD_FAB2(SCH_1):M_G_DQ(50)
 126 M_G_DQ<51> DQ<50> @BASEBOARD_FAB2_LIB.BASEBOARD_FAB2(SCH_1):M_G_DQ(51)
 264 M_G_DQ<48> DQ<49> @BASEBOARD_FAB2_LIB.BASEBOARD_FAB2(SCH_1):M_G_DQ(48)
 119 M_G_DQ<49> DQ<48> @BASEBOARD_FAB2_LIB.BASEBOARD_FAB2(SCH_1):M_G_DQ(49)
 258 M_G_DQ<46> DQ<47> @BASEBOARD_FAB2_LIB.BASEBOARD_FAB2(SCH_1):M_G_DQ(46)
 113 M_G_DQ<47> DQ<46> @BASEBOARD_FAB2_LIB.BASEBOARD_FAB2(SCH_1):M_G_DQ(47)
 251 M_G_DQ<44> DQ<45> @BASEBOARD_FAB2_LIB.BASEBOARD_FAB2(SCH_1):M_G_DQ(44)
 106 M_G_DQ<45> DQ<44> @BASEBOARD_FAB2_LIB.BASEBOARD_FAB2(SCH_1):M_G_DQ(45)
 260 M_G_DQ<42> DQ<43> @BASEBOARD_FAB2_LIB.BASEBOARD_FAB2(SCH_1):M_G_DQ(42)
 115 M_G_DQ<43> DQ<42> @BASEBOARD_FAB2_LIB.BASEBOARD_FAB2(SCH_1):M_G_DQ(43)
 253 M_G_DQ<40> DQ<41> @BASEBOARD_FAB2_LIB.BASEBOARD_FAB2(SCH_1):M_G_DQ(40)
 108 M_G_DQ<41> DQ<40> @BASEBOARD_FAB2_LIB.BASEBOARD_FAB2(SCH_1):M_G_DQ(41)
 247 M_G_DQ<38> DQ<39> @BASEBOARD_FAB2_LIB.BASEBOARD_FAB2(SCH_1):M_G_DQ(38)
 102 M_G_DQ<39> DQ<38> @BASEBOARD_FAB2_LIB.BASEBOARD_FAB2(SCH_1):M_G_DQ(39)
 240 M_G_DQ<36> DQ<37> @BASEBOARD_FAB2_LIB.BASEBOARD_FAB2(SCH_1):M_G_DQ(36)
  95 M_G_DQ<37> DQ<36> @BASEBOARD_FAB2_LIB.BASEBOARD_FAB2(SCH_1):M_G_DQ(37)
 249 M_G_DQ<34> DQ<35> @BASEBOARD_FAB2_LIB.BASEBOARD_FAB2(SCH_1):M_G_DQ(34)
 104 M_G_DQ<35> DQ<34> @BASEBOARD_FAB2_LIB.BASEBOARD_FAB2(SCH_1):M_G_DQ(35)
 242 M_G_DQ<32> DQ<33> @BASEBOARD_FAB2_LIB.BASEBOARD_FAB2(SCH_1):M_G_DQ(32)
  97 M_G_DQ<33> DQ<32> @BASEBOARD_FAB2_LIB.BASEBOARD_FAB2(SCH_1):M_G_DQ(33)
 188 M_G_DQ<30> DQ<31> @BASEBOARD_FAB2_LIB.BASEBOARD_FAB2(SCH_1):M_G_DQ(30)
  43 M_G_DQ<31> DQ<30> @BASEBOARD_FAB2_LIB.BASEBOARD_FAB2(SCH_1):M_G_DQ(31)
 181 M_G_DQ<28> DQ<29> @BASEBOARD_FAB2_LIB.BASEBOARD_FAB2(SCH_1):M_G_DQ(28)
  36 M_G_DQ<29> DQ<28> @BASEBOARD_FAB2_LIB.BASEBOARD_FAB2(SCH_1):M_G_DQ(29)
 190 M_G_DQ<26> DQ<27> @BASEBOARD_FAB2_LIB.BASEBOARD_FAB2(SCH_1):M_G_DQ(26)
  45 M_G_DQ<27> DQ<26> @BASEBOARD_FAB2_LIB.BASEBOARD_FAB2(SCH_1):M_G_DQ(27)
 183 M_G_DQ<24> DQ<25> @BASEBOARD_FAB2_LIB.BASEBOARD_FAB2(SCH_1):M_G_DQ(24)
  38 M_G_DQ<25> DQ<24> @BASEBOARD_FAB2_LIB.BASEBOARD_FAB2(SCH_1):M_G_DQ(25)
 177 M_G_DQ<22> DQ<23> @BASEBOARD_FAB2_LIB.BASEBOARD_FAB2(SCH_1):M_G_DQ(22)
  32 M_G_DQ<23> DQ<22> @BASEBOARD_FAB2_LIB.BASEBOARD_FAB2(SCH_1):M_G_DQ(23)
 170 M_G_DQ<20> DQ<21> @BASEBOARD_FAB2_LIB.BASEBOARD_FAB2(SCH_1):M_G_DQ(20)
  25 M_G_DQ<21> DQ<20> @BASEBOARD_FAB2_LIB.BASEBOARD_FAB2(SCH_1):M_G_DQ(21)
 179 M_G_DQ<18> DQ<19> @BASEBOARD_FAB2_LIB.BASEBOARD_FAB2(SCH_1):M_G_DQ(18)
  34 M_G_DQ<19> DQ<18> @BASEBOARD_FAB2_LIB.BASEBOARD_FAB2(SCH_1):M_G_DQ(19)
 172 M_G_DQ<16> DQ<17> @BASEBOARD_FAB2_LIB.BASEBOARD_FAB2(SCH_1):M_G_DQ(16)
  27 M_G_DQ<17> DQ<16> @BASEBOARD_FAB2_LIB.BASEBOARD_FAB2(SCH_1):M_G_DQ(17)
 166 M_G_DQ<14> DQ<15> @BASEBOARD_FAB2_LIB.BASEBOARD_FAB2(SCH_1):M_G_DQ(14)
  21 M_G_DQ<15> DQ<14> @BASEBOARD_FAB2_LIB.BASEBOARD_FAB2(SCH_1):M_G_DQ(15)
 159 M_G_DQ<12> DQ<13> @BASEBOARD_FAB2_LIB.BASEBOARD_FAB2(SCH_1):M_G_DQ(12)
  14 M_G_DQ<13> DQ<12> @BASEBOARD_FAB2_LIB.BASEBOARD_FAB2(SCH_1):M_G_DQ(13)
 168 M_G_DQ<10> DQ<11> @BASEBOARD_FAB2_LIB.BASEBOARD_FAB2(SCH_1):M_G_DQ(10)
  23 M_G_DQ<11> DQ<10> @BASEBOARD_FAB2_LIB.BASEBOARD_FAB2(SCH_1):M_G_DQ(11)
 161 M_G_DQ<8>  DQ<9> @BASEBOARD_FAB2_LIB.BASEBOARD_FAB2(SCH_1):M_G_DQ(8)
  16 M_G_DQ<9>  DQ<8> @BASEBOARD_FAB2_LIB.BASEBOARD_FAB2(SCH_1):M_G_DQ(9)
 155 M_G_DQ<6>  DQ<7> @BASEBOARD_FAB2_LIB.BASEBOARD_FAB2(SCH_1):M_G_DQ(6)
  10 M_G_DQ<7>  DQ<6> @BASEBOARD_FAB2_LIB.BASEBOARD_FAB2(SCH_1):M_G_DQ(7)
 148 M_G_DQ<4>  DQ<5> @BASEBOARD_FAB2_LIB.BASEBOARD_FAB2(SCH_1):M_G_DQ(4)
   3 M_G_DQ<5>  DQ<4> @BASEBOARD_FAB2_LIB.BASEBOARD_FAB2(SCH_1):M_G_DQ(5)
 157 M_G_DQ<2>  DQ<3> @BASEBOARD_FAB2_LIB.BASEBOARD_FAB2(SCH_1):M_G_DQ(2)
  12 M_G_DQ<3>  DQ<2> @BASEBOARD_FAB2_LIB.BASEBOARD_FAB2(SCH_1):M_G_DQ(3)
 150 M_G_DQ<0>  DQ<1> @BASEBOARD_FAB2_LIB.BASEBOARD_FAB2(SCH_1):M_G_DQ(0)
   5 M_G_DQ<1>  DQ<0> @BASEBOARD_FAB2_LIB.BASEBOARD_FAB2(SCH_1):M_G_DQ(1)
  78 FM_DIMM_EVENT_COD_N EVENT_N @BASEBOARD_FAB2_LIB.BASEBOARD_FAB2(SCH_1):FM_DIMM_EVENT_COD_N
  91 M_G_ODT<1> ODT<1> @BASEBOARD_FAB2_LIB.BASEBOARD_FAB2(SCH_1):M_G_ODT(1)
  87 M_G_ODT<0> ODT<0> @BASEBOARD_FAB2_LIB.BASEBOARD_FAB2(SCH_1):M_G_ODT(0)
 222 M_G_PAR    PAR @BASEBOARD_FAB2_LIB.BASEBOARD_FAB2(SCH_1):M_G_PAR
  58 M_GHJ_RST_N RESET_N @BASEBOARD_FAB2_LIB.BASEBOARD_FAB2(SCH_1):M_GHJ_RST_N
 144 TP_CH_G_DIMM_G0_RFU_2 RFU<2> @BASEBOARD_FAB2_LIB.BASEBOARD_FAB2(SCH_1):TP_CH_G_DIMM_G0_RFU_2
 227 TP_CH_G_DIMM_G0_RFU_1 RFU<1> @BASEBOARD_FAB2_LIB.BASEBOARD_FAB2(SCH_1):TP_CH_G_DIMM_G0_RFU_1
 205 TP_CH_G_DIMM_G0_RFU_0 RFU<0> @BASEBOARD_FAB2_LIB.BASEBOARD_FAB2(SCH_1):TP_CH_G_DIMM_G0_RFU_0
  84 M_G_CS_N<0>   S0_N @BASEBOARD_FAB2_LIB.BASEBOARD_FAB2(SCH_1):M_G_CS_N(0)
  89 M_G_CS_N<1>   S1_N @BASEBOARD_FAB2_LIB.BASEBOARD_FAB2(SCH_1):M_G_CS_N(1)
  93 M_G_CS_N<2> S2_N_C<0> @BASEBOARD_FAB2_LIB.BASEBOARD_FAB2(SCH_1):M_G_CS_N(2)
 237 M_G_CS_N<3> S3_N_C<1> @BASEBOARD_FAB2_LIB.BASEBOARD_FAB2(SCH_1):M_G_CS_N(3)
 238    GND  SA<2> @BASEBOARD_FAB2_LIB.BASEBOARD_FAB2(SCH_1):GND
 140    GND  SA<1> @BASEBOARD_FAB2_LIB.BASEBOARD_FAB2(SCH_1):GND
 139    GND  SA<0> @BASEBOARD_FAB2_LIB.BASEBOARD_FAB2(SCH_1):GND
 230 FM_ADR_COMPLETE_GHJ_N SAVE_N_NC @BASEBOARD_FAB2_LIB.BASEBOARD_FAB2(SCH_1):FM_ADR_COMPLETE_GHJ_N
 141 SMB_DDR_GHJ_VPP_SCL    SCL @BASEBOARD_FAB2_LIB.BASEBOARD_FAB2(SCH_1):SMB_DDR_GHJ_VPP_SCL
 285 SMB_DDR_GHJ_VPP_SDA    SDA @BASEBOARD_FAB2_LIB.BASEBOARD_FAB2(SCH_1):SMB_DDR_GHJ_VPP_SDA
 284 PVPP_GHJ VDDSPD @BASEBOARD_FAB2_LIB.BASEBOARD_FAB2(SCH_1):PVPP_GHJ
 146 M_G_VREF VREFCA @BASEBOARD_FAB2_LIB.BASEBOARD_FAB2(SCH_1):M_G_VREF

SCONN288_H44441004_PIP-SCONN,HA  I171  J1G1
   1 P12V_NVDIMM_GHJ 12V<1> @BASEBOARD_FAB2_LIB.BASEBOARD_FAB2(SCH_1):P12V_NVDIMM_GHJ
 145 P12V_NVDIMM_GHJ 12V<0> @BASEBOARD_FAB2_LIB.BASEBOARD_FAB2(SCH_1):P12V_NVDIMM_GHJ
  59 PVDDQ_GHJ VDD<25> @BASEBOARD_FAB2_LIB.BASEBOARD_FAB2(SCH_1):PVDDQ_GHJ
  61 PVDDQ_GHJ VDD<24> @BASEBOARD_FAB2_LIB.BASEBOARD_FAB2(SCH_1):PVDDQ_GHJ
  64 PVDDQ_GHJ VDD<23> @BASEBOARD_FAB2_LIB.BASEBOARD_FAB2(SCH_1):PVDDQ_GHJ
  67 PVDDQ_GHJ VDD<22> @BASEBOARD_FAB2_LIB.BASEBOARD_FAB2(SCH_1):PVDDQ_GHJ
  70 PVDDQ_GHJ VDD<21> @BASEBOARD_FAB2_LIB.BASEBOARD_FAB2(SCH_1):PVDDQ_GHJ
  73 PVDDQ_GHJ VDD<20> @BASEBOARD_FAB2_LIB.BASEBOARD_FAB2(SCH_1):PVDDQ_GHJ
  76 PVDDQ_GHJ VDD<19> @BASEBOARD_FAB2_LIB.BASEBOARD_FAB2(SCH_1):PVDDQ_GHJ
  80 PVDDQ_GHJ VDD<18> @BASEBOARD_FAB2_LIB.BASEBOARD_FAB2(SCH_1):PVDDQ_GHJ
  83 PVDDQ_GHJ VDD<17> @BASEBOARD_FAB2_LIB.BASEBOARD_FAB2(SCH_1):PVDDQ_GHJ
  85 PVDDQ_GHJ VDD<16> @BASEBOARD_FAB2_LIB.BASEBOARD_FAB2(SCH_1):PVDDQ_GHJ
  88 PVDDQ_GHJ VDD<15> @BASEBOARD_FAB2_LIB.BASEBOARD_FAB2(SCH_1):PVDDQ_GHJ
  90 PVDDQ_GHJ VDD<14> @BASEBOARD_FAB2_LIB.BASEBOARD_FAB2(SCH_1):PVDDQ_GHJ
  92 PVDDQ_GHJ VDD<13> @BASEBOARD_FAB2_LIB.BASEBOARD_FAB2(SCH_1):PVDDQ_GHJ
 204 PVDDQ_GHJ VDD<12> @BASEBOARD_FAB2_LIB.BASEBOARD_FAB2(SCH_1):PVDDQ_GHJ
 206 PVDDQ_GHJ VDD<11> @BASEBOARD_FAB2_LIB.BASEBOARD_FAB2(SCH_1):PVDDQ_GHJ
 209 PVDDQ_GHJ VDD<10> @BASEBOARD_FAB2_LIB.BASEBOARD_FAB2(SCH_1):PVDDQ_GHJ
 212 PVDDQ_GHJ VDD<9> @BASEBOARD_FAB2_LIB.BASEBOARD_FAB2(SCH_1):PVDDQ_GHJ
 215 PVDDQ_GHJ VDD<8> @BASEBOARD_FAB2_LIB.BASEBOARD_FAB2(SCH_1):PVDDQ_GHJ
 217 PVDDQ_GHJ VDD<7> @BASEBOARD_FAB2_LIB.BASEBOARD_FAB2(SCH_1):PVDDQ_GHJ
 220 PVDDQ_GHJ VDD<6> @BASEBOARD_FAB2_LIB.BASEBOARD_FAB2(SCH_1):PVDDQ_GHJ
 223 PVDDQ_GHJ VDD<5> @BASEBOARD_FAB2_LIB.BASEBOARD_FAB2(SCH_1):PVDDQ_GHJ
 226 PVDDQ_GHJ VDD<4> @BASEBOARD_FAB2_LIB.BASEBOARD_FAB2(SCH_1):PVDDQ_GHJ
 229 PVDDQ_GHJ VDD<3> @BASEBOARD_FAB2_LIB.BASEBOARD_FAB2(SCH_1):PVDDQ_GHJ
 231 PVDDQ_GHJ VDD<2> @BASEBOARD_FAB2_LIB.BASEBOARD_FAB2(SCH_1):PVDDQ_GHJ
 233 PVDDQ_GHJ VDD<1> @BASEBOARD_FAB2_LIB.BASEBOARD_FAB2(SCH_1):PVDDQ_GHJ
 236 PVDDQ_GHJ VDD<0> @BASEBOARD_FAB2_LIB.BASEBOARD_FAB2(SCH_1):PVDDQ_GHJ
 142 PVPP_GHJ VPP<4> @BASEBOARD_FAB2_LIB.BASEBOARD_FAB2(SCH_1):PVPP_GHJ
 143 PVPP_GHJ VPP<3> @BASEBOARD_FAB2_LIB.BASEBOARD_FAB2(SCH_1):PVPP_GHJ
 288 PVPP_GHJ VPP<2> @BASEBOARD_FAB2_LIB.BASEBOARD_FAB2(SCH_1):PVPP_GHJ
 286 PVPP_GHJ VPP<1> @BASEBOARD_FAB2_LIB.BASEBOARD_FAB2(SCH_1):PVPP_GHJ
 287 PVPP_GHJ VPP<0> @BASEBOARD_FAB2_LIB.BASEBOARD_FAB2(SCH_1):PVPP_GHJ
  77 PVTT_GHJ VTT<1> @BASEBOARD_FAB2_LIB.BASEBOARD_FAB2(SCH_1):PVTT_GHJ
 221 PVTT_GHJ VTT<0> @BASEBOARD_FAB2_LIB.BASEBOARD_FAB2(SCH_1):PVTT_GHJ

CAP_A_0402V-0.01UF,25V,10%,X7RA  I181  C1F22
   1 M_G_VREF      A @BASEBOARD_FAB2_LIB.BASEBOARD_FAB2(SCH_1):M_G_VREF
   2    GND      B @BASEBOARD_FAB2_LIB.BASEBOARD_FAB2(SCH_1):GND


DRAWING: @BASEBOARD_FAB2_LIB.BASEBOARD_FAB2(SCH_1):PAGE78 

CAP_A_0402V-0.01UF,25V,10%,X7RA  I2  C9T7
   1 M_G_VREF      A @BASEBOARD_FAB2_LIB.BASEBOARD_FAB2(SCH_1):M_G_VREF
   2    GND      B @BASEBOARD_FAB2_LIB.BASEBOARD_FAB2(SCH_1):GND

SCONN288_H44441003_PIP-SCONN,HA  I13  J9T1
  79 M_G_MA<0>     A0 @BASEBOARD_FAB2_LIB.BASEBOARD_FAB2(SCH_1):M_G_MA(0)
  72 M_G_MA<1>     A1 @BASEBOARD_FAB2_LIB.BASEBOARD_FAB2(SCH_1):M_G_MA(1)
 225 M_G_MA<10>    A10 @BASEBOARD_FAB2_LIB.BASEBOARD_FAB2(SCH_1):M_G_MA(10)
 210 M_G_MA<11>    A11 @BASEBOARD_FAB2_LIB.BASEBOARD_FAB2(SCH_1):M_G_MA(11)
  65 M_G_MA<12>    A12 @BASEBOARD_FAB2_LIB.BASEBOARD_FAB2(SCH_1):M_G_MA(12)
 232 M_G_MA<13>    A13 @BASEBOARD_FAB2_LIB.BASEBOARD_FAB2(SCH_1):M_G_MA(13)
 228 M_G_MA<14> A14_WE_N @BASEBOARD_FAB2_LIB.BASEBOARD_FAB2(SCH_1):M_G_MA(14)
  86 M_G_MA<15> A15_CAS_N @BASEBOARD_FAB2_LIB.BASEBOARD_FAB2(SCH_1):M_G_MA(15)
  82 M_G_MA<16> A16_RAS_N @BASEBOARD_FAB2_LIB.BASEBOARD_FAB2(SCH_1):M_G_MA(16)
 234 M_G_MA<17>    A17 @BASEBOARD_FAB2_LIB.BASEBOARD_FAB2(SCH_1):M_G_MA(17)
 216 M_G_MA<2>     A2 @BASEBOARD_FAB2_LIB.BASEBOARD_FAB2(SCH_1):M_G_MA(2)
  71 M_G_MA<3>     A3 @BASEBOARD_FAB2_LIB.BASEBOARD_FAB2(SCH_1):M_G_MA(3)
 214 M_G_MA<4>     A4 @BASEBOARD_FAB2_LIB.BASEBOARD_FAB2(SCH_1):M_G_MA(4)
 213 M_G_MA<5>     A5 @BASEBOARD_FAB2_LIB.BASEBOARD_FAB2(SCH_1):M_G_MA(5)
  69 M_G_MA<6>     A6 @BASEBOARD_FAB2_LIB.BASEBOARD_FAB2(SCH_1):M_G_MA(6)
 211 M_G_MA<7>     A7 @BASEBOARD_FAB2_LIB.BASEBOARD_FAB2(SCH_1):M_G_MA(7)
  68 M_G_MA<8>     A8 @BASEBOARD_FAB2_LIB.BASEBOARD_FAB2(SCH_1):M_G_MA(8)
  66 M_G_MA<9>     A9 @BASEBOARD_FAB2_LIB.BASEBOARD_FAB2(SCH_1):M_G_MA(9)
  62 M_G_ACT_N  ACT_N @BASEBOARD_FAB2_LIB.BASEBOARD_FAB2(SCH_1):M_G_ACT_N
 208 M_G_ALERT_N ALERT_N @BASEBOARD_FAB2_LIB.BASEBOARD_FAB2(SCH_1):M_G_ALERT_N
 224 M_G_BA<1>  BA<1> @BASEBOARD_FAB2_LIB.BASEBOARD_FAB2(SCH_1):M_G_BA(1)
  81 M_G_BA<0>  BA<0> @BASEBOARD_FAB2_LIB.BASEBOARD_FAB2(SCH_1):M_G_BA(0)
 207 M_G_BG<1>  BG<1> @BASEBOARD_FAB2_LIB.BASEBOARD_FAB2(SCH_1):M_G_BG(1)
  63 M_G_BG<0>  BG<0> @BASEBOARD_FAB2_LIB.BASEBOARD_FAB2(SCH_1):M_G_BG(0)
 235 M_G_C<2>   C<2> @BASEBOARD_FAB2_LIB.BASEBOARD_FAB2(SCH_1):M_G_C(2)
 199 M_G_ECC<7>  CB<7> @BASEBOARD_FAB2_LIB.BASEBOARD_FAB2(SCH_1):M_G_ECC(7)
  54 M_G_ECC<6>  CB<6> @BASEBOARD_FAB2_LIB.BASEBOARD_FAB2(SCH_1):M_G_ECC(6)
 192 M_G_ECC<5>  CB<5> @BASEBOARD_FAB2_LIB.BASEBOARD_FAB2(SCH_1):M_G_ECC(5)
  47 M_G_ECC<4>  CB<4> @BASEBOARD_FAB2_LIB.BASEBOARD_FAB2(SCH_1):M_G_ECC(4)
 201 M_G_ECC<3>  CB<3> @BASEBOARD_FAB2_LIB.BASEBOARD_FAB2(SCH_1):M_G_ECC(3)
  56 M_G_ECC<2>  CB<2> @BASEBOARD_FAB2_LIB.BASEBOARD_FAB2(SCH_1):M_G_ECC(2)
 194 M_G_ECC<1>  CB<1> @BASEBOARD_FAB2_LIB.BASEBOARD_FAB2(SCH_1):M_G_ECC(1)
  49 M_G_ECC<0>  CB<0> @BASEBOARD_FAB2_LIB.BASEBOARD_FAB2(SCH_1):M_G_ECC(0)
  75 M_G_CLK_DN<2>   CK0N @BASEBOARD_FAB2_LIB.BASEBOARD_FAB2(SCH_1):M_G_CLK_DN(2)
  74 M_G_CLK_DP<2>   CK0P @BASEBOARD_FAB2_LIB.BASEBOARD_FAB2(SCH_1):M_G_CLK_DP(2)
 219 M_G_CLK_DN<3>   CK1N @BASEBOARD_FAB2_LIB.BASEBOARD_FAB2(SCH_1):M_G_CLK_DN(3)
 218 M_G_CLK_DP<3>   CK1P @BASEBOARD_FAB2_LIB.BASEBOARD_FAB2(SCH_1):M_G_CLK_DP(3)
 203 M_G_CKE<3> CKE<1> @BASEBOARD_FAB2_LIB.BASEBOARD_FAB2(SCH_1):M_G_CKE(3)
  60 M_G_CKE<2> CKE<0> @BASEBOARD_FAB2_LIB.BASEBOARD_FAB2(SCH_1):M_G_CKE(2)
 280 M_G_DQ<63> DQ<63> @BASEBOARD_FAB2_LIB.BASEBOARD_FAB2(SCH_1):M_G_DQ(63)
 135 M_G_DQ<62> DQ<62> @BASEBOARD_FAB2_LIB.BASEBOARD_FAB2(SCH_1):M_G_DQ(62)
 273 M_G_DQ<61> DQ<61> @BASEBOARD_FAB2_LIB.BASEBOARD_FAB2(SCH_1):M_G_DQ(61)
 128 M_G_DQ<60> DQ<60> @BASEBOARD_FAB2_LIB.BASEBOARD_FAB2(SCH_1):M_G_DQ(60)
 282 M_G_DQ<59> DQ<59> @BASEBOARD_FAB2_LIB.BASEBOARD_FAB2(SCH_1):M_G_DQ(59)
 137 M_G_DQ<58> DQ<58> @BASEBOARD_FAB2_LIB.BASEBOARD_FAB2(SCH_1):M_G_DQ(58)
 275 M_G_DQ<57> DQ<57> @BASEBOARD_FAB2_LIB.BASEBOARD_FAB2(SCH_1):M_G_DQ(57)
 130 M_G_DQ<56> DQ<56> @BASEBOARD_FAB2_LIB.BASEBOARD_FAB2(SCH_1):M_G_DQ(56)
 269 M_G_DQ<55> DQ<55> @BASEBOARD_FAB2_LIB.BASEBOARD_FAB2(SCH_1):M_G_DQ(55)
 124 M_G_DQ<54> DQ<54> @BASEBOARD_FAB2_LIB.BASEBOARD_FAB2(SCH_1):M_G_DQ(54)
 262 M_G_DQ<53> DQ<53> @BASEBOARD_FAB2_LIB.BASEBOARD_FAB2(SCH_1):M_G_DQ(53)
 117 M_G_DQ<52> DQ<52> @BASEBOARD_FAB2_LIB.BASEBOARD_FAB2(SCH_1):M_G_DQ(52)
 271 M_G_DQ<51> DQ<51> @BASEBOARD_FAB2_LIB.BASEBOARD_FAB2(SCH_1):M_G_DQ(51)
 126 M_G_DQ<50> DQ<50> @BASEBOARD_FAB2_LIB.BASEBOARD_FAB2(SCH_1):M_G_DQ(50)
 264 M_G_DQ<49> DQ<49> @BASEBOARD_FAB2_LIB.BASEBOARD_FAB2(SCH_1):M_G_DQ(49)
 119 M_G_DQ<48> DQ<48> @BASEBOARD_FAB2_LIB.BASEBOARD_FAB2(SCH_1):M_G_DQ(48)
 258 M_G_DQ<47> DQ<47> @BASEBOARD_FAB2_LIB.BASEBOARD_FAB2(SCH_1):M_G_DQ(47)
 113 M_G_DQ<46> DQ<46> @BASEBOARD_FAB2_LIB.BASEBOARD_FAB2(SCH_1):M_G_DQ(46)
 251 M_G_DQ<45> DQ<45> @BASEBOARD_FAB2_LIB.BASEBOARD_FAB2(SCH_1):M_G_DQ(45)
 106 M_G_DQ<44> DQ<44> @BASEBOARD_FAB2_LIB.BASEBOARD_FAB2(SCH_1):M_G_DQ(44)
 260 M_G_DQ<43> DQ<43> @BASEBOARD_FAB2_LIB.BASEBOARD_FAB2(SCH_1):M_G_DQ(43)
 115 M_G_DQ<42> DQ<42> @BASEBOARD_FAB2_LIB.BASEBOARD_FAB2(SCH_1):M_G_DQ(42)
 253 M_G_DQ<41> DQ<41> @BASEBOARD_FAB2_LIB.BASEBOARD_FAB2(SCH_1):M_G_DQ(41)
 108 M_G_DQ<40> DQ<40> @BASEBOARD_FAB2_LIB.BASEBOARD_FAB2(SCH_1):M_G_DQ(40)
 247 M_G_DQ<39> DQ<39> @BASEBOARD_FAB2_LIB.BASEBOARD_FAB2(SCH_1):M_G_DQ(39)
 102 M_G_DQ<38> DQ<38> @BASEBOARD_FAB2_LIB.BASEBOARD_FAB2(SCH_1):M_G_DQ(38)
 240 M_G_DQ<37> DQ<37> @BASEBOARD_FAB2_LIB.BASEBOARD_FAB2(SCH_1):M_G_DQ(37)
  95 M_G_DQ<36> DQ<36> @BASEBOARD_FAB2_LIB.BASEBOARD_FAB2(SCH_1):M_G_DQ(36)
 249 M_G_DQ<35> DQ<35> @BASEBOARD_FAB2_LIB.BASEBOARD_FAB2(SCH_1):M_G_DQ(35)
 104 M_G_DQ<34> DQ<34> @BASEBOARD_FAB2_LIB.BASEBOARD_FAB2(SCH_1):M_G_DQ(34)
 242 M_G_DQ<33> DQ<33> @BASEBOARD_FAB2_LIB.BASEBOARD_FAB2(SCH_1):M_G_DQ(33)
  97 M_G_DQ<32> DQ<32> @BASEBOARD_FAB2_LIB.BASEBOARD_FAB2(SCH_1):M_G_DQ(32)
 188 M_G_DQ<31> DQ<31> @BASEBOARD_FAB2_LIB.BASEBOARD_FAB2(SCH_1):M_G_DQ(31)
  43 M_G_DQ<30> DQ<30> @BASEBOARD_FAB2_LIB.BASEBOARD_FAB2(SCH_1):M_G_DQ(30)
 181 M_G_DQ<29> DQ<29> @BASEBOARD_FAB2_LIB.BASEBOARD_FAB2(SCH_1):M_G_DQ(29)
  36 M_G_DQ<28> DQ<28> @BASEBOARD_FAB2_LIB.BASEBOARD_FAB2(SCH_1):M_G_DQ(28)
 190 M_G_DQ<27> DQ<27> @BASEBOARD_FAB2_LIB.BASEBOARD_FAB2(SCH_1):M_G_DQ(27)
  45 M_G_DQ<26> DQ<26> @BASEBOARD_FAB2_LIB.BASEBOARD_FAB2(SCH_1):M_G_DQ(26)
 183 M_G_DQ<25> DQ<25> @BASEBOARD_FAB2_LIB.BASEBOARD_FAB2(SCH_1):M_G_DQ(25)
  38 M_G_DQ<24> DQ<24> @BASEBOARD_FAB2_LIB.BASEBOARD_FAB2(SCH_1):M_G_DQ(24)
 177 M_G_DQ<23> DQ<23> @BASEBOARD_FAB2_LIB.BASEBOARD_FAB2(SCH_1):M_G_DQ(23)
  32 M_G_DQ<22> DQ<22> @BASEBOARD_FAB2_LIB.BASEBOARD_FAB2(SCH_1):M_G_DQ(22)
 170 M_G_DQ<21> DQ<21> @BASEBOARD_FAB2_LIB.BASEBOARD_FAB2(SCH_1):M_G_DQ(21)
  25 M_G_DQ<20> DQ<20> @BASEBOARD_FAB2_LIB.BASEBOARD_FAB2(SCH_1):M_G_DQ(20)
 179 M_G_DQ<19> DQ<19> @BASEBOARD_FAB2_LIB.BASEBOARD_FAB2(SCH_1):M_G_DQ(19)
  34 M_G_DQ<18> DQ<18> @BASEBOARD_FAB2_LIB.BASEBOARD_FAB2(SCH_1):M_G_DQ(18)
 172 M_G_DQ<17> DQ<17> @BASEBOARD_FAB2_LIB.BASEBOARD_FAB2(SCH_1):M_G_DQ(17)
  27 M_G_DQ<16> DQ<16> @BASEBOARD_FAB2_LIB.BASEBOARD_FAB2(SCH_1):M_G_DQ(16)
 166 M_G_DQ<15> DQ<15> @BASEBOARD_FAB2_LIB.BASEBOARD_FAB2(SCH_1):M_G_DQ(15)
  21 M_G_DQ<14> DQ<14> @BASEBOARD_FAB2_LIB.BASEBOARD_FAB2(SCH_1):M_G_DQ(14)
 159 M_G_DQ<13> DQ<13> @BASEBOARD_FAB2_LIB.BASEBOARD_FAB2(SCH_1):M_G_DQ(13)
  14 M_G_DQ<12> DQ<12> @BASEBOARD_FAB2_LIB.BASEBOARD_FAB2(SCH_1):M_G_DQ(12)
 168 M_G_DQ<11> DQ<11> @BASEBOARD_FAB2_LIB.BASEBOARD_FAB2(SCH_1):M_G_DQ(11)
  23 M_G_DQ<10> DQ<10> @BASEBOARD_FAB2_LIB.BASEBOARD_FAB2(SCH_1):M_G_DQ(10)
 161 M_G_DQ<9>  DQ<9> @BASEBOARD_FAB2_LIB.BASEBOARD_FAB2(SCH_1):M_G_DQ(9)
  16 M_G_DQ<8>  DQ<8> @BASEBOARD_FAB2_LIB.BASEBOARD_FAB2(SCH_1):M_G_DQ(8)
 155 M_G_DQ<7>  DQ<7> @BASEBOARD_FAB2_LIB.BASEBOARD_FAB2(SCH_1):M_G_DQ(7)
  10 M_G_DQ<6>  DQ<6> @BASEBOARD_FAB2_LIB.BASEBOARD_FAB2(SCH_1):M_G_DQ(6)
 148 M_G_DQ<5>  DQ<5> @BASEBOARD_FAB2_LIB.BASEBOARD_FAB2(SCH_1):M_G_DQ(5)
   3 M_G_DQ<4>  DQ<4> @BASEBOARD_FAB2_LIB.BASEBOARD_FAB2(SCH_1):M_G_DQ(4)
 157 M_G_DQ<3>  DQ<3> @BASEBOARD_FAB2_LIB.BASEBOARD_FAB2(SCH_1):M_G_DQ(3)
  12 M_G_DQ<2>  DQ<2> @BASEBOARD_FAB2_LIB.BASEBOARD_FAB2(SCH_1):M_G_DQ(2)
 150 M_G_DQ<1>  DQ<1> @BASEBOARD_FAB2_LIB.BASEBOARD_FAB2(SCH_1):M_G_DQ(1)
   5 M_G_DQ<0>  DQ<0> @BASEBOARD_FAB2_LIB.BASEBOARD_FAB2(SCH_1):M_G_DQ(0)
  78 FM_DIMM_EVENT_COD_N EVENT_N @BASEBOARD_FAB2_LIB.BASEBOARD_FAB2(SCH_1):FM_DIMM_EVENT_COD_N
  91 M_G_ODT<3> ODT<1> @BASEBOARD_FAB2_LIB.BASEBOARD_FAB2(SCH_1):M_G_ODT(3)
  87 M_G_ODT<2> ODT<0> @BASEBOARD_FAB2_LIB.BASEBOARD_FAB2(SCH_1):M_G_ODT(2)
 222 M_G_PAR    PAR @BASEBOARD_FAB2_LIB.BASEBOARD_FAB2(SCH_1):M_G_PAR
  58 M_GHJ_RST_N RESET_N @BASEBOARD_FAB2_LIB.BASEBOARD_FAB2(SCH_1):M_GHJ_RST_N
 144 TP_CH_G_DIMM0_RFU_2 RFU<2> @BASEBOARD_FAB2_LIB.BASEBOARD_FAB2(SCH_1):TP_CH_G_DIMM0_RFU_2
 227 TP_CH_G_DIMM0_RFU_1 RFU<1> @BASEBOARD_FAB2_LIB.BASEBOARD_FAB2(SCH_1):TP_CH_G_DIMM0_RFU_1
 205 TP_CH_G_DIMM0_RFU_0 RFU<0> @BASEBOARD_FAB2_LIB.BASEBOARD_FAB2(SCH_1):TP_CH_G_DIMM0_RFU_0
  84 M_G_CS_N<4>   S0_N @BASEBOARD_FAB2_LIB.BASEBOARD_FAB2(SCH_1):M_G_CS_N(4)
  89 M_G_CS_N<5>   S1_N @BASEBOARD_FAB2_LIB.BASEBOARD_FAB2(SCH_1):M_G_CS_N(5)
  93 M_G_CS_N<6> S2_N_C<0> @BASEBOARD_FAB2_LIB.BASEBOARD_FAB2(SCH_1):M_G_CS_N(6)
 237 M_G_CS_N<7> S3_N_C<1> @BASEBOARD_FAB2_LIB.BASEBOARD_FAB2(SCH_1):M_G_CS_N(7)
 238    GND  SA<2> @BASEBOARD_FAB2_LIB.BASEBOARD_FAB2(SCH_1):GND
 140    GND  SA<1> @BASEBOARD_FAB2_LIB.BASEBOARD_FAB2(SCH_1):GND
 139 PVPP_GHJ  SA<0> @BASEBOARD_FAB2_LIB.BASEBOARD_FAB2(SCH_1):PVPP_GHJ
 230 FM_ADR_COMPLETE_GHJ_N SAVE_N_NC @BASEBOARD_FAB2_LIB.BASEBOARD_FAB2(SCH_1):FM_ADR_COMPLETE_GHJ_N
 141 SMB_DDR_GHJ_VPP_SCL    SCL @BASEBOARD_FAB2_LIB.BASEBOARD_FAB2(SCH_1):SMB_DDR_GHJ_VPP_SCL
 285 SMB_DDR_GHJ_VPP_SDA    SDA @BASEBOARD_FAB2_LIB.BASEBOARD_FAB2(SCH_1):SMB_DDR_GHJ_VPP_SDA
 284 PVPP_GHJ VDDSPD @BASEBOARD_FAB2_LIB.BASEBOARD_FAB2(SCH_1):PVPP_GHJ
 146 M_G_VREF VREFCA @BASEBOARD_FAB2_LIB.BASEBOARD_FAB2(SCH_1):M_G_VREF

SCONN288_H44441003_PIP-SCONN,HA  I75  J9T1
   1 P12V_NVDIMM_GHJ 12V<1> @BASEBOARD_FAB2_LIB.BASEBOARD_FAB2(SCH_1):P12V_NVDIMM_GHJ
 145 P12V_NVDIMM_GHJ 12V<0> @BASEBOARD_FAB2_LIB.BASEBOARD_FAB2(SCH_1):P12V_NVDIMM_GHJ
  59 PVDDQ_GHJ VDD<25> @BASEBOARD_FAB2_LIB.BASEBOARD_FAB2(SCH_1):PVDDQ_GHJ
  61 PVDDQ_GHJ VDD<24> @BASEBOARD_FAB2_LIB.BASEBOARD_FAB2(SCH_1):PVDDQ_GHJ
  64 PVDDQ_GHJ VDD<23> @BASEBOARD_FAB2_LIB.BASEBOARD_FAB2(SCH_1):PVDDQ_GHJ
  67 PVDDQ_GHJ VDD<22> @BASEBOARD_FAB2_LIB.BASEBOARD_FAB2(SCH_1):PVDDQ_GHJ
  70 PVDDQ_GHJ VDD<21> @BASEBOARD_FAB2_LIB.BASEBOARD_FAB2(SCH_1):PVDDQ_GHJ
  73 PVDDQ_GHJ VDD<20> @BASEBOARD_FAB2_LIB.BASEBOARD_FAB2(SCH_1):PVDDQ_GHJ
  76 PVDDQ_GHJ VDD<19> @BASEBOARD_FAB2_LIB.BASEBOARD_FAB2(SCH_1):PVDDQ_GHJ
  80 PVDDQ_GHJ VDD<18> @BASEBOARD_FAB2_LIB.BASEBOARD_FAB2(SCH_1):PVDDQ_GHJ
  83 PVDDQ_GHJ VDD<17> @BASEBOARD_FAB2_LIB.BASEBOARD_FAB2(SCH_1):PVDDQ_GHJ
  85 PVDDQ_GHJ VDD<16> @BASEBOARD_FAB2_LIB.BASEBOARD_FAB2(SCH_1):PVDDQ_GHJ
  88 PVDDQ_GHJ VDD<15> @BASEBOARD_FAB2_LIB.BASEBOARD_FAB2(SCH_1):PVDDQ_GHJ
  90 PVDDQ_GHJ VDD<14> @BASEBOARD_FAB2_LIB.BASEBOARD_FAB2(SCH_1):PVDDQ_GHJ
  92 PVDDQ_GHJ VDD<13> @BASEBOARD_FAB2_LIB.BASEBOARD_FAB2(SCH_1):PVDDQ_GHJ
 204 PVDDQ_GHJ VDD<12> @BASEBOARD_FAB2_LIB.BASEBOARD_FAB2(SCH_1):PVDDQ_GHJ
 206 PVDDQ_GHJ VDD<11> @BASEBOARD_FAB2_LIB.BASEBOARD_FAB2(SCH_1):PVDDQ_GHJ
 209 PVDDQ_GHJ VDD<10> @BASEBOARD_FAB2_LIB.BASEBOARD_FAB2(SCH_1):PVDDQ_GHJ
 212 PVDDQ_GHJ VDD<9> @BASEBOARD_FAB2_LIB.BASEBOARD_FAB2(SCH_1):PVDDQ_GHJ
 215 PVDDQ_GHJ VDD<8> @BASEBOARD_FAB2_LIB.BASEBOARD_FAB2(SCH_1):PVDDQ_GHJ
 217 PVDDQ_GHJ VDD<7> @BASEBOARD_FAB2_LIB.BASEBOARD_FAB2(SCH_1):PVDDQ_GHJ
 220 PVDDQ_GHJ VDD<6> @BASEBOARD_FAB2_LIB.BASEBOARD_FAB2(SCH_1):PVDDQ_GHJ
 223 PVDDQ_GHJ VDD<5> @BASEBOARD_FAB2_LIB.BASEBOARD_FAB2(SCH_1):PVDDQ_GHJ
 226 PVDDQ_GHJ VDD<4> @BASEBOARD_FAB2_LIB.BASEBOARD_FAB2(SCH_1):PVDDQ_GHJ
 229 PVDDQ_GHJ VDD<3> @BASEBOARD_FAB2_LIB.BASEBOARD_FAB2(SCH_1):PVDDQ_GHJ
 231 PVDDQ_GHJ VDD<2> @BASEBOARD_FAB2_LIB.BASEBOARD_FAB2(SCH_1):PVDDQ_GHJ
 233 PVDDQ_GHJ VDD<1> @BASEBOARD_FAB2_LIB.BASEBOARD_FAB2(SCH_1):PVDDQ_GHJ
 236 PVDDQ_GHJ VDD<0> @BASEBOARD_FAB2_LIB.BASEBOARD_FAB2(SCH_1):PVDDQ_GHJ
 142 PVPP_GHJ VPP<4> @BASEBOARD_FAB2_LIB.BASEBOARD_FAB2(SCH_1):PVPP_GHJ
 143 PVPP_GHJ VPP<3> @BASEBOARD_FAB2_LIB.BASEBOARD_FAB2(SCH_1):PVPP_GHJ
 288 PVPP_GHJ VPP<2> @BASEBOARD_FAB2_LIB.BASEBOARD_FAB2(SCH_1):PVPP_GHJ
 286 PVPP_GHJ VPP<1> @BASEBOARD_FAB2_LIB.BASEBOARD_FAB2(SCH_1):PVPP_GHJ
 287 PVPP_GHJ VPP<0> @BASEBOARD_FAB2_LIB.BASEBOARD_FAB2(SCH_1):PVPP_GHJ
  77 PVTT_GHJ VTT<1> @BASEBOARD_FAB2_LIB.BASEBOARD_FAB2(SCH_1):PVTT_GHJ
 221 PVTT_GHJ VTT<0> @BASEBOARD_FAB2_LIB.BASEBOARD_FAB2(SCH_1):PVTT_GHJ

SCONN288_H44441003_PIP-SCONN,HA  I120  J9T1
 152 M_G_DQS_DN<0>  DQS0N @BASEBOARD_FAB2_LIB.BASEBOARD_FAB2(SCH_1):M_G_DQS_DN(0)
 153 M_G_DQS_DP<0>  DQS0P @BASEBOARD_FAB2_LIB.BASEBOARD_FAB2(SCH_1):M_G_DQS_DP(0)
  19 M_G_DQS_DN<10> DQS10N @BASEBOARD_FAB2_LIB.BASEBOARD_FAB2(SCH_1):M_G_DQS_DN(10)
  18 M_G_DQS_DP<10> DQS10P @BASEBOARD_FAB2_LIB.BASEBOARD_FAB2(SCH_1):M_G_DQS_DP(10)
  30 M_G_DQS_DN<11> DQS11N @BASEBOARD_FAB2_LIB.BASEBOARD_FAB2(SCH_1):M_G_DQS_DN(11)
  29 M_G_DQS_DP<11> DQS11P @BASEBOARD_FAB2_LIB.BASEBOARD_FAB2(SCH_1):M_G_DQS_DP(11)
  41 M_G_DQS_DN<12> DQS12N @BASEBOARD_FAB2_LIB.BASEBOARD_FAB2(SCH_1):M_G_DQS_DN(12)
  40 M_G_DQS_DP<12> DQS12P @BASEBOARD_FAB2_LIB.BASEBOARD_FAB2(SCH_1):M_G_DQS_DP(12)
 100 M_G_DQS_DN<13> DQS13N @BASEBOARD_FAB2_LIB.BASEBOARD_FAB2(SCH_1):M_G_DQS_DN(13)
  99 M_G_DQS_DP<13> DQS13P @BASEBOARD_FAB2_LIB.BASEBOARD_FAB2(SCH_1):M_G_DQS_DP(13)
 111 M_G_DQS_DN<14> DQS14N @BASEBOARD_FAB2_LIB.BASEBOARD_FAB2(SCH_1):M_G_DQS_DN(14)
 110 M_G_DQS_DP<14> DQS14P @BASEBOARD_FAB2_LIB.BASEBOARD_FAB2(SCH_1):M_G_DQS_DP(14)
 122 M_G_DQS_DN<15> DQS15N @BASEBOARD_FAB2_LIB.BASEBOARD_FAB2(SCH_1):M_G_DQS_DN(15)
 121 M_G_DQS_DP<15> DQS15P @BASEBOARD_FAB2_LIB.BASEBOARD_FAB2(SCH_1):M_G_DQS_DP(15)
 133 M_G_DQS_DN<16> DQS16N @BASEBOARD_FAB2_LIB.BASEBOARD_FAB2(SCH_1):M_G_DQS_DN(16)
 132 M_G_DQS_DP<16> DQS16P @BASEBOARD_FAB2_LIB.BASEBOARD_FAB2(SCH_1):M_G_DQS_DP(16)
  52 M_G_DQS_DN<17> DQS17N @BASEBOARD_FAB2_LIB.BASEBOARD_FAB2(SCH_1):M_G_DQS_DN(17)
  51 M_G_DQS_DP<17> DQS17P @BASEBOARD_FAB2_LIB.BASEBOARD_FAB2(SCH_1):M_G_DQS_DP(17)
 163 M_G_DQS_DN<1>  DQS1N @BASEBOARD_FAB2_LIB.BASEBOARD_FAB2(SCH_1):M_G_DQS_DN(1)
 164 M_G_DQS_DP<1>  DQS1P @BASEBOARD_FAB2_LIB.BASEBOARD_FAB2(SCH_1):M_G_DQS_DP(1)
 174 M_G_DQS_DN<2>  DQS2N @BASEBOARD_FAB2_LIB.BASEBOARD_FAB2(SCH_1):M_G_DQS_DN(2)
 175 M_G_DQS_DP<2>  DQS2P @BASEBOARD_FAB2_LIB.BASEBOARD_FAB2(SCH_1):M_G_DQS_DP(2)
 185 M_G_DQS_DN<3>  DQS3N @BASEBOARD_FAB2_LIB.BASEBOARD_FAB2(SCH_1):M_G_DQS_DN(3)
 186 M_G_DQS_DP<3>  DQS3P @BASEBOARD_FAB2_LIB.BASEBOARD_FAB2(SCH_1):M_G_DQS_DP(3)
 244 M_G_DQS_DN<4>  DQS4N @BASEBOARD_FAB2_LIB.BASEBOARD_FAB2(SCH_1):M_G_DQS_DN(4)
 245 M_G_DQS_DP<4>  DQS4P @BASEBOARD_FAB2_LIB.BASEBOARD_FAB2(SCH_1):M_G_DQS_DP(4)
 255 M_G_DQS_DN<5>  DQS5N @BASEBOARD_FAB2_LIB.BASEBOARD_FAB2(SCH_1):M_G_DQS_DN(5)
 256 M_G_DQS_DP<5>  DQS5P @BASEBOARD_FAB2_LIB.BASEBOARD_FAB2(SCH_1):M_G_DQS_DP(5)
 266 M_G_DQS_DN<6>  DQS6N @BASEBOARD_FAB2_LIB.BASEBOARD_FAB2(SCH_1):M_G_DQS_DN(6)
 267 M_G_DQS_DP<6>  DQS6P @BASEBOARD_FAB2_LIB.BASEBOARD_FAB2(SCH_1):M_G_DQS_DP(6)
 277 M_G_DQS_DN<7>  DQS7N @BASEBOARD_FAB2_LIB.BASEBOARD_FAB2(SCH_1):M_G_DQS_DN(7)
 278 M_G_DQS_DP<7>  DQS7P @BASEBOARD_FAB2_LIB.BASEBOARD_FAB2(SCH_1):M_G_DQS_DP(7)
 196 M_G_DQS_DN<8>  DQS8N @BASEBOARD_FAB2_LIB.BASEBOARD_FAB2(SCH_1):M_G_DQS_DN(8)
 197 M_G_DQS_DP<8>  DQS8P @BASEBOARD_FAB2_LIB.BASEBOARD_FAB2(SCH_1):M_G_DQS_DP(8)
   8 M_G_DQS_DN<9>  DQS9N @BASEBOARD_FAB2_LIB.BASEBOARD_FAB2(SCH_1):M_G_DQS_DN(9)
   7 M_G_DQS_DP<9>  DQS9P @BASEBOARD_FAB2_LIB.BASEBOARD_FAB2(SCH_1):M_G_DQS_DP(9)

SCONN288_H44441003_PIP-SCONN,HA  I144  J9T1
   2    GND VSS<93> @BASEBOARD_FAB2_LIB.BASEBOARD_FAB2(SCH_1):GND
   4    GND VSS<92> @BASEBOARD_FAB2_LIB.BASEBOARD_FAB2(SCH_1):GND
   6    GND VSS<91> @BASEBOARD_FAB2_LIB.BASEBOARD_FAB2(SCH_1):GND
   9    GND VSS<90> @BASEBOARD_FAB2_LIB.BASEBOARD_FAB2(SCH_1):GND
  11    GND VSS<89> @BASEBOARD_FAB2_LIB.BASEBOARD_FAB2(SCH_1):GND
  13    GND VSS<88> @BASEBOARD_FAB2_LIB.BASEBOARD_FAB2(SCH_1):GND
  15    GND VSS<87> @BASEBOARD_FAB2_LIB.BASEBOARD_FAB2(SCH_1):GND
  17    GND VSS<86> @BASEBOARD_FAB2_LIB.BASEBOARD_FAB2(SCH_1):GND
  20    GND VSS<85> @BASEBOARD_FAB2_LIB.BASEBOARD_FAB2(SCH_1):GND
  22    GND VSS<84> @BASEBOARD_FAB2_LIB.BASEBOARD_FAB2(SCH_1):GND
  24    GND VSS<83> @BASEBOARD_FAB2_LIB.BASEBOARD_FAB2(SCH_1):GND
  26    GND VSS<82> @BASEBOARD_FAB2_LIB.BASEBOARD_FAB2(SCH_1):GND
  28    GND VSS<81> @BASEBOARD_FAB2_LIB.BASEBOARD_FAB2(SCH_1):GND
  31    GND VSS<80> @BASEBOARD_FAB2_LIB.BASEBOARD_FAB2(SCH_1):GND
  33    GND VSS<79> @BASEBOARD_FAB2_LIB.BASEBOARD_FAB2(SCH_1):GND
  35    GND VSS<78> @BASEBOARD_FAB2_LIB.BASEBOARD_FAB2(SCH_1):GND
  37    GND VSS<77> @BASEBOARD_FAB2_LIB.BASEBOARD_FAB2(SCH_1):GND
  39    GND VSS<76> @BASEBOARD_FAB2_LIB.BASEBOARD_FAB2(SCH_1):GND
  42    GND VSS<75> @BASEBOARD_FAB2_LIB.BASEBOARD_FAB2(SCH_1):GND
  44    GND VSS<74> @BASEBOARD_FAB2_LIB.BASEBOARD_FAB2(SCH_1):GND
  46    GND VSS<73> @BASEBOARD_FAB2_LIB.BASEBOARD_FAB2(SCH_1):GND
  48    GND VSS<72> @BASEBOARD_FAB2_LIB.BASEBOARD_FAB2(SCH_1):GND
  50    GND VSS<71> @BASEBOARD_FAB2_LIB.BASEBOARD_FAB2(SCH_1):GND
  53    GND VSS<70> @BASEBOARD_FAB2_LIB.BASEBOARD_FAB2(SCH_1):GND
  55    GND VSS<69> @BASEBOARD_FAB2_LIB.BASEBOARD_FAB2(SCH_1):GND
  57    GND VSS<68> @BASEBOARD_FAB2_LIB.BASEBOARD_FAB2(SCH_1):GND
  94    GND VSS<67> @BASEBOARD_FAB2_LIB.BASEBOARD_FAB2(SCH_1):GND
  96    GND VSS<66> @BASEBOARD_FAB2_LIB.BASEBOARD_FAB2(SCH_1):GND
  98    GND VSS<65> @BASEBOARD_FAB2_LIB.BASEBOARD_FAB2(SCH_1):GND
 101    GND VSS<64> @BASEBOARD_FAB2_LIB.BASEBOARD_FAB2(SCH_1):GND
 103    GND VSS<63> @BASEBOARD_FAB2_LIB.BASEBOARD_FAB2(SCH_1):GND
 105    GND VSS<62> @BASEBOARD_FAB2_LIB.BASEBOARD_FAB2(SCH_1):GND
 107    GND VSS<61> @BASEBOARD_FAB2_LIB.BASEBOARD_FAB2(SCH_1):GND
 109    GND VSS<60> @BASEBOARD_FAB2_LIB.BASEBOARD_FAB2(SCH_1):GND
 112    GND VSS<59> @BASEBOARD_FAB2_LIB.BASEBOARD_FAB2(SCH_1):GND
 114    GND VSS<58> @BASEBOARD_FAB2_LIB.BASEBOARD_FAB2(SCH_1):GND
 116    GND VSS<57> @BASEBOARD_FAB2_LIB.BASEBOARD_FAB2(SCH_1):GND
 118    GND VSS<56> @BASEBOARD_FAB2_LIB.BASEBOARD_FAB2(SCH_1):GND
 120    GND VSS<55> @BASEBOARD_FAB2_LIB.BASEBOARD_FAB2(SCH_1):GND
 123    GND VSS<54> @BASEBOARD_FAB2_LIB.BASEBOARD_FAB2(SCH_1):GND
 125    GND VSS<53> @BASEBOARD_FAB2_LIB.BASEBOARD_FAB2(SCH_1):GND
 127    GND VSS<52> @BASEBOARD_FAB2_LIB.BASEBOARD_FAB2(SCH_1):GND
 129    GND VSS<51> @BASEBOARD_FAB2_LIB.BASEBOARD_FAB2(SCH_1):GND
 131    GND VSS<50> @BASEBOARD_FAB2_LIB.BASEBOARD_FAB2(SCH_1):GND
 134    GND VSS<49> @BASEBOARD_FAB2_LIB.BASEBOARD_FAB2(SCH_1):GND
 136    GND VSS<48> @BASEBOARD_FAB2_LIB.BASEBOARD_FAB2(SCH_1):GND
 138    GND VSS<47> @BASEBOARD_FAB2_LIB.BASEBOARD_FAB2(SCH_1):GND
 147    GND VSS<46> @BASEBOARD_FAB2_LIB.BASEBOARD_FAB2(SCH_1):GND
 149    GND VSS<45> @BASEBOARD_FAB2_LIB.BASEBOARD_FAB2(SCH_1):GND
 151    GND VSS<44> @BASEBOARD_FAB2_LIB.BASEBOARD_FAB2(SCH_1):GND
 154    GND VSS<43> @BASEBOARD_FAB2_LIB.BASEBOARD_FAB2(SCH_1):GND
 156    GND VSS<42> @BASEBOARD_FAB2_LIB.BASEBOARD_FAB2(SCH_1):GND
 158    GND VSS<41> @BASEBOARD_FAB2_LIB.BASEBOARD_FAB2(SCH_1):GND
 160    GND VSS<40> @BASEBOARD_FAB2_LIB.BASEBOARD_FAB2(SCH_1):GND
 162    GND VSS<39> @BASEBOARD_FAB2_LIB.BASEBOARD_FAB2(SCH_1):GND
 165    GND VSS<38> @BASEBOARD_FAB2_LIB.BASEBOARD_FAB2(SCH_1):GND
 167    GND VSS<37> @BASEBOARD_FAB2_LIB.BASEBOARD_FAB2(SCH_1):GND
 169    GND VSS<36> @BASEBOARD_FAB2_LIB.BASEBOARD_FAB2(SCH_1):GND
 171    GND VSS<35> @BASEBOARD_FAB2_LIB.BASEBOARD_FAB2(SCH_1):GND
 173    GND VSS<34> @BASEBOARD_FAB2_LIB.BASEBOARD_FAB2(SCH_1):GND
 176    GND VSS<33> @BASEBOARD_FAB2_LIB.BASEBOARD_FAB2(SCH_1):GND
 178    GND VSS<32> @BASEBOARD_FAB2_LIB.BASEBOARD_FAB2(SCH_1):GND
 180    GND VSS<31> @BASEBOARD_FAB2_LIB.BASEBOARD_FAB2(SCH_1):GND
 182    GND VSS<30> @BASEBOARD_FAB2_LIB.BASEBOARD_FAB2(SCH_1):GND
 184    GND VSS<29> @BASEBOARD_FAB2_LIB.BASEBOARD_FAB2(SCH_1):GND
 187    GND VSS<28> @BASEBOARD_FAB2_LIB.BASEBOARD_FAB2(SCH_1):GND
 189    GND VSS<27> @BASEBOARD_FAB2_LIB.BASEBOARD_FAB2(SCH_1):GND
 191    GND VSS<26> @BASEBOARD_FAB2_LIB.BASEBOARD_FAB2(SCH_1):GND
 193    GND VSS<25> @BASEBOARD_FAB2_LIB.BASEBOARD_FAB2(SCH_1):GND
 195    GND VSS<24> @BASEBOARD_FAB2_LIB.BASEBOARD_FAB2(SCH_1):GND
 198    GND VSS<23> @BASEBOARD_FAB2_LIB.BASEBOARD_FAB2(SCH_1):GND
 200    GND VSS<22> @BASEBOARD_FAB2_LIB.BASEBOARD_FAB2(SCH_1):GND
 202    GND VSS<21> @BASEBOARD_FAB2_LIB.BASEBOARD_FAB2(SCH_1):GND
 239    GND VSS<20> @BASEBOARD_FAB2_LIB.BASEBOARD_FAB2(SCH_1):GND
 241    GND VSS<19> @BASEBOARD_FAB2_LIB.BASEBOARD_FAB2(SCH_1):GND
 243    GND VSS<18> @BASEBOARD_FAB2_LIB.BASEBOARD_FAB2(SCH_1):GND
 246    GND VSS<17> @BASEBOARD_FAB2_LIB.BASEBOARD_FAB2(SCH_1):GND
 248    GND VSS<16> @BASEBOARD_FAB2_LIB.BASEBOARD_FAB2(SCH_1):GND
 250    GND VSS<15> @BASEBOARD_FAB2_LIB.BASEBOARD_FAB2(SCH_1):GND
 252    GND VSS<14> @BASEBOARD_FAB2_LIB.BASEBOARD_FAB2(SCH_1):GND
 254    GND VSS<13> @BASEBOARD_FAB2_LIB.BASEBOARD_FAB2(SCH_1):GND
 257    GND VSS<12> @BASEBOARD_FAB2_LIB.BASEBOARD_FAB2(SCH_1):GND
 259    GND VSS<11> @BASEBOARD_FAB2_LIB.BASEBOARD_FAB2(SCH_1):GND
 261    GND VSS<10> @BASEBOARD_FAB2_LIB.BASEBOARD_FAB2(SCH_1):GND
 263    GND VSS<9> @BASEBOARD_FAB2_LIB.BASEBOARD_FAB2(SCH_1):GND
 265    GND VSS<8> @BASEBOARD_FAB2_LIB.BASEBOARD_FAB2(SCH_1):GND
 268    GND VSS<7> @BASEBOARD_FAB2_LIB.BASEBOARD_FAB2(SCH_1):GND
 270    GND VSS<6> @BASEBOARD_FAB2_LIB.BASEBOARD_FAB2(SCH_1):GND
 272    GND VSS<5> @BASEBOARD_FAB2_LIB.BASEBOARD_FAB2(SCH_1):GND
 274    GND VSS<4> @BASEBOARD_FAB2_LIB.BASEBOARD_FAB2(SCH_1):GND
 276    GND VSS<3> @BASEBOARD_FAB2_LIB.BASEBOARD_FAB2(SCH_1):GND
 279    GND VSS<2> @BASEBOARD_FAB2_LIB.BASEBOARD_FAB2(SCH_1):GND
 281    GND VSS<1> @BASEBOARD_FAB2_LIB.BASEBOARD_FAB2(SCH_1):GND
 283    GND VSS<0> @BASEBOARD_FAB2_LIB.BASEBOARD_FAB2(SCH_1):GND


DRAWING: @BASEBOARD_FAB2_LIB.BASEBOARD_FAB2(SCH_1):PAGE79 

SCONN288_H44441004_PIP-SCONN,HA  I43  J1G2
   2    GND VSS<93> @BASEBOARD_FAB2_LIB.BASEBOARD_FAB2(SCH_1):GND
   4    GND VSS<92> @BASEBOARD_FAB2_LIB.BASEBOARD_FAB2(SCH_1):GND
   6    GND VSS<91> @BASEBOARD_FAB2_LIB.BASEBOARD_FAB2(SCH_1):GND
   9    GND VSS<90> @BASEBOARD_FAB2_LIB.BASEBOARD_FAB2(SCH_1):GND
  11    GND VSS<89> @BASEBOARD_FAB2_LIB.BASEBOARD_FAB2(SCH_1):GND
  13    GND VSS<88> @BASEBOARD_FAB2_LIB.BASEBOARD_FAB2(SCH_1):GND
  15    GND VSS<87> @BASEBOARD_FAB2_LIB.BASEBOARD_FAB2(SCH_1):GND
  17    GND VSS<86> @BASEBOARD_FAB2_LIB.BASEBOARD_FAB2(SCH_1):GND
  20    GND VSS<85> @BASEBOARD_FAB2_LIB.BASEBOARD_FAB2(SCH_1):GND
  22    GND VSS<84> @BASEBOARD_FAB2_LIB.BASEBOARD_FAB2(SCH_1):GND
  24    GND VSS<83> @BASEBOARD_FAB2_LIB.BASEBOARD_FAB2(SCH_1):GND
  26    GND VSS<82> @BASEBOARD_FAB2_LIB.BASEBOARD_FAB2(SCH_1):GND
  28    GND VSS<81> @BASEBOARD_FAB2_LIB.BASEBOARD_FAB2(SCH_1):GND
  31    GND VSS<80> @BASEBOARD_FAB2_LIB.BASEBOARD_FAB2(SCH_1):GND
  33    GND VSS<79> @BASEBOARD_FAB2_LIB.BASEBOARD_FAB2(SCH_1):GND
  35    GND VSS<78> @BASEBOARD_FAB2_LIB.BASEBOARD_FAB2(SCH_1):GND
  37    GND VSS<77> @BASEBOARD_FAB2_LIB.BASEBOARD_FAB2(SCH_1):GND
  39    GND VSS<76> @BASEBOARD_FAB2_LIB.BASEBOARD_FAB2(SCH_1):GND
  42    GND VSS<75> @BASEBOARD_FAB2_LIB.BASEBOARD_FAB2(SCH_1):GND
  44    GND VSS<74> @BASEBOARD_FAB2_LIB.BASEBOARD_FAB2(SCH_1):GND
  46    GND VSS<73> @BASEBOARD_FAB2_LIB.BASEBOARD_FAB2(SCH_1):GND
  48    GND VSS<72> @BASEBOARD_FAB2_LIB.BASEBOARD_FAB2(SCH_1):GND
  50    GND VSS<71> @BASEBOARD_FAB2_LIB.BASEBOARD_FAB2(SCH_1):GND
  53    GND VSS<70> @BASEBOARD_FAB2_LIB.BASEBOARD_FAB2(SCH_1):GND
  55    GND VSS<69> @BASEBOARD_FAB2_LIB.BASEBOARD_FAB2(SCH_1):GND
  57    GND VSS<68> @BASEBOARD_FAB2_LIB.BASEBOARD_FAB2(SCH_1):GND
  94    GND VSS<67> @BASEBOARD_FAB2_LIB.BASEBOARD_FAB2(SCH_1):GND
  96    GND VSS<66> @BASEBOARD_FAB2_LIB.BASEBOARD_FAB2(SCH_1):GND
  98    GND VSS<65> @BASEBOARD_FAB2_LIB.BASEBOARD_FAB2(SCH_1):GND
 101    GND VSS<64> @BASEBOARD_FAB2_LIB.BASEBOARD_FAB2(SCH_1):GND
 103    GND VSS<63> @BASEBOARD_FAB2_LIB.BASEBOARD_FAB2(SCH_1):GND
 105    GND VSS<62> @BASEBOARD_FAB2_LIB.BASEBOARD_FAB2(SCH_1):GND
 107    GND VSS<61> @BASEBOARD_FAB2_LIB.BASEBOARD_FAB2(SCH_1):GND
 109    GND VSS<60> @BASEBOARD_FAB2_LIB.BASEBOARD_FAB2(SCH_1):GND
 112    GND VSS<59> @BASEBOARD_FAB2_LIB.BASEBOARD_FAB2(SCH_1):GND
 114    GND VSS<58> @BASEBOARD_FAB2_LIB.BASEBOARD_FAB2(SCH_1):GND
 116    GND VSS<57> @BASEBOARD_FAB2_LIB.BASEBOARD_FAB2(SCH_1):GND
 118    GND VSS<56> @BASEBOARD_FAB2_LIB.BASEBOARD_FAB2(SCH_1):GND
 120    GND VSS<55> @BASEBOARD_FAB2_LIB.BASEBOARD_FAB2(SCH_1):GND
 123    GND VSS<54> @BASEBOARD_FAB2_LIB.BASEBOARD_FAB2(SCH_1):GND
 125    GND VSS<53> @BASEBOARD_FAB2_LIB.BASEBOARD_FAB2(SCH_1):GND
 127    GND VSS<52> @BASEBOARD_FAB2_LIB.BASEBOARD_FAB2(SCH_1):GND
 129    GND VSS<51> @BASEBOARD_FAB2_LIB.BASEBOARD_FAB2(SCH_1):GND
 131    GND VSS<50> @BASEBOARD_FAB2_LIB.BASEBOARD_FAB2(SCH_1):GND
 134    GND VSS<49> @BASEBOARD_FAB2_LIB.BASEBOARD_FAB2(SCH_1):GND
 136    GND VSS<48> @BASEBOARD_FAB2_LIB.BASEBOARD_FAB2(SCH_1):GND
 138    GND VSS<47> @BASEBOARD_FAB2_LIB.BASEBOARD_FAB2(SCH_1):GND
 147    GND VSS<46> @BASEBOARD_FAB2_LIB.BASEBOARD_FAB2(SCH_1):GND
 149    GND VSS<45> @BASEBOARD_FAB2_LIB.BASEBOARD_FAB2(SCH_1):GND
 151    GND VSS<44> @BASEBOARD_FAB2_LIB.BASEBOARD_FAB2(SCH_1):GND
 154    GND VSS<43> @BASEBOARD_FAB2_LIB.BASEBOARD_FAB2(SCH_1):GND
 156    GND VSS<42> @BASEBOARD_FAB2_LIB.BASEBOARD_FAB2(SCH_1):GND
 158    GND VSS<41> @BASEBOARD_FAB2_LIB.BASEBOARD_FAB2(SCH_1):GND
 160    GND VSS<40> @BASEBOARD_FAB2_LIB.BASEBOARD_FAB2(SCH_1):GND
 162    GND VSS<39> @BASEBOARD_FAB2_LIB.BASEBOARD_FAB2(SCH_1):GND
 165    GND VSS<38> @BASEBOARD_FAB2_LIB.BASEBOARD_FAB2(SCH_1):GND
 167    GND VSS<37> @BASEBOARD_FAB2_LIB.BASEBOARD_FAB2(SCH_1):GND
 169    GND VSS<36> @BASEBOARD_FAB2_LIB.BASEBOARD_FAB2(SCH_1):GND
 171    GND VSS<35> @BASEBOARD_FAB2_LIB.BASEBOARD_FAB2(SCH_1):GND
 173    GND VSS<34> @BASEBOARD_FAB2_LIB.BASEBOARD_FAB2(SCH_1):GND
 176    GND VSS<33> @BASEBOARD_FAB2_LIB.BASEBOARD_FAB2(SCH_1):GND
 178    GND VSS<32> @BASEBOARD_FAB2_LIB.BASEBOARD_FAB2(SCH_1):GND
 180    GND VSS<31> @BASEBOARD_FAB2_LIB.BASEBOARD_FAB2(SCH_1):GND
 182    GND VSS<30> @BASEBOARD_FAB2_LIB.BASEBOARD_FAB2(SCH_1):GND
 184    GND VSS<29> @BASEBOARD_FAB2_LIB.BASEBOARD_FAB2(SCH_1):GND
 187    GND VSS<28> @BASEBOARD_FAB2_LIB.BASEBOARD_FAB2(SCH_1):GND
 189    GND VSS<27> @BASEBOARD_FAB2_LIB.BASEBOARD_FAB2(SCH_1):GND
 191    GND VSS<26> @BASEBOARD_FAB2_LIB.BASEBOARD_FAB2(SCH_1):GND
 193    GND VSS<25> @BASEBOARD_FAB2_LIB.BASEBOARD_FAB2(SCH_1):GND
 195    GND VSS<24> @BASEBOARD_FAB2_LIB.BASEBOARD_FAB2(SCH_1):GND
 198    GND VSS<23> @BASEBOARD_FAB2_LIB.BASEBOARD_FAB2(SCH_1):GND
 200    GND VSS<22> @BASEBOARD_FAB2_LIB.BASEBOARD_FAB2(SCH_1):GND
 202    GND VSS<21> @BASEBOARD_FAB2_LIB.BASEBOARD_FAB2(SCH_1):GND
 239    GND VSS<20> @BASEBOARD_FAB2_LIB.BASEBOARD_FAB2(SCH_1):GND
 241    GND VSS<19> @BASEBOARD_FAB2_LIB.BASEBOARD_FAB2(SCH_1):GND
 243    GND VSS<18> @BASEBOARD_FAB2_LIB.BASEBOARD_FAB2(SCH_1):GND
 246    GND VSS<17> @BASEBOARD_FAB2_LIB.BASEBOARD_FAB2(SCH_1):GND
 248    GND VSS<16> @BASEBOARD_FAB2_LIB.BASEBOARD_FAB2(SCH_1):GND
 250    GND VSS<15> @BASEBOARD_FAB2_LIB.BASEBOARD_FAB2(SCH_1):GND
 252    GND VSS<14> @BASEBOARD_FAB2_LIB.BASEBOARD_FAB2(SCH_1):GND
 254    GND VSS<13> @BASEBOARD_FAB2_LIB.BASEBOARD_FAB2(SCH_1):GND
 257    GND VSS<12> @BASEBOARD_FAB2_LIB.BASEBOARD_FAB2(SCH_1):GND
 259    GND VSS<11> @BASEBOARD_FAB2_LIB.BASEBOARD_FAB2(SCH_1):GND
 261    GND VSS<10> @BASEBOARD_FAB2_LIB.BASEBOARD_FAB2(SCH_1):GND
 263    GND VSS<9> @BASEBOARD_FAB2_LIB.BASEBOARD_FAB2(SCH_1):GND
 265    GND VSS<8> @BASEBOARD_FAB2_LIB.BASEBOARD_FAB2(SCH_1):GND
 268    GND VSS<7> @BASEBOARD_FAB2_LIB.BASEBOARD_FAB2(SCH_1):GND
 270    GND VSS<6> @BASEBOARD_FAB2_LIB.BASEBOARD_FAB2(SCH_1):GND
 272    GND VSS<5> @BASEBOARD_FAB2_LIB.BASEBOARD_FAB2(SCH_1):GND
 274    GND VSS<4> @BASEBOARD_FAB2_LIB.BASEBOARD_FAB2(SCH_1):GND
 276    GND VSS<3> @BASEBOARD_FAB2_LIB.BASEBOARD_FAB2(SCH_1):GND
 279    GND VSS<2> @BASEBOARD_FAB2_LIB.BASEBOARD_FAB2(SCH_1):GND
 281    GND VSS<1> @BASEBOARD_FAB2_LIB.BASEBOARD_FAB2(SCH_1):GND
 283    GND VSS<0> @BASEBOARD_FAB2_LIB.BASEBOARD_FAB2(SCH_1):GND

SCONN288_H44441004_PIP-SCONN,HA  I64  J1G2
 152 M_H_DQS_DN<0>  DQS0N @BASEBOARD_FAB2_LIB.BASEBOARD_FAB2(SCH_1):M_H_DQS_DN(0)
 153 M_H_DQS_DP<0>  DQS0P @BASEBOARD_FAB2_LIB.BASEBOARD_FAB2(SCH_1):M_H_DQS_DP(0)
  19 M_H_DQS_DN<10> DQS10N @BASEBOARD_FAB2_LIB.BASEBOARD_FAB2(SCH_1):M_H_DQS_DN(10)
  18 M_H_DQS_DP<10> DQS10P @BASEBOARD_FAB2_LIB.BASEBOARD_FAB2(SCH_1):M_H_DQS_DP(10)
  30 M_H_DQS_DN<11> DQS11N @BASEBOARD_FAB2_LIB.BASEBOARD_FAB2(SCH_1):M_H_DQS_DN(11)
  29 M_H_DQS_DP<11> DQS11P @BASEBOARD_FAB2_LIB.BASEBOARD_FAB2(SCH_1):M_H_DQS_DP(11)
  41 M_H_DQS_DN<12> DQS12N @BASEBOARD_FAB2_LIB.BASEBOARD_FAB2(SCH_1):M_H_DQS_DN(12)
  40 M_H_DQS_DP<12> DQS12P @BASEBOARD_FAB2_LIB.BASEBOARD_FAB2(SCH_1):M_H_DQS_DP(12)
 100 M_H_DQS_DN<13> DQS13N @BASEBOARD_FAB2_LIB.BASEBOARD_FAB2(SCH_1):M_H_DQS_DN(13)
  99 M_H_DQS_DP<13> DQS13P @BASEBOARD_FAB2_LIB.BASEBOARD_FAB2(SCH_1):M_H_DQS_DP(13)
 111 M_H_DQS_DN<14> DQS14N @BASEBOARD_FAB2_LIB.BASEBOARD_FAB2(SCH_1):M_H_DQS_DN(14)
 110 M_H_DQS_DP<14> DQS14P @BASEBOARD_FAB2_LIB.BASEBOARD_FAB2(SCH_1):M_H_DQS_DP(14)
 122 M_H_DQS_DN<15> DQS15N @BASEBOARD_FAB2_LIB.BASEBOARD_FAB2(SCH_1):M_H_DQS_DN(15)
 121 M_H_DQS_DP<15> DQS15P @BASEBOARD_FAB2_LIB.BASEBOARD_FAB2(SCH_1):M_H_DQS_DP(15)
 133 M_H_DQS_DN<16> DQS16N @BASEBOARD_FAB2_LIB.BASEBOARD_FAB2(SCH_1):M_H_DQS_DN(16)
 132 M_H_DQS_DP<16> DQS16P @BASEBOARD_FAB2_LIB.BASEBOARD_FAB2(SCH_1):M_H_DQS_DP(16)
  52 M_H_DQS_DN<17> DQS17N @BASEBOARD_FAB2_LIB.BASEBOARD_FAB2(SCH_1):M_H_DQS_DN(17)
  51 M_H_DQS_DP<17> DQS17P @BASEBOARD_FAB2_LIB.BASEBOARD_FAB2(SCH_1):M_H_DQS_DP(17)
 163 M_H_DQS_DN<1>  DQS1N @BASEBOARD_FAB2_LIB.BASEBOARD_FAB2(SCH_1):M_H_DQS_DN(1)
 164 M_H_DQS_DP<1>  DQS1P @BASEBOARD_FAB2_LIB.BASEBOARD_FAB2(SCH_1):M_H_DQS_DP(1)
 174 M_H_DQS_DN<2>  DQS2N @BASEBOARD_FAB2_LIB.BASEBOARD_FAB2(SCH_1):M_H_DQS_DN(2)
 175 M_H_DQS_DP<2>  DQS2P @BASEBOARD_FAB2_LIB.BASEBOARD_FAB2(SCH_1):M_H_DQS_DP(2)
 185 M_H_DQS_DN<3>  DQS3N @BASEBOARD_FAB2_LIB.BASEBOARD_FAB2(SCH_1):M_H_DQS_DN(3)
 186 M_H_DQS_DP<3>  DQS3P @BASEBOARD_FAB2_LIB.BASEBOARD_FAB2(SCH_1):M_H_DQS_DP(3)
 244 M_H_DQS_DN<4>  DQS4N @BASEBOARD_FAB2_LIB.BASEBOARD_FAB2(SCH_1):M_H_DQS_DN(4)
 245 M_H_DQS_DP<4>  DQS4P @BASEBOARD_FAB2_LIB.BASEBOARD_FAB2(SCH_1):M_H_DQS_DP(4)
 255 M_H_DQS_DN<5>  DQS5N @BASEBOARD_FAB2_LIB.BASEBOARD_FAB2(SCH_1):M_H_DQS_DN(5)
 256 M_H_DQS_DP<5>  DQS5P @BASEBOARD_FAB2_LIB.BASEBOARD_FAB2(SCH_1):M_H_DQS_DP(5)
 266 M_H_DQS_DN<6>  DQS6N @BASEBOARD_FAB2_LIB.BASEBOARD_FAB2(SCH_1):M_H_DQS_DN(6)
 267 M_H_DQS_DP<6>  DQS6P @BASEBOARD_FAB2_LIB.BASEBOARD_FAB2(SCH_1):M_H_DQS_DP(6)
 277 M_H_DQS_DN<7>  DQS7N @BASEBOARD_FAB2_LIB.BASEBOARD_FAB2(SCH_1):M_H_DQS_DN(7)
 278 M_H_DQS_DP<7>  DQS7P @BASEBOARD_FAB2_LIB.BASEBOARD_FAB2(SCH_1):M_H_DQS_DP(7)
 196 M_H_DQS_DN<8>  DQS8N @BASEBOARD_FAB2_LIB.BASEBOARD_FAB2(SCH_1):M_H_DQS_DN(8)
 197 M_H_DQS_DP<8>  DQS8P @BASEBOARD_FAB2_LIB.BASEBOARD_FAB2(SCH_1):M_H_DQS_DP(8)
   8 M_H_DQS_DN<9>  DQS9N @BASEBOARD_FAB2_LIB.BASEBOARD_FAB2(SCH_1):M_H_DQS_DN(9)
   7 M_H_DQS_DP<9>  DQS9P @BASEBOARD_FAB2_LIB.BASEBOARD_FAB2(SCH_1):M_H_DQS_DP(9)

SCONN288_H44441004_PIP-SCONN,HA  I111  J1G2
  79 M_H_MA<0>     A0 @BASEBOARD_FAB2_LIB.BASEBOARD_FAB2(SCH_1):M_H_MA(0)
  72 M_H_MA<1>     A1 @BASEBOARD_FAB2_LIB.BASEBOARD_FAB2(SCH_1):M_H_MA(1)
 225 M_H_MA<10>    A10 @BASEBOARD_FAB2_LIB.BASEBOARD_FAB2(SCH_1):M_H_MA(10)
 210 M_H_MA<11>    A11 @BASEBOARD_FAB2_LIB.BASEBOARD_FAB2(SCH_1):M_H_MA(11)
  65 M_H_MA<12>    A12 @BASEBOARD_FAB2_LIB.BASEBOARD_FAB2(SCH_1):M_H_MA(12)
 232 M_H_MA<13>    A13 @BASEBOARD_FAB2_LIB.BASEBOARD_FAB2(SCH_1):M_H_MA(13)
 228 M_H_MA<14> A14_WE_N @BASEBOARD_FAB2_LIB.BASEBOARD_FAB2(SCH_1):M_H_MA(14)
  86 M_H_MA<15> A15_CAS_N @BASEBOARD_FAB2_LIB.BASEBOARD_FAB2(SCH_1):M_H_MA(15)
  82 M_H_MA<16> A16_RAS_N @BASEBOARD_FAB2_LIB.BASEBOARD_FAB2(SCH_1):M_H_MA(16)
 234 M_H_MA<17>    A17 @BASEBOARD_FAB2_LIB.BASEBOARD_FAB2(SCH_1):M_H_MA(17)
 216 M_H_MA<2>     A2 @BASEBOARD_FAB2_LIB.BASEBOARD_FAB2(SCH_1):M_H_MA(2)
  71 M_H_MA<3>     A3 @BASEBOARD_FAB2_LIB.BASEBOARD_FAB2(SCH_1):M_H_MA(3)
 214 M_H_MA<4>     A4 @BASEBOARD_FAB2_LIB.BASEBOARD_FAB2(SCH_1):M_H_MA(4)
 213 M_H_MA<5>     A5 @BASEBOARD_FAB2_LIB.BASEBOARD_FAB2(SCH_1):M_H_MA(5)
  69 M_H_MA<6>     A6 @BASEBOARD_FAB2_LIB.BASEBOARD_FAB2(SCH_1):M_H_MA(6)
 211 M_H_MA<7>     A7 @BASEBOARD_FAB2_LIB.BASEBOARD_FAB2(SCH_1):M_H_MA(7)
  68 M_H_MA<8>     A8 @BASEBOARD_FAB2_LIB.BASEBOARD_FAB2(SCH_1):M_H_MA(8)
  66 M_H_MA<9>     A9 @BASEBOARD_FAB2_LIB.BASEBOARD_FAB2(SCH_1):M_H_MA(9)
  62 M_H_ACT_N  ACT_N @BASEBOARD_FAB2_LIB.BASEBOARD_FAB2(SCH_1):M_H_ACT_N
 208 M_H_ALERT_N ALERT_N @BASEBOARD_FAB2_LIB.BASEBOARD_FAB2(SCH_1):M_H_ALERT_N
 224 M_H_BA<1>  BA<1> @BASEBOARD_FAB2_LIB.BASEBOARD_FAB2(SCH_1):M_H_BA(1)
  81 M_H_BA<0>  BA<0> @BASEBOARD_FAB2_LIB.BASEBOARD_FAB2(SCH_1):M_H_BA(0)
 207 M_H_BG<1>  BG<1> @BASEBOARD_FAB2_LIB.BASEBOARD_FAB2(SCH_1):M_H_BG(1)
  63 M_H_BG<0>  BG<0> @BASEBOARD_FAB2_LIB.BASEBOARD_FAB2(SCH_1):M_H_BG(0)
 235 M_H_C<2>   C<2> @BASEBOARD_FAB2_LIB.BASEBOARD_FAB2(SCH_1):M_H_C(2)
 199 M_H_ECC<6>  CB<7> @BASEBOARD_FAB2_LIB.BASEBOARD_FAB2(SCH_1):M_H_ECC(6)
  54 M_H_ECC<7>  CB<6> @BASEBOARD_FAB2_LIB.BASEBOARD_FAB2(SCH_1):M_H_ECC(7)
 192 M_H_ECC<4>  CB<5> @BASEBOARD_FAB2_LIB.BASEBOARD_FAB2(SCH_1):M_H_ECC(4)
  47 M_H_ECC<5>  CB<4> @BASEBOARD_FAB2_LIB.BASEBOARD_FAB2(SCH_1):M_H_ECC(5)
 201 M_H_ECC<2>  CB<3> @BASEBOARD_FAB2_LIB.BASEBOARD_FAB2(SCH_1):M_H_ECC(2)
  56 M_H_ECC<3>  CB<2> @BASEBOARD_FAB2_LIB.BASEBOARD_FAB2(SCH_1):M_H_ECC(3)
 194 M_H_ECC<0>  CB<1> @BASEBOARD_FAB2_LIB.BASEBOARD_FAB2(SCH_1):M_H_ECC(0)
  49 M_H_ECC<1>  CB<0> @BASEBOARD_FAB2_LIB.BASEBOARD_FAB2(SCH_1):M_H_ECC(1)
  75 M_H_CLK_DN<0>   CK0N @BASEBOARD_FAB2_LIB.BASEBOARD_FAB2(SCH_1):M_H_CLK_DN(0)
  74 M_H_CLK_DP<0>   CK0P @BASEBOARD_FAB2_LIB.BASEBOARD_FAB2(SCH_1):M_H_CLK_DP(0)
 219 M_H_CLK_DN<1>   CK1N @BASEBOARD_FAB2_LIB.BASEBOARD_FAB2(SCH_1):M_H_CLK_DN(1)
 218 M_H_CLK_DP<1>   CK1P @BASEBOARD_FAB2_LIB.BASEBOARD_FAB2(SCH_1):M_H_CLK_DP(1)
 203 M_H_CKE<1> CKE<1> @BASEBOARD_FAB2_LIB.BASEBOARD_FAB2(SCH_1):M_H_CKE(1)
  60 M_H_CKE<0> CKE<0> @BASEBOARD_FAB2_LIB.BASEBOARD_FAB2(SCH_1):M_H_CKE(0)
 280 M_H_DQ<62> DQ<63> @BASEBOARD_FAB2_LIB.BASEBOARD_FAB2(SCH_1):M_H_DQ(62)
 135 M_H_DQ<63> DQ<62> @BASEBOARD_FAB2_LIB.BASEBOARD_FAB2(SCH_1):M_H_DQ(63)
 273 M_H_DQ<60> DQ<61> @BASEBOARD_FAB2_LIB.BASEBOARD_FAB2(SCH_1):M_H_DQ(60)
 128 M_H_DQ<61> DQ<60> @BASEBOARD_FAB2_LIB.BASEBOARD_FAB2(SCH_1):M_H_DQ(61)
 282 M_H_DQ<58> DQ<59> @BASEBOARD_FAB2_LIB.BASEBOARD_FAB2(SCH_1):M_H_DQ(58)
 137 M_H_DQ<59> DQ<58> @BASEBOARD_FAB2_LIB.BASEBOARD_FAB2(SCH_1):M_H_DQ(59)
 275 M_H_DQ<56> DQ<57> @BASEBOARD_FAB2_LIB.BASEBOARD_FAB2(SCH_1):M_H_DQ(56)
 130 M_H_DQ<57> DQ<56> @BASEBOARD_FAB2_LIB.BASEBOARD_FAB2(SCH_1):M_H_DQ(57)
 269 M_H_DQ<54> DQ<55> @BASEBOARD_FAB2_LIB.BASEBOARD_FAB2(SCH_1):M_H_DQ(54)
 124 M_H_DQ<55> DQ<54> @BASEBOARD_FAB2_LIB.BASEBOARD_FAB2(SCH_1):M_H_DQ(55)
 262 M_H_DQ<52> DQ<53> @BASEBOARD_FAB2_LIB.BASEBOARD_FAB2(SCH_1):M_H_DQ(52)
 117 M_H_DQ<53> DQ<52> @BASEBOARD_FAB2_LIB.BASEBOARD_FAB2(SCH_1):M_H_DQ(53)
 271 M_H_DQ<50> DQ<51> @BASEBOARD_FAB2_LIB.BASEBOARD_FAB2(SCH_1):M_H_DQ(50)
 126 M_H_DQ<51> DQ<50> @BASEBOARD_FAB2_LIB.BASEBOARD_FAB2(SCH_1):M_H_DQ(51)
 264 M_H_DQ<48> DQ<49> @BASEBOARD_FAB2_LIB.BASEBOARD_FAB2(SCH_1):M_H_DQ(48)
 119 M_H_DQ<49> DQ<48> @BASEBOARD_FAB2_LIB.BASEBOARD_FAB2(SCH_1):M_H_DQ(49)
 258 M_H_DQ<46> DQ<47> @BASEBOARD_FAB2_LIB.BASEBOARD_FAB2(SCH_1):M_H_DQ(46)
 113 M_H_DQ<47> DQ<46> @BASEBOARD_FAB2_LIB.BASEBOARD_FAB2(SCH_1):M_H_DQ(47)
 251 M_H_DQ<44> DQ<45> @BASEBOARD_FAB2_LIB.BASEBOARD_FAB2(SCH_1):M_H_DQ(44)
 106 M_H_DQ<45> DQ<44> @BASEBOARD_FAB2_LIB.BASEBOARD_FAB2(SCH_1):M_H_DQ(45)
 260 M_H_DQ<42> DQ<43> @BASEBOARD_FAB2_LIB.BASEBOARD_FAB2(SCH_1):M_H_DQ(42)
 115 M_H_DQ<43> DQ<42> @BASEBOARD_FAB2_LIB.BASEBOARD_FAB2(SCH_1):M_H_DQ(43)
 253 M_H_DQ<40> DQ<41> @BASEBOARD_FAB2_LIB.BASEBOARD_FAB2(SCH_1):M_H_DQ(40)
 108 M_H_DQ<41> DQ<40> @BASEBOARD_FAB2_LIB.BASEBOARD_FAB2(SCH_1):M_H_DQ(41)
 247 M_H_DQ<38> DQ<39> @BASEBOARD_FAB2_LIB.BASEBOARD_FAB2(SCH_1):M_H_DQ(38)
 102 M_H_DQ<39> DQ<38> @BASEBOARD_FAB2_LIB.BASEBOARD_FAB2(SCH_1):M_H_DQ(39)
 240 M_H_DQ<36> DQ<37> @BASEBOARD_FAB2_LIB.BASEBOARD_FAB2(SCH_1):M_H_DQ(36)
  95 M_H_DQ<37> DQ<36> @BASEBOARD_FAB2_LIB.BASEBOARD_FAB2(SCH_1):M_H_DQ(37)
 249 M_H_DQ<34> DQ<35> @BASEBOARD_FAB2_LIB.BASEBOARD_FAB2(SCH_1):M_H_DQ(34)
 104 M_H_DQ<35> DQ<34> @BASEBOARD_FAB2_LIB.BASEBOARD_FAB2(SCH_1):M_H_DQ(35)
 242 M_H_DQ<32> DQ<33> @BASEBOARD_FAB2_LIB.BASEBOARD_FAB2(SCH_1):M_H_DQ(32)
  97 M_H_DQ<33> DQ<32> @BASEBOARD_FAB2_LIB.BASEBOARD_FAB2(SCH_1):M_H_DQ(33)
 188 M_H_DQ<30> DQ<31> @BASEBOARD_FAB2_LIB.BASEBOARD_FAB2(SCH_1):M_H_DQ(30)
  43 M_H_DQ<31> DQ<30> @BASEBOARD_FAB2_LIB.BASEBOARD_FAB2(SCH_1):M_H_DQ(31)
 181 M_H_DQ<28> DQ<29> @BASEBOARD_FAB2_LIB.BASEBOARD_FAB2(SCH_1):M_H_DQ(28)
  36 M_H_DQ<29> DQ<28> @BASEBOARD_FAB2_LIB.BASEBOARD_FAB2(SCH_1):M_H_DQ(29)
 190 M_H_DQ<26> DQ<27> @BASEBOARD_FAB2_LIB.BASEBOARD_FAB2(SCH_1):M_H_DQ(26)
  45 M_H_DQ<27> DQ<26> @BASEBOARD_FAB2_LIB.BASEBOARD_FAB2(SCH_1):M_H_DQ(27)
 183 M_H_DQ<24> DQ<25> @BASEBOARD_FAB2_LIB.BASEBOARD_FAB2(SCH_1):M_H_DQ(24)
  38 M_H_DQ<25> DQ<24> @BASEBOARD_FAB2_LIB.BASEBOARD_FAB2(SCH_1):M_H_DQ(25)
 177 M_H_DQ<22> DQ<23> @BASEBOARD_FAB2_LIB.BASEBOARD_FAB2(SCH_1):M_H_DQ(22)
  32 M_H_DQ<23> DQ<22> @BASEBOARD_FAB2_LIB.BASEBOARD_FAB2(SCH_1):M_H_DQ(23)
 170 M_H_DQ<20> DQ<21> @BASEBOARD_FAB2_LIB.BASEBOARD_FAB2(SCH_1):M_H_DQ(20)
  25 M_H_DQ<21> DQ<20> @BASEBOARD_FAB2_LIB.BASEBOARD_FAB2(SCH_1):M_H_DQ(21)
 179 M_H_DQ<18> DQ<19> @BASEBOARD_FAB2_LIB.BASEBOARD_FAB2(SCH_1):M_H_DQ(18)
  34 M_H_DQ<19> DQ<18> @BASEBOARD_FAB2_LIB.BASEBOARD_FAB2(SCH_1):M_H_DQ(19)
 172 M_H_DQ<16> DQ<17> @BASEBOARD_FAB2_LIB.BASEBOARD_FAB2(SCH_1):M_H_DQ(16)
  27 M_H_DQ<17> DQ<16> @BASEBOARD_FAB2_LIB.BASEBOARD_FAB2(SCH_1):M_H_DQ(17)
 166 M_H_DQ<14> DQ<15> @BASEBOARD_FAB2_LIB.BASEBOARD_FAB2(SCH_1):M_H_DQ(14)
  21 M_H_DQ<15> DQ<14> @BASEBOARD_FAB2_LIB.BASEBOARD_FAB2(SCH_1):M_H_DQ(15)
 159 M_H_DQ<12> DQ<13> @BASEBOARD_FAB2_LIB.BASEBOARD_FAB2(SCH_1):M_H_DQ(12)
  14 M_H_DQ<13> DQ<12> @BASEBOARD_FAB2_LIB.BASEBOARD_FAB2(SCH_1):M_H_DQ(13)
 168 M_H_DQ<10> DQ<11> @BASEBOARD_FAB2_LIB.BASEBOARD_FAB2(SCH_1):M_H_DQ(10)
  23 M_H_DQ<11> DQ<10> @BASEBOARD_FAB2_LIB.BASEBOARD_FAB2(SCH_1):M_H_DQ(11)
 161 M_H_DQ<8>  DQ<9> @BASEBOARD_FAB2_LIB.BASEBOARD_FAB2(SCH_1):M_H_DQ(8)
  16 M_H_DQ<9>  DQ<8> @BASEBOARD_FAB2_LIB.BASEBOARD_FAB2(SCH_1):M_H_DQ(9)
 155 M_H_DQ<6>  DQ<7> @BASEBOARD_FAB2_LIB.BASEBOARD_FAB2(SCH_1):M_H_DQ(6)
  10 M_H_DQ<7>  DQ<6> @BASEBOARD_FAB2_LIB.BASEBOARD_FAB2(SCH_1):M_H_DQ(7)
 148 M_H_DQ<4>  DQ<5> @BASEBOARD_FAB2_LIB.BASEBOARD_FAB2(SCH_1):M_H_DQ(4)
   3 M_H_DQ<5>  DQ<4> @BASEBOARD_FAB2_LIB.BASEBOARD_FAB2(SCH_1):M_H_DQ(5)
 157 M_H_DQ<2>  DQ<3> @BASEBOARD_FAB2_LIB.BASEBOARD_FAB2(SCH_1):M_H_DQ(2)
  12 M_H_DQ<3>  DQ<2> @BASEBOARD_FAB2_LIB.BASEBOARD_FAB2(SCH_1):M_H_DQ(3)
 150 M_H_DQ<0>  DQ<1> @BASEBOARD_FAB2_LIB.BASEBOARD_FAB2(SCH_1):M_H_DQ(0)
   5 M_H_DQ<1>  DQ<0> @BASEBOARD_FAB2_LIB.BASEBOARD_FAB2(SCH_1):M_H_DQ(1)
  78 FM_DIMM_EVENT_COD_N EVENT_N @BASEBOARD_FAB2_LIB.BASEBOARD_FAB2(SCH_1):FM_DIMM_EVENT_COD_N
  91 M_H_ODT<1> ODT<1> @BASEBOARD_FAB2_LIB.BASEBOARD_FAB2(SCH_1):M_H_ODT(1)
  87 M_H_ODT<0> ODT<0> @BASEBOARD_FAB2_LIB.BASEBOARD_FAB2(SCH_1):M_H_ODT(0)
 222 M_H_PAR    PAR @BASEBOARD_FAB2_LIB.BASEBOARD_FAB2(SCH_1):M_H_PAR
  58 M_GHJ_RST_N RESET_N @BASEBOARD_FAB2_LIB.BASEBOARD_FAB2(SCH_1):M_GHJ_RST_N
 144 TP_CH_H_DIMM_H0_RFU_2 RFU<2> @BASEBOARD_FAB2_LIB.BASEBOARD_FAB2(SCH_1):TP_CH_H_DIMM_H0_RFU_2
 227 TP_CH_H_DIMM_H0_RFU_1 RFU<1> @BASEBOARD_FAB2_LIB.BASEBOARD_FAB2(SCH_1):TP_CH_H_DIMM_H0_RFU_1
 205 TP_CH_H_DIMM_H0_RFU_0 RFU<0> @BASEBOARD_FAB2_LIB.BASEBOARD_FAB2(SCH_1):TP_CH_H_DIMM_H0_RFU_0
  84 M_H_CS_N<0>   S0_N @BASEBOARD_FAB2_LIB.BASEBOARD_FAB2(SCH_1):M_H_CS_N(0)
  89 M_H_CS_N<1>   S1_N @BASEBOARD_FAB2_LIB.BASEBOARD_FAB2(SCH_1):M_H_CS_N(1)
  93 M_H_CS_N<2> S2_N_C<0> @BASEBOARD_FAB2_LIB.BASEBOARD_FAB2(SCH_1):M_H_CS_N(2)
 237 M_H_CS_N<3> S3_N_C<1> @BASEBOARD_FAB2_LIB.BASEBOARD_FAB2(SCH_1):M_H_CS_N(3)
 238    GND  SA<2> @BASEBOARD_FAB2_LIB.BASEBOARD_FAB2(SCH_1):GND
 140 PVPP_GHJ  SA<1> @BASEBOARD_FAB2_LIB.BASEBOARD_FAB2(SCH_1):PVPP_GHJ
 139    GND  SA<0> @BASEBOARD_FAB2_LIB.BASEBOARD_FAB2(SCH_1):GND
 230 FM_ADR_COMPLETE_GHJ_N SAVE_N_NC @BASEBOARD_FAB2_LIB.BASEBOARD_FAB2(SCH_1):FM_ADR_COMPLETE_GHJ_N
 141 SMB_DDR_GHJ_VPP_SCL    SCL @BASEBOARD_FAB2_LIB.BASEBOARD_FAB2(SCH_1):SMB_DDR_GHJ_VPP_SCL
 285 SMB_DDR_GHJ_VPP_SDA    SDA @BASEBOARD_FAB2_LIB.BASEBOARD_FAB2(SCH_1):SMB_DDR_GHJ_VPP_SDA
 284 PVPP_GHJ VDDSPD @BASEBOARD_FAB2_LIB.BASEBOARD_FAB2(SCH_1):PVPP_GHJ
 146 M_H_VREF VREFCA @BASEBOARD_FAB2_LIB.BASEBOARD_FAB2(SCH_1):M_H_VREF

SCONN288_H44441004_PIP-SCONN,HA  I169  J1G2
   1 P12V_NVDIMM_GHJ 12V<1> @BASEBOARD_FAB2_LIB.BASEBOARD_FAB2(SCH_1):P12V_NVDIMM_GHJ
 145 P12V_NVDIMM_GHJ 12V<0> @BASEBOARD_FAB2_LIB.BASEBOARD_FAB2(SCH_1):P12V_NVDIMM_GHJ
  59 PVDDQ_GHJ VDD<25> @BASEBOARD_FAB2_LIB.BASEBOARD_FAB2(SCH_1):PVDDQ_GHJ
  61 PVDDQ_GHJ VDD<24> @BASEBOARD_FAB2_LIB.BASEBOARD_FAB2(SCH_1):PVDDQ_GHJ
  64 PVDDQ_GHJ VDD<23> @BASEBOARD_FAB2_LIB.BASEBOARD_FAB2(SCH_1):PVDDQ_GHJ
  67 PVDDQ_GHJ VDD<22> @BASEBOARD_FAB2_LIB.BASEBOARD_FAB2(SCH_1):PVDDQ_GHJ
  70 PVDDQ_GHJ VDD<21> @BASEBOARD_FAB2_LIB.BASEBOARD_FAB2(SCH_1):PVDDQ_GHJ
  73 PVDDQ_GHJ VDD<20> @BASEBOARD_FAB2_LIB.BASEBOARD_FAB2(SCH_1):PVDDQ_GHJ
  76 PVDDQ_GHJ VDD<19> @BASEBOARD_FAB2_LIB.BASEBOARD_FAB2(SCH_1):PVDDQ_GHJ
  80 PVDDQ_GHJ VDD<18> @BASEBOARD_FAB2_LIB.BASEBOARD_FAB2(SCH_1):PVDDQ_GHJ
  83 PVDDQ_GHJ VDD<17> @BASEBOARD_FAB2_LIB.BASEBOARD_FAB2(SCH_1):PVDDQ_GHJ
  85 PVDDQ_GHJ VDD<16> @BASEBOARD_FAB2_LIB.BASEBOARD_FAB2(SCH_1):PVDDQ_GHJ
  88 PVDDQ_GHJ VDD<15> @BASEBOARD_FAB2_LIB.BASEBOARD_FAB2(SCH_1):PVDDQ_GHJ
  90 PVDDQ_GHJ VDD<14> @BASEBOARD_FAB2_LIB.BASEBOARD_FAB2(SCH_1):PVDDQ_GHJ
  92 PVDDQ_GHJ VDD<13> @BASEBOARD_FAB2_LIB.BASEBOARD_FAB2(SCH_1):PVDDQ_GHJ
 204 PVDDQ_GHJ VDD<12> @BASEBOARD_FAB2_LIB.BASEBOARD_FAB2(SCH_1):PVDDQ_GHJ
 206 PVDDQ_GHJ VDD<11> @BASEBOARD_FAB2_LIB.BASEBOARD_FAB2(SCH_1):PVDDQ_GHJ
 209 PVDDQ_GHJ VDD<10> @BASEBOARD_FAB2_LIB.BASEBOARD_FAB2(SCH_1):PVDDQ_GHJ
 212 PVDDQ_GHJ VDD<9> @BASEBOARD_FAB2_LIB.BASEBOARD_FAB2(SCH_1):PVDDQ_GHJ
 215 PVDDQ_GHJ VDD<8> @BASEBOARD_FAB2_LIB.BASEBOARD_FAB2(SCH_1):PVDDQ_GHJ
 217 PVDDQ_GHJ VDD<7> @BASEBOARD_FAB2_LIB.BASEBOARD_FAB2(SCH_1):PVDDQ_GHJ
 220 PVDDQ_GHJ VDD<6> @BASEBOARD_FAB2_LIB.BASEBOARD_FAB2(SCH_1):PVDDQ_GHJ
 223 PVDDQ_GHJ VDD<5> @BASEBOARD_FAB2_LIB.BASEBOARD_FAB2(SCH_1):PVDDQ_GHJ
 226 PVDDQ_GHJ VDD<4> @BASEBOARD_FAB2_LIB.BASEBOARD_FAB2(SCH_1):PVDDQ_GHJ
 229 PVDDQ_GHJ VDD<3> @BASEBOARD_FAB2_LIB.BASEBOARD_FAB2(SCH_1):PVDDQ_GHJ
 231 PVDDQ_GHJ VDD<2> @BASEBOARD_FAB2_LIB.BASEBOARD_FAB2(SCH_1):PVDDQ_GHJ
 233 PVDDQ_GHJ VDD<1> @BASEBOARD_FAB2_LIB.BASEBOARD_FAB2(SCH_1):PVDDQ_GHJ
 236 PVDDQ_GHJ VDD<0> @BASEBOARD_FAB2_LIB.BASEBOARD_FAB2(SCH_1):PVDDQ_GHJ
 142 PVPP_GHJ VPP<4> @BASEBOARD_FAB2_LIB.BASEBOARD_FAB2(SCH_1):PVPP_GHJ
 143 PVPP_GHJ VPP<3> @BASEBOARD_FAB2_LIB.BASEBOARD_FAB2(SCH_1):PVPP_GHJ
 288 PVPP_GHJ VPP<2> @BASEBOARD_FAB2_LIB.BASEBOARD_FAB2(SCH_1):PVPP_GHJ
 286 PVPP_GHJ VPP<1> @BASEBOARD_FAB2_LIB.BASEBOARD_FAB2(SCH_1):PVPP_GHJ
 287 PVPP_GHJ VPP<0> @BASEBOARD_FAB2_LIB.BASEBOARD_FAB2(SCH_1):PVPP_GHJ
  77 PVTT_GHJ VTT<1> @BASEBOARD_FAB2_LIB.BASEBOARD_FAB2(SCH_1):PVTT_GHJ
 221 PVTT_GHJ VTT<0> @BASEBOARD_FAB2_LIB.BASEBOARD_FAB2(SCH_1):PVTT_GHJ

CAP_A_0402V-0.01UF,25V,10%,X7RA  I178  C9U7
   1 M_H_VREF      A @BASEBOARD_FAB2_LIB.BASEBOARD_FAB2(SCH_1):M_H_VREF
   2    GND      B @BASEBOARD_FAB2_LIB.BASEBOARD_FAB2(SCH_1):GND


DRAWING: @BASEBOARD_FAB2_LIB.BASEBOARD_FAB2(SCH_1):PAGE80 

CAP_A_0402V-0.01UF,25V,10%,X7RA  I3  C1G10
   1 M_H_VREF      A @BASEBOARD_FAB2_LIB.BASEBOARD_FAB2(SCH_1):M_H_VREF
   2    GND      B @BASEBOARD_FAB2_LIB.BASEBOARD_FAB2(SCH_1):GND

SCONN288_H44441003_PIP-SCONN,HA  I24  J9U1
  79 M_H_MA<0>     A0 @BASEBOARD_FAB2_LIB.BASEBOARD_FAB2(SCH_1):M_H_MA(0)
  72 M_H_MA<1>     A1 @BASEBOARD_FAB2_LIB.BASEBOARD_FAB2(SCH_1):M_H_MA(1)
 225 M_H_MA<10>    A10 @BASEBOARD_FAB2_LIB.BASEBOARD_FAB2(SCH_1):M_H_MA(10)
 210 M_H_MA<11>    A11 @BASEBOARD_FAB2_LIB.BASEBOARD_FAB2(SCH_1):M_H_MA(11)
  65 M_H_MA<12>    A12 @BASEBOARD_FAB2_LIB.BASEBOARD_FAB2(SCH_1):M_H_MA(12)
 232 M_H_MA<13>    A13 @BASEBOARD_FAB2_LIB.BASEBOARD_FAB2(SCH_1):M_H_MA(13)
 228 M_H_MA<14> A14_WE_N @BASEBOARD_FAB2_LIB.BASEBOARD_FAB2(SCH_1):M_H_MA(14)
  86 M_H_MA<15> A15_CAS_N @BASEBOARD_FAB2_LIB.BASEBOARD_FAB2(SCH_1):M_H_MA(15)
  82 M_H_MA<16> A16_RAS_N @BASEBOARD_FAB2_LIB.BASEBOARD_FAB2(SCH_1):M_H_MA(16)
 234 M_H_MA<17>    A17 @BASEBOARD_FAB2_LIB.BASEBOARD_FAB2(SCH_1):M_H_MA(17)
 216 M_H_MA<2>     A2 @BASEBOARD_FAB2_LIB.BASEBOARD_FAB2(SCH_1):M_H_MA(2)
  71 M_H_MA<3>     A3 @BASEBOARD_FAB2_LIB.BASEBOARD_FAB2(SCH_1):M_H_MA(3)
 214 M_H_MA<4>     A4 @BASEBOARD_FAB2_LIB.BASEBOARD_FAB2(SCH_1):M_H_MA(4)
 213 M_H_MA<5>     A5 @BASEBOARD_FAB2_LIB.BASEBOARD_FAB2(SCH_1):M_H_MA(5)
  69 M_H_MA<6>     A6 @BASEBOARD_FAB2_LIB.BASEBOARD_FAB2(SCH_1):M_H_MA(6)
 211 M_H_MA<7>     A7 @BASEBOARD_FAB2_LIB.BASEBOARD_FAB2(SCH_1):M_H_MA(7)
  68 M_H_MA<8>     A8 @BASEBOARD_FAB2_LIB.BASEBOARD_FAB2(SCH_1):M_H_MA(8)
  66 M_H_MA<9>     A9 @BASEBOARD_FAB2_LIB.BASEBOARD_FAB2(SCH_1):M_H_MA(9)
  62 M_H_ACT_N  ACT_N @BASEBOARD_FAB2_LIB.BASEBOARD_FAB2(SCH_1):M_H_ACT_N
 208 M_H_ALERT_N ALERT_N @BASEBOARD_FAB2_LIB.BASEBOARD_FAB2(SCH_1):M_H_ALERT_N
 224 M_H_BA<1>  BA<1> @BASEBOARD_FAB2_LIB.BASEBOARD_FAB2(SCH_1):M_H_BA(1)
  81 M_H_BA<0>  BA<0> @BASEBOARD_FAB2_LIB.BASEBOARD_FAB2(SCH_1):M_H_BA(0)
 207 M_H_BG<1>  BG<1> @BASEBOARD_FAB2_LIB.BASEBOARD_FAB2(SCH_1):M_H_BG(1)
  63 M_H_BG<0>  BG<0> @BASEBOARD_FAB2_LIB.BASEBOARD_FAB2(SCH_1):M_H_BG(0)
 235 M_H_C<2>   C<2> @BASEBOARD_FAB2_LIB.BASEBOARD_FAB2(SCH_1):M_H_C(2)
 199 M_H_ECC<7>  CB<7> @BASEBOARD_FAB2_LIB.BASEBOARD_FAB2(SCH_1):M_H_ECC(7)
  54 M_H_ECC<6>  CB<6> @BASEBOARD_FAB2_LIB.BASEBOARD_FAB2(SCH_1):M_H_ECC(6)
 192 M_H_ECC<5>  CB<5> @BASEBOARD_FAB2_LIB.BASEBOARD_FAB2(SCH_1):M_H_ECC(5)
  47 M_H_ECC<4>  CB<4> @BASEBOARD_FAB2_LIB.BASEBOARD_FAB2(SCH_1):M_H_ECC(4)
 201 M_H_ECC<3>  CB<3> @BASEBOARD_FAB2_LIB.BASEBOARD_FAB2(SCH_1):M_H_ECC(3)
  56 M_H_ECC<2>  CB<2> @BASEBOARD_FAB2_LIB.BASEBOARD_FAB2(SCH_1):M_H_ECC(2)
 194 M_H_ECC<1>  CB<1> @BASEBOARD_FAB2_LIB.BASEBOARD_FAB2(SCH_1):M_H_ECC(1)
  49 M_H_ECC<0>  CB<0> @BASEBOARD_FAB2_LIB.BASEBOARD_FAB2(SCH_1):M_H_ECC(0)
  75 M_H_CLK_DN<2>   CK0N @BASEBOARD_FAB2_LIB.BASEBOARD_FAB2(SCH_1):M_H_CLK_DN(2)
  74 M_H_CLK_DP<2>   CK0P @BASEBOARD_FAB2_LIB.BASEBOARD_FAB2(SCH_1):M_H_CLK_DP(2)
 219 M_H_CLK_DN<3>   CK1N @BASEBOARD_FAB2_LIB.BASEBOARD_FAB2(SCH_1):M_H_CLK_DN(3)
 218 M_H_CLK_DP<3>   CK1P @BASEBOARD_FAB2_LIB.BASEBOARD_FAB2(SCH_1):M_H_CLK_DP(3)
 203 M_H_CKE<3> CKE<1> @BASEBOARD_FAB2_LIB.BASEBOARD_FAB2(SCH_1):M_H_CKE(3)
  60 M_H_CKE<2> CKE<0> @BASEBOARD_FAB2_LIB.BASEBOARD_FAB2(SCH_1):M_H_CKE(2)
 280 M_H_DQ<63> DQ<63> @BASEBOARD_FAB2_LIB.BASEBOARD_FAB2(SCH_1):M_H_DQ(63)
 135 M_H_DQ<62> DQ<62> @BASEBOARD_FAB2_LIB.BASEBOARD_FAB2(SCH_1):M_H_DQ(62)
 273 M_H_DQ<61> DQ<61> @BASEBOARD_FAB2_LIB.BASEBOARD_FAB2(SCH_1):M_H_DQ(61)
 128 M_H_DQ<60> DQ<60> @BASEBOARD_FAB2_LIB.BASEBOARD_FAB2(SCH_1):M_H_DQ(60)
 282 M_H_DQ<59> DQ<59> @BASEBOARD_FAB2_LIB.BASEBOARD_FAB2(SCH_1):M_H_DQ(59)
 137 M_H_DQ<58> DQ<58> @BASEBOARD_FAB2_LIB.BASEBOARD_FAB2(SCH_1):M_H_DQ(58)
 275 M_H_DQ<57> DQ<57> @BASEBOARD_FAB2_LIB.BASEBOARD_FAB2(SCH_1):M_H_DQ(57)
 130 M_H_DQ<56> DQ<56> @BASEBOARD_FAB2_LIB.BASEBOARD_FAB2(SCH_1):M_H_DQ(56)
 269 M_H_DQ<55> DQ<55> @BASEBOARD_FAB2_LIB.BASEBOARD_FAB2(SCH_1):M_H_DQ(55)
 124 M_H_DQ<54> DQ<54> @BASEBOARD_FAB2_LIB.BASEBOARD_FAB2(SCH_1):M_H_DQ(54)
 262 M_H_DQ<53> DQ<53> @BASEBOARD_FAB2_LIB.BASEBOARD_FAB2(SCH_1):M_H_DQ(53)
 117 M_H_DQ<52> DQ<52> @BASEBOARD_FAB2_LIB.BASEBOARD_FAB2(SCH_1):M_H_DQ(52)
 271 M_H_DQ<51> DQ<51> @BASEBOARD_FAB2_LIB.BASEBOARD_FAB2(SCH_1):M_H_DQ(51)
 126 M_H_DQ<50> DQ<50> @BASEBOARD_FAB2_LIB.BASEBOARD_FAB2(SCH_1):M_H_DQ(50)
 264 M_H_DQ<49> DQ<49> @BASEBOARD_FAB2_LIB.BASEBOARD_FAB2(SCH_1):M_H_DQ(49)
 119 M_H_DQ<48> DQ<48> @BASEBOARD_FAB2_LIB.BASEBOARD_FAB2(SCH_1):M_H_DQ(48)
 258 M_H_DQ<47> DQ<47> @BASEBOARD_FAB2_LIB.BASEBOARD_FAB2(SCH_1):M_H_DQ(47)
 113 M_H_DQ<46> DQ<46> @BASEBOARD_FAB2_LIB.BASEBOARD_FAB2(SCH_1):M_H_DQ(46)
 251 M_H_DQ<45> DQ<45> @BASEBOARD_FAB2_LIB.BASEBOARD_FAB2(SCH_1):M_H_DQ(45)
 106 M_H_DQ<44> DQ<44> @BASEBOARD_FAB2_LIB.BASEBOARD_FAB2(SCH_1):M_H_DQ(44)
 260 M_H_DQ<43> DQ<43> @BASEBOARD_FAB2_LIB.BASEBOARD_FAB2(SCH_1):M_H_DQ(43)
 115 M_H_DQ<42> DQ<42> @BASEBOARD_FAB2_LIB.BASEBOARD_FAB2(SCH_1):M_H_DQ(42)
 253 M_H_DQ<41> DQ<41> @BASEBOARD_FAB2_LIB.BASEBOARD_FAB2(SCH_1):M_H_DQ(41)
 108 M_H_DQ<40> DQ<40> @BASEBOARD_FAB2_LIB.BASEBOARD_FAB2(SCH_1):M_H_DQ(40)
 247 M_H_DQ<39> DQ<39> @BASEBOARD_FAB2_LIB.BASEBOARD_FAB2(SCH_1):M_H_DQ(39)
 102 M_H_DQ<38> DQ<38> @BASEBOARD_FAB2_LIB.BASEBOARD_FAB2(SCH_1):M_H_DQ(38)
 240 M_H_DQ<37> DQ<37> @BASEBOARD_FAB2_LIB.BASEBOARD_FAB2(SCH_1):M_H_DQ(37)
  95 M_H_DQ<36> DQ<36> @BASEBOARD_FAB2_LIB.BASEBOARD_FAB2(SCH_1):M_H_DQ(36)
 249 M_H_DQ<35> DQ<35> @BASEBOARD_FAB2_LIB.BASEBOARD_FAB2(SCH_1):M_H_DQ(35)
 104 M_H_DQ<34> DQ<34> @BASEBOARD_FAB2_LIB.BASEBOARD_FAB2(SCH_1):M_H_DQ(34)
 242 M_H_DQ<33> DQ<33> @BASEBOARD_FAB2_LIB.BASEBOARD_FAB2(SCH_1):M_H_DQ(33)
  97 M_H_DQ<32> DQ<32> @BASEBOARD_FAB2_LIB.BASEBOARD_FAB2(SCH_1):M_H_DQ(32)
 188 M_H_DQ<31> DQ<31> @BASEBOARD_FAB2_LIB.BASEBOARD_FAB2(SCH_1):M_H_DQ(31)
  43 M_H_DQ<30> DQ<30> @BASEBOARD_FAB2_LIB.BASEBOARD_FAB2(SCH_1):M_H_DQ(30)
 181 M_H_DQ<29> DQ<29> @BASEBOARD_FAB2_LIB.BASEBOARD_FAB2(SCH_1):M_H_DQ(29)
  36 M_H_DQ<28> DQ<28> @BASEBOARD_FAB2_LIB.BASEBOARD_FAB2(SCH_1):M_H_DQ(28)
 190 M_H_DQ<27> DQ<27> @BASEBOARD_FAB2_LIB.BASEBOARD_FAB2(SCH_1):M_H_DQ(27)
  45 M_H_DQ<26> DQ<26> @BASEBOARD_FAB2_LIB.BASEBOARD_FAB2(SCH_1):M_H_DQ(26)
 183 M_H_DQ<25> DQ<25> @BASEBOARD_FAB2_LIB.BASEBOARD_FAB2(SCH_1):M_H_DQ(25)
  38 M_H_DQ<24> DQ<24> @BASEBOARD_FAB2_LIB.BASEBOARD_FAB2(SCH_1):M_H_DQ(24)
 177 M_H_DQ<23> DQ<23> @BASEBOARD_FAB2_LIB.BASEBOARD_FAB2(SCH_1):M_H_DQ(23)
  32 M_H_DQ<22> DQ<22> @BASEBOARD_FAB2_LIB.BASEBOARD_FAB2(SCH_1):M_H_DQ(22)
 170 M_H_DQ<21> DQ<21> @BASEBOARD_FAB2_LIB.BASEBOARD_FAB2(SCH_1):M_H_DQ(21)
  25 M_H_DQ<20> DQ<20> @BASEBOARD_FAB2_LIB.BASEBOARD_FAB2(SCH_1):M_H_DQ(20)
 179 M_H_DQ<19> DQ<19> @BASEBOARD_FAB2_LIB.BASEBOARD_FAB2(SCH_1):M_H_DQ(19)
  34 M_H_DQ<18> DQ<18> @BASEBOARD_FAB2_LIB.BASEBOARD_FAB2(SCH_1):M_H_DQ(18)
 172 M_H_DQ<17> DQ<17> @BASEBOARD_FAB2_LIB.BASEBOARD_FAB2(SCH_1):M_H_DQ(17)
  27 M_H_DQ<16> DQ<16> @BASEBOARD_FAB2_LIB.BASEBOARD_FAB2(SCH_1):M_H_DQ(16)
 166 M_H_DQ<15> DQ<15> @BASEBOARD_FAB2_LIB.BASEBOARD_FAB2(SCH_1):M_H_DQ(15)
  21 M_H_DQ<14> DQ<14> @BASEBOARD_FAB2_LIB.BASEBOARD_FAB2(SCH_1):M_H_DQ(14)
 159 M_H_DQ<13> DQ<13> @BASEBOARD_FAB2_LIB.BASEBOARD_FAB2(SCH_1):M_H_DQ(13)
  14 M_H_DQ<12> DQ<12> @BASEBOARD_FAB2_LIB.BASEBOARD_FAB2(SCH_1):M_H_DQ(12)
 168 M_H_DQ<11> DQ<11> @BASEBOARD_FAB2_LIB.BASEBOARD_FAB2(SCH_1):M_H_DQ(11)
  23 M_H_DQ<10> DQ<10> @BASEBOARD_FAB2_LIB.BASEBOARD_FAB2(SCH_1):M_H_DQ(10)
 161 M_H_DQ<9>  DQ<9> @BASEBOARD_FAB2_LIB.BASEBOARD_FAB2(SCH_1):M_H_DQ(9)
  16 M_H_DQ<8>  DQ<8> @BASEBOARD_FAB2_LIB.BASEBOARD_FAB2(SCH_1):M_H_DQ(8)
 155 M_H_DQ<7>  DQ<7> @BASEBOARD_FAB2_LIB.BASEBOARD_FAB2(SCH_1):M_H_DQ(7)
  10 M_H_DQ<6>  DQ<6> @BASEBOARD_FAB2_LIB.BASEBOARD_FAB2(SCH_1):M_H_DQ(6)
 148 M_H_DQ<5>  DQ<5> @BASEBOARD_FAB2_LIB.BASEBOARD_FAB2(SCH_1):M_H_DQ(5)
   3 M_H_DQ<4>  DQ<4> @BASEBOARD_FAB2_LIB.BASEBOARD_FAB2(SCH_1):M_H_DQ(4)
 157 M_H_DQ<3>  DQ<3> @BASEBOARD_FAB2_LIB.BASEBOARD_FAB2(SCH_1):M_H_DQ(3)
  12 M_H_DQ<2>  DQ<2> @BASEBOARD_FAB2_LIB.BASEBOARD_FAB2(SCH_1):M_H_DQ(2)
 150 M_H_DQ<1>  DQ<1> @BASEBOARD_FAB2_LIB.BASEBOARD_FAB2(SCH_1):M_H_DQ(1)
   5 M_H_DQ<0>  DQ<0> @BASEBOARD_FAB2_LIB.BASEBOARD_FAB2(SCH_1):M_H_DQ(0)
  78 FM_DIMM_EVENT_COD_N EVENT_N @BASEBOARD_FAB2_LIB.BASEBOARD_FAB2(SCH_1):FM_DIMM_EVENT_COD_N
  91 M_H_ODT<3> ODT<1> @BASEBOARD_FAB2_LIB.BASEBOARD_FAB2(SCH_1):M_H_ODT(3)
  87 M_H_ODT<2> ODT<0> @BASEBOARD_FAB2_LIB.BASEBOARD_FAB2(SCH_1):M_H_ODT(2)
 222 M_H_PAR    PAR @BASEBOARD_FAB2_LIB.BASEBOARD_FAB2(SCH_1):M_H_PAR
  58 M_GHJ_RST_N RESET_N @BASEBOARD_FAB2_LIB.BASEBOARD_FAB2(SCH_1):M_GHJ_RST_N
 144 TP_CH_H_DIMM0_RFU_2 RFU<2> @BASEBOARD_FAB2_LIB.BASEBOARD_FAB2(SCH_1):TP_CH_H_DIMM0_RFU_2
 227 TP_CH_H_DIMM0_RFU_1 RFU<1> @BASEBOARD_FAB2_LIB.BASEBOARD_FAB2(SCH_1):TP_CH_H_DIMM0_RFU_1
 205 TP_CH_H_DIMM0_RFU_0 RFU<0> @BASEBOARD_FAB2_LIB.BASEBOARD_FAB2(SCH_1):TP_CH_H_DIMM0_RFU_0
  84 M_H_CS_N<4>   S0_N @BASEBOARD_FAB2_LIB.BASEBOARD_FAB2(SCH_1):M_H_CS_N(4)
  89 M_H_CS_N<5>   S1_N @BASEBOARD_FAB2_LIB.BASEBOARD_FAB2(SCH_1):M_H_CS_N(5)
  93 M_H_CS_N<6> S2_N_C<0> @BASEBOARD_FAB2_LIB.BASEBOARD_FAB2(SCH_1):M_H_CS_N(6)
 237 M_H_CS_N<7> S3_N_C<1> @BASEBOARD_FAB2_LIB.BASEBOARD_FAB2(SCH_1):M_H_CS_N(7)
 238    GND  SA<2> @BASEBOARD_FAB2_LIB.BASEBOARD_FAB2(SCH_1):GND
 140 PVPP_GHJ  SA<1> @BASEBOARD_FAB2_LIB.BASEBOARD_FAB2(SCH_1):PVPP_GHJ
 139 PVPP_GHJ  SA<0> @BASEBOARD_FAB2_LIB.BASEBOARD_FAB2(SCH_1):PVPP_GHJ
 230 FM_ADR_COMPLETE_GHJ_N SAVE_N_NC @BASEBOARD_FAB2_LIB.BASEBOARD_FAB2(SCH_1):FM_ADR_COMPLETE_GHJ_N
 141 SMB_DDR_GHJ_VPP_SCL    SCL @BASEBOARD_FAB2_LIB.BASEBOARD_FAB2(SCH_1):SMB_DDR_GHJ_VPP_SCL
 285 SMB_DDR_GHJ_VPP_SDA    SDA @BASEBOARD_FAB2_LIB.BASEBOARD_FAB2(SCH_1):SMB_DDR_GHJ_VPP_SDA
 284 PVPP_GHJ VDDSPD @BASEBOARD_FAB2_LIB.BASEBOARD_FAB2(SCH_1):PVPP_GHJ
 146 M_H_VREF VREFCA @BASEBOARD_FAB2_LIB.BASEBOARD_FAB2(SCH_1):M_H_VREF

SCONN288_H44441003_PIP-SCONN,HA  I56  J9U1
   1 P12V_NVDIMM_GHJ 12V<1> @BASEBOARD_FAB2_LIB.BASEBOARD_FAB2(SCH_1):P12V_NVDIMM_GHJ
 145 P12V_NVDIMM_GHJ 12V<0> @BASEBOARD_FAB2_LIB.BASEBOARD_FAB2(SCH_1):P12V_NVDIMM_GHJ
  59 PVDDQ_GHJ VDD<25> @BASEBOARD_FAB2_LIB.BASEBOARD_FAB2(SCH_1):PVDDQ_GHJ
  61 PVDDQ_GHJ VDD<24> @BASEBOARD_FAB2_LIB.BASEBOARD_FAB2(SCH_1):PVDDQ_GHJ
  64 PVDDQ_GHJ VDD<23> @BASEBOARD_FAB2_LIB.BASEBOARD_FAB2(SCH_1):PVDDQ_GHJ
  67 PVDDQ_GHJ VDD<22> @BASEBOARD_FAB2_LIB.BASEBOARD_FAB2(SCH_1):PVDDQ_GHJ
  70 PVDDQ_GHJ VDD<21> @BASEBOARD_FAB2_LIB.BASEBOARD_FAB2(SCH_1):PVDDQ_GHJ
  73 PVDDQ_GHJ VDD<20> @BASEBOARD_FAB2_LIB.BASEBOARD_FAB2(SCH_1):PVDDQ_GHJ
  76 PVDDQ_GHJ VDD<19> @BASEBOARD_FAB2_LIB.BASEBOARD_FAB2(SCH_1):PVDDQ_GHJ
  80 PVDDQ_GHJ VDD<18> @BASEBOARD_FAB2_LIB.BASEBOARD_FAB2(SCH_1):PVDDQ_GHJ
  83 PVDDQ_GHJ VDD<17> @BASEBOARD_FAB2_LIB.BASEBOARD_FAB2(SCH_1):PVDDQ_GHJ
  85 PVDDQ_GHJ VDD<16> @BASEBOARD_FAB2_LIB.BASEBOARD_FAB2(SCH_1):PVDDQ_GHJ
  88 PVDDQ_GHJ VDD<15> @BASEBOARD_FAB2_LIB.BASEBOARD_FAB2(SCH_1):PVDDQ_GHJ
  90 PVDDQ_GHJ VDD<14> @BASEBOARD_FAB2_LIB.BASEBOARD_FAB2(SCH_1):PVDDQ_GHJ
  92 PVDDQ_GHJ VDD<13> @BASEBOARD_FAB2_LIB.BASEBOARD_FAB2(SCH_1):PVDDQ_GHJ
 204 PVDDQ_GHJ VDD<12> @BASEBOARD_FAB2_LIB.BASEBOARD_FAB2(SCH_1):PVDDQ_GHJ
 206 PVDDQ_GHJ VDD<11> @BASEBOARD_FAB2_LIB.BASEBOARD_FAB2(SCH_1):PVDDQ_GHJ
 209 PVDDQ_GHJ VDD<10> @BASEBOARD_FAB2_LIB.BASEBOARD_FAB2(SCH_1):PVDDQ_GHJ
 212 PVDDQ_GHJ VDD<9> @BASEBOARD_FAB2_LIB.BASEBOARD_FAB2(SCH_1):PVDDQ_GHJ
 215 PVDDQ_GHJ VDD<8> @BASEBOARD_FAB2_LIB.BASEBOARD_FAB2(SCH_1):PVDDQ_GHJ
 217 PVDDQ_GHJ VDD<7> @BASEBOARD_FAB2_LIB.BASEBOARD_FAB2(SCH_1):PVDDQ_GHJ
 220 PVDDQ_GHJ VDD<6> @BASEBOARD_FAB2_LIB.BASEBOARD_FAB2(SCH_1):PVDDQ_GHJ
 223 PVDDQ_GHJ VDD<5> @BASEBOARD_FAB2_LIB.BASEBOARD_FAB2(SCH_1):PVDDQ_GHJ
 226 PVDDQ_GHJ VDD<4> @BASEBOARD_FAB2_LIB.BASEBOARD_FAB2(SCH_1):PVDDQ_GHJ
 229 PVDDQ_GHJ VDD<3> @BASEBOARD_FAB2_LIB.BASEBOARD_FAB2(SCH_1):PVDDQ_GHJ
 231 PVDDQ_GHJ VDD<2> @BASEBOARD_FAB2_LIB.BASEBOARD_FAB2(SCH_1):PVDDQ_GHJ
 233 PVDDQ_GHJ VDD<1> @BASEBOARD_FAB2_LIB.BASEBOARD_FAB2(SCH_1):PVDDQ_GHJ
 236 PVDDQ_GHJ VDD<0> @BASEBOARD_FAB2_LIB.BASEBOARD_FAB2(SCH_1):PVDDQ_GHJ
 142 PVPP_GHJ VPP<4> @BASEBOARD_FAB2_LIB.BASEBOARD_FAB2(SCH_1):PVPP_GHJ
 143 PVPP_GHJ VPP<3> @BASEBOARD_FAB2_LIB.BASEBOARD_FAB2(SCH_1):PVPP_GHJ
 288 PVPP_GHJ VPP<2> @BASEBOARD_FAB2_LIB.BASEBOARD_FAB2(SCH_1):PVPP_GHJ
 286 PVPP_GHJ VPP<1> @BASEBOARD_FAB2_LIB.BASEBOARD_FAB2(SCH_1):PVPP_GHJ
 287 PVPP_GHJ VPP<0> @BASEBOARD_FAB2_LIB.BASEBOARD_FAB2(SCH_1):PVPP_GHJ
  77 PVTT_GHJ VTT<1> @BASEBOARD_FAB2_LIB.BASEBOARD_FAB2(SCH_1):PVTT_GHJ
 221 PVTT_GHJ VTT<0> @BASEBOARD_FAB2_LIB.BASEBOARD_FAB2(SCH_1):PVTT_GHJ

SCONN288_H44441003_PIP-SCONN,HA  I101  J9U1
 152 M_H_DQS_DN<0>  DQS0N @BASEBOARD_FAB2_LIB.BASEBOARD_FAB2(SCH_1):M_H_DQS_DN(0)
 153 M_H_DQS_DP<0>  DQS0P @BASEBOARD_FAB2_LIB.BASEBOARD_FAB2(SCH_1):M_H_DQS_DP(0)
  19 M_H_DQS_DN<10> DQS10N @BASEBOARD_FAB2_LIB.BASEBOARD_FAB2(SCH_1):M_H_DQS_DN(10)
  18 M_H_DQS_DP<10> DQS10P @BASEBOARD_FAB2_LIB.BASEBOARD_FAB2(SCH_1):M_H_DQS_DP(10)
  30 M_H_DQS_DN<11> DQS11N @BASEBOARD_FAB2_LIB.BASEBOARD_FAB2(SCH_1):M_H_DQS_DN(11)
  29 M_H_DQS_DP<11> DQS11P @BASEBOARD_FAB2_LIB.BASEBOARD_FAB2(SCH_1):M_H_DQS_DP(11)
  41 M_H_DQS_DN<12> DQS12N @BASEBOARD_FAB2_LIB.BASEBOARD_FAB2(SCH_1):M_H_DQS_DN(12)
  40 M_H_DQS_DP<12> DQS12P @BASEBOARD_FAB2_LIB.BASEBOARD_FAB2(SCH_1):M_H_DQS_DP(12)
 100 M_H_DQS_DN<13> DQS13N @BASEBOARD_FAB2_LIB.BASEBOARD_FAB2(SCH_1):M_H_DQS_DN(13)
  99 M_H_DQS_DP<13> DQS13P @BASEBOARD_FAB2_LIB.BASEBOARD_FAB2(SCH_1):M_H_DQS_DP(13)
 111 M_H_DQS_DN<14> DQS14N @BASEBOARD_FAB2_LIB.BASEBOARD_FAB2(SCH_1):M_H_DQS_DN(14)
 110 M_H_DQS_DP<14> DQS14P @BASEBOARD_FAB2_LIB.BASEBOARD_FAB2(SCH_1):M_H_DQS_DP(14)
 122 M_H_DQS_DN<15> DQS15N @BASEBOARD_FAB2_LIB.BASEBOARD_FAB2(SCH_1):M_H_DQS_DN(15)
 121 M_H_DQS_DP<15> DQS15P @BASEBOARD_FAB2_LIB.BASEBOARD_FAB2(SCH_1):M_H_DQS_DP(15)
 133 M_H_DQS_DN<16> DQS16N @BASEBOARD_FAB2_LIB.BASEBOARD_FAB2(SCH_1):M_H_DQS_DN(16)
 132 M_H_DQS_DP<16> DQS16P @BASEBOARD_FAB2_LIB.BASEBOARD_FAB2(SCH_1):M_H_DQS_DP(16)
  52 M_H_DQS_DN<17> DQS17N @BASEBOARD_FAB2_LIB.BASEBOARD_FAB2(SCH_1):M_H_DQS_DN(17)
  51 M_H_DQS_DP<17> DQS17P @BASEBOARD_FAB2_LIB.BASEBOARD_FAB2(SCH_1):M_H_DQS_DP(17)
 163 M_H_DQS_DN<1>  DQS1N @BASEBOARD_FAB2_LIB.BASEBOARD_FAB2(SCH_1):M_H_DQS_DN(1)
 164 M_H_DQS_DP<1>  DQS1P @BASEBOARD_FAB2_LIB.BASEBOARD_FAB2(SCH_1):M_H_DQS_DP(1)
 174 M_H_DQS_DN<2>  DQS2N @BASEBOARD_FAB2_LIB.BASEBOARD_FAB2(SCH_1):M_H_DQS_DN(2)
 175 M_H_DQS_DP<2>  DQS2P @BASEBOARD_FAB2_LIB.BASEBOARD_FAB2(SCH_1):M_H_DQS_DP(2)
 185 M_H_DQS_DN<3>  DQS3N @BASEBOARD_FAB2_LIB.BASEBOARD_FAB2(SCH_1):M_H_DQS_DN(3)
 186 M_H_DQS_DP<3>  DQS3P @BASEBOARD_FAB2_LIB.BASEBOARD_FAB2(SCH_1):M_H_DQS_DP(3)
 244 M_H_DQS_DN<4>  DQS4N @BASEBOARD_FAB2_LIB.BASEBOARD_FAB2(SCH_1):M_H_DQS_DN(4)
 245 M_H_DQS_DP<4>  DQS4P @BASEBOARD_FAB2_LIB.BASEBOARD_FAB2(SCH_1):M_H_DQS_DP(4)
 255 M_H_DQS_DN<5>  DQS5N @BASEBOARD_FAB2_LIB.BASEBOARD_FAB2(SCH_1):M_H_DQS_DN(5)
 256 M_H_DQS_DP<5>  DQS5P @BASEBOARD_FAB2_LIB.BASEBOARD_FAB2(SCH_1):M_H_DQS_DP(5)
 266 M_H_DQS_DN<6>  DQS6N @BASEBOARD_FAB2_LIB.BASEBOARD_FAB2(SCH_1):M_H_DQS_DN(6)
 267 M_H_DQS_DP<6>  DQS6P @BASEBOARD_FAB2_LIB.BASEBOARD_FAB2(SCH_1):M_H_DQS_DP(6)
 277 M_H_DQS_DN<7>  DQS7N @BASEBOARD_FAB2_LIB.BASEBOARD_FAB2(SCH_1):M_H_DQS_DN(7)
 278 M_H_DQS_DP<7>  DQS7P @BASEBOARD_FAB2_LIB.BASEBOARD_FAB2(SCH_1):M_H_DQS_DP(7)
 196 M_H_DQS_DN<8>  DQS8N @BASEBOARD_FAB2_LIB.BASEBOARD_FAB2(SCH_1):M_H_DQS_DN(8)
 197 M_H_DQS_DP<8>  DQS8P @BASEBOARD_FAB2_LIB.BASEBOARD_FAB2(SCH_1):M_H_DQS_DP(8)
   8 M_H_DQS_DN<9>  DQS9N @BASEBOARD_FAB2_LIB.BASEBOARD_FAB2(SCH_1):M_H_DQS_DN(9)
   7 M_H_DQS_DP<9>  DQS9P @BASEBOARD_FAB2_LIB.BASEBOARD_FAB2(SCH_1):M_H_DQS_DP(9)

SCONN288_H44441003_PIP-SCONN,HA  I138  J9U1
   2    GND VSS<93> @BASEBOARD_FAB2_LIB.BASEBOARD_FAB2(SCH_1):GND
   4    GND VSS<92> @BASEBOARD_FAB2_LIB.BASEBOARD_FAB2(SCH_1):GND
   6    GND VSS<91> @BASEBOARD_FAB2_LIB.BASEBOARD_FAB2(SCH_1):GND
   9    GND VSS<90> @BASEBOARD_FAB2_LIB.BASEBOARD_FAB2(SCH_1):GND
  11    GND VSS<89> @BASEBOARD_FAB2_LIB.BASEBOARD_FAB2(SCH_1):GND
  13    GND VSS<88> @BASEBOARD_FAB2_LIB.BASEBOARD_FAB2(SCH_1):GND
  15    GND VSS<87> @BASEBOARD_FAB2_LIB.BASEBOARD_FAB2(SCH_1):GND
  17    GND VSS<86> @BASEBOARD_FAB2_LIB.BASEBOARD_FAB2(SCH_1):GND
  20    GND VSS<85> @BASEBOARD_FAB2_LIB.BASEBOARD_FAB2(SCH_1):GND
  22    GND VSS<84> @BASEBOARD_FAB2_LIB.BASEBOARD_FAB2(SCH_1):GND
  24    GND VSS<83> @BASEBOARD_FAB2_LIB.BASEBOARD_FAB2(SCH_1):GND
  26    GND VSS<82> @BASEBOARD_FAB2_LIB.BASEBOARD_FAB2(SCH_1):GND
  28    GND VSS<81> @BASEBOARD_FAB2_LIB.BASEBOARD_FAB2(SCH_1):GND
  31    GND VSS<80> @BASEBOARD_FAB2_LIB.BASEBOARD_FAB2(SCH_1):GND
  33    GND VSS<79> @BASEBOARD_FAB2_LIB.BASEBOARD_FAB2(SCH_1):GND
  35    GND VSS<78> @BASEBOARD_FAB2_LIB.BASEBOARD_FAB2(SCH_1):GND
  37    GND VSS<77> @BASEBOARD_FAB2_LIB.BASEBOARD_FAB2(SCH_1):GND
  39    GND VSS<76> @BASEBOARD_FAB2_LIB.BASEBOARD_FAB2(SCH_1):GND
  42    GND VSS<75> @BASEBOARD_FAB2_LIB.BASEBOARD_FAB2(SCH_1):GND
  44    GND VSS<74> @BASEBOARD_FAB2_LIB.BASEBOARD_FAB2(SCH_1):GND
  46    GND VSS<73> @BASEBOARD_FAB2_LIB.BASEBOARD_FAB2(SCH_1):GND
  48    GND VSS<72> @BASEBOARD_FAB2_LIB.BASEBOARD_FAB2(SCH_1):GND
  50    GND VSS<71> @BASEBOARD_FAB2_LIB.BASEBOARD_FAB2(SCH_1):GND
  53    GND VSS<70> @BASEBOARD_FAB2_LIB.BASEBOARD_FAB2(SCH_1):GND
  55    GND VSS<69> @BASEBOARD_FAB2_LIB.BASEBOARD_FAB2(SCH_1):GND
  57    GND VSS<68> @BASEBOARD_FAB2_LIB.BASEBOARD_FAB2(SCH_1):GND
  94    GND VSS<67> @BASEBOARD_FAB2_LIB.BASEBOARD_FAB2(SCH_1):GND
  96    GND VSS<66> @BASEBOARD_FAB2_LIB.BASEBOARD_FAB2(SCH_1):GND
  98    GND VSS<65> @BASEBOARD_FAB2_LIB.BASEBOARD_FAB2(SCH_1):GND
 101    GND VSS<64> @BASEBOARD_FAB2_LIB.BASEBOARD_FAB2(SCH_1):GND
 103    GND VSS<63> @BASEBOARD_FAB2_LIB.BASEBOARD_FAB2(SCH_1):GND
 105    GND VSS<62> @BASEBOARD_FAB2_LIB.BASEBOARD_FAB2(SCH_1):GND
 107    GND VSS<61> @BASEBOARD_FAB2_LIB.BASEBOARD_FAB2(SCH_1):GND
 109    GND VSS<60> @BASEBOARD_FAB2_LIB.BASEBOARD_FAB2(SCH_1):GND
 112    GND VSS<59> @BASEBOARD_FAB2_LIB.BASEBOARD_FAB2(SCH_1):GND
 114    GND VSS<58> @BASEBOARD_FAB2_LIB.BASEBOARD_FAB2(SCH_1):GND
 116    GND VSS<57> @BASEBOARD_FAB2_LIB.BASEBOARD_FAB2(SCH_1):GND
 118    GND VSS<56> @BASEBOARD_FAB2_LIB.BASEBOARD_FAB2(SCH_1):GND
 120    GND VSS<55> @BASEBOARD_FAB2_LIB.BASEBOARD_FAB2(SCH_1):GND
 123    GND VSS<54> @BASEBOARD_FAB2_LIB.BASEBOARD_FAB2(SCH_1):GND
 125    GND VSS<53> @BASEBOARD_FAB2_LIB.BASEBOARD_FAB2(SCH_1):GND
 127    GND VSS<52> @BASEBOARD_FAB2_LIB.BASEBOARD_FAB2(SCH_1):GND
 129    GND VSS<51> @BASEBOARD_FAB2_LIB.BASEBOARD_FAB2(SCH_1):GND
 131    GND VSS<50> @BASEBOARD_FAB2_LIB.BASEBOARD_FAB2(SCH_1):GND
 134    GND VSS<49> @BASEBOARD_FAB2_LIB.BASEBOARD_FAB2(SCH_1):GND
 136    GND VSS<48> @BASEBOARD_FAB2_LIB.BASEBOARD_FAB2(SCH_1):GND
 138    GND VSS<47> @BASEBOARD_FAB2_LIB.BASEBOARD_FAB2(SCH_1):GND
 147    GND VSS<46> @BASEBOARD_FAB2_LIB.BASEBOARD_FAB2(SCH_1):GND
 149    GND VSS<45> @BASEBOARD_FAB2_LIB.BASEBOARD_FAB2(SCH_1):GND
 151    GND VSS<44> @BASEBOARD_FAB2_LIB.BASEBOARD_FAB2(SCH_1):GND
 154    GND VSS<43> @BASEBOARD_FAB2_LIB.BASEBOARD_FAB2(SCH_1):GND
 156    GND VSS<42> @BASEBOARD_FAB2_LIB.BASEBOARD_FAB2(SCH_1):GND
 158    GND VSS<41> @BASEBOARD_FAB2_LIB.BASEBOARD_FAB2(SCH_1):GND
 160    GND VSS<40> @BASEBOARD_FAB2_LIB.BASEBOARD_FAB2(SCH_1):GND
 162    GND VSS<39> @BASEBOARD_FAB2_LIB.BASEBOARD_FAB2(SCH_1):GND
 165    GND VSS<38> @BASEBOARD_FAB2_LIB.BASEBOARD_FAB2(SCH_1):GND
 167    GND VSS<37> @BASEBOARD_FAB2_LIB.BASEBOARD_FAB2(SCH_1):GND
 169    GND VSS<36> @BASEBOARD_FAB2_LIB.BASEBOARD_FAB2(SCH_1):GND
 171    GND VSS<35> @BASEBOARD_FAB2_LIB.BASEBOARD_FAB2(SCH_1):GND
 173    GND VSS<34> @BASEBOARD_FAB2_LIB.BASEBOARD_FAB2(SCH_1):GND
 176    GND VSS<33> @BASEBOARD_FAB2_LIB.BASEBOARD_FAB2(SCH_1):GND
 178    GND VSS<32> @BASEBOARD_FAB2_LIB.BASEBOARD_FAB2(SCH_1):GND
 180    GND VSS<31> @BASEBOARD_FAB2_LIB.BASEBOARD_FAB2(SCH_1):GND
 182    GND VSS<30> @BASEBOARD_FAB2_LIB.BASEBOARD_FAB2(SCH_1):GND
 184    GND VSS<29> @BASEBOARD_FAB2_LIB.BASEBOARD_FAB2(SCH_1):GND
 187    GND VSS<28> @BASEBOARD_FAB2_LIB.BASEBOARD_FAB2(SCH_1):GND
 189    GND VSS<27> @BASEBOARD_FAB2_LIB.BASEBOARD_FAB2(SCH_1):GND
 191    GND VSS<26> @BASEBOARD_FAB2_LIB.BASEBOARD_FAB2(SCH_1):GND
 193    GND VSS<25> @BASEBOARD_FAB2_LIB.BASEBOARD_FAB2(SCH_1):GND
 195    GND VSS<24> @BASEBOARD_FAB2_LIB.BASEBOARD_FAB2(SCH_1):GND
 198    GND VSS<23> @BASEBOARD_FAB2_LIB.BASEBOARD_FAB2(SCH_1):GND
 200    GND VSS<22> @BASEBOARD_FAB2_LIB.BASEBOARD_FAB2(SCH_1):GND
 202    GND VSS<21> @BASEBOARD_FAB2_LIB.BASEBOARD_FAB2(SCH_1):GND
 239    GND VSS<20> @BASEBOARD_FAB2_LIB.BASEBOARD_FAB2(SCH_1):GND
 241    GND VSS<19> @BASEBOARD_FAB2_LIB.BASEBOARD_FAB2(SCH_1):GND
 243    GND VSS<18> @BASEBOARD_FAB2_LIB.BASEBOARD_FAB2(SCH_1):GND
 246    GND VSS<17> @BASEBOARD_FAB2_LIB.BASEBOARD_FAB2(SCH_1):GND
 248    GND VSS<16> @BASEBOARD_FAB2_LIB.BASEBOARD_FAB2(SCH_1):GND
 250    GND VSS<15> @BASEBOARD_FAB2_LIB.BASEBOARD_FAB2(SCH_1):GND
 252    GND VSS<14> @BASEBOARD_FAB2_LIB.BASEBOARD_FAB2(SCH_1):GND
 254    GND VSS<13> @BASEBOARD_FAB2_LIB.BASEBOARD_FAB2(SCH_1):GND
 257    GND VSS<12> @BASEBOARD_FAB2_LIB.BASEBOARD_FAB2(SCH_1):GND
 259    GND VSS<11> @BASEBOARD_FAB2_LIB.BASEBOARD_FAB2(SCH_1):GND
 261    GND VSS<10> @BASEBOARD_FAB2_LIB.BASEBOARD_FAB2(SCH_1):GND
 263    GND VSS<9> @BASEBOARD_FAB2_LIB.BASEBOARD_FAB2(SCH_1):GND
 265    GND VSS<8> @BASEBOARD_FAB2_LIB.BASEBOARD_FAB2(SCH_1):GND
 268    GND VSS<7> @BASEBOARD_FAB2_LIB.BASEBOARD_FAB2(SCH_1):GND
 270    GND VSS<6> @BASEBOARD_FAB2_LIB.BASEBOARD_FAB2(SCH_1):GND
 272    GND VSS<5> @BASEBOARD_FAB2_LIB.BASEBOARD_FAB2(SCH_1):GND
 274    GND VSS<4> @BASEBOARD_FAB2_LIB.BASEBOARD_FAB2(SCH_1):GND
 276    GND VSS<3> @BASEBOARD_FAB2_LIB.BASEBOARD_FAB2(SCH_1):GND
 279    GND VSS<2> @BASEBOARD_FAB2_LIB.BASEBOARD_FAB2(SCH_1):GND
 281    GND VSS<1> @BASEBOARD_FAB2_LIB.BASEBOARD_FAB2(SCH_1):GND
 283    GND VSS<0> @BASEBOARD_FAB2_LIB.BASEBOARD_FAB2(SCH_1):GND


DRAWING: @BASEBOARD_FAB2_LIB.BASEBOARD_FAB2(SCH_1):PAGE81 

SCONN288_H44441004_PIP-SCONN,HA  I67  J1G3
 152 M_J_DQS_DN<0>  DQS0N @BASEBOARD_FAB2_LIB.BASEBOARD_FAB2(SCH_1):M_J_DQS_DN(0)
 153 M_J_DQS_DP<0>  DQS0P @BASEBOARD_FAB2_LIB.BASEBOARD_FAB2(SCH_1):M_J_DQS_DP(0)
  19 M_J_DQS_DN<10> DQS10N @BASEBOARD_FAB2_LIB.BASEBOARD_FAB2(SCH_1):M_J_DQS_DN(10)
  18 M_J_DQS_DP<10> DQS10P @BASEBOARD_FAB2_LIB.BASEBOARD_FAB2(SCH_1):M_J_DQS_DP(10)
  30 M_J_DQS_DN<11> DQS11N @BASEBOARD_FAB2_LIB.BASEBOARD_FAB2(SCH_1):M_J_DQS_DN(11)
  29 M_J_DQS_DP<11> DQS11P @BASEBOARD_FAB2_LIB.BASEBOARD_FAB2(SCH_1):M_J_DQS_DP(11)
  41 M_J_DQS_DN<12> DQS12N @BASEBOARD_FAB2_LIB.BASEBOARD_FAB2(SCH_1):M_J_DQS_DN(12)
  40 M_J_DQS_DP<12> DQS12P @BASEBOARD_FAB2_LIB.BASEBOARD_FAB2(SCH_1):M_J_DQS_DP(12)
 100 M_J_DQS_DN<13> DQS13N @BASEBOARD_FAB2_LIB.BASEBOARD_FAB2(SCH_1):M_J_DQS_DN(13)
  99 M_J_DQS_DP<13> DQS13P @BASEBOARD_FAB2_LIB.BASEBOARD_FAB2(SCH_1):M_J_DQS_DP(13)
 111 M_J_DQS_DN<14> DQS14N @BASEBOARD_FAB2_LIB.BASEBOARD_FAB2(SCH_1):M_J_DQS_DN(14)
 110 M_J_DQS_DP<14> DQS14P @BASEBOARD_FAB2_LIB.BASEBOARD_FAB2(SCH_1):M_J_DQS_DP(14)
 122 M_J_DQS_DN<15> DQS15N @BASEBOARD_FAB2_LIB.BASEBOARD_FAB2(SCH_1):M_J_DQS_DN(15)
 121 M_J_DQS_DP<15> DQS15P @BASEBOARD_FAB2_LIB.BASEBOARD_FAB2(SCH_1):M_J_DQS_DP(15)
 133 M_J_DQS_DN<16> DQS16N @BASEBOARD_FAB2_LIB.BASEBOARD_FAB2(SCH_1):M_J_DQS_DN(16)
 132 M_J_DQS_DP<16> DQS16P @BASEBOARD_FAB2_LIB.BASEBOARD_FAB2(SCH_1):M_J_DQS_DP(16)
  52 M_J_DQS_DN<17> DQS17N @BASEBOARD_FAB2_LIB.BASEBOARD_FAB2(SCH_1):M_J_DQS_DN(17)
  51 M_J_DQS_DP<17> DQS17P @BASEBOARD_FAB2_LIB.BASEBOARD_FAB2(SCH_1):M_J_DQS_DP(17)
 163 M_J_DQS_DN<1>  DQS1N @BASEBOARD_FAB2_LIB.BASEBOARD_FAB2(SCH_1):M_J_DQS_DN(1)
 164 M_J_DQS_DP<1>  DQS1P @BASEBOARD_FAB2_LIB.BASEBOARD_FAB2(SCH_1):M_J_DQS_DP(1)
 174 M_J_DQS_DN<2>  DQS2N @BASEBOARD_FAB2_LIB.BASEBOARD_FAB2(SCH_1):M_J_DQS_DN(2)
 175 M_J_DQS_DP<2>  DQS2P @BASEBOARD_FAB2_LIB.BASEBOARD_FAB2(SCH_1):M_J_DQS_DP(2)
 185 M_J_DQS_DN<3>  DQS3N @BASEBOARD_FAB2_LIB.BASEBOARD_FAB2(SCH_1):M_J_DQS_DN(3)
 186 M_J_DQS_DP<3>  DQS3P @BASEBOARD_FAB2_LIB.BASEBOARD_FAB2(SCH_1):M_J_DQS_DP(3)
 244 M_J_DQS_DN<4>  DQS4N @BASEBOARD_FAB2_LIB.BASEBOARD_FAB2(SCH_1):M_J_DQS_DN(4)
 245 M_J_DQS_DP<4>  DQS4P @BASEBOARD_FAB2_LIB.BASEBOARD_FAB2(SCH_1):M_J_DQS_DP(4)
 255 M_J_DQS_DN<5>  DQS5N @BASEBOARD_FAB2_LIB.BASEBOARD_FAB2(SCH_1):M_J_DQS_DN(5)
 256 M_J_DQS_DP<5>  DQS5P @BASEBOARD_FAB2_LIB.BASEBOARD_FAB2(SCH_1):M_J_DQS_DP(5)
 266 M_J_DQS_DN<6>  DQS6N @BASEBOARD_FAB2_LIB.BASEBOARD_FAB2(SCH_1):M_J_DQS_DN(6)
 267 M_J_DQS_DP<6>  DQS6P @BASEBOARD_FAB2_LIB.BASEBOARD_FAB2(SCH_1):M_J_DQS_DP(6)
 277 M_J_DQS_DN<7>  DQS7N @BASEBOARD_FAB2_LIB.BASEBOARD_FAB2(SCH_1):M_J_DQS_DN(7)
 278 M_J_DQS_DP<7>  DQS7P @BASEBOARD_FAB2_LIB.BASEBOARD_FAB2(SCH_1):M_J_DQS_DP(7)
 196 M_J_DQS_DN<8>  DQS8N @BASEBOARD_FAB2_LIB.BASEBOARD_FAB2(SCH_1):M_J_DQS_DN(8)
 197 M_J_DQS_DP<8>  DQS8P @BASEBOARD_FAB2_LIB.BASEBOARD_FAB2(SCH_1):M_J_DQS_DP(8)
   8 M_J_DQS_DN<9>  DQS9N @BASEBOARD_FAB2_LIB.BASEBOARD_FAB2(SCH_1):M_J_DQS_DN(9)
   7 M_J_DQS_DP<9>  DQS9P @BASEBOARD_FAB2_LIB.BASEBOARD_FAB2(SCH_1):M_J_DQS_DP(9)

SCONN288_H44441004_PIP-SCONN,HA  I169  J1G3
   1 P12V_NVDIMM_GHJ 12V<1> @BASEBOARD_FAB2_LIB.BASEBOARD_FAB2(SCH_1):P12V_NVDIMM_GHJ
 145 P12V_NVDIMM_GHJ 12V<0> @BASEBOARD_FAB2_LIB.BASEBOARD_FAB2(SCH_1):P12V_NVDIMM_GHJ
  59 PVDDQ_GHJ VDD<25> @BASEBOARD_FAB2_LIB.BASEBOARD_FAB2(SCH_1):PVDDQ_GHJ
  61 PVDDQ_GHJ VDD<24> @BASEBOARD_FAB2_LIB.BASEBOARD_FAB2(SCH_1):PVDDQ_GHJ
  64 PVDDQ_GHJ VDD<23> @BASEBOARD_FAB2_LIB.BASEBOARD_FAB2(SCH_1):PVDDQ_GHJ
  67 PVDDQ_GHJ VDD<22> @BASEBOARD_FAB2_LIB.BASEBOARD_FAB2(SCH_1):PVDDQ_GHJ
  70 PVDDQ_GHJ VDD<21> @BASEBOARD_FAB2_LIB.BASEBOARD_FAB2(SCH_1):PVDDQ_GHJ
  73 PVDDQ_GHJ VDD<20> @BASEBOARD_FAB2_LIB.BASEBOARD_FAB2(SCH_1):PVDDQ_GHJ
  76 PVDDQ_GHJ VDD<19> @BASEBOARD_FAB2_LIB.BASEBOARD_FAB2(SCH_1):PVDDQ_GHJ
  80 PVDDQ_GHJ VDD<18> @BASEBOARD_FAB2_LIB.BASEBOARD_FAB2(SCH_1):PVDDQ_GHJ
  83 PVDDQ_GHJ VDD<17> @BASEBOARD_FAB2_LIB.BASEBOARD_FAB2(SCH_1):PVDDQ_GHJ
  85 PVDDQ_GHJ VDD<16> @BASEBOARD_FAB2_LIB.BASEBOARD_FAB2(SCH_1):PVDDQ_GHJ
  88 PVDDQ_GHJ VDD<15> @BASEBOARD_FAB2_LIB.BASEBOARD_FAB2(SCH_1):PVDDQ_GHJ
  90 PVDDQ_GHJ VDD<14> @BASEBOARD_FAB2_LIB.BASEBOARD_FAB2(SCH_1):PVDDQ_GHJ
  92 PVDDQ_GHJ VDD<13> @BASEBOARD_FAB2_LIB.BASEBOARD_FAB2(SCH_1):PVDDQ_GHJ
 204 PVDDQ_GHJ VDD<12> @BASEBOARD_FAB2_LIB.BASEBOARD_FAB2(SCH_1):PVDDQ_GHJ
 206 PVDDQ_GHJ VDD<11> @BASEBOARD_FAB2_LIB.BASEBOARD_FAB2(SCH_1):PVDDQ_GHJ
 209 PVDDQ_GHJ VDD<10> @BASEBOARD_FAB2_LIB.BASEBOARD_FAB2(SCH_1):PVDDQ_GHJ
 212 PVDDQ_GHJ VDD<9> @BASEBOARD_FAB2_LIB.BASEBOARD_FAB2(SCH_1):PVDDQ_GHJ
 215 PVDDQ_GHJ VDD<8> @BASEBOARD_FAB2_LIB.BASEBOARD_FAB2(SCH_1):PVDDQ_GHJ
 217 PVDDQ_GHJ VDD<7> @BASEBOARD_FAB2_LIB.BASEBOARD_FAB2(SCH_1):PVDDQ_GHJ
 220 PVDDQ_GHJ VDD<6> @BASEBOARD_FAB2_LIB.BASEBOARD_FAB2(SCH_1):PVDDQ_GHJ
 223 PVDDQ_GHJ VDD<5> @BASEBOARD_FAB2_LIB.BASEBOARD_FAB2(SCH_1):PVDDQ_GHJ
 226 PVDDQ_GHJ VDD<4> @BASEBOARD_FAB2_LIB.BASEBOARD_FAB2(SCH_1):PVDDQ_GHJ
 229 PVDDQ_GHJ VDD<3> @BASEBOARD_FAB2_LIB.BASEBOARD_FAB2(SCH_1):PVDDQ_GHJ
 231 PVDDQ_GHJ VDD<2> @BASEBOARD_FAB2_LIB.BASEBOARD_FAB2(SCH_1):PVDDQ_GHJ
 233 PVDDQ_GHJ VDD<1> @BASEBOARD_FAB2_LIB.BASEBOARD_FAB2(SCH_1):PVDDQ_GHJ
 236 PVDDQ_GHJ VDD<0> @BASEBOARD_FAB2_LIB.BASEBOARD_FAB2(SCH_1):PVDDQ_GHJ
 142 PVPP_GHJ VPP<4> @BASEBOARD_FAB2_LIB.BASEBOARD_FAB2(SCH_1):PVPP_GHJ
 143 PVPP_GHJ VPP<3> @BASEBOARD_FAB2_LIB.BASEBOARD_FAB2(SCH_1):PVPP_GHJ
 288 PVPP_GHJ VPP<2> @BASEBOARD_FAB2_LIB.BASEBOARD_FAB2(SCH_1):PVPP_GHJ
 286 PVPP_GHJ VPP<1> @BASEBOARD_FAB2_LIB.BASEBOARD_FAB2(SCH_1):PVPP_GHJ
 287 PVPP_GHJ VPP<0> @BASEBOARD_FAB2_LIB.BASEBOARD_FAB2(SCH_1):PVPP_GHJ
  77 PVTT_GHJ VTT<1> @BASEBOARD_FAB2_LIB.BASEBOARD_FAB2(SCH_1):PVTT_GHJ
 221 PVTT_GHJ VTT<0> @BASEBOARD_FAB2_LIB.BASEBOARD_FAB2(SCH_1):PVTT_GHJ

CAP_A_0402V-0.01UF,25V,10%,X7RA  I178  C9U10
   1 M_J_VREF      A @BASEBOARD_FAB2_LIB.BASEBOARD_FAB2(SCH_1):M_J_VREF
   2    GND      B @BASEBOARD_FAB2_LIB.BASEBOARD_FAB2(SCH_1):GND

SCONN288_H44441004_PIP-SCONN,HA  I185  J1G3
   2    GND VSS<93> @BASEBOARD_FAB2_LIB.BASEBOARD_FAB2(SCH_1):GND
   4    GND VSS<92> @BASEBOARD_FAB2_LIB.BASEBOARD_FAB2(SCH_1):GND
   6    GND VSS<91> @BASEBOARD_FAB2_LIB.BASEBOARD_FAB2(SCH_1):GND
   9    GND VSS<90> @BASEBOARD_FAB2_LIB.BASEBOARD_FAB2(SCH_1):GND
  11    GND VSS<89> @BASEBOARD_FAB2_LIB.BASEBOARD_FAB2(SCH_1):GND
  13    GND VSS<88> @BASEBOARD_FAB2_LIB.BASEBOARD_FAB2(SCH_1):GND
  15    GND VSS<87> @BASEBOARD_FAB2_LIB.BASEBOARD_FAB2(SCH_1):GND
  17    GND VSS<86> @BASEBOARD_FAB2_LIB.BASEBOARD_FAB2(SCH_1):GND
  20    GND VSS<85> @BASEBOARD_FAB2_LIB.BASEBOARD_FAB2(SCH_1):GND
  22    GND VSS<84> @BASEBOARD_FAB2_LIB.BASEBOARD_FAB2(SCH_1):GND
  24    GND VSS<83> @BASEBOARD_FAB2_LIB.BASEBOARD_FAB2(SCH_1):GND
  26    GND VSS<82> @BASEBOARD_FAB2_LIB.BASEBOARD_FAB2(SCH_1):GND
  28    GND VSS<81> @BASEBOARD_FAB2_LIB.BASEBOARD_FAB2(SCH_1):GND
  31    GND VSS<80> @BASEBOARD_FAB2_LIB.BASEBOARD_FAB2(SCH_1):GND
  33    GND VSS<79> @BASEBOARD_FAB2_LIB.BASEBOARD_FAB2(SCH_1):GND
  35    GND VSS<78> @BASEBOARD_FAB2_LIB.BASEBOARD_FAB2(SCH_1):GND
  37    GND VSS<77> @BASEBOARD_FAB2_LIB.BASEBOARD_FAB2(SCH_1):GND
  39    GND VSS<76> @BASEBOARD_FAB2_LIB.BASEBOARD_FAB2(SCH_1):GND
  42    GND VSS<75> @BASEBOARD_FAB2_LIB.BASEBOARD_FAB2(SCH_1):GND
  44    GND VSS<74> @BASEBOARD_FAB2_LIB.BASEBOARD_FAB2(SCH_1):GND
  46    GND VSS<73> @BASEBOARD_FAB2_LIB.BASEBOARD_FAB2(SCH_1):GND
  48    GND VSS<72> @BASEBOARD_FAB2_LIB.BASEBOARD_FAB2(SCH_1):GND
  50    GND VSS<71> @BASEBOARD_FAB2_LIB.BASEBOARD_FAB2(SCH_1):GND
  53    GND VSS<70> @BASEBOARD_FAB2_LIB.BASEBOARD_FAB2(SCH_1):GND
  55    GND VSS<69> @BASEBOARD_FAB2_LIB.BASEBOARD_FAB2(SCH_1):GND
  57    GND VSS<68> @BASEBOARD_FAB2_LIB.BASEBOARD_FAB2(SCH_1):GND
  94    GND VSS<67> @BASEBOARD_FAB2_LIB.BASEBOARD_FAB2(SCH_1):GND
  96    GND VSS<66> @BASEBOARD_FAB2_LIB.BASEBOARD_FAB2(SCH_1):GND
  98    GND VSS<65> @BASEBOARD_FAB2_LIB.BASEBOARD_FAB2(SCH_1):GND
 101    GND VSS<64> @BASEBOARD_FAB2_LIB.BASEBOARD_FAB2(SCH_1):GND
 103    GND VSS<63> @BASEBOARD_FAB2_LIB.BASEBOARD_FAB2(SCH_1):GND
 105    GND VSS<62> @BASEBOARD_FAB2_LIB.BASEBOARD_FAB2(SCH_1):GND
 107    GND VSS<61> @BASEBOARD_FAB2_LIB.BASEBOARD_FAB2(SCH_1):GND
 109    GND VSS<60> @BASEBOARD_FAB2_LIB.BASEBOARD_FAB2(SCH_1):GND
 112    GND VSS<59> @BASEBOARD_FAB2_LIB.BASEBOARD_FAB2(SCH_1):GND
 114    GND VSS<58> @BASEBOARD_FAB2_LIB.BASEBOARD_FAB2(SCH_1):GND
 116    GND VSS<57> @BASEBOARD_FAB2_LIB.BASEBOARD_FAB2(SCH_1):GND
 118    GND VSS<56> @BASEBOARD_FAB2_LIB.BASEBOARD_FAB2(SCH_1):GND
 120    GND VSS<55> @BASEBOARD_FAB2_LIB.BASEBOARD_FAB2(SCH_1):GND
 123    GND VSS<54> @BASEBOARD_FAB2_LIB.BASEBOARD_FAB2(SCH_1):GND
 125    GND VSS<53> @BASEBOARD_FAB2_LIB.BASEBOARD_FAB2(SCH_1):GND
 127    GND VSS<52> @BASEBOARD_FAB2_LIB.BASEBOARD_FAB2(SCH_1):GND
 129    GND VSS<51> @BASEBOARD_FAB2_LIB.BASEBOARD_FAB2(SCH_1):GND
 131    GND VSS<50> @BASEBOARD_FAB2_LIB.BASEBOARD_FAB2(SCH_1):GND
 134    GND VSS<49> @BASEBOARD_FAB2_LIB.BASEBOARD_FAB2(SCH_1):GND
 136    GND VSS<48> @BASEBOARD_FAB2_LIB.BASEBOARD_FAB2(SCH_1):GND
 138    GND VSS<47> @BASEBOARD_FAB2_LIB.BASEBOARD_FAB2(SCH_1):GND
 147    GND VSS<46> @BASEBOARD_FAB2_LIB.BASEBOARD_FAB2(SCH_1):GND
 149    GND VSS<45> @BASEBOARD_FAB2_LIB.BASEBOARD_FAB2(SCH_1):GND
 151    GND VSS<44> @BASEBOARD_FAB2_LIB.BASEBOARD_FAB2(SCH_1):GND
 154    GND VSS<43> @BASEBOARD_FAB2_LIB.BASEBOARD_FAB2(SCH_1):GND
 156    GND VSS<42> @BASEBOARD_FAB2_LIB.BASEBOARD_FAB2(SCH_1):GND
 158    GND VSS<41> @BASEBOARD_FAB2_LIB.BASEBOARD_FAB2(SCH_1):GND
 160    GND VSS<40> @BASEBOARD_FAB2_LIB.BASEBOARD_FAB2(SCH_1):GND
 162    GND VSS<39> @BASEBOARD_FAB2_LIB.BASEBOARD_FAB2(SCH_1):GND
 165    GND VSS<38> @BASEBOARD_FAB2_LIB.BASEBOARD_FAB2(SCH_1):GND
 167    GND VSS<37> @BASEBOARD_FAB2_LIB.BASEBOARD_FAB2(SCH_1):GND
 169    GND VSS<36> @BASEBOARD_FAB2_LIB.BASEBOARD_FAB2(SCH_1):GND
 171    GND VSS<35> @BASEBOARD_FAB2_LIB.BASEBOARD_FAB2(SCH_1):GND
 173    GND VSS<34> @BASEBOARD_FAB2_LIB.BASEBOARD_FAB2(SCH_1):GND
 176    GND VSS<33> @BASEBOARD_FAB2_LIB.BASEBOARD_FAB2(SCH_1):GND
 178    GND VSS<32> @BASEBOARD_FAB2_LIB.BASEBOARD_FAB2(SCH_1):GND
 180    GND VSS<31> @BASEBOARD_FAB2_LIB.BASEBOARD_FAB2(SCH_1):GND
 182    GND VSS<30> @BASEBOARD_FAB2_LIB.BASEBOARD_FAB2(SCH_1):GND
 184    GND VSS<29> @BASEBOARD_FAB2_LIB.BASEBOARD_FAB2(SCH_1):GND
 187    GND VSS<28> @BASEBOARD_FAB2_LIB.BASEBOARD_FAB2(SCH_1):GND
 189    GND VSS<27> @BASEBOARD_FAB2_LIB.BASEBOARD_FAB2(SCH_1):GND
 191    GND VSS<26> @BASEBOARD_FAB2_LIB.BASEBOARD_FAB2(SCH_1):GND
 193    GND VSS<25> @BASEBOARD_FAB2_LIB.BASEBOARD_FAB2(SCH_1):GND
 195    GND VSS<24> @BASEBOARD_FAB2_LIB.BASEBOARD_FAB2(SCH_1):GND
 198    GND VSS<23> @BASEBOARD_FAB2_LIB.BASEBOARD_FAB2(SCH_1):GND
 200    GND VSS<22> @BASEBOARD_FAB2_LIB.BASEBOARD_FAB2(SCH_1):GND
 202    GND VSS<21> @BASEBOARD_FAB2_LIB.BASEBOARD_FAB2(SCH_1):GND
 239    GND VSS<20> @BASEBOARD_FAB2_LIB.BASEBOARD_FAB2(SCH_1):GND
 241    GND VSS<19> @BASEBOARD_FAB2_LIB.BASEBOARD_FAB2(SCH_1):GND
 243    GND VSS<18> @BASEBOARD_FAB2_LIB.BASEBOARD_FAB2(SCH_1):GND
 246    GND VSS<17> @BASEBOARD_FAB2_LIB.BASEBOARD_FAB2(SCH_1):GND
 248    GND VSS<16> @BASEBOARD_FAB2_LIB.BASEBOARD_FAB2(SCH_1):GND
 250    GND VSS<15> @BASEBOARD_FAB2_LIB.BASEBOARD_FAB2(SCH_1):GND
 252    GND VSS<14> @BASEBOARD_FAB2_LIB.BASEBOARD_FAB2(SCH_1):GND
 254    GND VSS<13> @BASEBOARD_FAB2_LIB.BASEBOARD_FAB2(SCH_1):GND
 257    GND VSS<12> @BASEBOARD_FAB2_LIB.BASEBOARD_FAB2(SCH_1):GND
 259    GND VSS<11> @BASEBOARD_FAB2_LIB.BASEBOARD_FAB2(SCH_1):GND
 261    GND VSS<10> @BASEBOARD_FAB2_LIB.BASEBOARD_FAB2(SCH_1):GND
 263    GND VSS<9> @BASEBOARD_FAB2_LIB.BASEBOARD_FAB2(SCH_1):GND
 265    GND VSS<8> @BASEBOARD_FAB2_LIB.BASEBOARD_FAB2(SCH_1):GND
 268    GND VSS<7> @BASEBOARD_FAB2_LIB.BASEBOARD_FAB2(SCH_1):GND
 270    GND VSS<6> @BASEBOARD_FAB2_LIB.BASEBOARD_FAB2(SCH_1):GND
 272    GND VSS<5> @BASEBOARD_FAB2_LIB.BASEBOARD_FAB2(SCH_1):GND
 274    GND VSS<4> @BASEBOARD_FAB2_LIB.BASEBOARD_FAB2(SCH_1):GND
 276    GND VSS<3> @BASEBOARD_FAB2_LIB.BASEBOARD_FAB2(SCH_1):GND
 279    GND VSS<2> @BASEBOARD_FAB2_LIB.BASEBOARD_FAB2(SCH_1):GND
 281    GND VSS<1> @BASEBOARD_FAB2_LIB.BASEBOARD_FAB2(SCH_1):GND
 283    GND VSS<0> @BASEBOARD_FAB2_LIB.BASEBOARD_FAB2(SCH_1):GND

SCONN288_H44441004_PIP-SCONN,HA  I186  J1G3
  79 M_J_MA<0>     A0 @BASEBOARD_FAB2_LIB.BASEBOARD_FAB2(SCH_1):M_J_MA(0)
  72 M_J_MA<1>     A1 @BASEBOARD_FAB2_LIB.BASEBOARD_FAB2(SCH_1):M_J_MA(1)
 225 M_J_MA<10>    A10 @BASEBOARD_FAB2_LIB.BASEBOARD_FAB2(SCH_1):M_J_MA(10)
 210 M_J_MA<11>    A11 @BASEBOARD_FAB2_LIB.BASEBOARD_FAB2(SCH_1):M_J_MA(11)
  65 M_J_MA<12>    A12 @BASEBOARD_FAB2_LIB.BASEBOARD_FAB2(SCH_1):M_J_MA(12)
 232 M_J_MA<13>    A13 @BASEBOARD_FAB2_LIB.BASEBOARD_FAB2(SCH_1):M_J_MA(13)
 228 M_J_MA<14> A14_WE_N @BASEBOARD_FAB2_LIB.BASEBOARD_FAB2(SCH_1):M_J_MA(14)
  86 M_J_MA<15> A15_CAS_N @BASEBOARD_FAB2_LIB.BASEBOARD_FAB2(SCH_1):M_J_MA(15)
  82 M_J_MA<16> A16_RAS_N @BASEBOARD_FAB2_LIB.BASEBOARD_FAB2(SCH_1):M_J_MA(16)
 234 M_J_MA<17>    A17 @BASEBOARD_FAB2_LIB.BASEBOARD_FAB2(SCH_1):M_J_MA(17)
 216 M_J_MA<2>     A2 @BASEBOARD_FAB2_LIB.BASEBOARD_FAB2(SCH_1):M_J_MA(2)
  71 M_J_MA<3>     A3 @BASEBOARD_FAB2_LIB.BASEBOARD_FAB2(SCH_1):M_J_MA(3)
 214 M_J_MA<4>     A4 @BASEBOARD_FAB2_LIB.BASEBOARD_FAB2(SCH_1):M_J_MA(4)
 213 M_J_MA<5>     A5 @BASEBOARD_FAB2_LIB.BASEBOARD_FAB2(SCH_1):M_J_MA(5)
  69 M_J_MA<6>     A6 @BASEBOARD_FAB2_LIB.BASEBOARD_FAB2(SCH_1):M_J_MA(6)
 211 M_J_MA<7>     A7 @BASEBOARD_FAB2_LIB.BASEBOARD_FAB2(SCH_1):M_J_MA(7)
  68 M_J_MA<8>     A8 @BASEBOARD_FAB2_LIB.BASEBOARD_FAB2(SCH_1):M_J_MA(8)
  66 M_J_MA<9>     A9 @BASEBOARD_FAB2_LIB.BASEBOARD_FAB2(SCH_1):M_J_MA(9)
  62 M_J_ACT_N  ACT_N @BASEBOARD_FAB2_LIB.BASEBOARD_FAB2(SCH_1):M_J_ACT_N
 208 M_J_ALERT_N ALERT_N @BASEBOARD_FAB2_LIB.BASEBOARD_FAB2(SCH_1):M_J_ALERT_N
 224 M_J_BA<1>  BA<1> @BASEBOARD_FAB2_LIB.BASEBOARD_FAB2(SCH_1):M_J_BA(1)
  81 M_J_BA<0>  BA<0> @BASEBOARD_FAB2_LIB.BASEBOARD_FAB2(SCH_1):M_J_BA(0)
 207 M_J_BG<1>  BG<1> @BASEBOARD_FAB2_LIB.BASEBOARD_FAB2(SCH_1):M_J_BG(1)
  63 M_J_BG<0>  BG<0> @BASEBOARD_FAB2_LIB.BASEBOARD_FAB2(SCH_1):M_J_BG(0)
 235 M_J_C<2>   C<2> @BASEBOARD_FAB2_LIB.BASEBOARD_FAB2(SCH_1):M_J_C(2)
 199 M_J_ECC<6>  CB<7> @BASEBOARD_FAB2_LIB.BASEBOARD_FAB2(SCH_1):M_J_ECC(6)
  54 M_J_ECC<7>  CB<6> @BASEBOARD_FAB2_LIB.BASEBOARD_FAB2(SCH_1):M_J_ECC(7)
 192 M_J_ECC<4>  CB<5> @BASEBOARD_FAB2_LIB.BASEBOARD_FAB2(SCH_1):M_J_ECC(4)
  47 M_J_ECC<5>  CB<4> @BASEBOARD_FAB2_LIB.BASEBOARD_FAB2(SCH_1):M_J_ECC(5)
 201 M_J_ECC<2>  CB<3> @BASEBOARD_FAB2_LIB.BASEBOARD_FAB2(SCH_1):M_J_ECC(2)
  56 M_J_ECC<3>  CB<2> @BASEBOARD_FAB2_LIB.BASEBOARD_FAB2(SCH_1):M_J_ECC(3)
 194 M_J_ECC<0>  CB<1> @BASEBOARD_FAB2_LIB.BASEBOARD_FAB2(SCH_1):M_J_ECC(0)
  49 M_J_ECC<1>  CB<0> @BASEBOARD_FAB2_LIB.BASEBOARD_FAB2(SCH_1):M_J_ECC(1)
  75 M_J_CLK_DN<0>   CK0N @BASEBOARD_FAB2_LIB.BASEBOARD_FAB2(SCH_1):M_J_CLK_DN(0)
  74 M_J_CLK_DP<0>   CK0P @BASEBOARD_FAB2_LIB.BASEBOARD_FAB2(SCH_1):M_J_CLK_DP(0)
 219 M_J_CLK_DN<1>   CK1N @BASEBOARD_FAB2_LIB.BASEBOARD_FAB2(SCH_1):M_J_CLK_DN(1)
 218 M_J_CLK_DP<1>   CK1P @BASEBOARD_FAB2_LIB.BASEBOARD_FAB2(SCH_1):M_J_CLK_DP(1)
 203 M_J_CKE<1> CKE<1> @BASEBOARD_FAB2_LIB.BASEBOARD_FAB2(SCH_1):M_J_CKE(1)
  60 M_J_CKE<0> CKE<0> @BASEBOARD_FAB2_LIB.BASEBOARD_FAB2(SCH_1):M_J_CKE(0)
 280 M_J_DQ<62> DQ<63> @BASEBOARD_FAB2_LIB.BASEBOARD_FAB2(SCH_1):M_J_DQ(62)
 135 M_J_DQ<63> DQ<62> @BASEBOARD_FAB2_LIB.BASEBOARD_FAB2(SCH_1):M_J_DQ(63)
 273 M_J_DQ<60> DQ<61> @BASEBOARD_FAB2_LIB.BASEBOARD_FAB2(SCH_1):M_J_DQ(60)
 128 M_J_DQ<61> DQ<60> @BASEBOARD_FAB2_LIB.BASEBOARD_FAB2(SCH_1):M_J_DQ(61)
 282 M_J_DQ<58> DQ<59> @BASEBOARD_FAB2_LIB.BASEBOARD_FAB2(SCH_1):M_J_DQ(58)
 137 M_J_DQ<59> DQ<58> @BASEBOARD_FAB2_LIB.BASEBOARD_FAB2(SCH_1):M_J_DQ(59)
 275 M_J_DQ<56> DQ<57> @BASEBOARD_FAB2_LIB.BASEBOARD_FAB2(SCH_1):M_J_DQ(56)
 130 M_J_DQ<57> DQ<56> @BASEBOARD_FAB2_LIB.BASEBOARD_FAB2(SCH_1):M_J_DQ(57)
 269 M_J_DQ<54> DQ<55> @BASEBOARD_FAB2_LIB.BASEBOARD_FAB2(SCH_1):M_J_DQ(54)
 124 M_J_DQ<55> DQ<54> @BASEBOARD_FAB2_LIB.BASEBOARD_FAB2(SCH_1):M_J_DQ(55)
 262 M_J_DQ<52> DQ<53> @BASEBOARD_FAB2_LIB.BASEBOARD_FAB2(SCH_1):M_J_DQ(52)
 117 M_J_DQ<53> DQ<52> @BASEBOARD_FAB2_LIB.BASEBOARD_FAB2(SCH_1):M_J_DQ(53)
 271 M_J_DQ<50> DQ<51> @BASEBOARD_FAB2_LIB.BASEBOARD_FAB2(SCH_1):M_J_DQ(50)
 126 M_J_DQ<51> DQ<50> @BASEBOARD_FAB2_LIB.BASEBOARD_FAB2(SCH_1):M_J_DQ(51)
 264 M_J_DQ<48> DQ<49> @BASEBOARD_FAB2_LIB.BASEBOARD_FAB2(SCH_1):M_J_DQ(48)
 119 M_J_DQ<49> DQ<48> @BASEBOARD_FAB2_LIB.BASEBOARD_FAB2(SCH_1):M_J_DQ(49)
 258 M_J_DQ<46> DQ<47> @BASEBOARD_FAB2_LIB.BASEBOARD_FAB2(SCH_1):M_J_DQ(46)
 113 M_J_DQ<47> DQ<46> @BASEBOARD_FAB2_LIB.BASEBOARD_FAB2(SCH_1):M_J_DQ(47)
 251 M_J_DQ<44> DQ<45> @BASEBOARD_FAB2_LIB.BASEBOARD_FAB2(SCH_1):M_J_DQ(44)
 106 M_J_DQ<45> DQ<44> @BASEBOARD_FAB2_LIB.BASEBOARD_FAB2(SCH_1):M_J_DQ(45)
 260 M_J_DQ<42> DQ<43> @BASEBOARD_FAB2_LIB.BASEBOARD_FAB2(SCH_1):M_J_DQ(42)
 115 M_J_DQ<43> DQ<42> @BASEBOARD_FAB2_LIB.BASEBOARD_FAB2(SCH_1):M_J_DQ(43)
 253 M_J_DQ<40> DQ<41> @BASEBOARD_FAB2_LIB.BASEBOARD_FAB2(SCH_1):M_J_DQ(40)
 108 M_J_DQ<41> DQ<40> @BASEBOARD_FAB2_LIB.BASEBOARD_FAB2(SCH_1):M_J_DQ(41)
 247 M_J_DQ<38> DQ<39> @BASEBOARD_FAB2_LIB.BASEBOARD_FAB2(SCH_1):M_J_DQ(38)
 102 M_J_DQ<39> DQ<38> @BASEBOARD_FAB2_LIB.BASEBOARD_FAB2(SCH_1):M_J_DQ(39)
 240 M_J_DQ<36> DQ<37> @BASEBOARD_FAB2_LIB.BASEBOARD_FAB2(SCH_1):M_J_DQ(36)
  95 M_J_DQ<37> DQ<36> @BASEBOARD_FAB2_LIB.BASEBOARD_FAB2(SCH_1):M_J_DQ(37)
 249 M_J_DQ<34> DQ<35> @BASEBOARD_FAB2_LIB.BASEBOARD_FAB2(SCH_1):M_J_DQ(34)
 104 M_J_DQ<35> DQ<34> @BASEBOARD_FAB2_LIB.BASEBOARD_FAB2(SCH_1):M_J_DQ(35)
 242 M_J_DQ<32> DQ<33> @BASEBOARD_FAB2_LIB.BASEBOARD_FAB2(SCH_1):M_J_DQ(32)
  97 M_J_DQ<33> DQ<32> @BASEBOARD_FAB2_LIB.BASEBOARD_FAB2(SCH_1):M_J_DQ(33)
 188 M_J_DQ<30> DQ<31> @BASEBOARD_FAB2_LIB.BASEBOARD_FAB2(SCH_1):M_J_DQ(30)
  43 M_J_DQ<31> DQ<30> @BASEBOARD_FAB2_LIB.BASEBOARD_FAB2(SCH_1):M_J_DQ(31)
 181 M_J_DQ<28> DQ<29> @BASEBOARD_FAB2_LIB.BASEBOARD_FAB2(SCH_1):M_J_DQ(28)
  36 M_J_DQ<29> DQ<28> @BASEBOARD_FAB2_LIB.BASEBOARD_FAB2(SCH_1):M_J_DQ(29)
 190 M_J_DQ<26> DQ<27> @BASEBOARD_FAB2_LIB.BASEBOARD_FAB2(SCH_1):M_J_DQ(26)
  45 M_J_DQ<27> DQ<26> @BASEBOARD_FAB2_LIB.BASEBOARD_FAB2(SCH_1):M_J_DQ(27)
 183 M_J_DQ<24> DQ<25> @BASEBOARD_FAB2_LIB.BASEBOARD_FAB2(SCH_1):M_J_DQ(24)
  38 M_J_DQ<25> DQ<24> @BASEBOARD_FAB2_LIB.BASEBOARD_FAB2(SCH_1):M_J_DQ(25)
 177 M_J_DQ<22> DQ<23> @BASEBOARD_FAB2_LIB.BASEBOARD_FAB2(SCH_1):M_J_DQ(22)
  32 M_J_DQ<23> DQ<22> @BASEBOARD_FAB2_LIB.BASEBOARD_FAB2(SCH_1):M_J_DQ(23)
 170 M_J_DQ<20> DQ<21> @BASEBOARD_FAB2_LIB.BASEBOARD_FAB2(SCH_1):M_J_DQ(20)
  25 M_J_DQ<21> DQ<20> @BASEBOARD_FAB2_LIB.BASEBOARD_FAB2(SCH_1):M_J_DQ(21)
 179 M_J_DQ<18> DQ<19> @BASEBOARD_FAB2_LIB.BASEBOARD_FAB2(SCH_1):M_J_DQ(18)
  34 M_J_DQ<19> DQ<18> @BASEBOARD_FAB2_LIB.BASEBOARD_FAB2(SCH_1):M_J_DQ(19)
 172 M_J_DQ<16> DQ<17> @BASEBOARD_FAB2_LIB.BASEBOARD_FAB2(SCH_1):M_J_DQ(16)
  27 M_J_DQ<17> DQ<16> @BASEBOARD_FAB2_LIB.BASEBOARD_FAB2(SCH_1):M_J_DQ(17)
 166 M_J_DQ<14> DQ<15> @BASEBOARD_FAB2_LIB.BASEBOARD_FAB2(SCH_1):M_J_DQ(14)
  21 M_J_DQ<15> DQ<14> @BASEBOARD_FAB2_LIB.BASEBOARD_FAB2(SCH_1):M_J_DQ(15)
 159 M_J_DQ<12> DQ<13> @BASEBOARD_FAB2_LIB.BASEBOARD_FAB2(SCH_1):M_J_DQ(12)
  14 M_J_DQ<13> DQ<12> @BASEBOARD_FAB2_LIB.BASEBOARD_FAB2(SCH_1):M_J_DQ(13)
 168 M_J_DQ<10> DQ<11> @BASEBOARD_FAB2_LIB.BASEBOARD_FAB2(SCH_1):M_J_DQ(10)
  23 M_J_DQ<11> DQ<10> @BASEBOARD_FAB2_LIB.BASEBOARD_FAB2(SCH_1):M_J_DQ(11)
 161 M_J_DQ<8>  DQ<9> @BASEBOARD_FAB2_LIB.BASEBOARD_FAB2(SCH_1):M_J_DQ(8)
  16 M_J_DQ<9>  DQ<8> @BASEBOARD_FAB2_LIB.BASEBOARD_FAB2(SCH_1):M_J_DQ(9)
 155 M_J_DQ<6>  DQ<7> @BASEBOARD_FAB2_LIB.BASEBOARD_FAB2(SCH_1):M_J_DQ(6)
  10 M_J_DQ<7>  DQ<6> @BASEBOARD_FAB2_LIB.BASEBOARD_FAB2(SCH_1):M_J_DQ(7)
 148 M_J_DQ<4>  DQ<5> @BASEBOARD_FAB2_LIB.BASEBOARD_FAB2(SCH_1):M_J_DQ(4)
   3 M_J_DQ<5>  DQ<4> @BASEBOARD_FAB2_LIB.BASEBOARD_FAB2(SCH_1):M_J_DQ(5)
 157 M_J_DQ<2>  DQ<3> @BASEBOARD_FAB2_LIB.BASEBOARD_FAB2(SCH_1):M_J_DQ(2)
  12 M_J_DQ<3>  DQ<2> @BASEBOARD_FAB2_LIB.BASEBOARD_FAB2(SCH_1):M_J_DQ(3)
 150 M_J_DQ<0>  DQ<1> @BASEBOARD_FAB2_LIB.BASEBOARD_FAB2(SCH_1):M_J_DQ(0)
   5 M_J_DQ<1>  DQ<0> @BASEBOARD_FAB2_LIB.BASEBOARD_FAB2(SCH_1):M_J_DQ(1)
  78 FM_DIMM_EVENT_COD_N EVENT_N @BASEBOARD_FAB2_LIB.BASEBOARD_FAB2(SCH_1):FM_DIMM_EVENT_COD_N
  91 M_J_ODT<1> ODT<1> @BASEBOARD_FAB2_LIB.BASEBOARD_FAB2(SCH_1):M_J_ODT(1)
  87 M_J_ODT<0> ODT<0> @BASEBOARD_FAB2_LIB.BASEBOARD_FAB2(SCH_1):M_J_ODT(0)
 222 M_J_PAR    PAR @BASEBOARD_FAB2_LIB.BASEBOARD_FAB2(SCH_1):M_J_PAR
  58 M_GHJ_RST_N RESET_N @BASEBOARD_FAB2_LIB.BASEBOARD_FAB2(SCH_1):M_GHJ_RST_N
 144 TP_CH_J_DIMM_J0_RFU_2 RFU<2> @BASEBOARD_FAB2_LIB.BASEBOARD_FAB2(SCH_1):TP_CH_J_DIMM_J0_RFU_2
 227 TP_CH_J_DIMM_J0_RFU_1 RFU<1> @BASEBOARD_FAB2_LIB.BASEBOARD_FAB2(SCH_1):TP_CH_J_DIMM_J0_RFU_1
 205 TP_CH_J_DIMM_J0_RFU_0 RFU<0> @BASEBOARD_FAB2_LIB.BASEBOARD_FAB2(SCH_1):TP_CH_J_DIMM_J0_RFU_0
  84 M_J_CS_N<0>   S0_N @BASEBOARD_FAB2_LIB.BASEBOARD_FAB2(SCH_1):M_J_CS_N(0)
  89 M_J_CS_N<1>   S1_N @BASEBOARD_FAB2_LIB.BASEBOARD_FAB2(SCH_1):M_J_CS_N(1)
  93 M_J_CS_N<2> S2_N_C<0> @BASEBOARD_FAB2_LIB.BASEBOARD_FAB2(SCH_1):M_J_CS_N(2)
 237 M_J_CS_N<3> S3_N_C<1> @BASEBOARD_FAB2_LIB.BASEBOARD_FAB2(SCH_1):M_J_CS_N(3)
 238 PVPP_GHJ  SA<2> @BASEBOARD_FAB2_LIB.BASEBOARD_FAB2(SCH_1):PVPP_GHJ
 140    GND  SA<1> @BASEBOARD_FAB2_LIB.BASEBOARD_FAB2(SCH_1):GND
 139    GND  SA<0> @BASEBOARD_FAB2_LIB.BASEBOARD_FAB2(SCH_1):GND
 230 FM_ADR_COMPLETE_GHJ_N SAVE_N_NC @BASEBOARD_FAB2_LIB.BASEBOARD_FAB2(SCH_1):FM_ADR_COMPLETE_GHJ_N
 141 SMB_DDR_GHJ_VPP_SCL    SCL @BASEBOARD_FAB2_LIB.BASEBOARD_FAB2(SCH_1):SMB_DDR_GHJ_VPP_SCL
 285 SMB_DDR_GHJ_VPP_SDA    SDA @BASEBOARD_FAB2_LIB.BASEBOARD_FAB2(SCH_1):SMB_DDR_GHJ_VPP_SDA
 284 PVPP_GHJ VDDSPD @BASEBOARD_FAB2_LIB.BASEBOARD_FAB2(SCH_1):PVPP_GHJ
 146 M_J_VREF VREFCA @BASEBOARD_FAB2_LIB.BASEBOARD_FAB2(SCH_1):M_J_VREF


DRAWING: @BASEBOARD_FAB2_LIB.BASEBOARD_FAB2(SCH_1):PAGE82 

SCONN288_H44441003_PIP-SCONN,HA  I64  J9U2
 152 M_J_DQS_DN<0>  DQS0N @BASEBOARD_FAB2_LIB.BASEBOARD_FAB2(SCH_1):M_J_DQS_DN(0)
 153 M_J_DQS_DP<0>  DQS0P @BASEBOARD_FAB2_LIB.BASEBOARD_FAB2(SCH_1):M_J_DQS_DP(0)
  19 M_J_DQS_DN<10> DQS10N @BASEBOARD_FAB2_LIB.BASEBOARD_FAB2(SCH_1):M_J_DQS_DN(10)
  18 M_J_DQS_DP<10> DQS10P @BASEBOARD_FAB2_LIB.BASEBOARD_FAB2(SCH_1):M_J_DQS_DP(10)
  30 M_J_DQS_DN<11> DQS11N @BASEBOARD_FAB2_LIB.BASEBOARD_FAB2(SCH_1):M_J_DQS_DN(11)
  29 M_J_DQS_DP<11> DQS11P @BASEBOARD_FAB2_LIB.BASEBOARD_FAB2(SCH_1):M_J_DQS_DP(11)
  41 M_J_DQS_DN<12> DQS12N @BASEBOARD_FAB2_LIB.BASEBOARD_FAB2(SCH_1):M_J_DQS_DN(12)
  40 M_J_DQS_DP<12> DQS12P @BASEBOARD_FAB2_LIB.BASEBOARD_FAB2(SCH_1):M_J_DQS_DP(12)
 100 M_J_DQS_DN<13> DQS13N @BASEBOARD_FAB2_LIB.BASEBOARD_FAB2(SCH_1):M_J_DQS_DN(13)
  99 M_J_DQS_DP<13> DQS13P @BASEBOARD_FAB2_LIB.BASEBOARD_FAB2(SCH_1):M_J_DQS_DP(13)
 111 M_J_DQS_DN<14> DQS14N @BASEBOARD_FAB2_LIB.BASEBOARD_FAB2(SCH_1):M_J_DQS_DN(14)
 110 M_J_DQS_DP<14> DQS14P @BASEBOARD_FAB2_LIB.BASEBOARD_FAB2(SCH_1):M_J_DQS_DP(14)
 122 M_J_DQS_DN<15> DQS15N @BASEBOARD_FAB2_LIB.BASEBOARD_FAB2(SCH_1):M_J_DQS_DN(15)
 121 M_J_DQS_DP<15> DQS15P @BASEBOARD_FAB2_LIB.BASEBOARD_FAB2(SCH_1):M_J_DQS_DP(15)
 133 M_J_DQS_DN<16> DQS16N @BASEBOARD_FAB2_LIB.BASEBOARD_FAB2(SCH_1):M_J_DQS_DN(16)
 132 M_J_DQS_DP<16> DQS16P @BASEBOARD_FAB2_LIB.BASEBOARD_FAB2(SCH_1):M_J_DQS_DP(16)
  52 M_J_DQS_DN<17> DQS17N @BASEBOARD_FAB2_LIB.BASEBOARD_FAB2(SCH_1):M_J_DQS_DN(17)
  51 M_J_DQS_DP<17> DQS17P @BASEBOARD_FAB2_LIB.BASEBOARD_FAB2(SCH_1):M_J_DQS_DP(17)
 163 M_J_DQS_DN<1>  DQS1N @BASEBOARD_FAB2_LIB.BASEBOARD_FAB2(SCH_1):M_J_DQS_DN(1)
 164 M_J_DQS_DP<1>  DQS1P @BASEBOARD_FAB2_LIB.BASEBOARD_FAB2(SCH_1):M_J_DQS_DP(1)
 174 M_J_DQS_DN<2>  DQS2N @BASEBOARD_FAB2_LIB.BASEBOARD_FAB2(SCH_1):M_J_DQS_DN(2)
 175 M_J_DQS_DP<2>  DQS2P @BASEBOARD_FAB2_LIB.BASEBOARD_FAB2(SCH_1):M_J_DQS_DP(2)
 185 M_J_DQS_DN<3>  DQS3N @BASEBOARD_FAB2_LIB.BASEBOARD_FAB2(SCH_1):M_J_DQS_DN(3)
 186 M_J_DQS_DP<3>  DQS3P @BASEBOARD_FAB2_LIB.BASEBOARD_FAB2(SCH_1):M_J_DQS_DP(3)
 244 M_J_DQS_DN<4>  DQS4N @BASEBOARD_FAB2_LIB.BASEBOARD_FAB2(SCH_1):M_J_DQS_DN(4)
 245 M_J_DQS_DP<4>  DQS4P @BASEBOARD_FAB2_LIB.BASEBOARD_FAB2(SCH_1):M_J_DQS_DP(4)
 255 M_J_DQS_DN<5>  DQS5N @BASEBOARD_FAB2_LIB.BASEBOARD_FAB2(SCH_1):M_J_DQS_DN(5)
 256 M_J_DQS_DP<5>  DQS5P @BASEBOARD_FAB2_LIB.BASEBOARD_FAB2(SCH_1):M_J_DQS_DP(5)
 266 M_J_DQS_DN<6>  DQS6N @BASEBOARD_FAB2_LIB.BASEBOARD_FAB2(SCH_1):M_J_DQS_DN(6)
 267 M_J_DQS_DP<6>  DQS6P @BASEBOARD_FAB2_LIB.BASEBOARD_FAB2(SCH_1):M_J_DQS_DP(6)
 277 M_J_DQS_DN<7>  DQS7N @BASEBOARD_FAB2_LIB.BASEBOARD_FAB2(SCH_1):M_J_DQS_DN(7)
 278 M_J_DQS_DP<7>  DQS7P @BASEBOARD_FAB2_LIB.BASEBOARD_FAB2(SCH_1):M_J_DQS_DP(7)
 196 M_J_DQS_DN<8>  DQS8N @BASEBOARD_FAB2_LIB.BASEBOARD_FAB2(SCH_1):M_J_DQS_DN(8)
 197 M_J_DQS_DP<8>  DQS8P @BASEBOARD_FAB2_LIB.BASEBOARD_FAB2(SCH_1):M_J_DQS_DP(8)
   8 M_J_DQS_DN<9>  DQS9N @BASEBOARD_FAB2_LIB.BASEBOARD_FAB2(SCH_1):M_J_DQS_DN(9)
   7 M_J_DQS_DP<9>  DQS9P @BASEBOARD_FAB2_LIB.BASEBOARD_FAB2(SCH_1):M_J_DQS_DP(9)

SCONN288_H44441003_PIP-SCONN,HA  I171  J9U2
   1 P12V_NVDIMM_GHJ 12V<1> @BASEBOARD_FAB2_LIB.BASEBOARD_FAB2(SCH_1):P12V_NVDIMM_GHJ
 145 P12V_NVDIMM_GHJ 12V<0> @BASEBOARD_FAB2_LIB.BASEBOARD_FAB2(SCH_1):P12V_NVDIMM_GHJ
  59 PVDDQ_GHJ VDD<25> @BASEBOARD_FAB2_LIB.BASEBOARD_FAB2(SCH_1):PVDDQ_GHJ
  61 PVDDQ_GHJ VDD<24> @BASEBOARD_FAB2_LIB.BASEBOARD_FAB2(SCH_1):PVDDQ_GHJ
  64 PVDDQ_GHJ VDD<23> @BASEBOARD_FAB2_LIB.BASEBOARD_FAB2(SCH_1):PVDDQ_GHJ
  67 PVDDQ_GHJ VDD<22> @BASEBOARD_FAB2_LIB.BASEBOARD_FAB2(SCH_1):PVDDQ_GHJ
  70 PVDDQ_GHJ VDD<21> @BASEBOARD_FAB2_LIB.BASEBOARD_FAB2(SCH_1):PVDDQ_GHJ
  73 PVDDQ_GHJ VDD<20> @BASEBOARD_FAB2_LIB.BASEBOARD_FAB2(SCH_1):PVDDQ_GHJ
  76 PVDDQ_GHJ VDD<19> @BASEBOARD_FAB2_LIB.BASEBOARD_FAB2(SCH_1):PVDDQ_GHJ
  80 PVDDQ_GHJ VDD<18> @BASEBOARD_FAB2_LIB.BASEBOARD_FAB2(SCH_1):PVDDQ_GHJ
  83 PVDDQ_GHJ VDD<17> @BASEBOARD_FAB2_LIB.BASEBOARD_FAB2(SCH_1):PVDDQ_GHJ
  85 PVDDQ_GHJ VDD<16> @BASEBOARD_FAB2_LIB.BASEBOARD_FAB2(SCH_1):PVDDQ_GHJ
  88 PVDDQ_GHJ VDD<15> @BASEBOARD_FAB2_LIB.BASEBOARD_FAB2(SCH_1):PVDDQ_GHJ
  90 PVDDQ_GHJ VDD<14> @BASEBOARD_FAB2_LIB.BASEBOARD_FAB2(SCH_1):PVDDQ_GHJ
  92 PVDDQ_GHJ VDD<13> @BASEBOARD_FAB2_LIB.BASEBOARD_FAB2(SCH_1):PVDDQ_GHJ
 204 PVDDQ_GHJ VDD<12> @BASEBOARD_FAB2_LIB.BASEBOARD_FAB2(SCH_1):PVDDQ_GHJ
 206 PVDDQ_GHJ VDD<11> @BASEBOARD_FAB2_LIB.BASEBOARD_FAB2(SCH_1):PVDDQ_GHJ
 209 PVDDQ_GHJ VDD<10> @BASEBOARD_FAB2_LIB.BASEBOARD_FAB2(SCH_1):PVDDQ_GHJ
 212 PVDDQ_GHJ VDD<9> @BASEBOARD_FAB2_LIB.BASEBOARD_FAB2(SCH_1):PVDDQ_GHJ
 215 PVDDQ_GHJ VDD<8> @BASEBOARD_FAB2_LIB.BASEBOARD_FAB2(SCH_1):PVDDQ_GHJ
 217 PVDDQ_GHJ VDD<7> @BASEBOARD_FAB2_LIB.BASEBOARD_FAB2(SCH_1):PVDDQ_GHJ
 220 PVDDQ_GHJ VDD<6> @BASEBOARD_FAB2_LIB.BASEBOARD_FAB2(SCH_1):PVDDQ_GHJ
 223 PVDDQ_GHJ VDD<5> @BASEBOARD_FAB2_LIB.BASEBOARD_FAB2(SCH_1):PVDDQ_GHJ
 226 PVDDQ_GHJ VDD<4> @BASEBOARD_FAB2_LIB.BASEBOARD_FAB2(SCH_1):PVDDQ_GHJ
 229 PVDDQ_GHJ VDD<3> @BASEBOARD_FAB2_LIB.BASEBOARD_FAB2(SCH_1):PVDDQ_GHJ
 231 PVDDQ_GHJ VDD<2> @BASEBOARD_FAB2_LIB.BASEBOARD_FAB2(SCH_1):PVDDQ_GHJ
 233 PVDDQ_GHJ VDD<1> @BASEBOARD_FAB2_LIB.BASEBOARD_FAB2(SCH_1):PVDDQ_GHJ
 236 PVDDQ_GHJ VDD<0> @BASEBOARD_FAB2_LIB.BASEBOARD_FAB2(SCH_1):PVDDQ_GHJ
 142 PVPP_GHJ VPP<4> @BASEBOARD_FAB2_LIB.BASEBOARD_FAB2(SCH_1):PVPP_GHJ
 143 PVPP_GHJ VPP<3> @BASEBOARD_FAB2_LIB.BASEBOARD_FAB2(SCH_1):PVPP_GHJ
 288 PVPP_GHJ VPP<2> @BASEBOARD_FAB2_LIB.BASEBOARD_FAB2(SCH_1):PVPP_GHJ
 286 PVPP_GHJ VPP<1> @BASEBOARD_FAB2_LIB.BASEBOARD_FAB2(SCH_1):PVPP_GHJ
 287 PVPP_GHJ VPP<0> @BASEBOARD_FAB2_LIB.BASEBOARD_FAB2(SCH_1):PVPP_GHJ
  77 PVTT_GHJ VTT<1> @BASEBOARD_FAB2_LIB.BASEBOARD_FAB2(SCH_1):PVTT_GHJ
 221 PVTT_GHJ VTT<0> @BASEBOARD_FAB2_LIB.BASEBOARD_FAB2(SCH_1):PVTT_GHJ

CAP_A_0402V-0.01UF,25V,10%,X7RA  I180  C1G19
   1 M_J_VREF      A @BASEBOARD_FAB2_LIB.BASEBOARD_FAB2(SCH_1):M_J_VREF
   2    GND      B @BASEBOARD_FAB2_LIB.BASEBOARD_FAB2(SCH_1):GND

SCONN288_H44441003_PIP-SCONN,HA  I187  J9U2
  79 M_J_MA<0>     A0 @BASEBOARD_FAB2_LIB.BASEBOARD_FAB2(SCH_1):M_J_MA(0)
  72 M_J_MA<1>     A1 @BASEBOARD_FAB2_LIB.BASEBOARD_FAB2(SCH_1):M_J_MA(1)
 225 M_J_MA<10>    A10 @BASEBOARD_FAB2_LIB.BASEBOARD_FAB2(SCH_1):M_J_MA(10)
 210 M_J_MA<11>    A11 @BASEBOARD_FAB2_LIB.BASEBOARD_FAB2(SCH_1):M_J_MA(11)
  65 M_J_MA<12>    A12 @BASEBOARD_FAB2_LIB.BASEBOARD_FAB2(SCH_1):M_J_MA(12)
 232 M_J_MA<13>    A13 @BASEBOARD_FAB2_LIB.BASEBOARD_FAB2(SCH_1):M_J_MA(13)
 228 M_J_MA<14> A14_WE_N @BASEBOARD_FAB2_LIB.BASEBOARD_FAB2(SCH_1):M_J_MA(14)
  86 M_J_MA<15> A15_CAS_N @BASEBOARD_FAB2_LIB.BASEBOARD_FAB2(SCH_1):M_J_MA(15)
  82 M_J_MA<16> A16_RAS_N @BASEBOARD_FAB2_LIB.BASEBOARD_FAB2(SCH_1):M_J_MA(16)
 234 M_J_MA<17>    A17 @BASEBOARD_FAB2_LIB.BASEBOARD_FAB2(SCH_1):M_J_MA(17)
 216 M_J_MA<2>     A2 @BASEBOARD_FAB2_LIB.BASEBOARD_FAB2(SCH_1):M_J_MA(2)
  71 M_J_MA<3>     A3 @BASEBOARD_FAB2_LIB.BASEBOARD_FAB2(SCH_1):M_J_MA(3)
 214 M_J_MA<4>     A4 @BASEBOARD_FAB2_LIB.BASEBOARD_FAB2(SCH_1):M_J_MA(4)
 213 M_J_MA<5>     A5 @BASEBOARD_FAB2_LIB.BASEBOARD_FAB2(SCH_1):M_J_MA(5)
  69 M_J_MA<6>     A6 @BASEBOARD_FAB2_LIB.BASEBOARD_FAB2(SCH_1):M_J_MA(6)
 211 M_J_MA<7>     A7 @BASEBOARD_FAB2_LIB.BASEBOARD_FAB2(SCH_1):M_J_MA(7)
  68 M_J_MA<8>     A8 @BASEBOARD_FAB2_LIB.BASEBOARD_FAB2(SCH_1):M_J_MA(8)
  66 M_J_MA<9>     A9 @BASEBOARD_FAB2_LIB.BASEBOARD_FAB2(SCH_1):M_J_MA(9)
  62 M_J_ACT_N  ACT_N @BASEBOARD_FAB2_LIB.BASEBOARD_FAB2(SCH_1):M_J_ACT_N
 208 M_J_ALERT_N ALERT_N @BASEBOARD_FAB2_LIB.BASEBOARD_FAB2(SCH_1):M_J_ALERT_N
 224 M_J_BA<1>  BA<1> @BASEBOARD_FAB2_LIB.BASEBOARD_FAB2(SCH_1):M_J_BA(1)
  81 M_J_BA<0>  BA<0> @BASEBOARD_FAB2_LIB.BASEBOARD_FAB2(SCH_1):M_J_BA(0)
 207 M_J_BG<1>  BG<1> @BASEBOARD_FAB2_LIB.BASEBOARD_FAB2(SCH_1):M_J_BG(1)
  63 M_J_BG<0>  BG<0> @BASEBOARD_FAB2_LIB.BASEBOARD_FAB2(SCH_1):M_J_BG(0)
 235 M_J_C<2>   C<2> @BASEBOARD_FAB2_LIB.BASEBOARD_FAB2(SCH_1):M_J_C(2)
 199 M_J_ECC<7>  CB<7> @BASEBOARD_FAB2_LIB.BASEBOARD_FAB2(SCH_1):M_J_ECC(7)
  54 M_J_ECC<6>  CB<6> @BASEBOARD_FAB2_LIB.BASEBOARD_FAB2(SCH_1):M_J_ECC(6)
 192 M_J_ECC<5>  CB<5> @BASEBOARD_FAB2_LIB.BASEBOARD_FAB2(SCH_1):M_J_ECC(5)
  47 M_J_ECC<4>  CB<4> @BASEBOARD_FAB2_LIB.BASEBOARD_FAB2(SCH_1):M_J_ECC(4)
 201 M_J_ECC<3>  CB<3> @BASEBOARD_FAB2_LIB.BASEBOARD_FAB2(SCH_1):M_J_ECC(3)
  56 M_J_ECC<2>  CB<2> @BASEBOARD_FAB2_LIB.BASEBOARD_FAB2(SCH_1):M_J_ECC(2)
 194 M_J_ECC<1>  CB<1> @BASEBOARD_FAB2_LIB.BASEBOARD_FAB2(SCH_1):M_J_ECC(1)
  49 M_J_ECC<0>  CB<0> @BASEBOARD_FAB2_LIB.BASEBOARD_FAB2(SCH_1):M_J_ECC(0)
  75 M_J_CLK_DN<2>   CK0N @BASEBOARD_FAB2_LIB.BASEBOARD_FAB2(SCH_1):M_J_CLK_DN(2)
  74 M_J_CLK_DP<2>   CK0P @BASEBOARD_FAB2_LIB.BASEBOARD_FAB2(SCH_1):M_J_CLK_DP(2)
 219 M_J_CLK_DN<3>   CK1N @BASEBOARD_FAB2_LIB.BASEBOARD_FAB2(SCH_1):M_J_CLK_DN(3)
 218 M_J_CLK_DP<3>   CK1P @BASEBOARD_FAB2_LIB.BASEBOARD_FAB2(SCH_1):M_J_CLK_DP(3)
 203 M_J_CKE<3> CKE<1> @BASEBOARD_FAB2_LIB.BASEBOARD_FAB2(SCH_1):M_J_CKE(3)
  60 M_J_CKE<2> CKE<0> @BASEBOARD_FAB2_LIB.BASEBOARD_FAB2(SCH_1):M_J_CKE(2)
 280 M_J_DQ<63> DQ<63> @BASEBOARD_FAB2_LIB.BASEBOARD_FAB2(SCH_1):M_J_DQ(63)
 135 M_J_DQ<62> DQ<62> @BASEBOARD_FAB2_LIB.BASEBOARD_FAB2(SCH_1):M_J_DQ(62)
 273 M_J_DQ<61> DQ<61> @BASEBOARD_FAB2_LIB.BASEBOARD_FAB2(SCH_1):M_J_DQ(61)
 128 M_J_DQ<60> DQ<60> @BASEBOARD_FAB2_LIB.BASEBOARD_FAB2(SCH_1):M_J_DQ(60)
 282 M_J_DQ<59> DQ<59> @BASEBOARD_FAB2_LIB.BASEBOARD_FAB2(SCH_1):M_J_DQ(59)
 137 M_J_DQ<58> DQ<58> @BASEBOARD_FAB2_LIB.BASEBOARD_FAB2(SCH_1):M_J_DQ(58)
 275 M_J_DQ<57> DQ<57> @BASEBOARD_FAB2_LIB.BASEBOARD_FAB2(SCH_1):M_J_DQ(57)
 130 M_J_DQ<56> DQ<56> @BASEBOARD_FAB2_LIB.BASEBOARD_FAB2(SCH_1):M_J_DQ(56)
 269 M_J_DQ<55> DQ<55> @BASEBOARD_FAB2_LIB.BASEBOARD_FAB2(SCH_1):M_J_DQ(55)
 124 M_J_DQ<54> DQ<54> @BASEBOARD_FAB2_LIB.BASEBOARD_FAB2(SCH_1):M_J_DQ(54)
 262 M_J_DQ<53> DQ<53> @BASEBOARD_FAB2_LIB.BASEBOARD_FAB2(SCH_1):M_J_DQ(53)
 117 M_J_DQ<52> DQ<52> @BASEBOARD_FAB2_LIB.BASEBOARD_FAB2(SCH_1):M_J_DQ(52)
 271 M_J_DQ<51> DQ<51> @BASEBOARD_FAB2_LIB.BASEBOARD_FAB2(SCH_1):M_J_DQ(51)
 126 M_J_DQ<50> DQ<50> @BASEBOARD_FAB2_LIB.BASEBOARD_FAB2(SCH_1):M_J_DQ(50)
 264 M_J_DQ<49> DQ<49> @BASEBOARD_FAB2_LIB.BASEBOARD_FAB2(SCH_1):M_J_DQ(49)
 119 M_J_DQ<48> DQ<48> @BASEBOARD_FAB2_LIB.BASEBOARD_FAB2(SCH_1):M_J_DQ(48)
 258 M_J_DQ<47> DQ<47> @BASEBOARD_FAB2_LIB.BASEBOARD_FAB2(SCH_1):M_J_DQ(47)
 113 M_J_DQ<46> DQ<46> @BASEBOARD_FAB2_LIB.BASEBOARD_FAB2(SCH_1):M_J_DQ(46)
 251 M_J_DQ<45> DQ<45> @BASEBOARD_FAB2_LIB.BASEBOARD_FAB2(SCH_1):M_J_DQ(45)
 106 M_J_DQ<44> DQ<44> @BASEBOARD_FAB2_LIB.BASEBOARD_FAB2(SCH_1):M_J_DQ(44)
 260 M_J_DQ<43> DQ<43> @BASEBOARD_FAB2_LIB.BASEBOARD_FAB2(SCH_1):M_J_DQ(43)
 115 M_J_DQ<42> DQ<42> @BASEBOARD_FAB2_LIB.BASEBOARD_FAB2(SCH_1):M_J_DQ(42)
 253 M_J_DQ<41> DQ<41> @BASEBOARD_FAB2_LIB.BASEBOARD_FAB2(SCH_1):M_J_DQ(41)
 108 M_J_DQ<40> DQ<40> @BASEBOARD_FAB2_LIB.BASEBOARD_FAB2(SCH_1):M_J_DQ(40)
 247 M_J_DQ<39> DQ<39> @BASEBOARD_FAB2_LIB.BASEBOARD_FAB2(SCH_1):M_J_DQ(39)
 102 M_J_DQ<38> DQ<38> @BASEBOARD_FAB2_LIB.BASEBOARD_FAB2(SCH_1):M_J_DQ(38)
 240 M_J_DQ<37> DQ<37> @BASEBOARD_FAB2_LIB.BASEBOARD_FAB2(SCH_1):M_J_DQ(37)
  95 M_J_DQ<36> DQ<36> @BASEBOARD_FAB2_LIB.BASEBOARD_FAB2(SCH_1):M_J_DQ(36)
 249 M_J_DQ<35> DQ<35> @BASEBOARD_FAB2_LIB.BASEBOARD_FAB2(SCH_1):M_J_DQ(35)
 104 M_J_DQ<34> DQ<34> @BASEBOARD_FAB2_LIB.BASEBOARD_FAB2(SCH_1):M_J_DQ(34)
 242 M_J_DQ<33> DQ<33> @BASEBOARD_FAB2_LIB.BASEBOARD_FAB2(SCH_1):M_J_DQ(33)
  97 M_J_DQ<32> DQ<32> @BASEBOARD_FAB2_LIB.BASEBOARD_FAB2(SCH_1):M_J_DQ(32)
 188 M_J_DQ<31> DQ<31> @BASEBOARD_FAB2_LIB.BASEBOARD_FAB2(SCH_1):M_J_DQ(31)
  43 M_J_DQ<30> DQ<30> @BASEBOARD_FAB2_LIB.BASEBOARD_FAB2(SCH_1):M_J_DQ(30)
 181 M_J_DQ<29> DQ<29> @BASEBOARD_FAB2_LIB.BASEBOARD_FAB2(SCH_1):M_J_DQ(29)
  36 M_J_DQ<28> DQ<28> @BASEBOARD_FAB2_LIB.BASEBOARD_FAB2(SCH_1):M_J_DQ(28)
 190 M_J_DQ<27> DQ<27> @BASEBOARD_FAB2_LIB.BASEBOARD_FAB2(SCH_1):M_J_DQ(27)
  45 M_J_DQ<26> DQ<26> @BASEBOARD_FAB2_LIB.BASEBOARD_FAB2(SCH_1):M_J_DQ(26)
 183 M_J_DQ<25> DQ<25> @BASEBOARD_FAB2_LIB.BASEBOARD_FAB2(SCH_1):M_J_DQ(25)
  38 M_J_DQ<24> DQ<24> @BASEBOARD_FAB2_LIB.BASEBOARD_FAB2(SCH_1):M_J_DQ(24)
 177 M_J_DQ<23> DQ<23> @BASEBOARD_FAB2_LIB.BASEBOARD_FAB2(SCH_1):M_J_DQ(23)
  32 M_J_DQ<22> DQ<22> @BASEBOARD_FAB2_LIB.BASEBOARD_FAB2(SCH_1):M_J_DQ(22)
 170 M_J_DQ<21> DQ<21> @BASEBOARD_FAB2_LIB.BASEBOARD_FAB2(SCH_1):M_J_DQ(21)
  25 M_J_DQ<20> DQ<20> @BASEBOARD_FAB2_LIB.BASEBOARD_FAB2(SCH_1):M_J_DQ(20)
 179 M_J_DQ<19> DQ<19> @BASEBOARD_FAB2_LIB.BASEBOARD_FAB2(SCH_1):M_J_DQ(19)
  34 M_J_DQ<18> DQ<18> @BASEBOARD_FAB2_LIB.BASEBOARD_FAB2(SCH_1):M_J_DQ(18)
 172 M_J_DQ<17> DQ<17> @BASEBOARD_FAB2_LIB.BASEBOARD_FAB2(SCH_1):M_J_DQ(17)
  27 M_J_DQ<16> DQ<16> @BASEBOARD_FAB2_LIB.BASEBOARD_FAB2(SCH_1):M_J_DQ(16)
 166 M_J_DQ<15> DQ<15> @BASEBOARD_FAB2_LIB.BASEBOARD_FAB2(SCH_1):M_J_DQ(15)
  21 M_J_DQ<14> DQ<14> @BASEBOARD_FAB2_LIB.BASEBOARD_FAB2(SCH_1):M_J_DQ(14)
 159 M_J_DQ<13> DQ<13> @BASEBOARD_FAB2_LIB.BASEBOARD_FAB2(SCH_1):M_J_DQ(13)
  14 M_J_DQ<12> DQ<12> @BASEBOARD_FAB2_LIB.BASEBOARD_FAB2(SCH_1):M_J_DQ(12)
 168 M_J_DQ<11> DQ<11> @BASEBOARD_FAB2_LIB.BASEBOARD_FAB2(SCH_1):M_J_DQ(11)
  23 M_J_DQ<10> DQ<10> @BASEBOARD_FAB2_LIB.BASEBOARD_FAB2(SCH_1):M_J_DQ(10)
 161 M_J_DQ<9>  DQ<9> @BASEBOARD_FAB2_LIB.BASEBOARD_FAB2(SCH_1):M_J_DQ(9)
  16 M_J_DQ<8>  DQ<8> @BASEBOARD_FAB2_LIB.BASEBOARD_FAB2(SCH_1):M_J_DQ(8)
 155 M_J_DQ<7>  DQ<7> @BASEBOARD_FAB2_LIB.BASEBOARD_FAB2(SCH_1):M_J_DQ(7)
  10 M_J_DQ<6>  DQ<6> @BASEBOARD_FAB2_LIB.BASEBOARD_FAB2(SCH_1):M_J_DQ(6)
 148 M_J_DQ<5>  DQ<5> @BASEBOARD_FAB2_LIB.BASEBOARD_FAB2(SCH_1):M_J_DQ(5)
   3 M_J_DQ<4>  DQ<4> @BASEBOARD_FAB2_LIB.BASEBOARD_FAB2(SCH_1):M_J_DQ(4)
 157 M_J_DQ<3>  DQ<3> @BASEBOARD_FAB2_LIB.BASEBOARD_FAB2(SCH_1):M_J_DQ(3)
  12 M_J_DQ<2>  DQ<2> @BASEBOARD_FAB2_LIB.BASEBOARD_FAB2(SCH_1):M_J_DQ(2)
 150 M_J_DQ<1>  DQ<1> @BASEBOARD_FAB2_LIB.BASEBOARD_FAB2(SCH_1):M_J_DQ(1)
   5 M_J_DQ<0>  DQ<0> @BASEBOARD_FAB2_LIB.BASEBOARD_FAB2(SCH_1):M_J_DQ(0)
  78 FM_DIMM_EVENT_COD_N EVENT_N @BASEBOARD_FAB2_LIB.BASEBOARD_FAB2(SCH_1):FM_DIMM_EVENT_COD_N
  91 M_J_ODT<3> ODT<1> @BASEBOARD_FAB2_LIB.BASEBOARD_FAB2(SCH_1):M_J_ODT(3)
  87 M_J_ODT<2> ODT<0> @BASEBOARD_FAB2_LIB.BASEBOARD_FAB2(SCH_1):M_J_ODT(2)
 222 M_J_PAR    PAR @BASEBOARD_FAB2_LIB.BASEBOARD_FAB2(SCH_1):M_J_PAR
  58 M_GHJ_RST_N RESET_N @BASEBOARD_FAB2_LIB.BASEBOARD_FAB2(SCH_1):M_GHJ_RST_N
 144 TP_CH_J_DIMM_J1_RFU_2 RFU<2> @BASEBOARD_FAB2_LIB.BASEBOARD_FAB2(SCH_1):TP_CH_J_DIMM_J1_RFU_2
 227 TP_CH_J_DIMM_J1_RFU_1 RFU<1> @BASEBOARD_FAB2_LIB.BASEBOARD_FAB2(SCH_1):TP_CH_J_DIMM_J1_RFU_1
 205 TP_CH_J_DIMM_J1_RFU_0 RFU<0> @BASEBOARD_FAB2_LIB.BASEBOARD_FAB2(SCH_1):TP_CH_J_DIMM_J1_RFU_0
  84 M_J_CS_N<4>   S0_N @BASEBOARD_FAB2_LIB.BASEBOARD_FAB2(SCH_1):M_J_CS_N(4)
  89 M_J_CS_N<5>   S1_N @BASEBOARD_FAB2_LIB.BASEBOARD_FAB2(SCH_1):M_J_CS_N(5)
  93 M_J_CS_N<6> S2_N_C<0> @BASEBOARD_FAB2_LIB.BASEBOARD_FAB2(SCH_1):M_J_CS_N(6)
 237 M_J_CS_N<7> S3_N_C<1> @BASEBOARD_FAB2_LIB.BASEBOARD_FAB2(SCH_1):M_J_CS_N(7)
 238 PVPP_GHJ  SA<2> @BASEBOARD_FAB2_LIB.BASEBOARD_FAB2(SCH_1):PVPP_GHJ
 140    GND  SA<1> @BASEBOARD_FAB2_LIB.BASEBOARD_FAB2(SCH_1):GND
 139 PVPP_GHJ  SA<0> @BASEBOARD_FAB2_LIB.BASEBOARD_FAB2(SCH_1):PVPP_GHJ
 230 FM_ADR_COMPLETE_GHJ_N SAVE_N_NC @BASEBOARD_FAB2_LIB.BASEBOARD_FAB2(SCH_1):FM_ADR_COMPLETE_GHJ_N
 141 SMB_DDR_GHJ_VPP_SCL    SCL @BASEBOARD_FAB2_LIB.BASEBOARD_FAB2(SCH_1):SMB_DDR_GHJ_VPP_SCL
 285 SMB_DDR_GHJ_VPP_SDA    SDA @BASEBOARD_FAB2_LIB.BASEBOARD_FAB2(SCH_1):SMB_DDR_GHJ_VPP_SDA
 284 PVPP_GHJ VDDSPD @BASEBOARD_FAB2_LIB.BASEBOARD_FAB2(SCH_1):PVPP_GHJ
 146 M_J_VREF VREFCA @BASEBOARD_FAB2_LIB.BASEBOARD_FAB2(SCH_1):M_J_VREF

SCONN288_H44441003_PIP-SCONN,HA  I188  J9U2
   2    GND VSS<93> @BASEBOARD_FAB2_LIB.BASEBOARD_FAB2(SCH_1):GND
   4    GND VSS<92> @BASEBOARD_FAB2_LIB.BASEBOARD_FAB2(SCH_1):GND
   6    GND VSS<91> @BASEBOARD_FAB2_LIB.BASEBOARD_FAB2(SCH_1):GND
   9    GND VSS<90> @BASEBOARD_FAB2_LIB.BASEBOARD_FAB2(SCH_1):GND
  11    GND VSS<89> @BASEBOARD_FAB2_LIB.BASEBOARD_FAB2(SCH_1):GND
  13    GND VSS<88> @BASEBOARD_FAB2_LIB.BASEBOARD_FAB2(SCH_1):GND
  15    GND VSS<87> @BASEBOARD_FAB2_LIB.BASEBOARD_FAB2(SCH_1):GND
  17    GND VSS<86> @BASEBOARD_FAB2_LIB.BASEBOARD_FAB2(SCH_1):GND
  20    GND VSS<85> @BASEBOARD_FAB2_LIB.BASEBOARD_FAB2(SCH_1):GND
  22    GND VSS<84> @BASEBOARD_FAB2_LIB.BASEBOARD_FAB2(SCH_1):GND
  24    GND VSS<83> @BASEBOARD_FAB2_LIB.BASEBOARD_FAB2(SCH_1):GND
  26    GND VSS<82> @BASEBOARD_FAB2_LIB.BASEBOARD_FAB2(SCH_1):GND
  28    GND VSS<81> @BASEBOARD_FAB2_LIB.BASEBOARD_FAB2(SCH_1):GND
  31    GND VSS<80> @BASEBOARD_FAB2_LIB.BASEBOARD_FAB2(SCH_1):GND
  33    GND VSS<79> @BASEBOARD_FAB2_LIB.BASEBOARD_FAB2(SCH_1):GND
  35    GND VSS<78> @BASEBOARD_FAB2_LIB.BASEBOARD_FAB2(SCH_1):GND
  37    GND VSS<77> @BASEBOARD_FAB2_LIB.BASEBOARD_FAB2(SCH_1):GND
  39    GND VSS<76> @BASEBOARD_FAB2_LIB.BASEBOARD_FAB2(SCH_1):GND
  42    GND VSS<75> @BASEBOARD_FAB2_LIB.BASEBOARD_FAB2(SCH_1):GND
  44    GND VSS<74> @BASEBOARD_FAB2_LIB.BASEBOARD_FAB2(SCH_1):GND
  46    GND VSS<73> @BASEBOARD_FAB2_LIB.BASEBOARD_FAB2(SCH_1):GND
  48    GND VSS<72> @BASEBOARD_FAB2_LIB.BASEBOARD_FAB2(SCH_1):GND
  50    GND VSS<71> @BASEBOARD_FAB2_LIB.BASEBOARD_FAB2(SCH_1):GND
  53    GND VSS<70> @BASEBOARD_FAB2_LIB.BASEBOARD_FAB2(SCH_1):GND
  55    GND VSS<69> @BASEBOARD_FAB2_LIB.BASEBOARD_FAB2(SCH_1):GND
  57    GND VSS<68> @BASEBOARD_FAB2_LIB.BASEBOARD_FAB2(SCH_1):GND
  94    GND VSS<67> @BASEBOARD_FAB2_LIB.BASEBOARD_FAB2(SCH_1):GND
  96    GND VSS<66> @BASEBOARD_FAB2_LIB.BASEBOARD_FAB2(SCH_1):GND
  98    GND VSS<65> @BASEBOARD_FAB2_LIB.BASEBOARD_FAB2(SCH_1):GND
 101    GND VSS<64> @BASEBOARD_FAB2_LIB.BASEBOARD_FAB2(SCH_1):GND
 103    GND VSS<63> @BASEBOARD_FAB2_LIB.BASEBOARD_FAB2(SCH_1):GND
 105    GND VSS<62> @BASEBOARD_FAB2_LIB.BASEBOARD_FAB2(SCH_1):GND
 107    GND VSS<61> @BASEBOARD_FAB2_LIB.BASEBOARD_FAB2(SCH_1):GND
 109    GND VSS<60> @BASEBOARD_FAB2_LIB.BASEBOARD_FAB2(SCH_1):GND
 112    GND VSS<59> @BASEBOARD_FAB2_LIB.BASEBOARD_FAB2(SCH_1):GND
 114    GND VSS<58> @BASEBOARD_FAB2_LIB.BASEBOARD_FAB2(SCH_1):GND
 116    GND VSS<57> @BASEBOARD_FAB2_LIB.BASEBOARD_FAB2(SCH_1):GND
 118    GND VSS<56> @BASEBOARD_FAB2_LIB.BASEBOARD_FAB2(SCH_1):GND
 120    GND VSS<55> @BASEBOARD_FAB2_LIB.BASEBOARD_FAB2(SCH_1):GND
 123    GND VSS<54> @BASEBOARD_FAB2_LIB.BASEBOARD_FAB2(SCH_1):GND
 125    GND VSS<53> @BASEBOARD_FAB2_LIB.BASEBOARD_FAB2(SCH_1):GND
 127    GND VSS<52> @BASEBOARD_FAB2_LIB.BASEBOARD_FAB2(SCH_1):GND
 129    GND VSS<51> @BASEBOARD_FAB2_LIB.BASEBOARD_FAB2(SCH_1):GND
 131    GND VSS<50> @BASEBOARD_FAB2_LIB.BASEBOARD_FAB2(SCH_1):GND
 134    GND VSS<49> @BASEBOARD_FAB2_LIB.BASEBOARD_FAB2(SCH_1):GND
 136    GND VSS<48> @BASEBOARD_FAB2_LIB.BASEBOARD_FAB2(SCH_1):GND
 138    GND VSS<47> @BASEBOARD_FAB2_LIB.BASEBOARD_FAB2(SCH_1):GND
 147    GND VSS<46> @BASEBOARD_FAB2_LIB.BASEBOARD_FAB2(SCH_1):GND
 149    GND VSS<45> @BASEBOARD_FAB2_LIB.BASEBOARD_FAB2(SCH_1):GND
 151    GND VSS<44> @BASEBOARD_FAB2_LIB.BASEBOARD_FAB2(SCH_1):GND
 154    GND VSS<43> @BASEBOARD_FAB2_LIB.BASEBOARD_FAB2(SCH_1):GND
 156    GND VSS<42> @BASEBOARD_FAB2_LIB.BASEBOARD_FAB2(SCH_1):GND
 158    GND VSS<41> @BASEBOARD_FAB2_LIB.BASEBOARD_FAB2(SCH_1):GND
 160    GND VSS<40> @BASEBOARD_FAB2_LIB.BASEBOARD_FAB2(SCH_1):GND
 162    GND VSS<39> @BASEBOARD_FAB2_LIB.BASEBOARD_FAB2(SCH_1):GND
 165    GND VSS<38> @BASEBOARD_FAB2_LIB.BASEBOARD_FAB2(SCH_1):GND
 167    GND VSS<37> @BASEBOARD_FAB2_LIB.BASEBOARD_FAB2(SCH_1):GND
 169    GND VSS<36> @BASEBOARD_FAB2_LIB.BASEBOARD_FAB2(SCH_1):GND
 171    GND VSS<35> @BASEBOARD_FAB2_LIB.BASEBOARD_FAB2(SCH_1):GND
 173    GND VSS<34> @BASEBOARD_FAB2_LIB.BASEBOARD_FAB2(SCH_1):GND
 176    GND VSS<33> @BASEBOARD_FAB2_LIB.BASEBOARD_FAB2(SCH_1):GND
 178    GND VSS<32> @BASEBOARD_FAB2_LIB.BASEBOARD_FAB2(SCH_1):GND
 180    GND VSS<31> @BASEBOARD_FAB2_LIB.BASEBOARD_FAB2(SCH_1):GND
 182    GND VSS<30> @BASEBOARD_FAB2_LIB.BASEBOARD_FAB2(SCH_1):GND
 184    GND VSS<29> @BASEBOARD_FAB2_LIB.BASEBOARD_FAB2(SCH_1):GND
 187    GND VSS<28> @BASEBOARD_FAB2_LIB.BASEBOARD_FAB2(SCH_1):GND
 189    GND VSS<27> @BASEBOARD_FAB2_LIB.BASEBOARD_FAB2(SCH_1):GND
 191    GND VSS<26> @BASEBOARD_FAB2_LIB.BASEBOARD_FAB2(SCH_1):GND
 193    GND VSS<25> @BASEBOARD_FAB2_LIB.BASEBOARD_FAB2(SCH_1):GND
 195    GND VSS<24> @BASEBOARD_FAB2_LIB.BASEBOARD_FAB2(SCH_1):GND
 198    GND VSS<23> @BASEBOARD_FAB2_LIB.BASEBOARD_FAB2(SCH_1):GND
 200    GND VSS<22> @BASEBOARD_FAB2_LIB.BASEBOARD_FAB2(SCH_1):GND
 202    GND VSS<21> @BASEBOARD_FAB2_LIB.BASEBOARD_FAB2(SCH_1):GND
 239    GND VSS<20> @BASEBOARD_FAB2_LIB.BASEBOARD_FAB2(SCH_1):GND
 241    GND VSS<19> @BASEBOARD_FAB2_LIB.BASEBOARD_FAB2(SCH_1):GND
 243    GND VSS<18> @BASEBOARD_FAB2_LIB.BASEBOARD_FAB2(SCH_1):GND
 246    GND VSS<17> @BASEBOARD_FAB2_LIB.BASEBOARD_FAB2(SCH_1):GND
 248    GND VSS<16> @BASEBOARD_FAB2_LIB.BASEBOARD_FAB2(SCH_1):GND
 250    GND VSS<15> @BASEBOARD_FAB2_LIB.BASEBOARD_FAB2(SCH_1):GND
 252    GND VSS<14> @BASEBOARD_FAB2_LIB.BASEBOARD_FAB2(SCH_1):GND
 254    GND VSS<13> @BASEBOARD_FAB2_LIB.BASEBOARD_FAB2(SCH_1):GND
 257    GND VSS<12> @BASEBOARD_FAB2_LIB.BASEBOARD_FAB2(SCH_1):GND
 259    GND VSS<11> @BASEBOARD_FAB2_LIB.BASEBOARD_FAB2(SCH_1):GND
 261    GND VSS<10> @BASEBOARD_FAB2_LIB.BASEBOARD_FAB2(SCH_1):GND
 263    GND VSS<9> @BASEBOARD_FAB2_LIB.BASEBOARD_FAB2(SCH_1):GND
 265    GND VSS<8> @BASEBOARD_FAB2_LIB.BASEBOARD_FAB2(SCH_1):GND
 268    GND VSS<7> @BASEBOARD_FAB2_LIB.BASEBOARD_FAB2(SCH_1):GND
 270    GND VSS<6> @BASEBOARD_FAB2_LIB.BASEBOARD_FAB2(SCH_1):GND
 272    GND VSS<5> @BASEBOARD_FAB2_LIB.BASEBOARD_FAB2(SCH_1):GND
 274    GND VSS<4> @BASEBOARD_FAB2_LIB.BASEBOARD_FAB2(SCH_1):GND
 276    GND VSS<3> @BASEBOARD_FAB2_LIB.BASEBOARD_FAB2(SCH_1):GND
 279    GND VSS<2> @BASEBOARD_FAB2_LIB.BASEBOARD_FAB2(SCH_1):GND
 281    GND VSS<1> @BASEBOARD_FAB2_LIB.BASEBOARD_FAB2(SCH_1):GND
 283    GND VSS<0> @BASEBOARD_FAB2_LIB.BASEBOARD_FAB2(SCH_1):GND


DRAWING: @BASEBOARD_FAB2_LIB.BASEBOARD_FAB2(SCH_1):PAGE83 

SCONN288_H44441004_PIP-SCONN,HA  I43  J1B1
   2    GND VSS<93> @BASEBOARD_FAB2_LIB.BASEBOARD_FAB2(SCH_1):GND
   4    GND VSS<92> @BASEBOARD_FAB2_LIB.BASEBOARD_FAB2(SCH_1):GND
   6    GND VSS<91> @BASEBOARD_FAB2_LIB.BASEBOARD_FAB2(SCH_1):GND
   9    GND VSS<90> @BASEBOARD_FAB2_LIB.BASEBOARD_FAB2(SCH_1):GND
  11    GND VSS<89> @BASEBOARD_FAB2_LIB.BASEBOARD_FAB2(SCH_1):GND
  13    GND VSS<88> @BASEBOARD_FAB2_LIB.BASEBOARD_FAB2(SCH_1):GND
  15    GND VSS<87> @BASEBOARD_FAB2_LIB.BASEBOARD_FAB2(SCH_1):GND
  17    GND VSS<86> @BASEBOARD_FAB2_LIB.BASEBOARD_FAB2(SCH_1):GND
  20    GND VSS<85> @BASEBOARD_FAB2_LIB.BASEBOARD_FAB2(SCH_1):GND
  22    GND VSS<84> @BASEBOARD_FAB2_LIB.BASEBOARD_FAB2(SCH_1):GND
  24    GND VSS<83> @BASEBOARD_FAB2_LIB.BASEBOARD_FAB2(SCH_1):GND
  26    GND VSS<82> @BASEBOARD_FAB2_LIB.BASEBOARD_FAB2(SCH_1):GND
  28    GND VSS<81> @BASEBOARD_FAB2_LIB.BASEBOARD_FAB2(SCH_1):GND
  31    GND VSS<80> @BASEBOARD_FAB2_LIB.BASEBOARD_FAB2(SCH_1):GND
  33    GND VSS<79> @BASEBOARD_FAB2_LIB.BASEBOARD_FAB2(SCH_1):GND
  35    GND VSS<78> @BASEBOARD_FAB2_LIB.BASEBOARD_FAB2(SCH_1):GND
  37    GND VSS<77> @BASEBOARD_FAB2_LIB.BASEBOARD_FAB2(SCH_1):GND
  39    GND VSS<76> @BASEBOARD_FAB2_LIB.BASEBOARD_FAB2(SCH_1):GND
  42    GND VSS<75> @BASEBOARD_FAB2_LIB.BASEBOARD_FAB2(SCH_1):GND
  44    GND VSS<74> @BASEBOARD_FAB2_LIB.BASEBOARD_FAB2(SCH_1):GND
  46    GND VSS<73> @BASEBOARD_FAB2_LIB.BASEBOARD_FAB2(SCH_1):GND
  48    GND VSS<72> @BASEBOARD_FAB2_LIB.BASEBOARD_FAB2(SCH_1):GND
  50    GND VSS<71> @BASEBOARD_FAB2_LIB.BASEBOARD_FAB2(SCH_1):GND
  53    GND VSS<70> @BASEBOARD_FAB2_LIB.BASEBOARD_FAB2(SCH_1):GND
  55    GND VSS<69> @BASEBOARD_FAB2_LIB.BASEBOARD_FAB2(SCH_1):GND
  57    GND VSS<68> @BASEBOARD_FAB2_LIB.BASEBOARD_FAB2(SCH_1):GND
  94    GND VSS<67> @BASEBOARD_FAB2_LIB.BASEBOARD_FAB2(SCH_1):GND
  96    GND VSS<66> @BASEBOARD_FAB2_LIB.BASEBOARD_FAB2(SCH_1):GND
  98    GND VSS<65> @BASEBOARD_FAB2_LIB.BASEBOARD_FAB2(SCH_1):GND
 101    GND VSS<64> @BASEBOARD_FAB2_LIB.BASEBOARD_FAB2(SCH_1):GND
 103    GND VSS<63> @BASEBOARD_FAB2_LIB.BASEBOARD_FAB2(SCH_1):GND
 105    GND VSS<62> @BASEBOARD_FAB2_LIB.BASEBOARD_FAB2(SCH_1):GND
 107    GND VSS<61> @BASEBOARD_FAB2_LIB.BASEBOARD_FAB2(SCH_1):GND
 109    GND VSS<60> @BASEBOARD_FAB2_LIB.BASEBOARD_FAB2(SCH_1):GND
 112    GND VSS<59> @BASEBOARD_FAB2_LIB.BASEBOARD_FAB2(SCH_1):GND
 114    GND VSS<58> @BASEBOARD_FAB2_LIB.BASEBOARD_FAB2(SCH_1):GND
 116    GND VSS<57> @BASEBOARD_FAB2_LIB.BASEBOARD_FAB2(SCH_1):GND
 118    GND VSS<56> @BASEBOARD_FAB2_LIB.BASEBOARD_FAB2(SCH_1):GND
 120    GND VSS<55> @BASEBOARD_FAB2_LIB.BASEBOARD_FAB2(SCH_1):GND
 123    GND VSS<54> @BASEBOARD_FAB2_LIB.BASEBOARD_FAB2(SCH_1):GND
 125    GND VSS<53> @BASEBOARD_FAB2_LIB.BASEBOARD_FAB2(SCH_1):GND
 127    GND VSS<52> @BASEBOARD_FAB2_LIB.BASEBOARD_FAB2(SCH_1):GND
 129    GND VSS<51> @BASEBOARD_FAB2_LIB.BASEBOARD_FAB2(SCH_1):GND
 131    GND VSS<50> @BASEBOARD_FAB2_LIB.BASEBOARD_FAB2(SCH_1):GND
 134    GND VSS<49> @BASEBOARD_FAB2_LIB.BASEBOARD_FAB2(SCH_1):GND
 136    GND VSS<48> @BASEBOARD_FAB2_LIB.BASEBOARD_FAB2(SCH_1):GND
 138    GND VSS<47> @BASEBOARD_FAB2_LIB.BASEBOARD_FAB2(SCH_1):GND
 147    GND VSS<46> @BASEBOARD_FAB2_LIB.BASEBOARD_FAB2(SCH_1):GND
 149    GND VSS<45> @BASEBOARD_FAB2_LIB.BASEBOARD_FAB2(SCH_1):GND
 151    GND VSS<44> @BASEBOARD_FAB2_LIB.BASEBOARD_FAB2(SCH_1):GND
 154    GND VSS<43> @BASEBOARD_FAB2_LIB.BASEBOARD_FAB2(SCH_1):GND
 156    GND VSS<42> @BASEBOARD_FAB2_LIB.BASEBOARD_FAB2(SCH_1):GND
 158    GND VSS<41> @BASEBOARD_FAB2_LIB.BASEBOARD_FAB2(SCH_1):GND
 160    GND VSS<40> @BASEBOARD_FAB2_LIB.BASEBOARD_FAB2(SCH_1):GND
 162    GND VSS<39> @BASEBOARD_FAB2_LIB.BASEBOARD_FAB2(SCH_1):GND
 165    GND VSS<38> @BASEBOARD_FAB2_LIB.BASEBOARD_FAB2(SCH_1):GND
 167    GND VSS<37> @BASEBOARD_FAB2_LIB.BASEBOARD_FAB2(SCH_1):GND
 169    GND VSS<36> @BASEBOARD_FAB2_LIB.BASEBOARD_FAB2(SCH_1):GND
 171    GND VSS<35> @BASEBOARD_FAB2_LIB.BASEBOARD_FAB2(SCH_1):GND
 173    GND VSS<34> @BASEBOARD_FAB2_LIB.BASEBOARD_FAB2(SCH_1):GND
 176    GND VSS<33> @BASEBOARD_FAB2_LIB.BASEBOARD_FAB2(SCH_1):GND
 178    GND VSS<32> @BASEBOARD_FAB2_LIB.BASEBOARD_FAB2(SCH_1):GND
 180    GND VSS<31> @BASEBOARD_FAB2_LIB.BASEBOARD_FAB2(SCH_1):GND
 182    GND VSS<30> @BASEBOARD_FAB2_LIB.BASEBOARD_FAB2(SCH_1):GND
 184    GND VSS<29> @BASEBOARD_FAB2_LIB.BASEBOARD_FAB2(SCH_1):GND
 187    GND VSS<28> @BASEBOARD_FAB2_LIB.BASEBOARD_FAB2(SCH_1):GND
 189    GND VSS<27> @BASEBOARD_FAB2_LIB.BASEBOARD_FAB2(SCH_1):GND
 191    GND VSS<26> @BASEBOARD_FAB2_LIB.BASEBOARD_FAB2(SCH_1):GND
 193    GND VSS<25> @BASEBOARD_FAB2_LIB.BASEBOARD_FAB2(SCH_1):GND
 195    GND VSS<24> @BASEBOARD_FAB2_LIB.BASEBOARD_FAB2(SCH_1):GND
 198    GND VSS<23> @BASEBOARD_FAB2_LIB.BASEBOARD_FAB2(SCH_1):GND
 200    GND VSS<22> @BASEBOARD_FAB2_LIB.BASEBOARD_FAB2(SCH_1):GND
 202    GND VSS<21> @BASEBOARD_FAB2_LIB.BASEBOARD_FAB2(SCH_1):GND
 239    GND VSS<20> @BASEBOARD_FAB2_LIB.BASEBOARD_FAB2(SCH_1):GND
 241    GND VSS<19> @BASEBOARD_FAB2_LIB.BASEBOARD_FAB2(SCH_1):GND
 243    GND VSS<18> @BASEBOARD_FAB2_LIB.BASEBOARD_FAB2(SCH_1):GND
 246    GND VSS<17> @BASEBOARD_FAB2_LIB.BASEBOARD_FAB2(SCH_1):GND
 248    GND VSS<16> @BASEBOARD_FAB2_LIB.BASEBOARD_FAB2(SCH_1):GND
 250    GND VSS<15> @BASEBOARD_FAB2_LIB.BASEBOARD_FAB2(SCH_1):GND
 252    GND VSS<14> @BASEBOARD_FAB2_LIB.BASEBOARD_FAB2(SCH_1):GND
 254    GND VSS<13> @BASEBOARD_FAB2_LIB.BASEBOARD_FAB2(SCH_1):GND
 257    GND VSS<12> @BASEBOARD_FAB2_LIB.BASEBOARD_FAB2(SCH_1):GND
 259    GND VSS<11> @BASEBOARD_FAB2_LIB.BASEBOARD_FAB2(SCH_1):GND
 261    GND VSS<10> @BASEBOARD_FAB2_LIB.BASEBOARD_FAB2(SCH_1):GND
 263    GND VSS<9> @BASEBOARD_FAB2_LIB.BASEBOARD_FAB2(SCH_1):GND
 265    GND VSS<8> @BASEBOARD_FAB2_LIB.BASEBOARD_FAB2(SCH_1):GND
 268    GND VSS<7> @BASEBOARD_FAB2_LIB.BASEBOARD_FAB2(SCH_1):GND
 270    GND VSS<6> @BASEBOARD_FAB2_LIB.BASEBOARD_FAB2(SCH_1):GND
 272    GND VSS<5> @BASEBOARD_FAB2_LIB.BASEBOARD_FAB2(SCH_1):GND
 274    GND VSS<4> @BASEBOARD_FAB2_LIB.BASEBOARD_FAB2(SCH_1):GND
 276    GND VSS<3> @BASEBOARD_FAB2_LIB.BASEBOARD_FAB2(SCH_1):GND
 279    GND VSS<2> @BASEBOARD_FAB2_LIB.BASEBOARD_FAB2(SCH_1):GND
 281    GND VSS<1> @BASEBOARD_FAB2_LIB.BASEBOARD_FAB2(SCH_1):GND
 283    GND VSS<0> @BASEBOARD_FAB2_LIB.BASEBOARD_FAB2(SCH_1):GND

SCONN288_H44441004_PIP-SCONN,HA  I66  J1B1
 152 M_K_DQS_DN<0>  DQS0N @BASEBOARD_FAB2_LIB.BASEBOARD_FAB2(SCH_1):M_K_DQS_DN(0)
 153 M_K_DQS_DP<0>  DQS0P @BASEBOARD_FAB2_LIB.BASEBOARD_FAB2(SCH_1):M_K_DQS_DP(0)
  19 M_K_DQS_DN<10> DQS10N @BASEBOARD_FAB2_LIB.BASEBOARD_FAB2(SCH_1):M_K_DQS_DN(10)
  18 M_K_DQS_DP<10> DQS10P @BASEBOARD_FAB2_LIB.BASEBOARD_FAB2(SCH_1):M_K_DQS_DP(10)
  30 M_K_DQS_DN<11> DQS11N @BASEBOARD_FAB2_LIB.BASEBOARD_FAB2(SCH_1):M_K_DQS_DN(11)
  29 M_K_DQS_DP<11> DQS11P @BASEBOARD_FAB2_LIB.BASEBOARD_FAB2(SCH_1):M_K_DQS_DP(11)
  41 M_K_DQS_DN<12> DQS12N @BASEBOARD_FAB2_LIB.BASEBOARD_FAB2(SCH_1):M_K_DQS_DN(12)
  40 M_K_DQS_DP<12> DQS12P @BASEBOARD_FAB2_LIB.BASEBOARD_FAB2(SCH_1):M_K_DQS_DP(12)
 100 M_K_DQS_DN<13> DQS13N @BASEBOARD_FAB2_LIB.BASEBOARD_FAB2(SCH_1):M_K_DQS_DN(13)
  99 M_K_DQS_DP<13> DQS13P @BASEBOARD_FAB2_LIB.BASEBOARD_FAB2(SCH_1):M_K_DQS_DP(13)
 111 M_K_DQS_DN<14> DQS14N @BASEBOARD_FAB2_LIB.BASEBOARD_FAB2(SCH_1):M_K_DQS_DN(14)
 110 M_K_DQS_DP<14> DQS14P @BASEBOARD_FAB2_LIB.BASEBOARD_FAB2(SCH_1):M_K_DQS_DP(14)
 122 M_K_DQS_DN<15> DQS15N @BASEBOARD_FAB2_LIB.BASEBOARD_FAB2(SCH_1):M_K_DQS_DN(15)
 121 M_K_DQS_DP<15> DQS15P @BASEBOARD_FAB2_LIB.BASEBOARD_FAB2(SCH_1):M_K_DQS_DP(15)
 133 M_K_DQS_DN<16> DQS16N @BASEBOARD_FAB2_LIB.BASEBOARD_FAB2(SCH_1):M_K_DQS_DN(16)
 132 M_K_DQS_DP<16> DQS16P @BASEBOARD_FAB2_LIB.BASEBOARD_FAB2(SCH_1):M_K_DQS_DP(16)
  52 M_K_DQS_DN<17> DQS17N @BASEBOARD_FAB2_LIB.BASEBOARD_FAB2(SCH_1):M_K_DQS_DN(17)
  51 M_K_DQS_DP<17> DQS17P @BASEBOARD_FAB2_LIB.BASEBOARD_FAB2(SCH_1):M_K_DQS_DP(17)
 163 M_K_DQS_DN<1>  DQS1N @BASEBOARD_FAB2_LIB.BASEBOARD_FAB2(SCH_1):M_K_DQS_DN(1)
 164 M_K_DQS_DP<1>  DQS1P @BASEBOARD_FAB2_LIB.BASEBOARD_FAB2(SCH_1):M_K_DQS_DP(1)
 174 M_K_DQS_DN<2>  DQS2N @BASEBOARD_FAB2_LIB.BASEBOARD_FAB2(SCH_1):M_K_DQS_DN(2)
 175 M_K_DQS_DP<2>  DQS2P @BASEBOARD_FAB2_LIB.BASEBOARD_FAB2(SCH_1):M_K_DQS_DP(2)
 185 M_K_DQS_DN<3>  DQS3N @BASEBOARD_FAB2_LIB.BASEBOARD_FAB2(SCH_1):M_K_DQS_DN(3)
 186 M_K_DQS_DP<3>  DQS3P @BASEBOARD_FAB2_LIB.BASEBOARD_FAB2(SCH_1):M_K_DQS_DP(3)
 244 M_K_DQS_DN<4>  DQS4N @BASEBOARD_FAB2_LIB.BASEBOARD_FAB2(SCH_1):M_K_DQS_DN(4)
 245 M_K_DQS_DP<4>  DQS4P @BASEBOARD_FAB2_LIB.BASEBOARD_FAB2(SCH_1):M_K_DQS_DP(4)
 255 M_K_DQS_DN<5>  DQS5N @BASEBOARD_FAB2_LIB.BASEBOARD_FAB2(SCH_1):M_K_DQS_DN(5)
 256 M_K_DQS_DP<5>  DQS5P @BASEBOARD_FAB2_LIB.BASEBOARD_FAB2(SCH_1):M_K_DQS_DP(5)
 266 M_K_DQS_DN<6>  DQS6N @BASEBOARD_FAB2_LIB.BASEBOARD_FAB2(SCH_1):M_K_DQS_DN(6)
 267 M_K_DQS_DP<6>  DQS6P @BASEBOARD_FAB2_LIB.BASEBOARD_FAB2(SCH_1):M_K_DQS_DP(6)
 277 M_K_DQS_DN<7>  DQS7N @BASEBOARD_FAB2_LIB.BASEBOARD_FAB2(SCH_1):M_K_DQS_DN(7)
 278 M_K_DQS_DP<7>  DQS7P @BASEBOARD_FAB2_LIB.BASEBOARD_FAB2(SCH_1):M_K_DQS_DP(7)
 196 M_K_DQS_DN<8>  DQS8N @BASEBOARD_FAB2_LIB.BASEBOARD_FAB2(SCH_1):M_K_DQS_DN(8)
 197 M_K_DQS_DP<8>  DQS8P @BASEBOARD_FAB2_LIB.BASEBOARD_FAB2(SCH_1):M_K_DQS_DP(8)
   8 M_K_DQS_DN<9>  DQS9N @BASEBOARD_FAB2_LIB.BASEBOARD_FAB2(SCH_1):M_K_DQS_DN(9)
   7 M_K_DQS_DP<9>  DQS9P @BASEBOARD_FAB2_LIB.BASEBOARD_FAB2(SCH_1):M_K_DQS_DP(9)

SCONN288_H44441004_PIP-SCONN,HA  I111  J1B1
  79 M_K_MA<0>     A0 @BASEBOARD_FAB2_LIB.BASEBOARD_FAB2(SCH_1):M_K_MA(0)
  72 M_K_MA<1>     A1 @BASEBOARD_FAB2_LIB.BASEBOARD_FAB2(SCH_1):M_K_MA(1)
 225 M_K_MA<10>    A10 @BASEBOARD_FAB2_LIB.BASEBOARD_FAB2(SCH_1):M_K_MA(10)
 210 M_K_MA<11>    A11 @BASEBOARD_FAB2_LIB.BASEBOARD_FAB2(SCH_1):M_K_MA(11)
  65 M_K_MA<12>    A12 @BASEBOARD_FAB2_LIB.BASEBOARD_FAB2(SCH_1):M_K_MA(12)
 232 M_K_MA<13>    A13 @BASEBOARD_FAB2_LIB.BASEBOARD_FAB2(SCH_1):M_K_MA(13)
 228 M_K_MA<14> A14_WE_N @BASEBOARD_FAB2_LIB.BASEBOARD_FAB2(SCH_1):M_K_MA(14)
  86 M_K_MA<15> A15_CAS_N @BASEBOARD_FAB2_LIB.BASEBOARD_FAB2(SCH_1):M_K_MA(15)
  82 M_K_MA<16> A16_RAS_N @BASEBOARD_FAB2_LIB.BASEBOARD_FAB2(SCH_1):M_K_MA(16)
 234 M_K_MA<17>    A17 @BASEBOARD_FAB2_LIB.BASEBOARD_FAB2(SCH_1):M_K_MA(17)
 216 M_K_MA<2>     A2 @BASEBOARD_FAB2_LIB.BASEBOARD_FAB2(SCH_1):M_K_MA(2)
  71 M_K_MA<3>     A3 @BASEBOARD_FAB2_LIB.BASEBOARD_FAB2(SCH_1):M_K_MA(3)
 214 M_K_MA<4>     A4 @BASEBOARD_FAB2_LIB.BASEBOARD_FAB2(SCH_1):M_K_MA(4)
 213 M_K_MA<5>     A5 @BASEBOARD_FAB2_LIB.BASEBOARD_FAB2(SCH_1):M_K_MA(5)
  69 M_K_MA<6>     A6 @BASEBOARD_FAB2_LIB.BASEBOARD_FAB2(SCH_1):M_K_MA(6)
 211 M_K_MA<7>     A7 @BASEBOARD_FAB2_LIB.BASEBOARD_FAB2(SCH_1):M_K_MA(7)
  68 M_K_MA<8>     A8 @BASEBOARD_FAB2_LIB.BASEBOARD_FAB2(SCH_1):M_K_MA(8)
  66 M_K_MA<9>     A9 @BASEBOARD_FAB2_LIB.BASEBOARD_FAB2(SCH_1):M_K_MA(9)
  62 M_K_ACT_N  ACT_N @BASEBOARD_FAB2_LIB.BASEBOARD_FAB2(SCH_1):M_K_ACT_N
 208 M_K_ALERT_N ALERT_N @BASEBOARD_FAB2_LIB.BASEBOARD_FAB2(SCH_1):M_K_ALERT_N
 224 M_K_BA<1>  BA<1> @BASEBOARD_FAB2_LIB.BASEBOARD_FAB2(SCH_1):M_K_BA(1)
  81 M_K_BA<0>  BA<0> @BASEBOARD_FAB2_LIB.BASEBOARD_FAB2(SCH_1):M_K_BA(0)
 207 M_K_BG<1>  BG<1> @BASEBOARD_FAB2_LIB.BASEBOARD_FAB2(SCH_1):M_K_BG(1)
  63 M_K_BG<0>  BG<0> @BASEBOARD_FAB2_LIB.BASEBOARD_FAB2(SCH_1):M_K_BG(0)
 235 M_K_C<2>   C<2> @BASEBOARD_FAB2_LIB.BASEBOARD_FAB2(SCH_1):M_K_C(2)
 199 M_K_ECC<6>  CB<7> @BASEBOARD_FAB2_LIB.BASEBOARD_FAB2(SCH_1):M_K_ECC(6)
  54 M_K_ECC<7>  CB<6> @BASEBOARD_FAB2_LIB.BASEBOARD_FAB2(SCH_1):M_K_ECC(7)
 192 M_K_ECC<4>  CB<5> @BASEBOARD_FAB2_LIB.BASEBOARD_FAB2(SCH_1):M_K_ECC(4)
  47 M_K_ECC<5>  CB<4> @BASEBOARD_FAB2_LIB.BASEBOARD_FAB2(SCH_1):M_K_ECC(5)
 201 M_K_ECC<2>  CB<3> @BASEBOARD_FAB2_LIB.BASEBOARD_FAB2(SCH_1):M_K_ECC(2)
  56 M_K_ECC<3>  CB<2> @BASEBOARD_FAB2_LIB.BASEBOARD_FAB2(SCH_1):M_K_ECC(3)
 194 M_K_ECC<0>  CB<1> @BASEBOARD_FAB2_LIB.BASEBOARD_FAB2(SCH_1):M_K_ECC(0)
  49 M_K_ECC<1>  CB<0> @BASEBOARD_FAB2_LIB.BASEBOARD_FAB2(SCH_1):M_K_ECC(1)
  75 M_K_CLK_DN<0>   CK0N @BASEBOARD_FAB2_LIB.BASEBOARD_FAB2(SCH_1):M_K_CLK_DN(0)
  74 M_K_CLK_DP<0>   CK0P @BASEBOARD_FAB2_LIB.BASEBOARD_FAB2(SCH_1):M_K_CLK_DP(0)
 219 M_K_CLK_DN<1>   CK1N @BASEBOARD_FAB2_LIB.BASEBOARD_FAB2(SCH_1):M_K_CLK_DN(1)
 218 M_K_CLK_DP<1>   CK1P @BASEBOARD_FAB2_LIB.BASEBOARD_FAB2(SCH_1):M_K_CLK_DP(1)
 203 M_K_CKE<1> CKE<1> @BASEBOARD_FAB2_LIB.BASEBOARD_FAB2(SCH_1):M_K_CKE(1)
  60 M_K_CKE<0> CKE<0> @BASEBOARD_FAB2_LIB.BASEBOARD_FAB2(SCH_1):M_K_CKE(0)
 280 M_K_DQ<62> DQ<63> @BASEBOARD_FAB2_LIB.BASEBOARD_FAB2(SCH_1):M_K_DQ(62)
 135 M_K_DQ<63> DQ<62> @BASEBOARD_FAB2_LIB.BASEBOARD_FAB2(SCH_1):M_K_DQ(63)
 273 M_K_DQ<60> DQ<61> @BASEBOARD_FAB2_LIB.BASEBOARD_FAB2(SCH_1):M_K_DQ(60)
 128 M_K_DQ<61> DQ<60> @BASEBOARD_FAB2_LIB.BASEBOARD_FAB2(SCH_1):M_K_DQ(61)
 282 M_K_DQ<58> DQ<59> @BASEBOARD_FAB2_LIB.BASEBOARD_FAB2(SCH_1):M_K_DQ(58)
 137 M_K_DQ<59> DQ<58> @BASEBOARD_FAB2_LIB.BASEBOARD_FAB2(SCH_1):M_K_DQ(59)
 275 M_K_DQ<56> DQ<57> @BASEBOARD_FAB2_LIB.BASEBOARD_FAB2(SCH_1):M_K_DQ(56)
 130 M_K_DQ<57> DQ<56> @BASEBOARD_FAB2_LIB.BASEBOARD_FAB2(SCH_1):M_K_DQ(57)
 269 M_K_DQ<54> DQ<55> @BASEBOARD_FAB2_LIB.BASEBOARD_FAB2(SCH_1):M_K_DQ(54)
 124 M_K_DQ<55> DQ<54> @BASEBOARD_FAB2_LIB.BASEBOARD_FAB2(SCH_1):M_K_DQ(55)
 262 M_K_DQ<52> DQ<53> @BASEBOARD_FAB2_LIB.BASEBOARD_FAB2(SCH_1):M_K_DQ(52)
 117 M_K_DQ<53> DQ<52> @BASEBOARD_FAB2_LIB.BASEBOARD_FAB2(SCH_1):M_K_DQ(53)
 271 M_K_DQ<50> DQ<51> @BASEBOARD_FAB2_LIB.BASEBOARD_FAB2(SCH_1):M_K_DQ(50)
 126 M_K_DQ<51> DQ<50> @BASEBOARD_FAB2_LIB.BASEBOARD_FAB2(SCH_1):M_K_DQ(51)
 264 M_K_DQ<48> DQ<49> @BASEBOARD_FAB2_LIB.BASEBOARD_FAB2(SCH_1):M_K_DQ(48)
 119 M_K_DQ<49> DQ<48> @BASEBOARD_FAB2_LIB.BASEBOARD_FAB2(SCH_1):M_K_DQ(49)
 258 M_K_DQ<46> DQ<47> @BASEBOARD_FAB2_LIB.BASEBOARD_FAB2(SCH_1):M_K_DQ(46)
 113 M_K_DQ<47> DQ<46> @BASEBOARD_FAB2_LIB.BASEBOARD_FAB2(SCH_1):M_K_DQ(47)
 251 M_K_DQ<44> DQ<45> @BASEBOARD_FAB2_LIB.BASEBOARD_FAB2(SCH_1):M_K_DQ(44)
 106 M_K_DQ<45> DQ<44> @BASEBOARD_FAB2_LIB.BASEBOARD_FAB2(SCH_1):M_K_DQ(45)
 260 M_K_DQ<42> DQ<43> @BASEBOARD_FAB2_LIB.BASEBOARD_FAB2(SCH_1):M_K_DQ(42)
 115 M_K_DQ<43> DQ<42> @BASEBOARD_FAB2_LIB.BASEBOARD_FAB2(SCH_1):M_K_DQ(43)
 253 M_K_DQ<40> DQ<41> @BASEBOARD_FAB2_LIB.BASEBOARD_FAB2(SCH_1):M_K_DQ(40)
 108 M_K_DQ<41> DQ<40> @BASEBOARD_FAB2_LIB.BASEBOARD_FAB2(SCH_1):M_K_DQ(41)
 247 M_K_DQ<38> DQ<39> @BASEBOARD_FAB2_LIB.BASEBOARD_FAB2(SCH_1):M_K_DQ(38)
 102 M_K_DQ<39> DQ<38> @BASEBOARD_FAB2_LIB.BASEBOARD_FAB2(SCH_1):M_K_DQ(39)
 240 M_K_DQ<36> DQ<37> @BASEBOARD_FAB2_LIB.BASEBOARD_FAB2(SCH_1):M_K_DQ(36)
  95 M_K_DQ<37> DQ<36> @BASEBOARD_FAB2_LIB.BASEBOARD_FAB2(SCH_1):M_K_DQ(37)
 249 M_K_DQ<34> DQ<35> @BASEBOARD_FAB2_LIB.BASEBOARD_FAB2(SCH_1):M_K_DQ(34)
 104 M_K_DQ<35> DQ<34> @BASEBOARD_FAB2_LIB.BASEBOARD_FAB2(SCH_1):M_K_DQ(35)
 242 M_K_DQ<32> DQ<33> @BASEBOARD_FAB2_LIB.BASEBOARD_FAB2(SCH_1):M_K_DQ(32)
  97 M_K_DQ<33> DQ<32> @BASEBOARD_FAB2_LIB.BASEBOARD_FAB2(SCH_1):M_K_DQ(33)
 188 M_K_DQ<30> DQ<31> @BASEBOARD_FAB2_LIB.BASEBOARD_FAB2(SCH_1):M_K_DQ(30)
  43 M_K_DQ<31> DQ<30> @BASEBOARD_FAB2_LIB.BASEBOARD_FAB2(SCH_1):M_K_DQ(31)
 181 M_K_DQ<28> DQ<29> @BASEBOARD_FAB2_LIB.BASEBOARD_FAB2(SCH_1):M_K_DQ(28)
  36 M_K_DQ<29> DQ<28> @BASEBOARD_FAB2_LIB.BASEBOARD_FAB2(SCH_1):M_K_DQ(29)
 190 M_K_DQ<26> DQ<27> @BASEBOARD_FAB2_LIB.BASEBOARD_FAB2(SCH_1):M_K_DQ(26)
  45 M_K_DQ<27> DQ<26> @BASEBOARD_FAB2_LIB.BASEBOARD_FAB2(SCH_1):M_K_DQ(27)
 183 M_K_DQ<24> DQ<25> @BASEBOARD_FAB2_LIB.BASEBOARD_FAB2(SCH_1):M_K_DQ(24)
  38 M_K_DQ<25> DQ<24> @BASEBOARD_FAB2_LIB.BASEBOARD_FAB2(SCH_1):M_K_DQ(25)
 177 M_K_DQ<22> DQ<23> @BASEBOARD_FAB2_LIB.BASEBOARD_FAB2(SCH_1):M_K_DQ(22)
  32 M_K_DQ<23> DQ<22> @BASEBOARD_FAB2_LIB.BASEBOARD_FAB2(SCH_1):M_K_DQ(23)
 170 M_K_DQ<20> DQ<21> @BASEBOARD_FAB2_LIB.BASEBOARD_FAB2(SCH_1):M_K_DQ(20)
  25 M_K_DQ<21> DQ<20> @BASEBOARD_FAB2_LIB.BASEBOARD_FAB2(SCH_1):M_K_DQ(21)
 179 M_K_DQ<18> DQ<19> @BASEBOARD_FAB2_LIB.BASEBOARD_FAB2(SCH_1):M_K_DQ(18)
  34 M_K_DQ<19> DQ<18> @BASEBOARD_FAB2_LIB.BASEBOARD_FAB2(SCH_1):M_K_DQ(19)
 172 M_K_DQ<16> DQ<17> @BASEBOARD_FAB2_LIB.BASEBOARD_FAB2(SCH_1):M_K_DQ(16)
  27 M_K_DQ<17> DQ<16> @BASEBOARD_FAB2_LIB.BASEBOARD_FAB2(SCH_1):M_K_DQ(17)
 166 M_K_DQ<14> DQ<15> @BASEBOARD_FAB2_LIB.BASEBOARD_FAB2(SCH_1):M_K_DQ(14)
  21 M_K_DQ<15> DQ<14> @BASEBOARD_FAB2_LIB.BASEBOARD_FAB2(SCH_1):M_K_DQ(15)
 159 M_K_DQ<12> DQ<13> @BASEBOARD_FAB2_LIB.BASEBOARD_FAB2(SCH_1):M_K_DQ(12)
  14 M_K_DQ<13> DQ<12> @BASEBOARD_FAB2_LIB.BASEBOARD_FAB2(SCH_1):M_K_DQ(13)
 168 M_K_DQ<10> DQ<11> @BASEBOARD_FAB2_LIB.BASEBOARD_FAB2(SCH_1):M_K_DQ(10)
  23 M_K_DQ<11> DQ<10> @BASEBOARD_FAB2_LIB.BASEBOARD_FAB2(SCH_1):M_K_DQ(11)
 161 M_K_DQ<8>  DQ<9> @BASEBOARD_FAB2_LIB.BASEBOARD_FAB2(SCH_1):M_K_DQ(8)
  16 M_K_DQ<9>  DQ<8> @BASEBOARD_FAB2_LIB.BASEBOARD_FAB2(SCH_1):M_K_DQ(9)
 155 M_K_DQ<6>  DQ<7> @BASEBOARD_FAB2_LIB.BASEBOARD_FAB2(SCH_1):M_K_DQ(6)
  10 M_K_DQ<7>  DQ<6> @BASEBOARD_FAB2_LIB.BASEBOARD_FAB2(SCH_1):M_K_DQ(7)
 148 M_K_DQ<4>  DQ<5> @BASEBOARD_FAB2_LIB.BASEBOARD_FAB2(SCH_1):M_K_DQ(4)
   3 M_K_DQ<5>  DQ<4> @BASEBOARD_FAB2_LIB.BASEBOARD_FAB2(SCH_1):M_K_DQ(5)
 157 M_K_DQ<2>  DQ<3> @BASEBOARD_FAB2_LIB.BASEBOARD_FAB2(SCH_1):M_K_DQ(2)
  12 M_K_DQ<3>  DQ<2> @BASEBOARD_FAB2_LIB.BASEBOARD_FAB2(SCH_1):M_K_DQ(3)
 150 M_K_DQ<0>  DQ<1> @BASEBOARD_FAB2_LIB.BASEBOARD_FAB2(SCH_1):M_K_DQ(0)
   5 M_K_DQ<1>  DQ<0> @BASEBOARD_FAB2_LIB.BASEBOARD_FAB2(SCH_1):M_K_DQ(1)
  78 FM_DIMM_EVENT_COD_N EVENT_N @BASEBOARD_FAB2_LIB.BASEBOARD_FAB2(SCH_1):FM_DIMM_EVENT_COD_N
  91 M_K_ODT<1> ODT<1> @BASEBOARD_FAB2_LIB.BASEBOARD_FAB2(SCH_1):M_K_ODT(1)
  87 M_K_ODT<0> ODT<0> @BASEBOARD_FAB2_LIB.BASEBOARD_FAB2(SCH_1):M_K_ODT(0)
 222 M_K_PAR    PAR @BASEBOARD_FAB2_LIB.BASEBOARD_FAB2(SCH_1):M_K_PAR
  58 M_KLM_RST_N RESET_N @BASEBOARD_FAB2_LIB.BASEBOARD_FAB2(SCH_1):M_KLM_RST_N
 144 TP_CH_K_DIMM_K0_RFU_2 RFU<2> @BASEBOARD_FAB2_LIB.BASEBOARD_FAB2(SCH_1):TP_CH_K_DIMM_K0_RFU_2
 227 TP_CH_K_DIMM_K0_RFU_1 RFU<1> @BASEBOARD_FAB2_LIB.BASEBOARD_FAB2(SCH_1):TP_CH_K_DIMM_K0_RFU_1
 205 TP_CH_K_DIMM_K0_RFU_0 RFU<0> @BASEBOARD_FAB2_LIB.BASEBOARD_FAB2(SCH_1):TP_CH_K_DIMM_K0_RFU_0
  84 M_K_CS_N<0>   S0_N @BASEBOARD_FAB2_LIB.BASEBOARD_FAB2(SCH_1):M_K_CS_N(0)
  89 M_K_CS_N<1>   S1_N @BASEBOARD_FAB2_LIB.BASEBOARD_FAB2(SCH_1):M_K_CS_N(1)
  93 M_K_CS_N<2> S2_N_C<0> @BASEBOARD_FAB2_LIB.BASEBOARD_FAB2(SCH_1):M_K_CS_N(2)
 237 M_K_CS_N<3> S3_N_C<1> @BASEBOARD_FAB2_LIB.BASEBOARD_FAB2(SCH_1):M_K_CS_N(3)
 238    GND  SA<2> @BASEBOARD_FAB2_LIB.BASEBOARD_FAB2(SCH_1):GND
 140    GND  SA<1> @BASEBOARD_FAB2_LIB.BASEBOARD_FAB2(SCH_1):GND
 139    GND  SA<0> @BASEBOARD_FAB2_LIB.BASEBOARD_FAB2(SCH_1):GND
 230 FM_ADR_COMPLETE_KLM_N SAVE_N_NC @BASEBOARD_FAB2_LIB.BASEBOARD_FAB2(SCH_1):FM_ADR_COMPLETE_KLM_N
 141 SMB_DDR_KLM_VPP_SCL    SCL @BASEBOARD_FAB2_LIB.BASEBOARD_FAB2(SCH_1):SMB_DDR_KLM_VPP_SCL
 285 SMB_DDR_KLM_VPP_SDA    SDA @BASEBOARD_FAB2_LIB.BASEBOARD_FAB2(SCH_1):SMB_DDR_KLM_VPP_SDA
 284 PVPP_KLM VDDSPD @BASEBOARD_FAB2_LIB.BASEBOARD_FAB2(SCH_1):PVPP_KLM
 146 M_K_VREF VREFCA @BASEBOARD_FAB2_LIB.BASEBOARD_FAB2(SCH_1):M_K_VREF

SCONN288_H44441004_PIP-SCONN,HA  I167  J1B1
   1 P12V_NVDIMM_KLM 12V<1> @BASEBOARD_FAB2_LIB.BASEBOARD_FAB2(SCH_1):P12V_NVDIMM_KLM
 145 P12V_NVDIMM_KLM 12V<0> @BASEBOARD_FAB2_LIB.BASEBOARD_FAB2(SCH_1):P12V_NVDIMM_KLM
  59 PVDDQ_KLM VDD<25> @BASEBOARD_FAB2_LIB.BASEBOARD_FAB2(SCH_1):PVDDQ_KLM
  61 PVDDQ_KLM VDD<24> @BASEBOARD_FAB2_LIB.BASEBOARD_FAB2(SCH_1):PVDDQ_KLM
  64 PVDDQ_KLM VDD<23> @BASEBOARD_FAB2_LIB.BASEBOARD_FAB2(SCH_1):PVDDQ_KLM
  67 PVDDQ_KLM VDD<22> @BASEBOARD_FAB2_LIB.BASEBOARD_FAB2(SCH_1):PVDDQ_KLM
  70 PVDDQ_KLM VDD<21> @BASEBOARD_FAB2_LIB.BASEBOARD_FAB2(SCH_1):PVDDQ_KLM
  73 PVDDQ_KLM VDD<20> @BASEBOARD_FAB2_LIB.BASEBOARD_FAB2(SCH_1):PVDDQ_KLM
  76 PVDDQ_KLM VDD<19> @BASEBOARD_FAB2_LIB.BASEBOARD_FAB2(SCH_1):PVDDQ_KLM
  80 PVDDQ_KLM VDD<18> @BASEBOARD_FAB2_LIB.BASEBOARD_FAB2(SCH_1):PVDDQ_KLM
  83 PVDDQ_KLM VDD<17> @BASEBOARD_FAB2_LIB.BASEBOARD_FAB2(SCH_1):PVDDQ_KLM
  85 PVDDQ_KLM VDD<16> @BASEBOARD_FAB2_LIB.BASEBOARD_FAB2(SCH_1):PVDDQ_KLM
  88 PVDDQ_KLM VDD<15> @BASEBOARD_FAB2_LIB.BASEBOARD_FAB2(SCH_1):PVDDQ_KLM
  90 PVDDQ_KLM VDD<14> @BASEBOARD_FAB2_LIB.BASEBOARD_FAB2(SCH_1):PVDDQ_KLM
  92 PVDDQ_KLM VDD<13> @BASEBOARD_FAB2_LIB.BASEBOARD_FAB2(SCH_1):PVDDQ_KLM
 204 PVDDQ_KLM VDD<12> @BASEBOARD_FAB2_LIB.BASEBOARD_FAB2(SCH_1):PVDDQ_KLM
 206 PVDDQ_KLM VDD<11> @BASEBOARD_FAB2_LIB.BASEBOARD_FAB2(SCH_1):PVDDQ_KLM
 209 PVDDQ_KLM VDD<10> @BASEBOARD_FAB2_LIB.BASEBOARD_FAB2(SCH_1):PVDDQ_KLM
 212 PVDDQ_KLM VDD<9> @BASEBOARD_FAB2_LIB.BASEBOARD_FAB2(SCH_1):PVDDQ_KLM
 215 PVDDQ_KLM VDD<8> @BASEBOARD_FAB2_LIB.BASEBOARD_FAB2(SCH_1):PVDDQ_KLM
 217 PVDDQ_KLM VDD<7> @BASEBOARD_FAB2_LIB.BASEBOARD_FAB2(SCH_1):PVDDQ_KLM
 220 PVDDQ_KLM VDD<6> @BASEBOARD_FAB2_LIB.BASEBOARD_FAB2(SCH_1):PVDDQ_KLM
 223 PVDDQ_KLM VDD<5> @BASEBOARD_FAB2_LIB.BASEBOARD_FAB2(SCH_1):PVDDQ_KLM
 226 PVDDQ_KLM VDD<4> @BASEBOARD_FAB2_LIB.BASEBOARD_FAB2(SCH_1):PVDDQ_KLM
 229 PVDDQ_KLM VDD<3> @BASEBOARD_FAB2_LIB.BASEBOARD_FAB2(SCH_1):PVDDQ_KLM
 231 PVDDQ_KLM VDD<2> @BASEBOARD_FAB2_LIB.BASEBOARD_FAB2(SCH_1):PVDDQ_KLM
 233 PVDDQ_KLM VDD<1> @BASEBOARD_FAB2_LIB.BASEBOARD_FAB2(SCH_1):PVDDQ_KLM
 236 PVDDQ_KLM VDD<0> @BASEBOARD_FAB2_LIB.BASEBOARD_FAB2(SCH_1):PVDDQ_KLM
 142 PVPP_KLM VPP<4> @BASEBOARD_FAB2_LIB.BASEBOARD_FAB2(SCH_1):PVPP_KLM
 143 PVPP_KLM VPP<3> @BASEBOARD_FAB2_LIB.BASEBOARD_FAB2(SCH_1):PVPP_KLM
 288 PVPP_KLM VPP<2> @BASEBOARD_FAB2_LIB.BASEBOARD_FAB2(SCH_1):PVPP_KLM
 286 PVPP_KLM VPP<1> @BASEBOARD_FAB2_LIB.BASEBOARD_FAB2(SCH_1):PVPP_KLM
 287 PVPP_KLM VPP<0> @BASEBOARD_FAB2_LIB.BASEBOARD_FAB2(SCH_1):PVPP_KLM
  77 PVTT_KLM VTT<1> @BASEBOARD_FAB2_LIB.BASEBOARD_FAB2(SCH_1):PVTT_KLM
 221 PVTT_KLM VTT<0> @BASEBOARD_FAB2_LIB.BASEBOARD_FAB2(SCH_1):PVTT_KLM

CAP_A_0402V-0.01UF,25V,10%,X7RA  I176  C1B9
   1 M_K_VREF      A @BASEBOARD_FAB2_LIB.BASEBOARD_FAB2(SCH_1):M_K_VREF
   2    GND      B @BASEBOARD_FAB2_LIB.BASEBOARD_FAB2(SCH_1):GND


DRAWING: @BASEBOARD_FAB2_LIB.BASEBOARD_FAB2(SCH_1):PAGE84 

CAP_A_0402V-0.01UF,25V,10%,X7RA  I4  C9M1
   1 M_K_VREF      A @BASEBOARD_FAB2_LIB.BASEBOARD_FAB2(SCH_1):M_K_VREF
   2    GND      B @BASEBOARD_FAB2_LIB.BASEBOARD_FAB2(SCH_1):GND

SCONN288_H44441003_PIP-SCONN,HA  I14  J9M1
  79 M_K_MA<0>     A0 @BASEBOARD_FAB2_LIB.BASEBOARD_FAB2(SCH_1):M_K_MA(0)
  72 M_K_MA<1>     A1 @BASEBOARD_FAB2_LIB.BASEBOARD_FAB2(SCH_1):M_K_MA(1)
 225 M_K_MA<10>    A10 @BASEBOARD_FAB2_LIB.BASEBOARD_FAB2(SCH_1):M_K_MA(10)
 210 M_K_MA<11>    A11 @BASEBOARD_FAB2_LIB.BASEBOARD_FAB2(SCH_1):M_K_MA(11)
  65 M_K_MA<12>    A12 @BASEBOARD_FAB2_LIB.BASEBOARD_FAB2(SCH_1):M_K_MA(12)
 232 M_K_MA<13>    A13 @BASEBOARD_FAB2_LIB.BASEBOARD_FAB2(SCH_1):M_K_MA(13)
 228 M_K_MA<14> A14_WE_N @BASEBOARD_FAB2_LIB.BASEBOARD_FAB2(SCH_1):M_K_MA(14)
  86 M_K_MA<15> A15_CAS_N @BASEBOARD_FAB2_LIB.BASEBOARD_FAB2(SCH_1):M_K_MA(15)
  82 M_K_MA<16> A16_RAS_N @BASEBOARD_FAB2_LIB.BASEBOARD_FAB2(SCH_1):M_K_MA(16)
 234 M_K_MA<17>    A17 @BASEBOARD_FAB2_LIB.BASEBOARD_FAB2(SCH_1):M_K_MA(17)
 216 M_K_MA<2>     A2 @BASEBOARD_FAB2_LIB.BASEBOARD_FAB2(SCH_1):M_K_MA(2)
  71 M_K_MA<3>     A3 @BASEBOARD_FAB2_LIB.BASEBOARD_FAB2(SCH_1):M_K_MA(3)
 214 M_K_MA<4>     A4 @BASEBOARD_FAB2_LIB.BASEBOARD_FAB2(SCH_1):M_K_MA(4)
 213 M_K_MA<5>     A5 @BASEBOARD_FAB2_LIB.BASEBOARD_FAB2(SCH_1):M_K_MA(5)
  69 M_K_MA<6>     A6 @BASEBOARD_FAB2_LIB.BASEBOARD_FAB2(SCH_1):M_K_MA(6)
 211 M_K_MA<7>     A7 @BASEBOARD_FAB2_LIB.BASEBOARD_FAB2(SCH_1):M_K_MA(7)
  68 M_K_MA<8>     A8 @BASEBOARD_FAB2_LIB.BASEBOARD_FAB2(SCH_1):M_K_MA(8)
  66 M_K_MA<9>     A9 @BASEBOARD_FAB2_LIB.BASEBOARD_FAB2(SCH_1):M_K_MA(9)
  62 M_K_ACT_N  ACT_N @BASEBOARD_FAB2_LIB.BASEBOARD_FAB2(SCH_1):M_K_ACT_N
 208 M_K_ALERT_N ALERT_N @BASEBOARD_FAB2_LIB.BASEBOARD_FAB2(SCH_1):M_K_ALERT_N
 224 M_K_BA<1>  BA<1> @BASEBOARD_FAB2_LIB.BASEBOARD_FAB2(SCH_1):M_K_BA(1)
  81 M_K_BA<0>  BA<0> @BASEBOARD_FAB2_LIB.BASEBOARD_FAB2(SCH_1):M_K_BA(0)
 207 M_K_BG<1>  BG<1> @BASEBOARD_FAB2_LIB.BASEBOARD_FAB2(SCH_1):M_K_BG(1)
  63 M_K_BG<0>  BG<0> @BASEBOARD_FAB2_LIB.BASEBOARD_FAB2(SCH_1):M_K_BG(0)
 235 M_K_C<2>   C<2> @BASEBOARD_FAB2_LIB.BASEBOARD_FAB2(SCH_1):M_K_C(2)
 199 M_K_ECC<7>  CB<7> @BASEBOARD_FAB2_LIB.BASEBOARD_FAB2(SCH_1):M_K_ECC(7)
  54 M_K_ECC<6>  CB<6> @BASEBOARD_FAB2_LIB.BASEBOARD_FAB2(SCH_1):M_K_ECC(6)
 192 M_K_ECC<5>  CB<5> @BASEBOARD_FAB2_LIB.BASEBOARD_FAB2(SCH_1):M_K_ECC(5)
  47 M_K_ECC<4>  CB<4> @BASEBOARD_FAB2_LIB.BASEBOARD_FAB2(SCH_1):M_K_ECC(4)
 201 M_K_ECC<3>  CB<3> @BASEBOARD_FAB2_LIB.BASEBOARD_FAB2(SCH_1):M_K_ECC(3)
  56 M_K_ECC<2>  CB<2> @BASEBOARD_FAB2_LIB.BASEBOARD_FAB2(SCH_1):M_K_ECC(2)
 194 M_K_ECC<1>  CB<1> @BASEBOARD_FAB2_LIB.BASEBOARD_FAB2(SCH_1):M_K_ECC(1)
  49 M_K_ECC<0>  CB<0> @BASEBOARD_FAB2_LIB.BASEBOARD_FAB2(SCH_1):M_K_ECC(0)
  75 M_K_CLK_DN<2>   CK0N @BASEBOARD_FAB2_LIB.BASEBOARD_FAB2(SCH_1):M_K_CLK_DN(2)
  74 M_K_CLK_DP<2>   CK0P @BASEBOARD_FAB2_LIB.BASEBOARD_FAB2(SCH_1):M_K_CLK_DP(2)
 219 M_K_CLK_DN<3>   CK1N @BASEBOARD_FAB2_LIB.BASEBOARD_FAB2(SCH_1):M_K_CLK_DN(3)
 218 M_K_CLK_DP<3>   CK1P @BASEBOARD_FAB2_LIB.BASEBOARD_FAB2(SCH_1):M_K_CLK_DP(3)
 203 M_K_CKE<3> CKE<1> @BASEBOARD_FAB2_LIB.BASEBOARD_FAB2(SCH_1):M_K_CKE(3)
  60 M_K_CKE<2> CKE<0> @BASEBOARD_FAB2_LIB.BASEBOARD_FAB2(SCH_1):M_K_CKE(2)
 280 M_K_DQ<63> DQ<63> @BASEBOARD_FAB2_LIB.BASEBOARD_FAB2(SCH_1):M_K_DQ(63)
 135 M_K_DQ<62> DQ<62> @BASEBOARD_FAB2_LIB.BASEBOARD_FAB2(SCH_1):M_K_DQ(62)
 273 M_K_DQ<61> DQ<61> @BASEBOARD_FAB2_LIB.BASEBOARD_FAB2(SCH_1):M_K_DQ(61)
 128 M_K_DQ<60> DQ<60> @BASEBOARD_FAB2_LIB.BASEBOARD_FAB2(SCH_1):M_K_DQ(60)
 282 M_K_DQ<59> DQ<59> @BASEBOARD_FAB2_LIB.BASEBOARD_FAB2(SCH_1):M_K_DQ(59)
 137 M_K_DQ<58> DQ<58> @BASEBOARD_FAB2_LIB.BASEBOARD_FAB2(SCH_1):M_K_DQ(58)
 275 M_K_DQ<57> DQ<57> @BASEBOARD_FAB2_LIB.BASEBOARD_FAB2(SCH_1):M_K_DQ(57)
 130 M_K_DQ<56> DQ<56> @BASEBOARD_FAB2_LIB.BASEBOARD_FAB2(SCH_1):M_K_DQ(56)
 269 M_K_DQ<55> DQ<55> @BASEBOARD_FAB2_LIB.BASEBOARD_FAB2(SCH_1):M_K_DQ(55)
 124 M_K_DQ<54> DQ<54> @BASEBOARD_FAB2_LIB.BASEBOARD_FAB2(SCH_1):M_K_DQ(54)
 262 M_K_DQ<53> DQ<53> @BASEBOARD_FAB2_LIB.BASEBOARD_FAB2(SCH_1):M_K_DQ(53)
 117 M_K_DQ<52> DQ<52> @BASEBOARD_FAB2_LIB.BASEBOARD_FAB2(SCH_1):M_K_DQ(52)
 271 M_K_DQ<51> DQ<51> @BASEBOARD_FAB2_LIB.BASEBOARD_FAB2(SCH_1):M_K_DQ(51)
 126 M_K_DQ<50> DQ<50> @BASEBOARD_FAB2_LIB.BASEBOARD_FAB2(SCH_1):M_K_DQ(50)
 264 M_K_DQ<49> DQ<49> @BASEBOARD_FAB2_LIB.BASEBOARD_FAB2(SCH_1):M_K_DQ(49)
 119 M_K_DQ<48> DQ<48> @BASEBOARD_FAB2_LIB.BASEBOARD_FAB2(SCH_1):M_K_DQ(48)
 258 M_K_DQ<47> DQ<47> @BASEBOARD_FAB2_LIB.BASEBOARD_FAB2(SCH_1):M_K_DQ(47)
 113 M_K_DQ<46> DQ<46> @BASEBOARD_FAB2_LIB.BASEBOARD_FAB2(SCH_1):M_K_DQ(46)
 251 M_K_DQ<45> DQ<45> @BASEBOARD_FAB2_LIB.BASEBOARD_FAB2(SCH_1):M_K_DQ(45)
 106 M_K_DQ<44> DQ<44> @BASEBOARD_FAB2_LIB.BASEBOARD_FAB2(SCH_1):M_K_DQ(44)
 260 M_K_DQ<43> DQ<43> @BASEBOARD_FAB2_LIB.BASEBOARD_FAB2(SCH_1):M_K_DQ(43)
 115 M_K_DQ<42> DQ<42> @BASEBOARD_FAB2_LIB.BASEBOARD_FAB2(SCH_1):M_K_DQ(42)
 253 M_K_DQ<41> DQ<41> @BASEBOARD_FAB2_LIB.BASEBOARD_FAB2(SCH_1):M_K_DQ(41)
 108 M_K_DQ<40> DQ<40> @BASEBOARD_FAB2_LIB.BASEBOARD_FAB2(SCH_1):M_K_DQ(40)
 247 M_K_DQ<39> DQ<39> @BASEBOARD_FAB2_LIB.BASEBOARD_FAB2(SCH_1):M_K_DQ(39)
 102 M_K_DQ<38> DQ<38> @BASEBOARD_FAB2_LIB.BASEBOARD_FAB2(SCH_1):M_K_DQ(38)
 240 M_K_DQ<37> DQ<37> @BASEBOARD_FAB2_LIB.BASEBOARD_FAB2(SCH_1):M_K_DQ(37)
  95 M_K_DQ<36> DQ<36> @BASEBOARD_FAB2_LIB.BASEBOARD_FAB2(SCH_1):M_K_DQ(36)
 249 M_K_DQ<35> DQ<35> @BASEBOARD_FAB2_LIB.BASEBOARD_FAB2(SCH_1):M_K_DQ(35)
 104 M_K_DQ<34> DQ<34> @BASEBOARD_FAB2_LIB.BASEBOARD_FAB2(SCH_1):M_K_DQ(34)
 242 M_K_DQ<33> DQ<33> @BASEBOARD_FAB2_LIB.BASEBOARD_FAB2(SCH_1):M_K_DQ(33)
  97 M_K_DQ<32> DQ<32> @BASEBOARD_FAB2_LIB.BASEBOARD_FAB2(SCH_1):M_K_DQ(32)
 188 M_K_DQ<31> DQ<31> @BASEBOARD_FAB2_LIB.BASEBOARD_FAB2(SCH_1):M_K_DQ(31)
  43 M_K_DQ<30> DQ<30> @BASEBOARD_FAB2_LIB.BASEBOARD_FAB2(SCH_1):M_K_DQ(30)
 181 M_K_DQ<29> DQ<29> @BASEBOARD_FAB2_LIB.BASEBOARD_FAB2(SCH_1):M_K_DQ(29)
  36 M_K_DQ<28> DQ<28> @BASEBOARD_FAB2_LIB.BASEBOARD_FAB2(SCH_1):M_K_DQ(28)
 190 M_K_DQ<27> DQ<27> @BASEBOARD_FAB2_LIB.BASEBOARD_FAB2(SCH_1):M_K_DQ(27)
  45 M_K_DQ<26> DQ<26> @BASEBOARD_FAB2_LIB.BASEBOARD_FAB2(SCH_1):M_K_DQ(26)
 183 M_K_DQ<25> DQ<25> @BASEBOARD_FAB2_LIB.BASEBOARD_FAB2(SCH_1):M_K_DQ(25)
  38 M_K_DQ<24> DQ<24> @BASEBOARD_FAB2_LIB.BASEBOARD_FAB2(SCH_1):M_K_DQ(24)
 177 M_K_DQ<23> DQ<23> @BASEBOARD_FAB2_LIB.BASEBOARD_FAB2(SCH_1):M_K_DQ(23)
  32 M_K_DQ<22> DQ<22> @BASEBOARD_FAB2_LIB.BASEBOARD_FAB2(SCH_1):M_K_DQ(22)
 170 M_K_DQ<21> DQ<21> @BASEBOARD_FAB2_LIB.BASEBOARD_FAB2(SCH_1):M_K_DQ(21)
  25 M_K_DQ<20> DQ<20> @BASEBOARD_FAB2_LIB.BASEBOARD_FAB2(SCH_1):M_K_DQ(20)
 179 M_K_DQ<19> DQ<19> @BASEBOARD_FAB2_LIB.BASEBOARD_FAB2(SCH_1):M_K_DQ(19)
  34 M_K_DQ<18> DQ<18> @BASEBOARD_FAB2_LIB.BASEBOARD_FAB2(SCH_1):M_K_DQ(18)
 172 M_K_DQ<17> DQ<17> @BASEBOARD_FAB2_LIB.BASEBOARD_FAB2(SCH_1):M_K_DQ(17)
  27 M_K_DQ<16> DQ<16> @BASEBOARD_FAB2_LIB.BASEBOARD_FAB2(SCH_1):M_K_DQ(16)
 166 M_K_DQ<15> DQ<15> @BASEBOARD_FAB2_LIB.BASEBOARD_FAB2(SCH_1):M_K_DQ(15)
  21 M_K_DQ<14> DQ<14> @BASEBOARD_FAB2_LIB.BASEBOARD_FAB2(SCH_1):M_K_DQ(14)
 159 M_K_DQ<13> DQ<13> @BASEBOARD_FAB2_LIB.BASEBOARD_FAB2(SCH_1):M_K_DQ(13)
  14 M_K_DQ<12> DQ<12> @BASEBOARD_FAB2_LIB.BASEBOARD_FAB2(SCH_1):M_K_DQ(12)
 168 M_K_DQ<11> DQ<11> @BASEBOARD_FAB2_LIB.BASEBOARD_FAB2(SCH_1):M_K_DQ(11)
  23 M_K_DQ<10> DQ<10> @BASEBOARD_FAB2_LIB.BASEBOARD_FAB2(SCH_1):M_K_DQ(10)
 161 M_K_DQ<9>  DQ<9> @BASEBOARD_FAB2_LIB.BASEBOARD_FAB2(SCH_1):M_K_DQ(9)
  16 M_K_DQ<8>  DQ<8> @BASEBOARD_FAB2_LIB.BASEBOARD_FAB2(SCH_1):M_K_DQ(8)
 155 M_K_DQ<7>  DQ<7> @BASEBOARD_FAB2_LIB.BASEBOARD_FAB2(SCH_1):M_K_DQ(7)
  10 M_K_DQ<6>  DQ<6> @BASEBOARD_FAB2_LIB.BASEBOARD_FAB2(SCH_1):M_K_DQ(6)
 148 M_K_DQ<5>  DQ<5> @BASEBOARD_FAB2_LIB.BASEBOARD_FAB2(SCH_1):M_K_DQ(5)
   3 M_K_DQ<4>  DQ<4> @BASEBOARD_FAB2_LIB.BASEBOARD_FAB2(SCH_1):M_K_DQ(4)
 157 M_K_DQ<3>  DQ<3> @BASEBOARD_FAB2_LIB.BASEBOARD_FAB2(SCH_1):M_K_DQ(3)
  12 M_K_DQ<2>  DQ<2> @BASEBOARD_FAB2_LIB.BASEBOARD_FAB2(SCH_1):M_K_DQ(2)
 150 M_K_DQ<1>  DQ<1> @BASEBOARD_FAB2_LIB.BASEBOARD_FAB2(SCH_1):M_K_DQ(1)
   5 M_K_DQ<0>  DQ<0> @BASEBOARD_FAB2_LIB.BASEBOARD_FAB2(SCH_1):M_K_DQ(0)
  78 FM_DIMM_EVENT_COD_N EVENT_N @BASEBOARD_FAB2_LIB.BASEBOARD_FAB2(SCH_1):FM_DIMM_EVENT_COD_N
  91 M_K_ODT<3> ODT<1> @BASEBOARD_FAB2_LIB.BASEBOARD_FAB2(SCH_1):M_K_ODT(3)
  87 M_K_ODT<2> ODT<0> @BASEBOARD_FAB2_LIB.BASEBOARD_FAB2(SCH_1):M_K_ODT(2)
 222 M_K_PAR    PAR @BASEBOARD_FAB2_LIB.BASEBOARD_FAB2(SCH_1):M_K_PAR
  58 M_KLM_RST_N RESET_N @BASEBOARD_FAB2_LIB.BASEBOARD_FAB2(SCH_1):M_KLM_RST_N
 144 TP_CH_K_DIMM0_RFU_2 RFU<2> @BASEBOARD_FAB2_LIB.BASEBOARD_FAB2(SCH_1):TP_CH_K_DIMM0_RFU_2
 227 TP_CH_K_DIMM0_RFU_1 RFU<1> @BASEBOARD_FAB2_LIB.BASEBOARD_FAB2(SCH_1):TP_CH_K_DIMM0_RFU_1
 205 TP_CH_K_DIMM0_RFU_0 RFU<0> @BASEBOARD_FAB2_LIB.BASEBOARD_FAB2(SCH_1):TP_CH_K_DIMM0_RFU_0
  84 M_K_CS_N<4>   S0_N @BASEBOARD_FAB2_LIB.BASEBOARD_FAB2(SCH_1):M_K_CS_N(4)
  89 M_K_CS_N<5>   S1_N @BASEBOARD_FAB2_LIB.BASEBOARD_FAB2(SCH_1):M_K_CS_N(5)
  93 M_K_CS_N<6> S2_N_C<0> @BASEBOARD_FAB2_LIB.BASEBOARD_FAB2(SCH_1):M_K_CS_N(6)
 237 M_K_CS_N<7> S3_N_C<1> @BASEBOARD_FAB2_LIB.BASEBOARD_FAB2(SCH_1):M_K_CS_N(7)
 238    GND  SA<2> @BASEBOARD_FAB2_LIB.BASEBOARD_FAB2(SCH_1):GND
 140    GND  SA<1> @BASEBOARD_FAB2_LIB.BASEBOARD_FAB2(SCH_1):GND
 139 PVPP_KLM  SA<0> @BASEBOARD_FAB2_LIB.BASEBOARD_FAB2(SCH_1):PVPP_KLM
 230 FM_ADR_COMPLETE_KLM_N SAVE_N_NC @BASEBOARD_FAB2_LIB.BASEBOARD_FAB2(SCH_1):FM_ADR_COMPLETE_KLM_N
 141 SMB_DDR_KLM_VPP_SCL    SCL @BASEBOARD_FAB2_LIB.BASEBOARD_FAB2(SCH_1):SMB_DDR_KLM_VPP_SCL
 285 SMB_DDR_KLM_VPP_SDA    SDA @BASEBOARD_FAB2_LIB.BASEBOARD_FAB2(SCH_1):SMB_DDR_KLM_VPP_SDA
 284 PVPP_KLM VDDSPD @BASEBOARD_FAB2_LIB.BASEBOARD_FAB2(SCH_1):PVPP_KLM
 146 M_K_VREF VREFCA @BASEBOARD_FAB2_LIB.BASEBOARD_FAB2(SCH_1):M_K_VREF

SCONN288_H44441003_PIP-SCONN,HA  I57  J9M1
   1 P12V_NVDIMM_KLM 12V<1> @BASEBOARD_FAB2_LIB.BASEBOARD_FAB2(SCH_1):P12V_NVDIMM_KLM
 145 P12V_NVDIMM_KLM 12V<0> @BASEBOARD_FAB2_LIB.BASEBOARD_FAB2(SCH_1):P12V_NVDIMM_KLM
  59 PVDDQ_KLM VDD<25> @BASEBOARD_FAB2_LIB.BASEBOARD_FAB2(SCH_1):PVDDQ_KLM
  61 PVDDQ_KLM VDD<24> @BASEBOARD_FAB2_LIB.BASEBOARD_FAB2(SCH_1):PVDDQ_KLM
  64 PVDDQ_KLM VDD<23> @BASEBOARD_FAB2_LIB.BASEBOARD_FAB2(SCH_1):PVDDQ_KLM
  67 PVDDQ_KLM VDD<22> @BASEBOARD_FAB2_LIB.BASEBOARD_FAB2(SCH_1):PVDDQ_KLM
  70 PVDDQ_KLM VDD<21> @BASEBOARD_FAB2_LIB.BASEBOARD_FAB2(SCH_1):PVDDQ_KLM
  73 PVDDQ_KLM VDD<20> @BASEBOARD_FAB2_LIB.BASEBOARD_FAB2(SCH_1):PVDDQ_KLM
  76 PVDDQ_KLM VDD<19> @BASEBOARD_FAB2_LIB.BASEBOARD_FAB2(SCH_1):PVDDQ_KLM
  80 PVDDQ_KLM VDD<18> @BASEBOARD_FAB2_LIB.BASEBOARD_FAB2(SCH_1):PVDDQ_KLM
  83 PVDDQ_KLM VDD<17> @BASEBOARD_FAB2_LIB.BASEBOARD_FAB2(SCH_1):PVDDQ_KLM
  85 PVDDQ_KLM VDD<16> @BASEBOARD_FAB2_LIB.BASEBOARD_FAB2(SCH_1):PVDDQ_KLM
  88 PVDDQ_KLM VDD<15> @BASEBOARD_FAB2_LIB.BASEBOARD_FAB2(SCH_1):PVDDQ_KLM
  90 PVDDQ_KLM VDD<14> @BASEBOARD_FAB2_LIB.BASEBOARD_FAB2(SCH_1):PVDDQ_KLM
  92 PVDDQ_KLM VDD<13> @BASEBOARD_FAB2_LIB.BASEBOARD_FAB2(SCH_1):PVDDQ_KLM
 204 PVDDQ_KLM VDD<12> @BASEBOARD_FAB2_LIB.BASEBOARD_FAB2(SCH_1):PVDDQ_KLM
 206 PVDDQ_KLM VDD<11> @BASEBOARD_FAB2_LIB.BASEBOARD_FAB2(SCH_1):PVDDQ_KLM
 209 PVDDQ_KLM VDD<10> @BASEBOARD_FAB2_LIB.BASEBOARD_FAB2(SCH_1):PVDDQ_KLM
 212 PVDDQ_KLM VDD<9> @BASEBOARD_FAB2_LIB.BASEBOARD_FAB2(SCH_1):PVDDQ_KLM
 215 PVDDQ_KLM VDD<8> @BASEBOARD_FAB2_LIB.BASEBOARD_FAB2(SCH_1):PVDDQ_KLM
 217 PVDDQ_KLM VDD<7> @BASEBOARD_FAB2_LIB.BASEBOARD_FAB2(SCH_1):PVDDQ_KLM
 220 PVDDQ_KLM VDD<6> @BASEBOARD_FAB2_LIB.BASEBOARD_FAB2(SCH_1):PVDDQ_KLM
 223 PVDDQ_KLM VDD<5> @BASEBOARD_FAB2_LIB.BASEBOARD_FAB2(SCH_1):PVDDQ_KLM
 226 PVDDQ_KLM VDD<4> @BASEBOARD_FAB2_LIB.BASEBOARD_FAB2(SCH_1):PVDDQ_KLM
 229 PVDDQ_KLM VDD<3> @BASEBOARD_FAB2_LIB.BASEBOARD_FAB2(SCH_1):PVDDQ_KLM
 231 PVDDQ_KLM VDD<2> @BASEBOARD_FAB2_LIB.BASEBOARD_FAB2(SCH_1):PVDDQ_KLM
 233 PVDDQ_KLM VDD<1> @BASEBOARD_FAB2_LIB.BASEBOARD_FAB2(SCH_1):PVDDQ_KLM
 236 PVDDQ_KLM VDD<0> @BASEBOARD_FAB2_LIB.BASEBOARD_FAB2(SCH_1):PVDDQ_KLM
 142 PVPP_KLM VPP<4> @BASEBOARD_FAB2_LIB.BASEBOARD_FAB2(SCH_1):PVPP_KLM
 143 PVPP_KLM VPP<3> @BASEBOARD_FAB2_LIB.BASEBOARD_FAB2(SCH_1):PVPP_KLM
 288 PVPP_KLM VPP<2> @BASEBOARD_FAB2_LIB.BASEBOARD_FAB2(SCH_1):PVPP_KLM
 286 PVPP_KLM VPP<1> @BASEBOARD_FAB2_LIB.BASEBOARD_FAB2(SCH_1):PVPP_KLM
 287 PVPP_KLM VPP<0> @BASEBOARD_FAB2_LIB.BASEBOARD_FAB2(SCH_1):PVPP_KLM
  77 PVTT_KLM VTT<1> @BASEBOARD_FAB2_LIB.BASEBOARD_FAB2(SCH_1):PVTT_KLM
 221 PVTT_KLM VTT<0> @BASEBOARD_FAB2_LIB.BASEBOARD_FAB2(SCH_1):PVTT_KLM

SCONN288_H44441003_PIP-SCONN,HA  I102  J9M1
 152 M_K_DQS_DN<0>  DQS0N @BASEBOARD_FAB2_LIB.BASEBOARD_FAB2(SCH_1):M_K_DQS_DN(0)
 153 M_K_DQS_DP<0>  DQS0P @BASEBOARD_FAB2_LIB.BASEBOARD_FAB2(SCH_1):M_K_DQS_DP(0)
  19 M_K_DQS_DN<10> DQS10N @BASEBOARD_FAB2_LIB.BASEBOARD_FAB2(SCH_1):M_K_DQS_DN(10)
  18 M_K_DQS_DP<10> DQS10P @BASEBOARD_FAB2_LIB.BASEBOARD_FAB2(SCH_1):M_K_DQS_DP(10)
  30 M_K_DQS_DN<11> DQS11N @BASEBOARD_FAB2_LIB.BASEBOARD_FAB2(SCH_1):M_K_DQS_DN(11)
  29 M_K_DQS_DP<11> DQS11P @BASEBOARD_FAB2_LIB.BASEBOARD_FAB2(SCH_1):M_K_DQS_DP(11)
  41 M_K_DQS_DN<12> DQS12N @BASEBOARD_FAB2_LIB.BASEBOARD_FAB2(SCH_1):M_K_DQS_DN(12)
  40 M_K_DQS_DP<12> DQS12P @BASEBOARD_FAB2_LIB.BASEBOARD_FAB2(SCH_1):M_K_DQS_DP(12)
 100 M_K_DQS_DN<13> DQS13N @BASEBOARD_FAB2_LIB.BASEBOARD_FAB2(SCH_1):M_K_DQS_DN(13)
  99 M_K_DQS_DP<13> DQS13P @BASEBOARD_FAB2_LIB.BASEBOARD_FAB2(SCH_1):M_K_DQS_DP(13)
 111 M_K_DQS_DN<14> DQS14N @BASEBOARD_FAB2_LIB.BASEBOARD_FAB2(SCH_1):M_K_DQS_DN(14)
 110 M_K_DQS_DP<14> DQS14P @BASEBOARD_FAB2_LIB.BASEBOARD_FAB2(SCH_1):M_K_DQS_DP(14)
 122 M_K_DQS_DN<15> DQS15N @BASEBOARD_FAB2_LIB.BASEBOARD_FAB2(SCH_1):M_K_DQS_DN(15)
 121 M_K_DQS_DP<15> DQS15P @BASEBOARD_FAB2_LIB.BASEBOARD_FAB2(SCH_1):M_K_DQS_DP(15)
 133 M_K_DQS_DN<16> DQS16N @BASEBOARD_FAB2_LIB.BASEBOARD_FAB2(SCH_1):M_K_DQS_DN(16)
 132 M_K_DQS_DP<16> DQS16P @BASEBOARD_FAB2_LIB.BASEBOARD_FAB2(SCH_1):M_K_DQS_DP(16)
  52 M_K_DQS_DN<17> DQS17N @BASEBOARD_FAB2_LIB.BASEBOARD_FAB2(SCH_1):M_K_DQS_DN(17)
  51 M_K_DQS_DP<17> DQS17P @BASEBOARD_FAB2_LIB.BASEBOARD_FAB2(SCH_1):M_K_DQS_DP(17)
 163 M_K_DQS_DN<1>  DQS1N @BASEBOARD_FAB2_LIB.BASEBOARD_FAB2(SCH_1):M_K_DQS_DN(1)
 164 M_K_DQS_DP<1>  DQS1P @BASEBOARD_FAB2_LIB.BASEBOARD_FAB2(SCH_1):M_K_DQS_DP(1)
 174 M_K_DQS_DN<2>  DQS2N @BASEBOARD_FAB2_LIB.BASEBOARD_FAB2(SCH_1):M_K_DQS_DN(2)
 175 M_K_DQS_DP<2>  DQS2P @BASEBOARD_FAB2_LIB.BASEBOARD_FAB2(SCH_1):M_K_DQS_DP(2)
 185 M_K_DQS_DN<3>  DQS3N @BASEBOARD_FAB2_LIB.BASEBOARD_FAB2(SCH_1):M_K_DQS_DN(3)
 186 M_K_DQS_DP<3>  DQS3P @BASEBOARD_FAB2_LIB.BASEBOARD_FAB2(SCH_1):M_K_DQS_DP(3)
 244 M_K_DQS_DN<4>  DQS4N @BASEBOARD_FAB2_LIB.BASEBOARD_FAB2(SCH_1):M_K_DQS_DN(4)
 245 M_K_DQS_DP<4>  DQS4P @BASEBOARD_FAB2_LIB.BASEBOARD_FAB2(SCH_1):M_K_DQS_DP(4)
 255 M_K_DQS_DN<5>  DQS5N @BASEBOARD_FAB2_LIB.BASEBOARD_FAB2(SCH_1):M_K_DQS_DN(5)
 256 M_K_DQS_DP<5>  DQS5P @BASEBOARD_FAB2_LIB.BASEBOARD_FAB2(SCH_1):M_K_DQS_DP(5)
 266 M_K_DQS_DN<6>  DQS6N @BASEBOARD_FAB2_LIB.BASEBOARD_FAB2(SCH_1):M_K_DQS_DN(6)
 267 M_K_DQS_DP<6>  DQS6P @BASEBOARD_FAB2_LIB.BASEBOARD_FAB2(SCH_1):M_K_DQS_DP(6)
 277 M_K_DQS_DN<7>  DQS7N @BASEBOARD_FAB2_LIB.BASEBOARD_FAB2(SCH_1):M_K_DQS_DN(7)
 278 M_K_DQS_DP<7>  DQS7P @BASEBOARD_FAB2_LIB.BASEBOARD_FAB2(SCH_1):M_K_DQS_DP(7)
 196 M_K_DQS_DN<8>  DQS8N @BASEBOARD_FAB2_LIB.BASEBOARD_FAB2(SCH_1):M_K_DQS_DN(8)
 197 M_K_DQS_DP<8>  DQS8P @BASEBOARD_FAB2_LIB.BASEBOARD_FAB2(SCH_1):M_K_DQS_DP(8)
   8 M_K_DQS_DN<9>  DQS9N @BASEBOARD_FAB2_LIB.BASEBOARD_FAB2(SCH_1):M_K_DQS_DN(9)
   7 M_K_DQS_DP<9>  DQS9P @BASEBOARD_FAB2_LIB.BASEBOARD_FAB2(SCH_1):M_K_DQS_DP(9)

SCONN288_H44441003_PIP-SCONN,HA  I138  J9M1
   2    GND VSS<93> @BASEBOARD_FAB2_LIB.BASEBOARD_FAB2(SCH_1):GND
   4    GND VSS<92> @BASEBOARD_FAB2_LIB.BASEBOARD_FAB2(SCH_1):GND
   6    GND VSS<91> @BASEBOARD_FAB2_LIB.BASEBOARD_FAB2(SCH_1):GND
   9    GND VSS<90> @BASEBOARD_FAB2_LIB.BASEBOARD_FAB2(SCH_1):GND
  11    GND VSS<89> @BASEBOARD_FAB2_LIB.BASEBOARD_FAB2(SCH_1):GND
  13    GND VSS<88> @BASEBOARD_FAB2_LIB.BASEBOARD_FAB2(SCH_1):GND
  15    GND VSS<87> @BASEBOARD_FAB2_LIB.BASEBOARD_FAB2(SCH_1):GND
  17    GND VSS<86> @BASEBOARD_FAB2_LIB.BASEBOARD_FAB2(SCH_1):GND
  20    GND VSS<85> @BASEBOARD_FAB2_LIB.BASEBOARD_FAB2(SCH_1):GND
  22    GND VSS<84> @BASEBOARD_FAB2_LIB.BASEBOARD_FAB2(SCH_1):GND
  24    GND VSS<83> @BASEBOARD_FAB2_LIB.BASEBOARD_FAB2(SCH_1):GND
  26    GND VSS<82> @BASEBOARD_FAB2_LIB.BASEBOARD_FAB2(SCH_1):GND
  28    GND VSS<81> @BASEBOARD_FAB2_LIB.BASEBOARD_FAB2(SCH_1):GND
  31    GND VSS<80> @BASEBOARD_FAB2_LIB.BASEBOARD_FAB2(SCH_1):GND
  33    GND VSS<79> @BASEBOARD_FAB2_LIB.BASEBOARD_FAB2(SCH_1):GND
  35    GND VSS<78> @BASEBOARD_FAB2_LIB.BASEBOARD_FAB2(SCH_1):GND
  37    GND VSS<77> @BASEBOARD_FAB2_LIB.BASEBOARD_FAB2(SCH_1):GND
  39    GND VSS<76> @BASEBOARD_FAB2_LIB.BASEBOARD_FAB2(SCH_1):GND
  42    GND VSS<75> @BASEBOARD_FAB2_LIB.BASEBOARD_FAB2(SCH_1):GND
  44    GND VSS<74> @BASEBOARD_FAB2_LIB.BASEBOARD_FAB2(SCH_1):GND
  46    GND VSS<73> @BASEBOARD_FAB2_LIB.BASEBOARD_FAB2(SCH_1):GND
  48    GND VSS<72> @BASEBOARD_FAB2_LIB.BASEBOARD_FAB2(SCH_1):GND
  50    GND VSS<71> @BASEBOARD_FAB2_LIB.BASEBOARD_FAB2(SCH_1):GND
  53    GND VSS<70> @BASEBOARD_FAB2_LIB.BASEBOARD_FAB2(SCH_1):GND
  55    GND VSS<69> @BASEBOARD_FAB2_LIB.BASEBOARD_FAB2(SCH_1):GND
  57    GND VSS<68> @BASEBOARD_FAB2_LIB.BASEBOARD_FAB2(SCH_1):GND
  94    GND VSS<67> @BASEBOARD_FAB2_LIB.BASEBOARD_FAB2(SCH_1):GND
  96    GND VSS<66> @BASEBOARD_FAB2_LIB.BASEBOARD_FAB2(SCH_1):GND
  98    GND VSS<65> @BASEBOARD_FAB2_LIB.BASEBOARD_FAB2(SCH_1):GND
 101    GND VSS<64> @BASEBOARD_FAB2_LIB.BASEBOARD_FAB2(SCH_1):GND
 103    GND VSS<63> @BASEBOARD_FAB2_LIB.BASEBOARD_FAB2(SCH_1):GND
 105    GND VSS<62> @BASEBOARD_FAB2_LIB.BASEBOARD_FAB2(SCH_1):GND
 107    GND VSS<61> @BASEBOARD_FAB2_LIB.BASEBOARD_FAB2(SCH_1):GND
 109    GND VSS<60> @BASEBOARD_FAB2_LIB.BASEBOARD_FAB2(SCH_1):GND
 112    GND VSS<59> @BASEBOARD_FAB2_LIB.BASEBOARD_FAB2(SCH_1):GND
 114    GND VSS<58> @BASEBOARD_FAB2_LIB.BASEBOARD_FAB2(SCH_1):GND
 116    GND VSS<57> @BASEBOARD_FAB2_LIB.BASEBOARD_FAB2(SCH_1):GND
 118    GND VSS<56> @BASEBOARD_FAB2_LIB.BASEBOARD_FAB2(SCH_1):GND
 120    GND VSS<55> @BASEBOARD_FAB2_LIB.BASEBOARD_FAB2(SCH_1):GND
 123    GND VSS<54> @BASEBOARD_FAB2_LIB.BASEBOARD_FAB2(SCH_1):GND
 125    GND VSS<53> @BASEBOARD_FAB2_LIB.BASEBOARD_FAB2(SCH_1):GND
 127    GND VSS<52> @BASEBOARD_FAB2_LIB.BASEBOARD_FAB2(SCH_1):GND
 129    GND VSS<51> @BASEBOARD_FAB2_LIB.BASEBOARD_FAB2(SCH_1):GND
 131    GND VSS<50> @BASEBOARD_FAB2_LIB.BASEBOARD_FAB2(SCH_1):GND
 134    GND VSS<49> @BASEBOARD_FAB2_LIB.BASEBOARD_FAB2(SCH_1):GND
 136    GND VSS<48> @BASEBOARD_FAB2_LIB.BASEBOARD_FAB2(SCH_1):GND
 138    GND VSS<47> @BASEBOARD_FAB2_LIB.BASEBOARD_FAB2(SCH_1):GND
 147    GND VSS<46> @BASEBOARD_FAB2_LIB.BASEBOARD_FAB2(SCH_1):GND
 149    GND VSS<45> @BASEBOARD_FAB2_LIB.BASEBOARD_FAB2(SCH_1):GND
 151    GND VSS<44> @BASEBOARD_FAB2_LIB.BASEBOARD_FAB2(SCH_1):GND
 154    GND VSS<43> @BASEBOARD_FAB2_LIB.BASEBOARD_FAB2(SCH_1):GND
 156    GND VSS<42> @BASEBOARD_FAB2_LIB.BASEBOARD_FAB2(SCH_1):GND
 158    GND VSS<41> @BASEBOARD_FAB2_LIB.BASEBOARD_FAB2(SCH_1):GND
 160    GND VSS<40> @BASEBOARD_FAB2_LIB.BASEBOARD_FAB2(SCH_1):GND
 162    GND VSS<39> @BASEBOARD_FAB2_LIB.BASEBOARD_FAB2(SCH_1):GND
 165    GND VSS<38> @BASEBOARD_FAB2_LIB.BASEBOARD_FAB2(SCH_1):GND
 167    GND VSS<37> @BASEBOARD_FAB2_LIB.BASEBOARD_FAB2(SCH_1):GND
 169    GND VSS<36> @BASEBOARD_FAB2_LIB.BASEBOARD_FAB2(SCH_1):GND
 171    GND VSS<35> @BASEBOARD_FAB2_LIB.BASEBOARD_FAB2(SCH_1):GND
 173    GND VSS<34> @BASEBOARD_FAB2_LIB.BASEBOARD_FAB2(SCH_1):GND
 176    GND VSS<33> @BASEBOARD_FAB2_LIB.BASEBOARD_FAB2(SCH_1):GND
 178    GND VSS<32> @BASEBOARD_FAB2_LIB.BASEBOARD_FAB2(SCH_1):GND
 180    GND VSS<31> @BASEBOARD_FAB2_LIB.BASEBOARD_FAB2(SCH_1):GND
 182    GND VSS<30> @BASEBOARD_FAB2_LIB.BASEBOARD_FAB2(SCH_1):GND
 184    GND VSS<29> @BASEBOARD_FAB2_LIB.BASEBOARD_FAB2(SCH_1):GND
 187    GND VSS<28> @BASEBOARD_FAB2_LIB.BASEBOARD_FAB2(SCH_1):GND
 189    GND VSS<27> @BASEBOARD_FAB2_LIB.BASEBOARD_FAB2(SCH_1):GND
 191    GND VSS<26> @BASEBOARD_FAB2_LIB.BASEBOARD_FAB2(SCH_1):GND
 193    GND VSS<25> @BASEBOARD_FAB2_LIB.BASEBOARD_FAB2(SCH_1):GND
 195    GND VSS<24> @BASEBOARD_FAB2_LIB.BASEBOARD_FAB2(SCH_1):GND
 198    GND VSS<23> @BASEBOARD_FAB2_LIB.BASEBOARD_FAB2(SCH_1):GND
 200    GND VSS<22> @BASEBOARD_FAB2_LIB.BASEBOARD_FAB2(SCH_1):GND
 202    GND VSS<21> @BASEBOARD_FAB2_LIB.BASEBOARD_FAB2(SCH_1):GND
 239    GND VSS<20> @BASEBOARD_FAB2_LIB.BASEBOARD_FAB2(SCH_1):GND
 241    GND VSS<19> @BASEBOARD_FAB2_LIB.BASEBOARD_FAB2(SCH_1):GND
 243    GND VSS<18> @BASEBOARD_FAB2_LIB.BASEBOARD_FAB2(SCH_1):GND
 246    GND VSS<17> @BASEBOARD_FAB2_LIB.BASEBOARD_FAB2(SCH_1):GND
 248    GND VSS<16> @BASEBOARD_FAB2_LIB.BASEBOARD_FAB2(SCH_1):GND
 250    GND VSS<15> @BASEBOARD_FAB2_LIB.BASEBOARD_FAB2(SCH_1):GND
 252    GND VSS<14> @BASEBOARD_FAB2_LIB.BASEBOARD_FAB2(SCH_1):GND
 254    GND VSS<13> @BASEBOARD_FAB2_LIB.BASEBOARD_FAB2(SCH_1):GND
 257    GND VSS<12> @BASEBOARD_FAB2_LIB.BASEBOARD_FAB2(SCH_1):GND
 259    GND VSS<11> @BASEBOARD_FAB2_LIB.BASEBOARD_FAB2(SCH_1):GND
 261    GND VSS<10> @BASEBOARD_FAB2_LIB.BASEBOARD_FAB2(SCH_1):GND
 263    GND VSS<9> @BASEBOARD_FAB2_LIB.BASEBOARD_FAB2(SCH_1):GND
 265    GND VSS<8> @BASEBOARD_FAB2_LIB.BASEBOARD_FAB2(SCH_1):GND
 268    GND VSS<7> @BASEBOARD_FAB2_LIB.BASEBOARD_FAB2(SCH_1):GND
 270    GND VSS<6> @BASEBOARD_FAB2_LIB.BASEBOARD_FAB2(SCH_1):GND
 272    GND VSS<5> @BASEBOARD_FAB2_LIB.BASEBOARD_FAB2(SCH_1):GND
 274    GND VSS<4> @BASEBOARD_FAB2_LIB.BASEBOARD_FAB2(SCH_1):GND
 276    GND VSS<3> @BASEBOARD_FAB2_LIB.BASEBOARD_FAB2(SCH_1):GND
 279    GND VSS<2> @BASEBOARD_FAB2_LIB.BASEBOARD_FAB2(SCH_1):GND
 281    GND VSS<1> @BASEBOARD_FAB2_LIB.BASEBOARD_FAB2(SCH_1):GND
 283    GND VSS<0> @BASEBOARD_FAB2_LIB.BASEBOARD_FAB2(SCH_1):GND


DRAWING: @BASEBOARD_FAB2_LIB.BASEBOARD_FAB2(SCH_1):PAGE85 

SCONN288_H44441004_PIP-SCONN,HA  I43  J1A2
   2    GND VSS<93> @BASEBOARD_FAB2_LIB.BASEBOARD_FAB2(SCH_1):GND
   4    GND VSS<92> @BASEBOARD_FAB2_LIB.BASEBOARD_FAB2(SCH_1):GND
   6    GND VSS<91> @BASEBOARD_FAB2_LIB.BASEBOARD_FAB2(SCH_1):GND
   9    GND VSS<90> @BASEBOARD_FAB2_LIB.BASEBOARD_FAB2(SCH_1):GND
  11    GND VSS<89> @BASEBOARD_FAB2_LIB.BASEBOARD_FAB2(SCH_1):GND
  13    GND VSS<88> @BASEBOARD_FAB2_LIB.BASEBOARD_FAB2(SCH_1):GND
  15    GND VSS<87> @BASEBOARD_FAB2_LIB.BASEBOARD_FAB2(SCH_1):GND
  17    GND VSS<86> @BASEBOARD_FAB2_LIB.BASEBOARD_FAB2(SCH_1):GND
  20    GND VSS<85> @BASEBOARD_FAB2_LIB.BASEBOARD_FAB2(SCH_1):GND
  22    GND VSS<84> @BASEBOARD_FAB2_LIB.BASEBOARD_FAB2(SCH_1):GND
  24    GND VSS<83> @BASEBOARD_FAB2_LIB.BASEBOARD_FAB2(SCH_1):GND
  26    GND VSS<82> @BASEBOARD_FAB2_LIB.BASEBOARD_FAB2(SCH_1):GND
  28    GND VSS<81> @BASEBOARD_FAB2_LIB.BASEBOARD_FAB2(SCH_1):GND
  31    GND VSS<80> @BASEBOARD_FAB2_LIB.BASEBOARD_FAB2(SCH_1):GND
  33    GND VSS<79> @BASEBOARD_FAB2_LIB.BASEBOARD_FAB2(SCH_1):GND
  35    GND VSS<78> @BASEBOARD_FAB2_LIB.BASEBOARD_FAB2(SCH_1):GND
  37    GND VSS<77> @BASEBOARD_FAB2_LIB.BASEBOARD_FAB2(SCH_1):GND
  39    GND VSS<76> @BASEBOARD_FAB2_LIB.BASEBOARD_FAB2(SCH_1):GND
  42    GND VSS<75> @BASEBOARD_FAB2_LIB.BASEBOARD_FAB2(SCH_1):GND
  44    GND VSS<74> @BASEBOARD_FAB2_LIB.BASEBOARD_FAB2(SCH_1):GND
  46    GND VSS<73> @BASEBOARD_FAB2_LIB.BASEBOARD_FAB2(SCH_1):GND
  48    GND VSS<72> @BASEBOARD_FAB2_LIB.BASEBOARD_FAB2(SCH_1):GND
  50    GND VSS<71> @BASEBOARD_FAB2_LIB.BASEBOARD_FAB2(SCH_1):GND
  53    GND VSS<70> @BASEBOARD_FAB2_LIB.BASEBOARD_FAB2(SCH_1):GND
  55    GND VSS<69> @BASEBOARD_FAB2_LIB.BASEBOARD_FAB2(SCH_1):GND
  57    GND VSS<68> @BASEBOARD_FAB2_LIB.BASEBOARD_FAB2(SCH_1):GND
  94    GND VSS<67> @BASEBOARD_FAB2_LIB.BASEBOARD_FAB2(SCH_1):GND
  96    GND VSS<66> @BASEBOARD_FAB2_LIB.BASEBOARD_FAB2(SCH_1):GND
  98    GND VSS<65> @BASEBOARD_FAB2_LIB.BASEBOARD_FAB2(SCH_1):GND
 101    GND VSS<64> @BASEBOARD_FAB2_LIB.BASEBOARD_FAB2(SCH_1):GND
 103    GND VSS<63> @BASEBOARD_FAB2_LIB.BASEBOARD_FAB2(SCH_1):GND
 105    GND VSS<62> @BASEBOARD_FAB2_LIB.BASEBOARD_FAB2(SCH_1):GND
 107    GND VSS<61> @BASEBOARD_FAB2_LIB.BASEBOARD_FAB2(SCH_1):GND
 109    GND VSS<60> @BASEBOARD_FAB2_LIB.BASEBOARD_FAB2(SCH_1):GND
 112    GND VSS<59> @BASEBOARD_FAB2_LIB.BASEBOARD_FAB2(SCH_1):GND
 114    GND VSS<58> @BASEBOARD_FAB2_LIB.BASEBOARD_FAB2(SCH_1):GND
 116    GND VSS<57> @BASEBOARD_FAB2_LIB.BASEBOARD_FAB2(SCH_1):GND
 118    GND VSS<56> @BASEBOARD_FAB2_LIB.BASEBOARD_FAB2(SCH_1):GND
 120    GND VSS<55> @BASEBOARD_FAB2_LIB.BASEBOARD_FAB2(SCH_1):GND
 123    GND VSS<54> @BASEBOARD_FAB2_LIB.BASEBOARD_FAB2(SCH_1):GND
 125    GND VSS<53> @BASEBOARD_FAB2_LIB.BASEBOARD_FAB2(SCH_1):GND
 127    GND VSS<52> @BASEBOARD_FAB2_LIB.BASEBOARD_FAB2(SCH_1):GND
 129    GND VSS<51> @BASEBOARD_FAB2_LIB.BASEBOARD_FAB2(SCH_1):GND
 131    GND VSS<50> @BASEBOARD_FAB2_LIB.BASEBOARD_FAB2(SCH_1):GND
 134    GND VSS<49> @BASEBOARD_FAB2_LIB.BASEBOARD_FAB2(SCH_1):GND
 136    GND VSS<48> @BASEBOARD_FAB2_LIB.BASEBOARD_FAB2(SCH_1):GND
 138    GND VSS<47> @BASEBOARD_FAB2_LIB.BASEBOARD_FAB2(SCH_1):GND
 147    GND VSS<46> @BASEBOARD_FAB2_LIB.BASEBOARD_FAB2(SCH_1):GND
 149    GND VSS<45> @BASEBOARD_FAB2_LIB.BASEBOARD_FAB2(SCH_1):GND
 151    GND VSS<44> @BASEBOARD_FAB2_LIB.BASEBOARD_FAB2(SCH_1):GND
 154    GND VSS<43> @BASEBOARD_FAB2_LIB.BASEBOARD_FAB2(SCH_1):GND
 156    GND VSS<42> @BASEBOARD_FAB2_LIB.BASEBOARD_FAB2(SCH_1):GND
 158    GND VSS<41> @BASEBOARD_FAB2_LIB.BASEBOARD_FAB2(SCH_1):GND
 160    GND VSS<40> @BASEBOARD_FAB2_LIB.BASEBOARD_FAB2(SCH_1):GND
 162    GND VSS<39> @BASEBOARD_FAB2_LIB.BASEBOARD_FAB2(SCH_1):GND
 165    GND VSS<38> @BASEBOARD_FAB2_LIB.BASEBOARD_FAB2(SCH_1):GND
 167    GND VSS<37> @BASEBOARD_FAB2_LIB.BASEBOARD_FAB2(SCH_1):GND
 169    GND VSS<36> @BASEBOARD_FAB2_LIB.BASEBOARD_FAB2(SCH_1):GND
 171    GND VSS<35> @BASEBOARD_FAB2_LIB.BASEBOARD_FAB2(SCH_1):GND
 173    GND VSS<34> @BASEBOARD_FAB2_LIB.BASEBOARD_FAB2(SCH_1):GND
 176    GND VSS<33> @BASEBOARD_FAB2_LIB.BASEBOARD_FAB2(SCH_1):GND
 178    GND VSS<32> @BASEBOARD_FAB2_LIB.BASEBOARD_FAB2(SCH_1):GND
 180    GND VSS<31> @BASEBOARD_FAB2_LIB.BASEBOARD_FAB2(SCH_1):GND
 182    GND VSS<30> @BASEBOARD_FAB2_LIB.BASEBOARD_FAB2(SCH_1):GND
 184    GND VSS<29> @BASEBOARD_FAB2_LIB.BASEBOARD_FAB2(SCH_1):GND
 187    GND VSS<28> @BASEBOARD_FAB2_LIB.BASEBOARD_FAB2(SCH_1):GND
 189    GND VSS<27> @BASEBOARD_FAB2_LIB.BASEBOARD_FAB2(SCH_1):GND
 191    GND VSS<26> @BASEBOARD_FAB2_LIB.BASEBOARD_FAB2(SCH_1):GND
 193    GND VSS<25> @BASEBOARD_FAB2_LIB.BASEBOARD_FAB2(SCH_1):GND
 195    GND VSS<24> @BASEBOARD_FAB2_LIB.BASEBOARD_FAB2(SCH_1):GND
 198    GND VSS<23> @BASEBOARD_FAB2_LIB.BASEBOARD_FAB2(SCH_1):GND
 200    GND VSS<22> @BASEBOARD_FAB2_LIB.BASEBOARD_FAB2(SCH_1):GND
 202    GND VSS<21> @BASEBOARD_FAB2_LIB.BASEBOARD_FAB2(SCH_1):GND
 239    GND VSS<20> @BASEBOARD_FAB2_LIB.BASEBOARD_FAB2(SCH_1):GND
 241    GND VSS<19> @BASEBOARD_FAB2_LIB.BASEBOARD_FAB2(SCH_1):GND
 243    GND VSS<18> @BASEBOARD_FAB2_LIB.BASEBOARD_FAB2(SCH_1):GND
 246    GND VSS<17> @BASEBOARD_FAB2_LIB.BASEBOARD_FAB2(SCH_1):GND
 248    GND VSS<16> @BASEBOARD_FAB2_LIB.BASEBOARD_FAB2(SCH_1):GND
 250    GND VSS<15> @BASEBOARD_FAB2_LIB.BASEBOARD_FAB2(SCH_1):GND
 252    GND VSS<14> @BASEBOARD_FAB2_LIB.BASEBOARD_FAB2(SCH_1):GND
 254    GND VSS<13> @BASEBOARD_FAB2_LIB.BASEBOARD_FAB2(SCH_1):GND
 257    GND VSS<12> @BASEBOARD_FAB2_LIB.BASEBOARD_FAB2(SCH_1):GND
 259    GND VSS<11> @BASEBOARD_FAB2_LIB.BASEBOARD_FAB2(SCH_1):GND
 261    GND VSS<10> @BASEBOARD_FAB2_LIB.BASEBOARD_FAB2(SCH_1):GND
 263    GND VSS<9> @BASEBOARD_FAB2_LIB.BASEBOARD_FAB2(SCH_1):GND
 265    GND VSS<8> @BASEBOARD_FAB2_LIB.BASEBOARD_FAB2(SCH_1):GND
 268    GND VSS<7> @BASEBOARD_FAB2_LIB.BASEBOARD_FAB2(SCH_1):GND
 270    GND VSS<6> @BASEBOARD_FAB2_LIB.BASEBOARD_FAB2(SCH_1):GND
 272    GND VSS<5> @BASEBOARD_FAB2_LIB.BASEBOARD_FAB2(SCH_1):GND
 274    GND VSS<4> @BASEBOARD_FAB2_LIB.BASEBOARD_FAB2(SCH_1):GND
 276    GND VSS<3> @BASEBOARD_FAB2_LIB.BASEBOARD_FAB2(SCH_1):GND
 279    GND VSS<2> @BASEBOARD_FAB2_LIB.BASEBOARD_FAB2(SCH_1):GND
 281    GND VSS<1> @BASEBOARD_FAB2_LIB.BASEBOARD_FAB2(SCH_1):GND
 283    GND VSS<0> @BASEBOARD_FAB2_LIB.BASEBOARD_FAB2(SCH_1):GND

SCONN288_H44441004_PIP-SCONN,HA  I66  J1A2
 152 M_L_DQS_DN<0>  DQS0N @BASEBOARD_FAB2_LIB.BASEBOARD_FAB2(SCH_1):M_L_DQS_DN(0)
 153 M_L_DQS_DP<0>  DQS0P @BASEBOARD_FAB2_LIB.BASEBOARD_FAB2(SCH_1):M_L_DQS_DP(0)
  19 M_L_DQS_DN<10> DQS10N @BASEBOARD_FAB2_LIB.BASEBOARD_FAB2(SCH_1):M_L_DQS_DN(10)
  18 M_L_DQS_DP<10> DQS10P @BASEBOARD_FAB2_LIB.BASEBOARD_FAB2(SCH_1):M_L_DQS_DP(10)
  30 M_L_DQS_DN<11> DQS11N @BASEBOARD_FAB2_LIB.BASEBOARD_FAB2(SCH_1):M_L_DQS_DN(11)
  29 M_L_DQS_DP<11> DQS11P @BASEBOARD_FAB2_LIB.BASEBOARD_FAB2(SCH_1):M_L_DQS_DP(11)
  41 M_L_DQS_DN<12> DQS12N @BASEBOARD_FAB2_LIB.BASEBOARD_FAB2(SCH_1):M_L_DQS_DN(12)
  40 M_L_DQS_DP<12> DQS12P @BASEBOARD_FAB2_LIB.BASEBOARD_FAB2(SCH_1):M_L_DQS_DP(12)
 100 M_L_DQS_DN<13> DQS13N @BASEBOARD_FAB2_LIB.BASEBOARD_FAB2(SCH_1):M_L_DQS_DN(13)
  99 M_L_DQS_DP<13> DQS13P @BASEBOARD_FAB2_LIB.BASEBOARD_FAB2(SCH_1):M_L_DQS_DP(13)
 111 M_L_DQS_DN<14> DQS14N @BASEBOARD_FAB2_LIB.BASEBOARD_FAB2(SCH_1):M_L_DQS_DN(14)
 110 M_L_DQS_DP<14> DQS14P @BASEBOARD_FAB2_LIB.BASEBOARD_FAB2(SCH_1):M_L_DQS_DP(14)
 122 M_L_DQS_DN<15> DQS15N @BASEBOARD_FAB2_LIB.BASEBOARD_FAB2(SCH_1):M_L_DQS_DN(15)
 121 M_L_DQS_DP<15> DQS15P @BASEBOARD_FAB2_LIB.BASEBOARD_FAB2(SCH_1):M_L_DQS_DP(15)
 133 M_L_DQS_DN<16> DQS16N @BASEBOARD_FAB2_LIB.BASEBOARD_FAB2(SCH_1):M_L_DQS_DN(16)
 132 M_L_DQS_DP<16> DQS16P @BASEBOARD_FAB2_LIB.BASEBOARD_FAB2(SCH_1):M_L_DQS_DP(16)
  52 M_L_DQS_DN<17> DQS17N @BASEBOARD_FAB2_LIB.BASEBOARD_FAB2(SCH_1):M_L_DQS_DN(17)
  51 M_L_DQS_DP<17> DQS17P @BASEBOARD_FAB2_LIB.BASEBOARD_FAB2(SCH_1):M_L_DQS_DP(17)
 163 M_L_DQS_DN<1>  DQS1N @BASEBOARD_FAB2_LIB.BASEBOARD_FAB2(SCH_1):M_L_DQS_DN(1)
 164 M_L_DQS_DP<1>  DQS1P @BASEBOARD_FAB2_LIB.BASEBOARD_FAB2(SCH_1):M_L_DQS_DP(1)
 174 M_L_DQS_DN<2>  DQS2N @BASEBOARD_FAB2_LIB.BASEBOARD_FAB2(SCH_1):M_L_DQS_DN(2)
 175 M_L_DQS_DP<2>  DQS2P @BASEBOARD_FAB2_LIB.BASEBOARD_FAB2(SCH_1):M_L_DQS_DP(2)
 185 M_L_DQS_DN<3>  DQS3N @BASEBOARD_FAB2_LIB.BASEBOARD_FAB2(SCH_1):M_L_DQS_DN(3)
 186 M_L_DQS_DP<3>  DQS3P @BASEBOARD_FAB2_LIB.BASEBOARD_FAB2(SCH_1):M_L_DQS_DP(3)
 244 M_L_DQS_DN<4>  DQS4N @BASEBOARD_FAB2_LIB.BASEBOARD_FAB2(SCH_1):M_L_DQS_DN(4)
 245 M_L_DQS_DP<4>  DQS4P @BASEBOARD_FAB2_LIB.BASEBOARD_FAB2(SCH_1):M_L_DQS_DP(4)
 255 M_L_DQS_DN<5>  DQS5N @BASEBOARD_FAB2_LIB.BASEBOARD_FAB2(SCH_1):M_L_DQS_DN(5)
 256 M_L_DQS_DP<5>  DQS5P @BASEBOARD_FAB2_LIB.BASEBOARD_FAB2(SCH_1):M_L_DQS_DP(5)
 266 M_L_DQS_DN<6>  DQS6N @BASEBOARD_FAB2_LIB.BASEBOARD_FAB2(SCH_1):M_L_DQS_DN(6)
 267 M_L_DQS_DP<6>  DQS6P @BASEBOARD_FAB2_LIB.BASEBOARD_FAB2(SCH_1):M_L_DQS_DP(6)
 277 M_L_DQS_DN<7>  DQS7N @BASEBOARD_FAB2_LIB.BASEBOARD_FAB2(SCH_1):M_L_DQS_DN(7)
 278 M_L_DQS_DP<7>  DQS7P @BASEBOARD_FAB2_LIB.BASEBOARD_FAB2(SCH_1):M_L_DQS_DP(7)
 196 M_L_DQS_DN<8>  DQS8N @BASEBOARD_FAB2_LIB.BASEBOARD_FAB2(SCH_1):M_L_DQS_DN(8)
 197 M_L_DQS_DP<8>  DQS8P @BASEBOARD_FAB2_LIB.BASEBOARD_FAB2(SCH_1):M_L_DQS_DP(8)
   8 M_L_DQS_DN<9>  DQS9N @BASEBOARD_FAB2_LIB.BASEBOARD_FAB2(SCH_1):M_L_DQS_DN(9)
   7 M_L_DQS_DP<9>  DQS9P @BASEBOARD_FAB2_LIB.BASEBOARD_FAB2(SCH_1):M_L_DQS_DP(9)

SCONN288_H44441004_PIP-SCONN,HA  I111  J1A2
  79 M_L_MA<0>     A0 @BASEBOARD_FAB2_LIB.BASEBOARD_FAB2(SCH_1):M_L_MA(0)
  72 M_L_MA<1>     A1 @BASEBOARD_FAB2_LIB.BASEBOARD_FAB2(SCH_1):M_L_MA(1)
 225 M_L_MA<10>    A10 @BASEBOARD_FAB2_LIB.BASEBOARD_FAB2(SCH_1):M_L_MA(10)
 210 M_L_MA<11>    A11 @BASEBOARD_FAB2_LIB.BASEBOARD_FAB2(SCH_1):M_L_MA(11)
  65 M_L_MA<12>    A12 @BASEBOARD_FAB2_LIB.BASEBOARD_FAB2(SCH_1):M_L_MA(12)
 232 M_L_MA<13>    A13 @BASEBOARD_FAB2_LIB.BASEBOARD_FAB2(SCH_1):M_L_MA(13)
 228 M_L_MA<14> A14_WE_N @BASEBOARD_FAB2_LIB.BASEBOARD_FAB2(SCH_1):M_L_MA(14)
  86 M_L_MA<15> A15_CAS_N @BASEBOARD_FAB2_LIB.BASEBOARD_FAB2(SCH_1):M_L_MA(15)
  82 M_L_MA<16> A16_RAS_N @BASEBOARD_FAB2_LIB.BASEBOARD_FAB2(SCH_1):M_L_MA(16)
 234 M_L_MA<17>    A17 @BASEBOARD_FAB2_LIB.BASEBOARD_FAB2(SCH_1):M_L_MA(17)
 216 M_L_MA<2>     A2 @BASEBOARD_FAB2_LIB.BASEBOARD_FAB2(SCH_1):M_L_MA(2)
  71 M_L_MA<3>     A3 @BASEBOARD_FAB2_LIB.BASEBOARD_FAB2(SCH_1):M_L_MA(3)
 214 M_L_MA<4>     A4 @BASEBOARD_FAB2_LIB.BASEBOARD_FAB2(SCH_1):M_L_MA(4)
 213 M_L_MA<5>     A5 @BASEBOARD_FAB2_LIB.BASEBOARD_FAB2(SCH_1):M_L_MA(5)
  69 M_L_MA<6>     A6 @BASEBOARD_FAB2_LIB.BASEBOARD_FAB2(SCH_1):M_L_MA(6)
 211 M_L_MA<7>     A7 @BASEBOARD_FAB2_LIB.BASEBOARD_FAB2(SCH_1):M_L_MA(7)
  68 M_L_MA<8>     A8 @BASEBOARD_FAB2_LIB.BASEBOARD_FAB2(SCH_1):M_L_MA(8)
  66 M_L_MA<9>     A9 @BASEBOARD_FAB2_LIB.BASEBOARD_FAB2(SCH_1):M_L_MA(9)
  62 M_L_ACT_N  ACT_N @BASEBOARD_FAB2_LIB.BASEBOARD_FAB2(SCH_1):M_L_ACT_N
 208 M_L_ALERT_N ALERT_N @BASEBOARD_FAB2_LIB.BASEBOARD_FAB2(SCH_1):M_L_ALERT_N
 224 M_L_BA<1>  BA<1> @BASEBOARD_FAB2_LIB.BASEBOARD_FAB2(SCH_1):M_L_BA(1)
  81 M_L_BA<0>  BA<0> @BASEBOARD_FAB2_LIB.BASEBOARD_FAB2(SCH_1):M_L_BA(0)
 207 M_L_BG<1>  BG<1> @BASEBOARD_FAB2_LIB.BASEBOARD_FAB2(SCH_1):M_L_BG(1)
  63 M_L_BG<0>  BG<0> @BASEBOARD_FAB2_LIB.BASEBOARD_FAB2(SCH_1):M_L_BG(0)
 235 M_L_C<2>   C<2> @BASEBOARD_FAB2_LIB.BASEBOARD_FAB2(SCH_1):M_L_C(2)
 199 M_L_ECC<6>  CB<7> @BASEBOARD_FAB2_LIB.BASEBOARD_FAB2(SCH_1):M_L_ECC(6)
  54 M_L_ECC<7>  CB<6> @BASEBOARD_FAB2_LIB.BASEBOARD_FAB2(SCH_1):M_L_ECC(7)
 192 M_L_ECC<4>  CB<5> @BASEBOARD_FAB2_LIB.BASEBOARD_FAB2(SCH_1):M_L_ECC(4)
  47 M_L_ECC<5>  CB<4> @BASEBOARD_FAB2_LIB.BASEBOARD_FAB2(SCH_1):M_L_ECC(5)
 201 M_L_ECC<2>  CB<3> @BASEBOARD_FAB2_LIB.BASEBOARD_FAB2(SCH_1):M_L_ECC(2)
  56 M_L_ECC<3>  CB<2> @BASEBOARD_FAB2_LIB.BASEBOARD_FAB2(SCH_1):M_L_ECC(3)
 194 M_L_ECC<0>  CB<1> @BASEBOARD_FAB2_LIB.BASEBOARD_FAB2(SCH_1):M_L_ECC(0)
  49 M_L_ECC<1>  CB<0> @BASEBOARD_FAB2_LIB.BASEBOARD_FAB2(SCH_1):M_L_ECC(1)
  75 M_L_CLK_DN<0>   CK0N @BASEBOARD_FAB2_LIB.BASEBOARD_FAB2(SCH_1):M_L_CLK_DN(0)
  74 M_L_CLK_DP<0>   CK0P @BASEBOARD_FAB2_LIB.BASEBOARD_FAB2(SCH_1):M_L_CLK_DP(0)
 219 M_L_CLK_DN<1>   CK1N @BASEBOARD_FAB2_LIB.BASEBOARD_FAB2(SCH_1):M_L_CLK_DN(1)
 218 M_L_CLK_DP<1>   CK1P @BASEBOARD_FAB2_LIB.BASEBOARD_FAB2(SCH_1):M_L_CLK_DP(1)
 203 M_L_CKE<1> CKE<1> @BASEBOARD_FAB2_LIB.BASEBOARD_FAB2(SCH_1):M_L_CKE(1)
  60 M_L_CKE<0> CKE<0> @BASEBOARD_FAB2_LIB.BASEBOARD_FAB2(SCH_1):M_L_CKE(0)
 280 M_L_DQ<62> DQ<63> @BASEBOARD_FAB2_LIB.BASEBOARD_FAB2(SCH_1):M_L_DQ(62)
 135 M_L_DQ<63> DQ<62> @BASEBOARD_FAB2_LIB.BASEBOARD_FAB2(SCH_1):M_L_DQ(63)
 273 M_L_DQ<60> DQ<61> @BASEBOARD_FAB2_LIB.BASEBOARD_FAB2(SCH_1):M_L_DQ(60)
 128 M_L_DQ<61> DQ<60> @BASEBOARD_FAB2_LIB.BASEBOARD_FAB2(SCH_1):M_L_DQ(61)
 282 M_L_DQ<58> DQ<59> @BASEBOARD_FAB2_LIB.BASEBOARD_FAB2(SCH_1):M_L_DQ(58)
 137 M_L_DQ<59> DQ<58> @BASEBOARD_FAB2_LIB.BASEBOARD_FAB2(SCH_1):M_L_DQ(59)
 275 M_L_DQ<56> DQ<57> @BASEBOARD_FAB2_LIB.BASEBOARD_FAB2(SCH_1):M_L_DQ(56)
 130 M_L_DQ<57> DQ<56> @BASEBOARD_FAB2_LIB.BASEBOARD_FAB2(SCH_1):M_L_DQ(57)
 269 M_L_DQ<54> DQ<55> @BASEBOARD_FAB2_LIB.BASEBOARD_FAB2(SCH_1):M_L_DQ(54)
 124 M_L_DQ<55> DQ<54> @BASEBOARD_FAB2_LIB.BASEBOARD_FAB2(SCH_1):M_L_DQ(55)
 262 M_L_DQ<52> DQ<53> @BASEBOARD_FAB2_LIB.BASEBOARD_FAB2(SCH_1):M_L_DQ(52)
 117 M_L_DQ<53> DQ<52> @BASEBOARD_FAB2_LIB.BASEBOARD_FAB2(SCH_1):M_L_DQ(53)
 271 M_L_DQ<50> DQ<51> @BASEBOARD_FAB2_LIB.BASEBOARD_FAB2(SCH_1):M_L_DQ(50)
 126 M_L_DQ<51> DQ<50> @BASEBOARD_FAB2_LIB.BASEBOARD_FAB2(SCH_1):M_L_DQ(51)
 264 M_L_DQ<48> DQ<49> @BASEBOARD_FAB2_LIB.BASEBOARD_FAB2(SCH_1):M_L_DQ(48)
 119 M_L_DQ<49> DQ<48> @BASEBOARD_FAB2_LIB.BASEBOARD_FAB2(SCH_1):M_L_DQ(49)
 258 M_L_DQ<46> DQ<47> @BASEBOARD_FAB2_LIB.BASEBOARD_FAB2(SCH_1):M_L_DQ(46)
 113 M_L_DQ<47> DQ<46> @BASEBOARD_FAB2_LIB.BASEBOARD_FAB2(SCH_1):M_L_DQ(47)
 251 M_L_DQ<44> DQ<45> @BASEBOARD_FAB2_LIB.BASEBOARD_FAB2(SCH_1):M_L_DQ(44)
 106 M_L_DQ<45> DQ<44> @BASEBOARD_FAB2_LIB.BASEBOARD_FAB2(SCH_1):M_L_DQ(45)
 260 M_L_DQ<42> DQ<43> @BASEBOARD_FAB2_LIB.BASEBOARD_FAB2(SCH_1):M_L_DQ(42)
 115 M_L_DQ<43> DQ<42> @BASEBOARD_FAB2_LIB.BASEBOARD_FAB2(SCH_1):M_L_DQ(43)
 253 M_L_DQ<40> DQ<41> @BASEBOARD_FAB2_LIB.BASEBOARD_FAB2(SCH_1):M_L_DQ(40)
 108 M_L_DQ<41> DQ<40> @BASEBOARD_FAB2_LIB.BASEBOARD_FAB2(SCH_1):M_L_DQ(41)
 247 M_L_DQ<38> DQ<39> @BASEBOARD_FAB2_LIB.BASEBOARD_FAB2(SCH_1):M_L_DQ(38)
 102 M_L_DQ<39> DQ<38> @BASEBOARD_FAB2_LIB.BASEBOARD_FAB2(SCH_1):M_L_DQ(39)
 240 M_L_DQ<36> DQ<37> @BASEBOARD_FAB2_LIB.BASEBOARD_FAB2(SCH_1):M_L_DQ(36)
  95 M_L_DQ<37> DQ<36> @BASEBOARD_FAB2_LIB.BASEBOARD_FAB2(SCH_1):M_L_DQ(37)
 249 M_L_DQ<34> DQ<35> @BASEBOARD_FAB2_LIB.BASEBOARD_FAB2(SCH_1):M_L_DQ(34)
 104 M_L_DQ<35> DQ<34> @BASEBOARD_FAB2_LIB.BASEBOARD_FAB2(SCH_1):M_L_DQ(35)
 242 M_L_DQ<32> DQ<33> @BASEBOARD_FAB2_LIB.BASEBOARD_FAB2(SCH_1):M_L_DQ(32)
  97 M_L_DQ<33> DQ<32> @BASEBOARD_FAB2_LIB.BASEBOARD_FAB2(SCH_1):M_L_DQ(33)
 188 M_L_DQ<30> DQ<31> @BASEBOARD_FAB2_LIB.BASEBOARD_FAB2(SCH_1):M_L_DQ(30)
  43 M_L_DQ<31> DQ<30> @BASEBOARD_FAB2_LIB.BASEBOARD_FAB2(SCH_1):M_L_DQ(31)
 181 M_L_DQ<28> DQ<29> @BASEBOARD_FAB2_LIB.BASEBOARD_FAB2(SCH_1):M_L_DQ(28)
  36 M_L_DQ<29> DQ<28> @BASEBOARD_FAB2_LIB.BASEBOARD_FAB2(SCH_1):M_L_DQ(29)
 190 M_L_DQ<26> DQ<27> @BASEBOARD_FAB2_LIB.BASEBOARD_FAB2(SCH_1):M_L_DQ(26)
  45 M_L_DQ<27> DQ<26> @BASEBOARD_FAB2_LIB.BASEBOARD_FAB2(SCH_1):M_L_DQ(27)
 183 M_L_DQ<24> DQ<25> @BASEBOARD_FAB2_LIB.BASEBOARD_FAB2(SCH_1):M_L_DQ(24)
  38 M_L_DQ<25> DQ<24> @BASEBOARD_FAB2_LIB.BASEBOARD_FAB2(SCH_1):M_L_DQ(25)
 177 M_L_DQ<22> DQ<23> @BASEBOARD_FAB2_LIB.BASEBOARD_FAB2(SCH_1):M_L_DQ(22)
  32 M_L_DQ<23> DQ<22> @BASEBOARD_FAB2_LIB.BASEBOARD_FAB2(SCH_1):M_L_DQ(23)
 170 M_L_DQ<20> DQ<21> @BASEBOARD_FAB2_LIB.BASEBOARD_FAB2(SCH_1):M_L_DQ(20)
  25 M_L_DQ<21> DQ<20> @BASEBOARD_FAB2_LIB.BASEBOARD_FAB2(SCH_1):M_L_DQ(21)
 179 M_L_DQ<18> DQ<19> @BASEBOARD_FAB2_LIB.BASEBOARD_FAB2(SCH_1):M_L_DQ(18)
  34 M_L_DQ<19> DQ<18> @BASEBOARD_FAB2_LIB.BASEBOARD_FAB2(SCH_1):M_L_DQ(19)
 172 M_L_DQ<16> DQ<17> @BASEBOARD_FAB2_LIB.BASEBOARD_FAB2(SCH_1):M_L_DQ(16)
  27 M_L_DQ<17> DQ<16> @BASEBOARD_FAB2_LIB.BASEBOARD_FAB2(SCH_1):M_L_DQ(17)
 166 M_L_DQ<14> DQ<15> @BASEBOARD_FAB2_LIB.BASEBOARD_FAB2(SCH_1):M_L_DQ(14)
  21 M_L_DQ<15> DQ<14> @BASEBOARD_FAB2_LIB.BASEBOARD_FAB2(SCH_1):M_L_DQ(15)
 159 M_L_DQ<12> DQ<13> @BASEBOARD_FAB2_LIB.BASEBOARD_FAB2(SCH_1):M_L_DQ(12)
  14 M_L_DQ<13> DQ<12> @BASEBOARD_FAB2_LIB.BASEBOARD_FAB2(SCH_1):M_L_DQ(13)
 168 M_L_DQ<10> DQ<11> @BASEBOARD_FAB2_LIB.BASEBOARD_FAB2(SCH_1):M_L_DQ(10)
  23 M_L_DQ<11> DQ<10> @BASEBOARD_FAB2_LIB.BASEBOARD_FAB2(SCH_1):M_L_DQ(11)
 161 M_L_DQ<8>  DQ<9> @BASEBOARD_FAB2_LIB.BASEBOARD_FAB2(SCH_1):M_L_DQ(8)
  16 M_L_DQ<9>  DQ<8> @BASEBOARD_FAB2_LIB.BASEBOARD_FAB2(SCH_1):M_L_DQ(9)
 155 M_L_DQ<6>  DQ<7> @BASEBOARD_FAB2_LIB.BASEBOARD_FAB2(SCH_1):M_L_DQ(6)
  10 M_L_DQ<7>  DQ<6> @BASEBOARD_FAB2_LIB.BASEBOARD_FAB2(SCH_1):M_L_DQ(7)
 148 M_L_DQ<4>  DQ<5> @BASEBOARD_FAB2_LIB.BASEBOARD_FAB2(SCH_1):M_L_DQ(4)
   3 M_L_DQ<5>  DQ<4> @BASEBOARD_FAB2_LIB.BASEBOARD_FAB2(SCH_1):M_L_DQ(5)
 157 M_L_DQ<2>  DQ<3> @BASEBOARD_FAB2_LIB.BASEBOARD_FAB2(SCH_1):M_L_DQ(2)
  12 M_L_DQ<3>  DQ<2> @BASEBOARD_FAB2_LIB.BASEBOARD_FAB2(SCH_1):M_L_DQ(3)
 150 M_L_DQ<0>  DQ<1> @BASEBOARD_FAB2_LIB.BASEBOARD_FAB2(SCH_1):M_L_DQ(0)
   5 M_L_DQ<1>  DQ<0> @BASEBOARD_FAB2_LIB.BASEBOARD_FAB2(SCH_1):M_L_DQ(1)
  78 FM_DIMM_EVENT_COD_N EVENT_N @BASEBOARD_FAB2_LIB.BASEBOARD_FAB2(SCH_1):FM_DIMM_EVENT_COD_N
  91 M_L_ODT<1> ODT<1> @BASEBOARD_FAB2_LIB.BASEBOARD_FAB2(SCH_1):M_L_ODT(1)
  87 M_L_ODT<0> ODT<0> @BASEBOARD_FAB2_LIB.BASEBOARD_FAB2(SCH_1):M_L_ODT(0)
 222 M_L_PAR    PAR @BASEBOARD_FAB2_LIB.BASEBOARD_FAB2(SCH_1):M_L_PAR
  58 M_KLM_RST_N RESET_N @BASEBOARD_FAB2_LIB.BASEBOARD_FAB2(SCH_1):M_KLM_RST_N
 144 TP_CH_L_DIMM_L0_RFU_2 RFU<2> @BASEBOARD_FAB2_LIB.BASEBOARD_FAB2(SCH_1):TP_CH_L_DIMM_L0_RFU_2
 227 TP_CH_L_DIMM_L0_RFU_1 RFU<1> @BASEBOARD_FAB2_LIB.BASEBOARD_FAB2(SCH_1):TP_CH_L_DIMM_L0_RFU_1
 205 TP_CH_L_DIMM_L0_RFU_0 RFU<0> @BASEBOARD_FAB2_LIB.BASEBOARD_FAB2(SCH_1):TP_CH_L_DIMM_L0_RFU_0
  84 M_L_CS_N<0>   S0_N @BASEBOARD_FAB2_LIB.BASEBOARD_FAB2(SCH_1):M_L_CS_N(0)
  89 M_L_CS_N<1>   S1_N @BASEBOARD_FAB2_LIB.BASEBOARD_FAB2(SCH_1):M_L_CS_N(1)
  93 M_L_CS_N<2> S2_N_C<0> @BASEBOARD_FAB2_LIB.BASEBOARD_FAB2(SCH_1):M_L_CS_N(2)
 237 M_L_CS_N<3> S3_N_C<1> @BASEBOARD_FAB2_LIB.BASEBOARD_FAB2(SCH_1):M_L_CS_N(3)
 238    GND  SA<2> @BASEBOARD_FAB2_LIB.BASEBOARD_FAB2(SCH_1):GND
 140 PVPP_KLM  SA<1> @BASEBOARD_FAB2_LIB.BASEBOARD_FAB2(SCH_1):PVPP_KLM
 139    GND  SA<0> @BASEBOARD_FAB2_LIB.BASEBOARD_FAB2(SCH_1):GND
 230 FM_ADR_COMPLETE_KLM_N SAVE_N_NC @BASEBOARD_FAB2_LIB.BASEBOARD_FAB2(SCH_1):FM_ADR_COMPLETE_KLM_N
 141 SMB_DDR_KLM_VPP_SCL    SCL @BASEBOARD_FAB2_LIB.BASEBOARD_FAB2(SCH_1):SMB_DDR_KLM_VPP_SCL
 285 SMB_DDR_KLM_VPP_SDA    SDA @BASEBOARD_FAB2_LIB.BASEBOARD_FAB2(SCH_1):SMB_DDR_KLM_VPP_SDA
 284 PVPP_KLM VDDSPD @BASEBOARD_FAB2_LIB.BASEBOARD_FAB2(SCH_1):PVPP_KLM
 146 M_L_VREF VREFCA @BASEBOARD_FAB2_LIB.BASEBOARD_FAB2(SCH_1):M_L_VREF

SCONN288_H44441004_PIP-SCONN,HA  I172  J1A2
   1 P12V_NVDIMM_KLM 12V<1> @BASEBOARD_FAB2_LIB.BASEBOARD_FAB2(SCH_1):P12V_NVDIMM_KLM
 145 P12V_NVDIMM_KLM 12V<0> @BASEBOARD_FAB2_LIB.BASEBOARD_FAB2(SCH_1):P12V_NVDIMM_KLM
  59 PVDDQ_KLM VDD<25> @BASEBOARD_FAB2_LIB.BASEBOARD_FAB2(SCH_1):PVDDQ_KLM
  61 PVDDQ_KLM VDD<24> @BASEBOARD_FAB2_LIB.BASEBOARD_FAB2(SCH_1):PVDDQ_KLM
  64 PVDDQ_KLM VDD<23> @BASEBOARD_FAB2_LIB.BASEBOARD_FAB2(SCH_1):PVDDQ_KLM
  67 PVDDQ_KLM VDD<22> @BASEBOARD_FAB2_LIB.BASEBOARD_FAB2(SCH_1):PVDDQ_KLM
  70 PVDDQ_KLM VDD<21> @BASEBOARD_FAB2_LIB.BASEBOARD_FAB2(SCH_1):PVDDQ_KLM
  73 PVDDQ_KLM VDD<20> @BASEBOARD_FAB2_LIB.BASEBOARD_FAB2(SCH_1):PVDDQ_KLM
  76 PVDDQ_KLM VDD<19> @BASEBOARD_FAB2_LIB.BASEBOARD_FAB2(SCH_1):PVDDQ_KLM
  80 PVDDQ_KLM VDD<18> @BASEBOARD_FAB2_LIB.BASEBOARD_FAB2(SCH_1):PVDDQ_KLM
  83 PVDDQ_KLM VDD<17> @BASEBOARD_FAB2_LIB.BASEBOARD_FAB2(SCH_1):PVDDQ_KLM
  85 PVDDQ_KLM VDD<16> @BASEBOARD_FAB2_LIB.BASEBOARD_FAB2(SCH_1):PVDDQ_KLM
  88 PVDDQ_KLM VDD<15> @BASEBOARD_FAB2_LIB.BASEBOARD_FAB2(SCH_1):PVDDQ_KLM
  90 PVDDQ_KLM VDD<14> @BASEBOARD_FAB2_LIB.BASEBOARD_FAB2(SCH_1):PVDDQ_KLM
  92 PVDDQ_KLM VDD<13> @BASEBOARD_FAB2_LIB.BASEBOARD_FAB2(SCH_1):PVDDQ_KLM
 204 PVDDQ_KLM VDD<12> @BASEBOARD_FAB2_LIB.BASEBOARD_FAB2(SCH_1):PVDDQ_KLM
 206 PVDDQ_KLM VDD<11> @BASEBOARD_FAB2_LIB.BASEBOARD_FAB2(SCH_1):PVDDQ_KLM
 209 PVDDQ_KLM VDD<10> @BASEBOARD_FAB2_LIB.BASEBOARD_FAB2(SCH_1):PVDDQ_KLM
 212 PVDDQ_KLM VDD<9> @BASEBOARD_FAB2_LIB.BASEBOARD_FAB2(SCH_1):PVDDQ_KLM
 215 PVDDQ_KLM VDD<8> @BASEBOARD_FAB2_LIB.BASEBOARD_FAB2(SCH_1):PVDDQ_KLM
 217 PVDDQ_KLM VDD<7> @BASEBOARD_FAB2_LIB.BASEBOARD_FAB2(SCH_1):PVDDQ_KLM
 220 PVDDQ_KLM VDD<6> @BASEBOARD_FAB2_LIB.BASEBOARD_FAB2(SCH_1):PVDDQ_KLM
 223 PVDDQ_KLM VDD<5> @BASEBOARD_FAB2_LIB.BASEBOARD_FAB2(SCH_1):PVDDQ_KLM
 226 PVDDQ_KLM VDD<4> @BASEBOARD_FAB2_LIB.BASEBOARD_FAB2(SCH_1):PVDDQ_KLM
 229 PVDDQ_KLM VDD<3> @BASEBOARD_FAB2_LIB.BASEBOARD_FAB2(SCH_1):PVDDQ_KLM
 231 PVDDQ_KLM VDD<2> @BASEBOARD_FAB2_LIB.BASEBOARD_FAB2(SCH_1):PVDDQ_KLM
 233 PVDDQ_KLM VDD<1> @BASEBOARD_FAB2_LIB.BASEBOARD_FAB2(SCH_1):PVDDQ_KLM
 236 PVDDQ_KLM VDD<0> @BASEBOARD_FAB2_LIB.BASEBOARD_FAB2(SCH_1):PVDDQ_KLM
 142 PVPP_KLM VPP<4> @BASEBOARD_FAB2_LIB.BASEBOARD_FAB2(SCH_1):PVPP_KLM
 143 PVPP_KLM VPP<3> @BASEBOARD_FAB2_LIB.BASEBOARD_FAB2(SCH_1):PVPP_KLM
 288 PVPP_KLM VPP<2> @BASEBOARD_FAB2_LIB.BASEBOARD_FAB2(SCH_1):PVPP_KLM
 286 PVPP_KLM VPP<1> @BASEBOARD_FAB2_LIB.BASEBOARD_FAB2(SCH_1):PVPP_KLM
 287 PVPP_KLM VPP<0> @BASEBOARD_FAB2_LIB.BASEBOARD_FAB2(SCH_1):PVPP_KLM
  77 PVTT_KLM VTT<1> @BASEBOARD_FAB2_LIB.BASEBOARD_FAB2(SCH_1):PVTT_KLM
 221 PVTT_KLM VTT<0> @BASEBOARD_FAB2_LIB.BASEBOARD_FAB2(SCH_1):PVTT_KLM

CAP_A_0402V-0.01UF,25V,10%,X7RA  I181  C9L7
   1 M_L_VREF      A @BASEBOARD_FAB2_LIB.BASEBOARD_FAB2(SCH_1):M_L_VREF
   2    GND      B @BASEBOARD_FAB2_LIB.BASEBOARD_FAB2(SCH_1):GND


DRAWING: @BASEBOARD_FAB2_LIB.BASEBOARD_FAB2(SCH_1):PAGE86 

SCONN288_H44441003_PIP-SCONN,HA  I12  J9L2
  79 M_L_MA<0>     A0 @BASEBOARD_FAB2_LIB.BASEBOARD_FAB2(SCH_1):M_L_MA(0)
  72 M_L_MA<1>     A1 @BASEBOARD_FAB2_LIB.BASEBOARD_FAB2(SCH_1):M_L_MA(1)
 225 M_L_MA<10>    A10 @BASEBOARD_FAB2_LIB.BASEBOARD_FAB2(SCH_1):M_L_MA(10)
 210 M_L_MA<11>    A11 @BASEBOARD_FAB2_LIB.BASEBOARD_FAB2(SCH_1):M_L_MA(11)
  65 M_L_MA<12>    A12 @BASEBOARD_FAB2_LIB.BASEBOARD_FAB2(SCH_1):M_L_MA(12)
 232 M_L_MA<13>    A13 @BASEBOARD_FAB2_LIB.BASEBOARD_FAB2(SCH_1):M_L_MA(13)
 228 M_L_MA<14> A14_WE_N @BASEBOARD_FAB2_LIB.BASEBOARD_FAB2(SCH_1):M_L_MA(14)
  86 M_L_MA<15> A15_CAS_N @BASEBOARD_FAB2_LIB.BASEBOARD_FAB2(SCH_1):M_L_MA(15)
  82 M_L_MA<16> A16_RAS_N @BASEBOARD_FAB2_LIB.BASEBOARD_FAB2(SCH_1):M_L_MA(16)
 234 M_L_MA<17>    A17 @BASEBOARD_FAB2_LIB.BASEBOARD_FAB2(SCH_1):M_L_MA(17)
 216 M_L_MA<2>     A2 @BASEBOARD_FAB2_LIB.BASEBOARD_FAB2(SCH_1):M_L_MA(2)
  71 M_L_MA<3>     A3 @BASEBOARD_FAB2_LIB.BASEBOARD_FAB2(SCH_1):M_L_MA(3)
 214 M_L_MA<4>     A4 @BASEBOARD_FAB2_LIB.BASEBOARD_FAB2(SCH_1):M_L_MA(4)
 213 M_L_MA<5>     A5 @BASEBOARD_FAB2_LIB.BASEBOARD_FAB2(SCH_1):M_L_MA(5)
  69 M_L_MA<6>     A6 @BASEBOARD_FAB2_LIB.BASEBOARD_FAB2(SCH_1):M_L_MA(6)
 211 M_L_MA<7>     A7 @BASEBOARD_FAB2_LIB.BASEBOARD_FAB2(SCH_1):M_L_MA(7)
  68 M_L_MA<8>     A8 @BASEBOARD_FAB2_LIB.BASEBOARD_FAB2(SCH_1):M_L_MA(8)
  66 M_L_MA<9>     A9 @BASEBOARD_FAB2_LIB.BASEBOARD_FAB2(SCH_1):M_L_MA(9)
  62 M_L_ACT_N  ACT_N @BASEBOARD_FAB2_LIB.BASEBOARD_FAB2(SCH_1):M_L_ACT_N
 208 M_L_ALERT_N ALERT_N @BASEBOARD_FAB2_LIB.BASEBOARD_FAB2(SCH_1):M_L_ALERT_N
 224 M_L_BA<1>  BA<1> @BASEBOARD_FAB2_LIB.BASEBOARD_FAB2(SCH_1):M_L_BA(1)
  81 M_L_BA<0>  BA<0> @BASEBOARD_FAB2_LIB.BASEBOARD_FAB2(SCH_1):M_L_BA(0)
 207 M_L_BG<1>  BG<1> @BASEBOARD_FAB2_LIB.BASEBOARD_FAB2(SCH_1):M_L_BG(1)
  63 M_L_BG<0>  BG<0> @BASEBOARD_FAB2_LIB.BASEBOARD_FAB2(SCH_1):M_L_BG(0)
 235 M_L_C<2>   C<2> @BASEBOARD_FAB2_LIB.BASEBOARD_FAB2(SCH_1):M_L_C(2)
 199 M_L_ECC<7>  CB<7> @BASEBOARD_FAB2_LIB.BASEBOARD_FAB2(SCH_1):M_L_ECC(7)
  54 M_L_ECC<6>  CB<6> @BASEBOARD_FAB2_LIB.BASEBOARD_FAB2(SCH_1):M_L_ECC(6)
 192 M_L_ECC<5>  CB<5> @BASEBOARD_FAB2_LIB.BASEBOARD_FAB2(SCH_1):M_L_ECC(5)
  47 M_L_ECC<4>  CB<4> @BASEBOARD_FAB2_LIB.BASEBOARD_FAB2(SCH_1):M_L_ECC(4)
 201 M_L_ECC<3>  CB<3> @BASEBOARD_FAB2_LIB.BASEBOARD_FAB2(SCH_1):M_L_ECC(3)
  56 M_L_ECC<2>  CB<2> @BASEBOARD_FAB2_LIB.BASEBOARD_FAB2(SCH_1):M_L_ECC(2)
 194 M_L_ECC<1>  CB<1> @BASEBOARD_FAB2_LIB.BASEBOARD_FAB2(SCH_1):M_L_ECC(1)
  49 M_L_ECC<0>  CB<0> @BASEBOARD_FAB2_LIB.BASEBOARD_FAB2(SCH_1):M_L_ECC(0)
  75 M_L_CLK_DN<2>   CK0N @BASEBOARD_FAB2_LIB.BASEBOARD_FAB2(SCH_1):M_L_CLK_DN(2)
  74 M_L_CLK_DP<2>   CK0P @BASEBOARD_FAB2_LIB.BASEBOARD_FAB2(SCH_1):M_L_CLK_DP(2)
 219 M_L_CLK_DN<3>   CK1N @BASEBOARD_FAB2_LIB.BASEBOARD_FAB2(SCH_1):M_L_CLK_DN(3)
 218 M_L_CLK_DP<3>   CK1P @BASEBOARD_FAB2_LIB.BASEBOARD_FAB2(SCH_1):M_L_CLK_DP(3)
 203 M_L_CKE<3> CKE<1> @BASEBOARD_FAB2_LIB.BASEBOARD_FAB2(SCH_1):M_L_CKE(3)
  60 M_L_CKE<2> CKE<0> @BASEBOARD_FAB2_LIB.BASEBOARD_FAB2(SCH_1):M_L_CKE(2)
 280 M_L_DQ<63> DQ<63> @BASEBOARD_FAB2_LIB.BASEBOARD_FAB2(SCH_1):M_L_DQ(63)
 135 M_L_DQ<62> DQ<62> @BASEBOARD_FAB2_LIB.BASEBOARD_FAB2(SCH_1):M_L_DQ(62)
 273 M_L_DQ<61> DQ<61> @BASEBOARD_FAB2_LIB.BASEBOARD_FAB2(SCH_1):M_L_DQ(61)
 128 M_L_DQ<60> DQ<60> @BASEBOARD_FAB2_LIB.BASEBOARD_FAB2(SCH_1):M_L_DQ(60)
 282 M_L_DQ<59> DQ<59> @BASEBOARD_FAB2_LIB.BASEBOARD_FAB2(SCH_1):M_L_DQ(59)
 137 M_L_DQ<58> DQ<58> @BASEBOARD_FAB2_LIB.BASEBOARD_FAB2(SCH_1):M_L_DQ(58)
 275 M_L_DQ<57> DQ<57> @BASEBOARD_FAB2_LIB.BASEBOARD_FAB2(SCH_1):M_L_DQ(57)
 130 M_L_DQ<56> DQ<56> @BASEBOARD_FAB2_LIB.BASEBOARD_FAB2(SCH_1):M_L_DQ(56)
 269 M_L_DQ<55> DQ<55> @BASEBOARD_FAB2_LIB.BASEBOARD_FAB2(SCH_1):M_L_DQ(55)
 124 M_L_DQ<54> DQ<54> @BASEBOARD_FAB2_LIB.BASEBOARD_FAB2(SCH_1):M_L_DQ(54)
 262 M_L_DQ<53> DQ<53> @BASEBOARD_FAB2_LIB.BASEBOARD_FAB2(SCH_1):M_L_DQ(53)
 117 M_L_DQ<52> DQ<52> @BASEBOARD_FAB2_LIB.BASEBOARD_FAB2(SCH_1):M_L_DQ(52)
 271 M_L_DQ<51> DQ<51> @BASEBOARD_FAB2_LIB.BASEBOARD_FAB2(SCH_1):M_L_DQ(51)
 126 M_L_DQ<50> DQ<50> @BASEBOARD_FAB2_LIB.BASEBOARD_FAB2(SCH_1):M_L_DQ(50)
 264 M_L_DQ<49> DQ<49> @BASEBOARD_FAB2_LIB.BASEBOARD_FAB2(SCH_1):M_L_DQ(49)
 119 M_L_DQ<48> DQ<48> @BASEBOARD_FAB2_LIB.BASEBOARD_FAB2(SCH_1):M_L_DQ(48)
 258 M_L_DQ<47> DQ<47> @BASEBOARD_FAB2_LIB.BASEBOARD_FAB2(SCH_1):M_L_DQ(47)
 113 M_L_DQ<46> DQ<46> @BASEBOARD_FAB2_LIB.BASEBOARD_FAB2(SCH_1):M_L_DQ(46)
 251 M_L_DQ<45> DQ<45> @BASEBOARD_FAB2_LIB.BASEBOARD_FAB2(SCH_1):M_L_DQ(45)
 106 M_L_DQ<44> DQ<44> @BASEBOARD_FAB2_LIB.BASEBOARD_FAB2(SCH_1):M_L_DQ(44)
 260 M_L_DQ<43> DQ<43> @BASEBOARD_FAB2_LIB.BASEBOARD_FAB2(SCH_1):M_L_DQ(43)
 115 M_L_DQ<42> DQ<42> @BASEBOARD_FAB2_LIB.BASEBOARD_FAB2(SCH_1):M_L_DQ(42)
 253 M_L_DQ<41> DQ<41> @BASEBOARD_FAB2_LIB.BASEBOARD_FAB2(SCH_1):M_L_DQ(41)
 108 M_L_DQ<40> DQ<40> @BASEBOARD_FAB2_LIB.BASEBOARD_FAB2(SCH_1):M_L_DQ(40)
 247 M_L_DQ<39> DQ<39> @BASEBOARD_FAB2_LIB.BASEBOARD_FAB2(SCH_1):M_L_DQ(39)
 102 M_L_DQ<38> DQ<38> @BASEBOARD_FAB2_LIB.BASEBOARD_FAB2(SCH_1):M_L_DQ(38)
 240 M_L_DQ<37> DQ<37> @BASEBOARD_FAB2_LIB.BASEBOARD_FAB2(SCH_1):M_L_DQ(37)
  95 M_L_DQ<36> DQ<36> @BASEBOARD_FAB2_LIB.BASEBOARD_FAB2(SCH_1):M_L_DQ(36)
 249 M_L_DQ<35> DQ<35> @BASEBOARD_FAB2_LIB.BASEBOARD_FAB2(SCH_1):M_L_DQ(35)
 104 M_L_DQ<34> DQ<34> @BASEBOARD_FAB2_LIB.BASEBOARD_FAB2(SCH_1):M_L_DQ(34)
 242 M_L_DQ<33> DQ<33> @BASEBOARD_FAB2_LIB.BASEBOARD_FAB2(SCH_1):M_L_DQ(33)
  97 M_L_DQ<32> DQ<32> @BASEBOARD_FAB2_LIB.BASEBOARD_FAB2(SCH_1):M_L_DQ(32)
 188 M_L_DQ<31> DQ<31> @BASEBOARD_FAB2_LIB.BASEBOARD_FAB2(SCH_1):M_L_DQ(31)
  43 M_L_DQ<30> DQ<30> @BASEBOARD_FAB2_LIB.BASEBOARD_FAB2(SCH_1):M_L_DQ(30)
 181 M_L_DQ<29> DQ<29> @BASEBOARD_FAB2_LIB.BASEBOARD_FAB2(SCH_1):M_L_DQ(29)
  36 M_L_DQ<28> DQ<28> @BASEBOARD_FAB2_LIB.BASEBOARD_FAB2(SCH_1):M_L_DQ(28)
 190 M_L_DQ<27> DQ<27> @BASEBOARD_FAB2_LIB.BASEBOARD_FAB2(SCH_1):M_L_DQ(27)
  45 M_L_DQ<26> DQ<26> @BASEBOARD_FAB2_LIB.BASEBOARD_FAB2(SCH_1):M_L_DQ(26)
 183 M_L_DQ<25> DQ<25> @BASEBOARD_FAB2_LIB.BASEBOARD_FAB2(SCH_1):M_L_DQ(25)
  38 M_L_DQ<24> DQ<24> @BASEBOARD_FAB2_LIB.BASEBOARD_FAB2(SCH_1):M_L_DQ(24)
 177 M_L_DQ<23> DQ<23> @BASEBOARD_FAB2_LIB.BASEBOARD_FAB2(SCH_1):M_L_DQ(23)
  32 M_L_DQ<22> DQ<22> @BASEBOARD_FAB2_LIB.BASEBOARD_FAB2(SCH_1):M_L_DQ(22)
 170 M_L_DQ<21> DQ<21> @BASEBOARD_FAB2_LIB.BASEBOARD_FAB2(SCH_1):M_L_DQ(21)
  25 M_L_DQ<20> DQ<20> @BASEBOARD_FAB2_LIB.BASEBOARD_FAB2(SCH_1):M_L_DQ(20)
 179 M_L_DQ<19> DQ<19> @BASEBOARD_FAB2_LIB.BASEBOARD_FAB2(SCH_1):M_L_DQ(19)
  34 M_L_DQ<18> DQ<18> @BASEBOARD_FAB2_LIB.BASEBOARD_FAB2(SCH_1):M_L_DQ(18)
 172 M_L_DQ<17> DQ<17> @BASEBOARD_FAB2_LIB.BASEBOARD_FAB2(SCH_1):M_L_DQ(17)
  27 M_L_DQ<16> DQ<16> @BASEBOARD_FAB2_LIB.BASEBOARD_FAB2(SCH_1):M_L_DQ(16)
 166 M_L_DQ<15> DQ<15> @BASEBOARD_FAB2_LIB.BASEBOARD_FAB2(SCH_1):M_L_DQ(15)
  21 M_L_DQ<14> DQ<14> @BASEBOARD_FAB2_LIB.BASEBOARD_FAB2(SCH_1):M_L_DQ(14)
 159 M_L_DQ<13> DQ<13> @BASEBOARD_FAB2_LIB.BASEBOARD_FAB2(SCH_1):M_L_DQ(13)
  14 M_L_DQ<12> DQ<12> @BASEBOARD_FAB2_LIB.BASEBOARD_FAB2(SCH_1):M_L_DQ(12)
 168 M_L_DQ<11> DQ<11> @BASEBOARD_FAB2_LIB.BASEBOARD_FAB2(SCH_1):M_L_DQ(11)
  23 M_L_DQ<10> DQ<10> @BASEBOARD_FAB2_LIB.BASEBOARD_FAB2(SCH_1):M_L_DQ(10)
 161 M_L_DQ<9>  DQ<9> @BASEBOARD_FAB2_LIB.BASEBOARD_FAB2(SCH_1):M_L_DQ(9)
  16 M_L_DQ<8>  DQ<8> @BASEBOARD_FAB2_LIB.BASEBOARD_FAB2(SCH_1):M_L_DQ(8)
 155 M_L_DQ<7>  DQ<7> @BASEBOARD_FAB2_LIB.BASEBOARD_FAB2(SCH_1):M_L_DQ(7)
  10 M_L_DQ<6>  DQ<6> @BASEBOARD_FAB2_LIB.BASEBOARD_FAB2(SCH_1):M_L_DQ(6)
 148 M_L_DQ<5>  DQ<5> @BASEBOARD_FAB2_LIB.BASEBOARD_FAB2(SCH_1):M_L_DQ(5)
   3 M_L_DQ<4>  DQ<4> @BASEBOARD_FAB2_LIB.BASEBOARD_FAB2(SCH_1):M_L_DQ(4)
 157 M_L_DQ<3>  DQ<3> @BASEBOARD_FAB2_LIB.BASEBOARD_FAB2(SCH_1):M_L_DQ(3)
  12 M_L_DQ<2>  DQ<2> @BASEBOARD_FAB2_LIB.BASEBOARD_FAB2(SCH_1):M_L_DQ(2)
 150 M_L_DQ<1>  DQ<1> @BASEBOARD_FAB2_LIB.BASEBOARD_FAB2(SCH_1):M_L_DQ(1)
   5 M_L_DQ<0>  DQ<0> @BASEBOARD_FAB2_LIB.BASEBOARD_FAB2(SCH_1):M_L_DQ(0)
  78 FM_DIMM_EVENT_COD_N EVENT_N @BASEBOARD_FAB2_LIB.BASEBOARD_FAB2(SCH_1):FM_DIMM_EVENT_COD_N
  91 M_L_ODT<3> ODT<1> @BASEBOARD_FAB2_LIB.BASEBOARD_FAB2(SCH_1):M_L_ODT(3)
  87 M_L_ODT<2> ODT<0> @BASEBOARD_FAB2_LIB.BASEBOARD_FAB2(SCH_1):M_L_ODT(2)
 222 M_L_PAR    PAR @BASEBOARD_FAB2_LIB.BASEBOARD_FAB2(SCH_1):M_L_PAR
  58 M_KLM_RST_N RESET_N @BASEBOARD_FAB2_LIB.BASEBOARD_FAB2(SCH_1):M_KLM_RST_N
 144 TP_CH_L_DIMM0_RFU_2 RFU<2> @BASEBOARD_FAB2_LIB.BASEBOARD_FAB2(SCH_1):TP_CH_L_DIMM0_RFU_2
 227 TP_CH_L_DIMM0_RFU_1 RFU<1> @BASEBOARD_FAB2_LIB.BASEBOARD_FAB2(SCH_1):TP_CH_L_DIMM0_RFU_1
 205 TP_CH_L_DIMM0_RFU_0 RFU<0> @BASEBOARD_FAB2_LIB.BASEBOARD_FAB2(SCH_1):TP_CH_L_DIMM0_RFU_0
  84 M_L_CS_N<4>   S0_N @BASEBOARD_FAB2_LIB.BASEBOARD_FAB2(SCH_1):M_L_CS_N(4)
  89 M_L_CS_N<5>   S1_N @BASEBOARD_FAB2_LIB.BASEBOARD_FAB2(SCH_1):M_L_CS_N(5)
  93 M_L_CS_N<6> S2_N_C<0> @BASEBOARD_FAB2_LIB.BASEBOARD_FAB2(SCH_1):M_L_CS_N(6)
 237 M_L_CS_N<7> S3_N_C<1> @BASEBOARD_FAB2_LIB.BASEBOARD_FAB2(SCH_1):M_L_CS_N(7)
 238    GND  SA<2> @BASEBOARD_FAB2_LIB.BASEBOARD_FAB2(SCH_1):GND
 140 PVPP_KLM  SA<1> @BASEBOARD_FAB2_LIB.BASEBOARD_FAB2(SCH_1):PVPP_KLM
 139 PVPP_KLM  SA<0> @BASEBOARD_FAB2_LIB.BASEBOARD_FAB2(SCH_1):PVPP_KLM
 230 FM_ADR_COMPLETE_KLM_N SAVE_N_NC @BASEBOARD_FAB2_LIB.BASEBOARD_FAB2(SCH_1):FM_ADR_COMPLETE_KLM_N
 141 SMB_DDR_KLM_VPP_SCL    SCL @BASEBOARD_FAB2_LIB.BASEBOARD_FAB2(SCH_1):SMB_DDR_KLM_VPP_SCL
 285 SMB_DDR_KLM_VPP_SDA    SDA @BASEBOARD_FAB2_LIB.BASEBOARD_FAB2(SCH_1):SMB_DDR_KLM_VPP_SDA
 284 PVPP_KLM VDDSPD @BASEBOARD_FAB2_LIB.BASEBOARD_FAB2(SCH_1):PVPP_KLM
 146 M_L_VREF VREFCA @BASEBOARD_FAB2_LIB.BASEBOARD_FAB2(SCH_1):M_L_VREF

SCONN288_H44441003_PIP-SCONN,HA  I55  J9L2
   1 P12V_NVDIMM_KLM 12V<1> @BASEBOARD_FAB2_LIB.BASEBOARD_FAB2(SCH_1):P12V_NVDIMM_KLM
 145 P12V_NVDIMM_KLM 12V<0> @BASEBOARD_FAB2_LIB.BASEBOARD_FAB2(SCH_1):P12V_NVDIMM_KLM
  59 PVDDQ_KLM VDD<25> @BASEBOARD_FAB2_LIB.BASEBOARD_FAB2(SCH_1):PVDDQ_KLM
  61 PVDDQ_KLM VDD<24> @BASEBOARD_FAB2_LIB.BASEBOARD_FAB2(SCH_1):PVDDQ_KLM
  64 PVDDQ_KLM VDD<23> @BASEBOARD_FAB2_LIB.BASEBOARD_FAB2(SCH_1):PVDDQ_KLM
  67 PVDDQ_KLM VDD<22> @BASEBOARD_FAB2_LIB.BASEBOARD_FAB2(SCH_1):PVDDQ_KLM
  70 PVDDQ_KLM VDD<21> @BASEBOARD_FAB2_LIB.BASEBOARD_FAB2(SCH_1):PVDDQ_KLM
  73 PVDDQ_KLM VDD<20> @BASEBOARD_FAB2_LIB.BASEBOARD_FAB2(SCH_1):PVDDQ_KLM
  76 PVDDQ_KLM VDD<19> @BASEBOARD_FAB2_LIB.BASEBOARD_FAB2(SCH_1):PVDDQ_KLM
  80 PVDDQ_KLM VDD<18> @BASEBOARD_FAB2_LIB.BASEBOARD_FAB2(SCH_1):PVDDQ_KLM
  83 PVDDQ_KLM VDD<17> @BASEBOARD_FAB2_LIB.BASEBOARD_FAB2(SCH_1):PVDDQ_KLM
  85 PVDDQ_KLM VDD<16> @BASEBOARD_FAB2_LIB.BASEBOARD_FAB2(SCH_1):PVDDQ_KLM
  88 PVDDQ_KLM VDD<15> @BASEBOARD_FAB2_LIB.BASEBOARD_FAB2(SCH_1):PVDDQ_KLM
  90 PVDDQ_KLM VDD<14> @BASEBOARD_FAB2_LIB.BASEBOARD_FAB2(SCH_1):PVDDQ_KLM
  92 PVDDQ_KLM VDD<13> @BASEBOARD_FAB2_LIB.BASEBOARD_FAB2(SCH_1):PVDDQ_KLM
 204 PVDDQ_KLM VDD<12> @BASEBOARD_FAB2_LIB.BASEBOARD_FAB2(SCH_1):PVDDQ_KLM
 206 PVDDQ_KLM VDD<11> @BASEBOARD_FAB2_LIB.BASEBOARD_FAB2(SCH_1):PVDDQ_KLM
 209 PVDDQ_KLM VDD<10> @BASEBOARD_FAB2_LIB.BASEBOARD_FAB2(SCH_1):PVDDQ_KLM
 212 PVDDQ_KLM VDD<9> @BASEBOARD_FAB2_LIB.BASEBOARD_FAB2(SCH_1):PVDDQ_KLM
 215 PVDDQ_KLM VDD<8> @BASEBOARD_FAB2_LIB.BASEBOARD_FAB2(SCH_1):PVDDQ_KLM
 217 PVDDQ_KLM VDD<7> @BASEBOARD_FAB2_LIB.BASEBOARD_FAB2(SCH_1):PVDDQ_KLM
 220 PVDDQ_KLM VDD<6> @BASEBOARD_FAB2_LIB.BASEBOARD_FAB2(SCH_1):PVDDQ_KLM
 223 PVDDQ_KLM VDD<5> @BASEBOARD_FAB2_LIB.BASEBOARD_FAB2(SCH_1):PVDDQ_KLM
 226 PVDDQ_KLM VDD<4> @BASEBOARD_FAB2_LIB.BASEBOARD_FAB2(SCH_1):PVDDQ_KLM
 229 PVDDQ_KLM VDD<3> @BASEBOARD_FAB2_LIB.BASEBOARD_FAB2(SCH_1):PVDDQ_KLM
 231 PVDDQ_KLM VDD<2> @BASEBOARD_FAB2_LIB.BASEBOARD_FAB2(SCH_1):PVDDQ_KLM
 233 PVDDQ_KLM VDD<1> @BASEBOARD_FAB2_LIB.BASEBOARD_FAB2(SCH_1):PVDDQ_KLM
 236 PVDDQ_KLM VDD<0> @BASEBOARD_FAB2_LIB.BASEBOARD_FAB2(SCH_1):PVDDQ_KLM
 142 PVPP_KLM VPP<4> @BASEBOARD_FAB2_LIB.BASEBOARD_FAB2(SCH_1):PVPP_KLM
 143 PVPP_KLM VPP<3> @BASEBOARD_FAB2_LIB.BASEBOARD_FAB2(SCH_1):PVPP_KLM
 288 PVPP_KLM VPP<2> @BASEBOARD_FAB2_LIB.BASEBOARD_FAB2(SCH_1):PVPP_KLM
 286 PVPP_KLM VPP<1> @BASEBOARD_FAB2_LIB.BASEBOARD_FAB2(SCH_1):PVPP_KLM
 287 PVPP_KLM VPP<0> @BASEBOARD_FAB2_LIB.BASEBOARD_FAB2(SCH_1):PVPP_KLM
  77 PVTT_KLM VTT<1> @BASEBOARD_FAB2_LIB.BASEBOARD_FAB2(SCH_1):PVTT_KLM
 221 PVTT_KLM VTT<0> @BASEBOARD_FAB2_LIB.BASEBOARD_FAB2(SCH_1):PVTT_KLM

SCONN288_H44441003_PIP-SCONN,HA  I100  J9L2
 152 M_L_DQS_DN<0>  DQS0N @BASEBOARD_FAB2_LIB.BASEBOARD_FAB2(SCH_1):M_L_DQS_DN(0)
 153 M_L_DQS_DP<0>  DQS0P @BASEBOARD_FAB2_LIB.BASEBOARD_FAB2(SCH_1):M_L_DQS_DP(0)
  19 M_L_DQS_DN<10> DQS10N @BASEBOARD_FAB2_LIB.BASEBOARD_FAB2(SCH_1):M_L_DQS_DN(10)
  18 M_L_DQS_DP<10> DQS10P @BASEBOARD_FAB2_LIB.BASEBOARD_FAB2(SCH_1):M_L_DQS_DP(10)
  30 M_L_DQS_DN<11> DQS11N @BASEBOARD_FAB2_LIB.BASEBOARD_FAB2(SCH_1):M_L_DQS_DN(11)
  29 M_L_DQS_DP<11> DQS11P @BASEBOARD_FAB2_LIB.BASEBOARD_FAB2(SCH_1):M_L_DQS_DP(11)
  41 M_L_DQS_DN<12> DQS12N @BASEBOARD_FAB2_LIB.BASEBOARD_FAB2(SCH_1):M_L_DQS_DN(12)
  40 M_L_DQS_DP<12> DQS12P @BASEBOARD_FAB2_LIB.BASEBOARD_FAB2(SCH_1):M_L_DQS_DP(12)
 100 M_L_DQS_DN<13> DQS13N @BASEBOARD_FAB2_LIB.BASEBOARD_FAB2(SCH_1):M_L_DQS_DN(13)
  99 M_L_DQS_DP<13> DQS13P @BASEBOARD_FAB2_LIB.BASEBOARD_FAB2(SCH_1):M_L_DQS_DP(13)
 111 M_L_DQS_DN<14> DQS14N @BASEBOARD_FAB2_LIB.BASEBOARD_FAB2(SCH_1):M_L_DQS_DN(14)
 110 M_L_DQS_DP<14> DQS14P @BASEBOARD_FAB2_LIB.BASEBOARD_FAB2(SCH_1):M_L_DQS_DP(14)
 122 M_L_DQS_DN<15> DQS15N @BASEBOARD_FAB2_LIB.BASEBOARD_FAB2(SCH_1):M_L_DQS_DN(15)
 121 M_L_DQS_DP<15> DQS15P @BASEBOARD_FAB2_LIB.BASEBOARD_FAB2(SCH_1):M_L_DQS_DP(15)
 133 M_L_DQS_DN<16> DQS16N @BASEBOARD_FAB2_LIB.BASEBOARD_FAB2(SCH_1):M_L_DQS_DN(16)
 132 M_L_DQS_DP<16> DQS16P @BASEBOARD_FAB2_LIB.BASEBOARD_FAB2(SCH_1):M_L_DQS_DP(16)
  52 M_L_DQS_DN<17> DQS17N @BASEBOARD_FAB2_LIB.BASEBOARD_FAB2(SCH_1):M_L_DQS_DN(17)
  51 M_L_DQS_DP<17> DQS17P @BASEBOARD_FAB2_LIB.BASEBOARD_FAB2(SCH_1):M_L_DQS_DP(17)
 163 M_L_DQS_DN<1>  DQS1N @BASEBOARD_FAB2_LIB.BASEBOARD_FAB2(SCH_1):M_L_DQS_DN(1)
 164 M_L_DQS_DP<1>  DQS1P @BASEBOARD_FAB2_LIB.BASEBOARD_FAB2(SCH_1):M_L_DQS_DP(1)
 174 M_L_DQS_DN<2>  DQS2N @BASEBOARD_FAB2_LIB.BASEBOARD_FAB2(SCH_1):M_L_DQS_DN(2)
 175 M_L_DQS_DP<2>  DQS2P @BASEBOARD_FAB2_LIB.BASEBOARD_FAB2(SCH_1):M_L_DQS_DP(2)
 185 M_L_DQS_DN<3>  DQS3N @BASEBOARD_FAB2_LIB.BASEBOARD_FAB2(SCH_1):M_L_DQS_DN(3)
 186 M_L_DQS_DP<3>  DQS3P @BASEBOARD_FAB2_LIB.BASEBOARD_FAB2(SCH_1):M_L_DQS_DP(3)
 244 M_L_DQS_DN<4>  DQS4N @BASEBOARD_FAB2_LIB.BASEBOARD_FAB2(SCH_1):M_L_DQS_DN(4)
 245 M_L_DQS_DP<4>  DQS4P @BASEBOARD_FAB2_LIB.BASEBOARD_FAB2(SCH_1):M_L_DQS_DP(4)
 255 M_L_DQS_DN<5>  DQS5N @BASEBOARD_FAB2_LIB.BASEBOARD_FAB2(SCH_1):M_L_DQS_DN(5)
 256 M_L_DQS_DP<5>  DQS5P @BASEBOARD_FAB2_LIB.BASEBOARD_FAB2(SCH_1):M_L_DQS_DP(5)
 266 M_L_DQS_DN<6>  DQS6N @BASEBOARD_FAB2_LIB.BASEBOARD_FAB2(SCH_1):M_L_DQS_DN(6)
 267 M_L_DQS_DP<6>  DQS6P @BASEBOARD_FAB2_LIB.BASEBOARD_FAB2(SCH_1):M_L_DQS_DP(6)
 277 M_L_DQS_DN<7>  DQS7N @BASEBOARD_FAB2_LIB.BASEBOARD_FAB2(SCH_1):M_L_DQS_DN(7)
 278 M_L_DQS_DP<7>  DQS7P @BASEBOARD_FAB2_LIB.BASEBOARD_FAB2(SCH_1):M_L_DQS_DP(7)
 196 M_L_DQS_DN<8>  DQS8N @BASEBOARD_FAB2_LIB.BASEBOARD_FAB2(SCH_1):M_L_DQS_DN(8)
 197 M_L_DQS_DP<8>  DQS8P @BASEBOARD_FAB2_LIB.BASEBOARD_FAB2(SCH_1):M_L_DQS_DP(8)
   8 M_L_DQS_DN<9>  DQS9N @BASEBOARD_FAB2_LIB.BASEBOARD_FAB2(SCH_1):M_L_DQS_DN(9)
   7 M_L_DQS_DP<9>  DQS9P @BASEBOARD_FAB2_LIB.BASEBOARD_FAB2(SCH_1):M_L_DQS_DP(9)

SCONN288_H44441003_PIP-SCONN,HA  I138  J9L2
   2    GND VSS<93> @BASEBOARD_FAB2_LIB.BASEBOARD_FAB2(SCH_1):GND
   4    GND VSS<92> @BASEBOARD_FAB2_LIB.BASEBOARD_FAB2(SCH_1):GND
   6    GND VSS<91> @BASEBOARD_FAB2_LIB.BASEBOARD_FAB2(SCH_1):GND
   9    GND VSS<90> @BASEBOARD_FAB2_LIB.BASEBOARD_FAB2(SCH_1):GND
  11    GND VSS<89> @BASEBOARD_FAB2_LIB.BASEBOARD_FAB2(SCH_1):GND
  13    GND VSS<88> @BASEBOARD_FAB2_LIB.BASEBOARD_FAB2(SCH_1):GND
  15    GND VSS<87> @BASEBOARD_FAB2_LIB.BASEBOARD_FAB2(SCH_1):GND
  17    GND VSS<86> @BASEBOARD_FAB2_LIB.BASEBOARD_FAB2(SCH_1):GND
  20    GND VSS<85> @BASEBOARD_FAB2_LIB.BASEBOARD_FAB2(SCH_1):GND
  22    GND VSS<84> @BASEBOARD_FAB2_LIB.BASEBOARD_FAB2(SCH_1):GND
  24    GND VSS<83> @BASEBOARD_FAB2_LIB.BASEBOARD_FAB2(SCH_1):GND
  26    GND VSS<82> @BASEBOARD_FAB2_LIB.BASEBOARD_FAB2(SCH_1):GND
  28    GND VSS<81> @BASEBOARD_FAB2_LIB.BASEBOARD_FAB2(SCH_1):GND
  31    GND VSS<80> @BASEBOARD_FAB2_LIB.BASEBOARD_FAB2(SCH_1):GND
  33    GND VSS<79> @BASEBOARD_FAB2_LIB.BASEBOARD_FAB2(SCH_1):GND
  35    GND VSS<78> @BASEBOARD_FAB2_LIB.BASEBOARD_FAB2(SCH_1):GND
  37    GND VSS<77> @BASEBOARD_FAB2_LIB.BASEBOARD_FAB2(SCH_1):GND
  39    GND VSS<76> @BASEBOARD_FAB2_LIB.BASEBOARD_FAB2(SCH_1):GND
  42    GND VSS<75> @BASEBOARD_FAB2_LIB.BASEBOARD_FAB2(SCH_1):GND
  44    GND VSS<74> @BASEBOARD_FAB2_LIB.BASEBOARD_FAB2(SCH_1):GND
  46    GND VSS<73> @BASEBOARD_FAB2_LIB.BASEBOARD_FAB2(SCH_1):GND
  48    GND VSS<72> @BASEBOARD_FAB2_LIB.BASEBOARD_FAB2(SCH_1):GND
  50    GND VSS<71> @BASEBOARD_FAB2_LIB.BASEBOARD_FAB2(SCH_1):GND
  53    GND VSS<70> @BASEBOARD_FAB2_LIB.BASEBOARD_FAB2(SCH_1):GND
  55    GND VSS<69> @BASEBOARD_FAB2_LIB.BASEBOARD_FAB2(SCH_1):GND
  57    GND VSS<68> @BASEBOARD_FAB2_LIB.BASEBOARD_FAB2(SCH_1):GND
  94    GND VSS<67> @BASEBOARD_FAB2_LIB.BASEBOARD_FAB2(SCH_1):GND
  96    GND VSS<66> @BASEBOARD_FAB2_LIB.BASEBOARD_FAB2(SCH_1):GND
  98    GND VSS<65> @BASEBOARD_FAB2_LIB.BASEBOARD_FAB2(SCH_1):GND
 101    GND VSS<64> @BASEBOARD_FAB2_LIB.BASEBOARD_FAB2(SCH_1):GND
 103    GND VSS<63> @BASEBOARD_FAB2_LIB.BASEBOARD_FAB2(SCH_1):GND
 105    GND VSS<62> @BASEBOARD_FAB2_LIB.BASEBOARD_FAB2(SCH_1):GND
 107    GND VSS<61> @BASEBOARD_FAB2_LIB.BASEBOARD_FAB2(SCH_1):GND
 109    GND VSS<60> @BASEBOARD_FAB2_LIB.BASEBOARD_FAB2(SCH_1):GND
 112    GND VSS<59> @BASEBOARD_FAB2_LIB.BASEBOARD_FAB2(SCH_1):GND
 114    GND VSS<58> @BASEBOARD_FAB2_LIB.BASEBOARD_FAB2(SCH_1):GND
 116    GND VSS<57> @BASEBOARD_FAB2_LIB.BASEBOARD_FAB2(SCH_1):GND
 118    GND VSS<56> @BASEBOARD_FAB2_LIB.BASEBOARD_FAB2(SCH_1):GND
 120    GND VSS<55> @BASEBOARD_FAB2_LIB.BASEBOARD_FAB2(SCH_1):GND
 123    GND VSS<54> @BASEBOARD_FAB2_LIB.BASEBOARD_FAB2(SCH_1):GND
 125    GND VSS<53> @BASEBOARD_FAB2_LIB.BASEBOARD_FAB2(SCH_1):GND
 127    GND VSS<52> @BASEBOARD_FAB2_LIB.BASEBOARD_FAB2(SCH_1):GND
 129    GND VSS<51> @BASEBOARD_FAB2_LIB.BASEBOARD_FAB2(SCH_1):GND
 131    GND VSS<50> @BASEBOARD_FAB2_LIB.BASEBOARD_FAB2(SCH_1):GND
 134    GND VSS<49> @BASEBOARD_FAB2_LIB.BASEBOARD_FAB2(SCH_1):GND
 136    GND VSS<48> @BASEBOARD_FAB2_LIB.BASEBOARD_FAB2(SCH_1):GND
 138    GND VSS<47> @BASEBOARD_FAB2_LIB.BASEBOARD_FAB2(SCH_1):GND
 147    GND VSS<46> @BASEBOARD_FAB2_LIB.BASEBOARD_FAB2(SCH_1):GND
 149    GND VSS<45> @BASEBOARD_FAB2_LIB.BASEBOARD_FAB2(SCH_1):GND
 151    GND VSS<44> @BASEBOARD_FAB2_LIB.BASEBOARD_FAB2(SCH_1):GND
 154    GND VSS<43> @BASEBOARD_FAB2_LIB.BASEBOARD_FAB2(SCH_1):GND
 156    GND VSS<42> @BASEBOARD_FAB2_LIB.BASEBOARD_FAB2(SCH_1):GND
 158    GND VSS<41> @BASEBOARD_FAB2_LIB.BASEBOARD_FAB2(SCH_1):GND
 160    GND VSS<40> @BASEBOARD_FAB2_LIB.BASEBOARD_FAB2(SCH_1):GND
 162    GND VSS<39> @BASEBOARD_FAB2_LIB.BASEBOARD_FAB2(SCH_1):GND
 165    GND VSS<38> @BASEBOARD_FAB2_LIB.BASEBOARD_FAB2(SCH_1):GND
 167    GND VSS<37> @BASEBOARD_FAB2_LIB.BASEBOARD_FAB2(SCH_1):GND
 169    GND VSS<36> @BASEBOARD_FAB2_LIB.BASEBOARD_FAB2(SCH_1):GND
 171    GND VSS<35> @BASEBOARD_FAB2_LIB.BASEBOARD_FAB2(SCH_1):GND
 173    GND VSS<34> @BASEBOARD_FAB2_LIB.BASEBOARD_FAB2(SCH_1):GND
 176    GND VSS<33> @BASEBOARD_FAB2_LIB.BASEBOARD_FAB2(SCH_1):GND
 178    GND VSS<32> @BASEBOARD_FAB2_LIB.BASEBOARD_FAB2(SCH_1):GND
 180    GND VSS<31> @BASEBOARD_FAB2_LIB.BASEBOARD_FAB2(SCH_1):GND
 182    GND VSS<30> @BASEBOARD_FAB2_LIB.BASEBOARD_FAB2(SCH_1):GND
 184    GND VSS<29> @BASEBOARD_FAB2_LIB.BASEBOARD_FAB2(SCH_1):GND
 187    GND VSS<28> @BASEBOARD_FAB2_LIB.BASEBOARD_FAB2(SCH_1):GND
 189    GND VSS<27> @BASEBOARD_FAB2_LIB.BASEBOARD_FAB2(SCH_1):GND
 191    GND VSS<26> @BASEBOARD_FAB2_LIB.BASEBOARD_FAB2(SCH_1):GND
 193    GND VSS<25> @BASEBOARD_FAB2_LIB.BASEBOARD_FAB2(SCH_1):GND
 195    GND VSS<24> @BASEBOARD_FAB2_LIB.BASEBOARD_FAB2(SCH_1):GND
 198    GND VSS<23> @BASEBOARD_FAB2_LIB.BASEBOARD_FAB2(SCH_1):GND
 200    GND VSS<22> @BASEBOARD_FAB2_LIB.BASEBOARD_FAB2(SCH_1):GND
 202    GND VSS<21> @BASEBOARD_FAB2_LIB.BASEBOARD_FAB2(SCH_1):GND
 239    GND VSS<20> @BASEBOARD_FAB2_LIB.BASEBOARD_FAB2(SCH_1):GND
 241    GND VSS<19> @BASEBOARD_FAB2_LIB.BASEBOARD_FAB2(SCH_1):GND
 243    GND VSS<18> @BASEBOARD_FAB2_LIB.BASEBOARD_FAB2(SCH_1):GND
 246    GND VSS<17> @BASEBOARD_FAB2_LIB.BASEBOARD_FAB2(SCH_1):GND
 248    GND VSS<16> @BASEBOARD_FAB2_LIB.BASEBOARD_FAB2(SCH_1):GND
 250    GND VSS<15> @BASEBOARD_FAB2_LIB.BASEBOARD_FAB2(SCH_1):GND
 252    GND VSS<14> @BASEBOARD_FAB2_LIB.BASEBOARD_FAB2(SCH_1):GND
 254    GND VSS<13> @BASEBOARD_FAB2_LIB.BASEBOARD_FAB2(SCH_1):GND
 257    GND VSS<12> @BASEBOARD_FAB2_LIB.BASEBOARD_FAB2(SCH_1):GND
 259    GND VSS<11> @BASEBOARD_FAB2_LIB.BASEBOARD_FAB2(SCH_1):GND
 261    GND VSS<10> @BASEBOARD_FAB2_LIB.BASEBOARD_FAB2(SCH_1):GND
 263    GND VSS<9> @BASEBOARD_FAB2_LIB.BASEBOARD_FAB2(SCH_1):GND
 265    GND VSS<8> @BASEBOARD_FAB2_LIB.BASEBOARD_FAB2(SCH_1):GND
 268    GND VSS<7> @BASEBOARD_FAB2_LIB.BASEBOARD_FAB2(SCH_1):GND
 270    GND VSS<6> @BASEBOARD_FAB2_LIB.BASEBOARD_FAB2(SCH_1):GND
 272    GND VSS<5> @BASEBOARD_FAB2_LIB.BASEBOARD_FAB2(SCH_1):GND
 274    GND VSS<4> @BASEBOARD_FAB2_LIB.BASEBOARD_FAB2(SCH_1):GND
 276    GND VSS<3> @BASEBOARD_FAB2_LIB.BASEBOARD_FAB2(SCH_1):GND
 279    GND VSS<2> @BASEBOARD_FAB2_LIB.BASEBOARD_FAB2(SCH_1):GND
 281    GND VSS<1> @BASEBOARD_FAB2_LIB.BASEBOARD_FAB2(SCH_1):GND
 283    GND VSS<0> @BASEBOARD_FAB2_LIB.BASEBOARD_FAB2(SCH_1):GND

CAP_A_0402V-0.01UF,25V,10%,X7RA  I182  C1A17
   1 M_L_VREF      A @BASEBOARD_FAB2_LIB.BASEBOARD_FAB2(SCH_1):M_L_VREF
   2    GND      B @BASEBOARD_FAB2_LIB.BASEBOARD_FAB2(SCH_1):GND


DRAWING: @BASEBOARD_FAB2_LIB.BASEBOARD_FAB2(SCH_1):PAGE87 

SCONN288_H44441004_PIP-SCONN,HA  I169  J1A1
   1 P12V_NVDIMM_KLM 12V<1> @BASEBOARD_FAB2_LIB.BASEBOARD_FAB2(SCH_1):P12V_NVDIMM_KLM
 145 P12V_NVDIMM_KLM 12V<0> @BASEBOARD_FAB2_LIB.BASEBOARD_FAB2(SCH_1):P12V_NVDIMM_KLM
  59 PVDDQ_KLM VDD<25> @BASEBOARD_FAB2_LIB.BASEBOARD_FAB2(SCH_1):PVDDQ_KLM
  61 PVDDQ_KLM VDD<24> @BASEBOARD_FAB2_LIB.BASEBOARD_FAB2(SCH_1):PVDDQ_KLM
  64 PVDDQ_KLM VDD<23> @BASEBOARD_FAB2_LIB.BASEBOARD_FAB2(SCH_1):PVDDQ_KLM
  67 PVDDQ_KLM VDD<22> @BASEBOARD_FAB2_LIB.BASEBOARD_FAB2(SCH_1):PVDDQ_KLM
  70 PVDDQ_KLM VDD<21> @BASEBOARD_FAB2_LIB.BASEBOARD_FAB2(SCH_1):PVDDQ_KLM
  73 PVDDQ_KLM VDD<20> @BASEBOARD_FAB2_LIB.BASEBOARD_FAB2(SCH_1):PVDDQ_KLM
  76 PVDDQ_KLM VDD<19> @BASEBOARD_FAB2_LIB.BASEBOARD_FAB2(SCH_1):PVDDQ_KLM
  80 PVDDQ_KLM VDD<18> @BASEBOARD_FAB2_LIB.BASEBOARD_FAB2(SCH_1):PVDDQ_KLM
  83 PVDDQ_KLM VDD<17> @BASEBOARD_FAB2_LIB.BASEBOARD_FAB2(SCH_1):PVDDQ_KLM
  85 PVDDQ_KLM VDD<16> @BASEBOARD_FAB2_LIB.BASEBOARD_FAB2(SCH_1):PVDDQ_KLM
  88 PVDDQ_KLM VDD<15> @BASEBOARD_FAB2_LIB.BASEBOARD_FAB2(SCH_1):PVDDQ_KLM
  90 PVDDQ_KLM VDD<14> @BASEBOARD_FAB2_LIB.BASEBOARD_FAB2(SCH_1):PVDDQ_KLM
  92 PVDDQ_KLM VDD<13> @BASEBOARD_FAB2_LIB.BASEBOARD_FAB2(SCH_1):PVDDQ_KLM
 204 PVDDQ_KLM VDD<12> @BASEBOARD_FAB2_LIB.BASEBOARD_FAB2(SCH_1):PVDDQ_KLM
 206 PVDDQ_KLM VDD<11> @BASEBOARD_FAB2_LIB.BASEBOARD_FAB2(SCH_1):PVDDQ_KLM
 209 PVDDQ_KLM VDD<10> @BASEBOARD_FAB2_LIB.BASEBOARD_FAB2(SCH_1):PVDDQ_KLM
 212 PVDDQ_KLM VDD<9> @BASEBOARD_FAB2_LIB.BASEBOARD_FAB2(SCH_1):PVDDQ_KLM
 215 PVDDQ_KLM VDD<8> @BASEBOARD_FAB2_LIB.BASEBOARD_FAB2(SCH_1):PVDDQ_KLM
 217 PVDDQ_KLM VDD<7> @BASEBOARD_FAB2_LIB.BASEBOARD_FAB2(SCH_1):PVDDQ_KLM
 220 PVDDQ_KLM VDD<6> @BASEBOARD_FAB2_LIB.BASEBOARD_FAB2(SCH_1):PVDDQ_KLM
 223 PVDDQ_KLM VDD<5> @BASEBOARD_FAB2_LIB.BASEBOARD_FAB2(SCH_1):PVDDQ_KLM
 226 PVDDQ_KLM VDD<4> @BASEBOARD_FAB2_LIB.BASEBOARD_FAB2(SCH_1):PVDDQ_KLM
 229 PVDDQ_KLM VDD<3> @BASEBOARD_FAB2_LIB.BASEBOARD_FAB2(SCH_1):PVDDQ_KLM
 231 PVDDQ_KLM VDD<2> @BASEBOARD_FAB2_LIB.BASEBOARD_FAB2(SCH_1):PVDDQ_KLM
 233 PVDDQ_KLM VDD<1> @BASEBOARD_FAB2_LIB.BASEBOARD_FAB2(SCH_1):PVDDQ_KLM
 236 PVDDQ_KLM VDD<0> @BASEBOARD_FAB2_LIB.BASEBOARD_FAB2(SCH_1):PVDDQ_KLM
 142 PVPP_KLM VPP<4> @BASEBOARD_FAB2_LIB.BASEBOARD_FAB2(SCH_1):PVPP_KLM
 143 PVPP_KLM VPP<3> @BASEBOARD_FAB2_LIB.BASEBOARD_FAB2(SCH_1):PVPP_KLM
 288 PVPP_KLM VPP<2> @BASEBOARD_FAB2_LIB.BASEBOARD_FAB2(SCH_1):PVPP_KLM
 286 PVPP_KLM VPP<1> @BASEBOARD_FAB2_LIB.BASEBOARD_FAB2(SCH_1):PVPP_KLM
 287 PVPP_KLM VPP<0> @BASEBOARD_FAB2_LIB.BASEBOARD_FAB2(SCH_1):PVPP_KLM
  77 PVTT_KLM VTT<1> @BASEBOARD_FAB2_LIB.BASEBOARD_FAB2(SCH_1):PVTT_KLM
 221 PVTT_KLM VTT<0> @BASEBOARD_FAB2_LIB.BASEBOARD_FAB2(SCH_1):PVTT_KLM

CAP_A_0402V-0.01UF,25V,10%,X7RA  I178  C1A5
   1 M_M_VREF      A @BASEBOARD_FAB2_LIB.BASEBOARD_FAB2(SCH_1):M_M_VREF
   2    GND      B @BASEBOARD_FAB2_LIB.BASEBOARD_FAB2(SCH_1):GND

SCONN288_H44441004_PIP-SCONN,HA  I185  J1A1
   2    GND VSS<93> @BASEBOARD_FAB2_LIB.BASEBOARD_FAB2(SCH_1):GND
   4    GND VSS<92> @BASEBOARD_FAB2_LIB.BASEBOARD_FAB2(SCH_1):GND
   6    GND VSS<91> @BASEBOARD_FAB2_LIB.BASEBOARD_FAB2(SCH_1):GND
   9    GND VSS<90> @BASEBOARD_FAB2_LIB.BASEBOARD_FAB2(SCH_1):GND
  11    GND VSS<89> @BASEBOARD_FAB2_LIB.BASEBOARD_FAB2(SCH_1):GND
  13    GND VSS<88> @BASEBOARD_FAB2_LIB.BASEBOARD_FAB2(SCH_1):GND
  15    GND VSS<87> @BASEBOARD_FAB2_LIB.BASEBOARD_FAB2(SCH_1):GND
  17    GND VSS<86> @BASEBOARD_FAB2_LIB.BASEBOARD_FAB2(SCH_1):GND
  20    GND VSS<85> @BASEBOARD_FAB2_LIB.BASEBOARD_FAB2(SCH_1):GND
  22    GND VSS<84> @BASEBOARD_FAB2_LIB.BASEBOARD_FAB2(SCH_1):GND
  24    GND VSS<83> @BASEBOARD_FAB2_LIB.BASEBOARD_FAB2(SCH_1):GND
  26    GND VSS<82> @BASEBOARD_FAB2_LIB.BASEBOARD_FAB2(SCH_1):GND
  28    GND VSS<81> @BASEBOARD_FAB2_LIB.BASEBOARD_FAB2(SCH_1):GND
  31    GND VSS<80> @BASEBOARD_FAB2_LIB.BASEBOARD_FAB2(SCH_1):GND
  33    GND VSS<79> @BASEBOARD_FAB2_LIB.BASEBOARD_FAB2(SCH_1):GND
  35    GND VSS<78> @BASEBOARD_FAB2_LIB.BASEBOARD_FAB2(SCH_1):GND
  37    GND VSS<77> @BASEBOARD_FAB2_LIB.BASEBOARD_FAB2(SCH_1):GND
  39    GND VSS<76> @BASEBOARD_FAB2_LIB.BASEBOARD_FAB2(SCH_1):GND
  42    GND VSS<75> @BASEBOARD_FAB2_LIB.BASEBOARD_FAB2(SCH_1):GND
  44    GND VSS<74> @BASEBOARD_FAB2_LIB.BASEBOARD_FAB2(SCH_1):GND
  46    GND VSS<73> @BASEBOARD_FAB2_LIB.BASEBOARD_FAB2(SCH_1):GND
  48    GND VSS<72> @BASEBOARD_FAB2_LIB.BASEBOARD_FAB2(SCH_1):GND
  50    GND VSS<71> @BASEBOARD_FAB2_LIB.BASEBOARD_FAB2(SCH_1):GND
  53    GND VSS<70> @BASEBOARD_FAB2_LIB.BASEBOARD_FAB2(SCH_1):GND
  55    GND VSS<69> @BASEBOARD_FAB2_LIB.BASEBOARD_FAB2(SCH_1):GND
  57    GND VSS<68> @BASEBOARD_FAB2_LIB.BASEBOARD_FAB2(SCH_1):GND
  94    GND VSS<67> @BASEBOARD_FAB2_LIB.BASEBOARD_FAB2(SCH_1):GND
  96    GND VSS<66> @BASEBOARD_FAB2_LIB.BASEBOARD_FAB2(SCH_1):GND
  98    GND VSS<65> @BASEBOARD_FAB2_LIB.BASEBOARD_FAB2(SCH_1):GND
 101    GND VSS<64> @BASEBOARD_FAB2_LIB.BASEBOARD_FAB2(SCH_1):GND
 103    GND VSS<63> @BASEBOARD_FAB2_LIB.BASEBOARD_FAB2(SCH_1):GND
 105    GND VSS<62> @BASEBOARD_FAB2_LIB.BASEBOARD_FAB2(SCH_1):GND
 107    GND VSS<61> @BASEBOARD_FAB2_LIB.BASEBOARD_FAB2(SCH_1):GND
 109    GND VSS<60> @BASEBOARD_FAB2_LIB.BASEBOARD_FAB2(SCH_1):GND
 112    GND VSS<59> @BASEBOARD_FAB2_LIB.BASEBOARD_FAB2(SCH_1):GND
 114    GND VSS<58> @BASEBOARD_FAB2_LIB.BASEBOARD_FAB2(SCH_1):GND
 116    GND VSS<57> @BASEBOARD_FAB2_LIB.BASEBOARD_FAB2(SCH_1):GND
 118    GND VSS<56> @BASEBOARD_FAB2_LIB.BASEBOARD_FAB2(SCH_1):GND
 120    GND VSS<55> @BASEBOARD_FAB2_LIB.BASEBOARD_FAB2(SCH_1):GND
 123    GND VSS<54> @BASEBOARD_FAB2_LIB.BASEBOARD_FAB2(SCH_1):GND
 125    GND VSS<53> @BASEBOARD_FAB2_LIB.BASEBOARD_FAB2(SCH_1):GND
 127    GND VSS<52> @BASEBOARD_FAB2_LIB.BASEBOARD_FAB2(SCH_1):GND
 129    GND VSS<51> @BASEBOARD_FAB2_LIB.BASEBOARD_FAB2(SCH_1):GND
 131    GND VSS<50> @BASEBOARD_FAB2_LIB.BASEBOARD_FAB2(SCH_1):GND
 134    GND VSS<49> @BASEBOARD_FAB2_LIB.BASEBOARD_FAB2(SCH_1):GND
 136    GND VSS<48> @BASEBOARD_FAB2_LIB.BASEBOARD_FAB2(SCH_1):GND
 138    GND VSS<47> @BASEBOARD_FAB2_LIB.BASEBOARD_FAB2(SCH_1):GND
 147    GND VSS<46> @BASEBOARD_FAB2_LIB.BASEBOARD_FAB2(SCH_1):GND
 149    GND VSS<45> @BASEBOARD_FAB2_LIB.BASEBOARD_FAB2(SCH_1):GND
 151    GND VSS<44> @BASEBOARD_FAB2_LIB.BASEBOARD_FAB2(SCH_1):GND
 154    GND VSS<43> @BASEBOARD_FAB2_LIB.BASEBOARD_FAB2(SCH_1):GND
 156    GND VSS<42> @BASEBOARD_FAB2_LIB.BASEBOARD_FAB2(SCH_1):GND
 158    GND VSS<41> @BASEBOARD_FAB2_LIB.BASEBOARD_FAB2(SCH_1):GND
 160    GND VSS<40> @BASEBOARD_FAB2_LIB.BASEBOARD_FAB2(SCH_1):GND
 162    GND VSS<39> @BASEBOARD_FAB2_LIB.BASEBOARD_FAB2(SCH_1):GND
 165    GND VSS<38> @BASEBOARD_FAB2_LIB.BASEBOARD_FAB2(SCH_1):GND
 167    GND VSS<37> @BASEBOARD_FAB2_LIB.BASEBOARD_FAB2(SCH_1):GND
 169    GND VSS<36> @BASEBOARD_FAB2_LIB.BASEBOARD_FAB2(SCH_1):GND
 171    GND VSS<35> @BASEBOARD_FAB2_LIB.BASEBOARD_FAB2(SCH_1):GND
 173    GND VSS<34> @BASEBOARD_FAB2_LIB.BASEBOARD_FAB2(SCH_1):GND
 176    GND VSS<33> @BASEBOARD_FAB2_LIB.BASEBOARD_FAB2(SCH_1):GND
 178    GND VSS<32> @BASEBOARD_FAB2_LIB.BASEBOARD_FAB2(SCH_1):GND
 180    GND VSS<31> @BASEBOARD_FAB2_LIB.BASEBOARD_FAB2(SCH_1):GND
 182    GND VSS<30> @BASEBOARD_FAB2_LIB.BASEBOARD_FAB2(SCH_1):GND
 184    GND VSS<29> @BASEBOARD_FAB2_LIB.BASEBOARD_FAB2(SCH_1):GND
 187    GND VSS<28> @BASEBOARD_FAB2_LIB.BASEBOARD_FAB2(SCH_1):GND
 189    GND VSS<27> @BASEBOARD_FAB2_LIB.BASEBOARD_FAB2(SCH_1):GND
 191    GND VSS<26> @BASEBOARD_FAB2_LIB.BASEBOARD_FAB2(SCH_1):GND
 193    GND VSS<25> @BASEBOARD_FAB2_LIB.BASEBOARD_FAB2(SCH_1):GND
 195    GND VSS<24> @BASEBOARD_FAB2_LIB.BASEBOARD_FAB2(SCH_1):GND
 198    GND VSS<23> @BASEBOARD_FAB2_LIB.BASEBOARD_FAB2(SCH_1):GND
 200    GND VSS<22> @BASEBOARD_FAB2_LIB.BASEBOARD_FAB2(SCH_1):GND
 202    GND VSS<21> @BASEBOARD_FAB2_LIB.BASEBOARD_FAB2(SCH_1):GND
 239    GND VSS<20> @BASEBOARD_FAB2_LIB.BASEBOARD_FAB2(SCH_1):GND
 241    GND VSS<19> @BASEBOARD_FAB2_LIB.BASEBOARD_FAB2(SCH_1):GND
 243    GND VSS<18> @BASEBOARD_FAB2_LIB.BASEBOARD_FAB2(SCH_1):GND
 246    GND VSS<17> @BASEBOARD_FAB2_LIB.BASEBOARD_FAB2(SCH_1):GND
 248    GND VSS<16> @BASEBOARD_FAB2_LIB.BASEBOARD_FAB2(SCH_1):GND
 250    GND VSS<15> @BASEBOARD_FAB2_LIB.BASEBOARD_FAB2(SCH_1):GND
 252    GND VSS<14> @BASEBOARD_FAB2_LIB.BASEBOARD_FAB2(SCH_1):GND
 254    GND VSS<13> @BASEBOARD_FAB2_LIB.BASEBOARD_FAB2(SCH_1):GND
 257    GND VSS<12> @BASEBOARD_FAB2_LIB.BASEBOARD_FAB2(SCH_1):GND
 259    GND VSS<11> @BASEBOARD_FAB2_LIB.BASEBOARD_FAB2(SCH_1):GND
 261    GND VSS<10> @BASEBOARD_FAB2_LIB.BASEBOARD_FAB2(SCH_1):GND
 263    GND VSS<9> @BASEBOARD_FAB2_LIB.BASEBOARD_FAB2(SCH_1):GND
 265    GND VSS<8> @BASEBOARD_FAB2_LIB.BASEBOARD_FAB2(SCH_1):GND
 268    GND VSS<7> @BASEBOARD_FAB2_LIB.BASEBOARD_FAB2(SCH_1):GND
 270    GND VSS<6> @BASEBOARD_FAB2_LIB.BASEBOARD_FAB2(SCH_1):GND
 272    GND VSS<5> @BASEBOARD_FAB2_LIB.BASEBOARD_FAB2(SCH_1):GND
 274    GND VSS<4> @BASEBOARD_FAB2_LIB.BASEBOARD_FAB2(SCH_1):GND
 276    GND VSS<3> @BASEBOARD_FAB2_LIB.BASEBOARD_FAB2(SCH_1):GND
 279    GND VSS<2> @BASEBOARD_FAB2_LIB.BASEBOARD_FAB2(SCH_1):GND
 281    GND VSS<1> @BASEBOARD_FAB2_LIB.BASEBOARD_FAB2(SCH_1):GND
 283    GND VSS<0> @BASEBOARD_FAB2_LIB.BASEBOARD_FAB2(SCH_1):GND

SCONN288_H44441004_PIP-SCONN,HA  I186  J1A1
  79 M_M_MA<0>     A0 @BASEBOARD_FAB2_LIB.BASEBOARD_FAB2(SCH_1):M_M_MA(0)
  72 M_M_MA<1>     A1 @BASEBOARD_FAB2_LIB.BASEBOARD_FAB2(SCH_1):M_M_MA(1)
 225 M_M_MA<10>    A10 @BASEBOARD_FAB2_LIB.BASEBOARD_FAB2(SCH_1):M_M_MA(10)
 210 M_M_MA<11>    A11 @BASEBOARD_FAB2_LIB.BASEBOARD_FAB2(SCH_1):M_M_MA(11)
  65 M_M_MA<12>    A12 @BASEBOARD_FAB2_LIB.BASEBOARD_FAB2(SCH_1):M_M_MA(12)
 232 M_M_MA<13>    A13 @BASEBOARD_FAB2_LIB.BASEBOARD_FAB2(SCH_1):M_M_MA(13)
 228 M_M_MA<14> A14_WE_N @BASEBOARD_FAB2_LIB.BASEBOARD_FAB2(SCH_1):M_M_MA(14)
  86 M_M_MA<15> A15_CAS_N @BASEBOARD_FAB2_LIB.BASEBOARD_FAB2(SCH_1):M_M_MA(15)
  82 M_M_MA<16> A16_RAS_N @BASEBOARD_FAB2_LIB.BASEBOARD_FAB2(SCH_1):M_M_MA(16)
 234 M_M_MA<17>    A17 @BASEBOARD_FAB2_LIB.BASEBOARD_FAB2(SCH_1):M_M_MA(17)
 216 M_M_MA<2>     A2 @BASEBOARD_FAB2_LIB.BASEBOARD_FAB2(SCH_1):M_M_MA(2)
  71 M_M_MA<3>     A3 @BASEBOARD_FAB2_LIB.BASEBOARD_FAB2(SCH_1):M_M_MA(3)
 214 M_M_MA<4>     A4 @BASEBOARD_FAB2_LIB.BASEBOARD_FAB2(SCH_1):M_M_MA(4)
 213 M_M_MA<5>     A5 @BASEBOARD_FAB2_LIB.BASEBOARD_FAB2(SCH_1):M_M_MA(5)
  69 M_M_MA<6>     A6 @BASEBOARD_FAB2_LIB.BASEBOARD_FAB2(SCH_1):M_M_MA(6)
 211 M_M_MA<7>     A7 @BASEBOARD_FAB2_LIB.BASEBOARD_FAB2(SCH_1):M_M_MA(7)
  68 M_M_MA<8>     A8 @BASEBOARD_FAB2_LIB.BASEBOARD_FAB2(SCH_1):M_M_MA(8)
  66 M_M_MA<9>     A9 @BASEBOARD_FAB2_LIB.BASEBOARD_FAB2(SCH_1):M_M_MA(9)
  62 M_M_ACT_N  ACT_N @BASEBOARD_FAB2_LIB.BASEBOARD_FAB2(SCH_1):M_M_ACT_N
 208 M_M_ALERT_N ALERT_N @BASEBOARD_FAB2_LIB.BASEBOARD_FAB2(SCH_1):M_M_ALERT_N
 224 M_M_BA<1>  BA<1> @BASEBOARD_FAB2_LIB.BASEBOARD_FAB2(SCH_1):M_M_BA(1)
  81 M_M_BA<0>  BA<0> @BASEBOARD_FAB2_LIB.BASEBOARD_FAB2(SCH_1):M_M_BA(0)
 207 M_M_BG<1>  BG<1> @BASEBOARD_FAB2_LIB.BASEBOARD_FAB2(SCH_1):M_M_BG(1)
  63 M_M_BG<0>  BG<0> @BASEBOARD_FAB2_LIB.BASEBOARD_FAB2(SCH_1):M_M_BG(0)
 235 M_M_C<2>   C<2> @BASEBOARD_FAB2_LIB.BASEBOARD_FAB2(SCH_1):M_M_C(2)
 199 M_M_ECC<6>  CB<7> @BASEBOARD_FAB2_LIB.BASEBOARD_FAB2(SCH_1):M_M_ECC(6)
  54 M_M_ECC<7>  CB<6> @BASEBOARD_FAB2_LIB.BASEBOARD_FAB2(SCH_1):M_M_ECC(7)
 192 M_M_ECC<4>  CB<5> @BASEBOARD_FAB2_LIB.BASEBOARD_FAB2(SCH_1):M_M_ECC(4)
  47 M_M_ECC<5>  CB<4> @BASEBOARD_FAB2_LIB.BASEBOARD_FAB2(SCH_1):M_M_ECC(5)
 201 M_M_ECC<2>  CB<3> @BASEBOARD_FAB2_LIB.BASEBOARD_FAB2(SCH_1):M_M_ECC(2)
  56 M_M_ECC<3>  CB<2> @BASEBOARD_FAB2_LIB.BASEBOARD_FAB2(SCH_1):M_M_ECC(3)
 194 M_M_ECC<0>  CB<1> @BASEBOARD_FAB2_LIB.BASEBOARD_FAB2(SCH_1):M_M_ECC(0)
  49 M_M_ECC<1>  CB<0> @BASEBOARD_FAB2_LIB.BASEBOARD_FAB2(SCH_1):M_M_ECC(1)
  75 M_M_CLK_DN<0>   CK0N @BASEBOARD_FAB2_LIB.BASEBOARD_FAB2(SCH_1):M_M_CLK_DN(0)
  74 M_M_CLK_DP<0>   CK0P @BASEBOARD_FAB2_LIB.BASEBOARD_FAB2(SCH_1):M_M_CLK_DP(0)
 219 M_M_CLK_DN<1>   CK1N @BASEBOARD_FAB2_LIB.BASEBOARD_FAB2(SCH_1):M_M_CLK_DN(1)
 218 M_M_CLK_DP<1>   CK1P @BASEBOARD_FAB2_LIB.BASEBOARD_FAB2(SCH_1):M_M_CLK_DP(1)
 203 M_M_CKE<1> CKE<1> @BASEBOARD_FAB2_LIB.BASEBOARD_FAB2(SCH_1):M_M_CKE(1)
  60 M_M_CKE<0> CKE<0> @BASEBOARD_FAB2_LIB.BASEBOARD_FAB2(SCH_1):M_M_CKE(0)
 280 M_M_DQ<62> DQ<63> @BASEBOARD_FAB2_LIB.BASEBOARD_FAB2(SCH_1):M_M_DQ(62)
 135 M_M_DQ<63> DQ<62> @BASEBOARD_FAB2_LIB.BASEBOARD_FAB2(SCH_1):M_M_DQ(63)
 273 M_M_DQ<60> DQ<61> @BASEBOARD_FAB2_LIB.BASEBOARD_FAB2(SCH_1):M_M_DQ(60)
 128 M_M_DQ<61> DQ<60> @BASEBOARD_FAB2_LIB.BASEBOARD_FAB2(SCH_1):M_M_DQ(61)
 282 M_M_DQ<58> DQ<59> @BASEBOARD_FAB2_LIB.BASEBOARD_FAB2(SCH_1):M_M_DQ(58)
 137 M_M_DQ<59> DQ<58> @BASEBOARD_FAB2_LIB.BASEBOARD_FAB2(SCH_1):M_M_DQ(59)
 275 M_M_DQ<56> DQ<57> @BASEBOARD_FAB2_LIB.BASEBOARD_FAB2(SCH_1):M_M_DQ(56)
 130 M_M_DQ<57> DQ<56> @BASEBOARD_FAB2_LIB.BASEBOARD_FAB2(SCH_1):M_M_DQ(57)
 269 M_M_DQ<54> DQ<55> @BASEBOARD_FAB2_LIB.BASEBOARD_FAB2(SCH_1):M_M_DQ(54)
 124 M_M_DQ<55> DQ<54> @BASEBOARD_FAB2_LIB.BASEBOARD_FAB2(SCH_1):M_M_DQ(55)
 262 M_M_DQ<52> DQ<53> @BASEBOARD_FAB2_LIB.BASEBOARD_FAB2(SCH_1):M_M_DQ(52)
 117 M_M_DQ<53> DQ<52> @BASEBOARD_FAB2_LIB.BASEBOARD_FAB2(SCH_1):M_M_DQ(53)
 271 M_M_DQ<50> DQ<51> @BASEBOARD_FAB2_LIB.BASEBOARD_FAB2(SCH_1):M_M_DQ(50)
 126 M_M_DQ<51> DQ<50> @BASEBOARD_FAB2_LIB.BASEBOARD_FAB2(SCH_1):M_M_DQ(51)
 264 M_M_DQ<48> DQ<49> @BASEBOARD_FAB2_LIB.BASEBOARD_FAB2(SCH_1):M_M_DQ(48)
 119 M_M_DQ<49> DQ<48> @BASEBOARD_FAB2_LIB.BASEBOARD_FAB2(SCH_1):M_M_DQ(49)
 258 M_M_DQ<46> DQ<47> @BASEBOARD_FAB2_LIB.BASEBOARD_FAB2(SCH_1):M_M_DQ(46)
 113 M_M_DQ<47> DQ<46> @BASEBOARD_FAB2_LIB.BASEBOARD_FAB2(SCH_1):M_M_DQ(47)
 251 M_M_DQ<44> DQ<45> @BASEBOARD_FAB2_LIB.BASEBOARD_FAB2(SCH_1):M_M_DQ(44)
 106 M_M_DQ<45> DQ<44> @BASEBOARD_FAB2_LIB.BASEBOARD_FAB2(SCH_1):M_M_DQ(45)
 260 M_M_DQ<42> DQ<43> @BASEBOARD_FAB2_LIB.BASEBOARD_FAB2(SCH_1):M_M_DQ(42)
 115 M_M_DQ<43> DQ<42> @BASEBOARD_FAB2_LIB.BASEBOARD_FAB2(SCH_1):M_M_DQ(43)
 253 M_M_DQ<40> DQ<41> @BASEBOARD_FAB2_LIB.BASEBOARD_FAB2(SCH_1):M_M_DQ(40)
 108 M_M_DQ<41> DQ<40> @BASEBOARD_FAB2_LIB.BASEBOARD_FAB2(SCH_1):M_M_DQ(41)
 247 M_M_DQ<38> DQ<39> @BASEBOARD_FAB2_LIB.BASEBOARD_FAB2(SCH_1):M_M_DQ(38)
 102 M_M_DQ<39> DQ<38> @BASEBOARD_FAB2_LIB.BASEBOARD_FAB2(SCH_1):M_M_DQ(39)
 240 M_M_DQ<36> DQ<37> @BASEBOARD_FAB2_LIB.BASEBOARD_FAB2(SCH_1):M_M_DQ(36)
  95 M_M_DQ<37> DQ<36> @BASEBOARD_FAB2_LIB.BASEBOARD_FAB2(SCH_1):M_M_DQ(37)
 249 M_M_DQ<34> DQ<35> @BASEBOARD_FAB2_LIB.BASEBOARD_FAB2(SCH_1):M_M_DQ(34)
 104 M_M_DQ<35> DQ<34> @BASEBOARD_FAB2_LIB.BASEBOARD_FAB2(SCH_1):M_M_DQ(35)
 242 M_M_DQ<32> DQ<33> @BASEBOARD_FAB2_LIB.BASEBOARD_FAB2(SCH_1):M_M_DQ(32)
  97 M_M_DQ<33> DQ<32> @BASEBOARD_FAB2_LIB.BASEBOARD_FAB2(SCH_1):M_M_DQ(33)
 188 M_M_DQ<30> DQ<31> @BASEBOARD_FAB2_LIB.BASEBOARD_FAB2(SCH_1):M_M_DQ(30)
  43 M_M_DQ<31> DQ<30> @BASEBOARD_FAB2_LIB.BASEBOARD_FAB2(SCH_1):M_M_DQ(31)
 181 M_M_DQ<28> DQ<29> @BASEBOARD_FAB2_LIB.BASEBOARD_FAB2(SCH_1):M_M_DQ(28)
  36 M_M_DQ<29> DQ<28> @BASEBOARD_FAB2_LIB.BASEBOARD_FAB2(SCH_1):M_M_DQ(29)
 190 M_M_DQ<26> DQ<27> @BASEBOARD_FAB2_LIB.BASEBOARD_FAB2(SCH_1):M_M_DQ(26)
  45 M_M_DQ<27> DQ<26> @BASEBOARD_FAB2_LIB.BASEBOARD_FAB2(SCH_1):M_M_DQ(27)
 183 M_M_DQ<24> DQ<25> @BASEBOARD_FAB2_LIB.BASEBOARD_FAB2(SCH_1):M_M_DQ(24)
  38 M_M_DQ<25> DQ<24> @BASEBOARD_FAB2_LIB.BASEBOARD_FAB2(SCH_1):M_M_DQ(25)
 177 M_M_DQ<22> DQ<23> @BASEBOARD_FAB2_LIB.BASEBOARD_FAB2(SCH_1):M_M_DQ(22)
  32 M_M_DQ<23> DQ<22> @BASEBOARD_FAB2_LIB.BASEBOARD_FAB2(SCH_1):M_M_DQ(23)
 170 M_M_DQ<20> DQ<21> @BASEBOARD_FAB2_LIB.BASEBOARD_FAB2(SCH_1):M_M_DQ(20)
  25 M_M_DQ<21> DQ<20> @BASEBOARD_FAB2_LIB.BASEBOARD_FAB2(SCH_1):M_M_DQ(21)
 179 M_M_DQ<18> DQ<19> @BASEBOARD_FAB2_LIB.BASEBOARD_FAB2(SCH_1):M_M_DQ(18)
  34 M_M_DQ<19> DQ<18> @BASEBOARD_FAB2_LIB.BASEBOARD_FAB2(SCH_1):M_M_DQ(19)
 172 M_M_DQ<16> DQ<17> @BASEBOARD_FAB2_LIB.BASEBOARD_FAB2(SCH_1):M_M_DQ(16)
  27 M_M_DQ<17> DQ<16> @BASEBOARD_FAB2_LIB.BASEBOARD_FAB2(SCH_1):M_M_DQ(17)
 166 M_M_DQ<14> DQ<15> @BASEBOARD_FAB2_LIB.BASEBOARD_FAB2(SCH_1):M_M_DQ(14)
  21 M_M_DQ<15> DQ<14> @BASEBOARD_FAB2_LIB.BASEBOARD_FAB2(SCH_1):M_M_DQ(15)
 159 M_M_DQ<12> DQ<13> @BASEBOARD_FAB2_LIB.BASEBOARD_FAB2(SCH_1):M_M_DQ(12)
  14 M_M_DQ<13> DQ<12> @BASEBOARD_FAB2_LIB.BASEBOARD_FAB2(SCH_1):M_M_DQ(13)
 168 M_M_DQ<10> DQ<11> @BASEBOARD_FAB2_LIB.BASEBOARD_FAB2(SCH_1):M_M_DQ(10)
  23 M_M_DQ<11> DQ<10> @BASEBOARD_FAB2_LIB.BASEBOARD_FAB2(SCH_1):M_M_DQ(11)
 161 M_M_DQ<8>  DQ<9> @BASEBOARD_FAB2_LIB.BASEBOARD_FAB2(SCH_1):M_M_DQ(8)
  16 M_M_DQ<9>  DQ<8> @BASEBOARD_FAB2_LIB.BASEBOARD_FAB2(SCH_1):M_M_DQ(9)
 155 M_M_DQ<6>  DQ<7> @BASEBOARD_FAB2_LIB.BASEBOARD_FAB2(SCH_1):M_M_DQ(6)
  10 M_M_DQ<7>  DQ<6> @BASEBOARD_FAB2_LIB.BASEBOARD_FAB2(SCH_1):M_M_DQ(7)
 148 M_M_DQ<4>  DQ<5> @BASEBOARD_FAB2_LIB.BASEBOARD_FAB2(SCH_1):M_M_DQ(4)
   3 M_M_DQ<5>  DQ<4> @BASEBOARD_FAB2_LIB.BASEBOARD_FAB2(SCH_1):M_M_DQ(5)
 157 M_M_DQ<2>  DQ<3> @BASEBOARD_FAB2_LIB.BASEBOARD_FAB2(SCH_1):M_M_DQ(2)
  12 M_M_DQ<3>  DQ<2> @BASEBOARD_FAB2_LIB.BASEBOARD_FAB2(SCH_1):M_M_DQ(3)
 150 M_M_DQ<0>  DQ<1> @BASEBOARD_FAB2_LIB.BASEBOARD_FAB2(SCH_1):M_M_DQ(0)
   5 M_M_DQ<1>  DQ<0> @BASEBOARD_FAB2_LIB.BASEBOARD_FAB2(SCH_1):M_M_DQ(1)
  78 FM_DIMM_EVENT_COD_N EVENT_N @BASEBOARD_FAB2_LIB.BASEBOARD_FAB2(SCH_1):FM_DIMM_EVENT_COD_N
  91 M_M_ODT<1> ODT<1> @BASEBOARD_FAB2_LIB.BASEBOARD_FAB2(SCH_1):M_M_ODT(1)
  87 M_M_ODT<0> ODT<0> @BASEBOARD_FAB2_LIB.BASEBOARD_FAB2(SCH_1):M_M_ODT(0)
 222 M_M_PAR    PAR @BASEBOARD_FAB2_LIB.BASEBOARD_FAB2(SCH_1):M_M_PAR
  58 M_KLM_RST_N RESET_N @BASEBOARD_FAB2_LIB.BASEBOARD_FAB2(SCH_1):M_KLM_RST_N
 144 TP_CH_M_DIMM_M0_RFU_2 RFU<2> @BASEBOARD_FAB2_LIB.BASEBOARD_FAB2(SCH_1):TP_CH_M_DIMM_M0_RFU_2
 227 TP_CH_M_DIMM_M0_RFU_1 RFU<1> @BASEBOARD_FAB2_LIB.BASEBOARD_FAB2(SCH_1):TP_CH_M_DIMM_M0_RFU_1
 205 TP_CH_M_DIMM_M0_RFU_0 RFU<0> @BASEBOARD_FAB2_LIB.BASEBOARD_FAB2(SCH_1):TP_CH_M_DIMM_M0_RFU_0
  84 M_M_CS_N<0>   S0_N @BASEBOARD_FAB2_LIB.BASEBOARD_FAB2(SCH_1):M_M_CS_N(0)
  89 M_M_CS_N<1>   S1_N @BASEBOARD_FAB2_LIB.BASEBOARD_FAB2(SCH_1):M_M_CS_N(1)
  93 M_M_CS_N<2> S2_N_C<0> @BASEBOARD_FAB2_LIB.BASEBOARD_FAB2(SCH_1):M_M_CS_N(2)
 237 M_M_CS_N<3> S3_N_C<1> @BASEBOARD_FAB2_LIB.BASEBOARD_FAB2(SCH_1):M_M_CS_N(3)
 238 PVPP_KLM  SA<2> @BASEBOARD_FAB2_LIB.BASEBOARD_FAB2(SCH_1):PVPP_KLM
 140    GND  SA<1> @BASEBOARD_FAB2_LIB.BASEBOARD_FAB2(SCH_1):GND
 139    GND  SA<0> @BASEBOARD_FAB2_LIB.BASEBOARD_FAB2(SCH_1):GND
 230 FM_ADR_COMPLETE_KLM_N SAVE_N_NC @BASEBOARD_FAB2_LIB.BASEBOARD_FAB2(SCH_1):FM_ADR_COMPLETE_KLM_N
 141 SMB_DDR_KLM_VPP_SCL    SCL @BASEBOARD_FAB2_LIB.BASEBOARD_FAB2(SCH_1):SMB_DDR_KLM_VPP_SCL
 285 SMB_DDR_KLM_VPP_SDA    SDA @BASEBOARD_FAB2_LIB.BASEBOARD_FAB2(SCH_1):SMB_DDR_KLM_VPP_SDA
 284 PVPP_KLM VDDSPD @BASEBOARD_FAB2_LIB.BASEBOARD_FAB2(SCH_1):PVPP_KLM
 146 M_M_VREF VREFCA @BASEBOARD_FAB2_LIB.BASEBOARD_FAB2(SCH_1):M_M_VREF

SCONN288_H44441004_PIP-SCONN,HA  I187  J1A1
 152 M_M_DQS_DN<0>  DQS0N @BASEBOARD_FAB2_LIB.BASEBOARD_FAB2(SCH_1):M_M_DQS_DN(0)
 153 M_M_DQS_DP<0>  DQS0P @BASEBOARD_FAB2_LIB.BASEBOARD_FAB2(SCH_1):M_M_DQS_DP(0)
  19 M_M_DQS_DN<10> DQS10N @BASEBOARD_FAB2_LIB.BASEBOARD_FAB2(SCH_1):M_M_DQS_DN(10)
  18 M_M_DQS_DP<10> DQS10P @BASEBOARD_FAB2_LIB.BASEBOARD_FAB2(SCH_1):M_M_DQS_DP(10)
  30 M_M_DQS_DN<11> DQS11N @BASEBOARD_FAB2_LIB.BASEBOARD_FAB2(SCH_1):M_M_DQS_DN(11)
  29 M_M_DQS_DP<11> DQS11P @BASEBOARD_FAB2_LIB.BASEBOARD_FAB2(SCH_1):M_M_DQS_DP(11)
  41 M_M_DQS_DN<12> DQS12N @BASEBOARD_FAB2_LIB.BASEBOARD_FAB2(SCH_1):M_M_DQS_DN(12)
  40 M_M_DQS_DP<12> DQS12P @BASEBOARD_FAB2_LIB.BASEBOARD_FAB2(SCH_1):M_M_DQS_DP(12)
 100 M_M_DQS_DN<13> DQS13N @BASEBOARD_FAB2_LIB.BASEBOARD_FAB2(SCH_1):M_M_DQS_DN(13)
  99 M_M_DQS_DP<13> DQS13P @BASEBOARD_FAB2_LIB.BASEBOARD_FAB2(SCH_1):M_M_DQS_DP(13)
 111 M_M_DQS_DN<14> DQS14N @BASEBOARD_FAB2_LIB.BASEBOARD_FAB2(SCH_1):M_M_DQS_DN(14)
 110 M_M_DQS_DP<14> DQS14P @BASEBOARD_FAB2_LIB.BASEBOARD_FAB2(SCH_1):M_M_DQS_DP(14)
 122 M_M_DQS_DN<15> DQS15N @BASEBOARD_FAB2_LIB.BASEBOARD_FAB2(SCH_1):M_M_DQS_DN(15)
 121 M_M_DQS_DP<15> DQS15P @BASEBOARD_FAB2_LIB.BASEBOARD_FAB2(SCH_1):M_M_DQS_DP(15)
 133 M_M_DQS_DN<16> DQS16N @BASEBOARD_FAB2_LIB.BASEBOARD_FAB2(SCH_1):M_M_DQS_DN(16)
 132 M_M_DQS_DP<16> DQS16P @BASEBOARD_FAB2_LIB.BASEBOARD_FAB2(SCH_1):M_M_DQS_DP(16)
  52 M_M_DQS_DN<17> DQS17N @BASEBOARD_FAB2_LIB.BASEBOARD_FAB2(SCH_1):M_M_DQS_DN(17)
  51 M_M_DQS_DP<17> DQS17P @BASEBOARD_FAB2_LIB.BASEBOARD_FAB2(SCH_1):M_M_DQS_DP(17)
 163 M_M_DQS_DN<1>  DQS1N @BASEBOARD_FAB2_LIB.BASEBOARD_FAB2(SCH_1):M_M_DQS_DN(1)
 164 M_M_DQS_DP<1>  DQS1P @BASEBOARD_FAB2_LIB.BASEBOARD_FAB2(SCH_1):M_M_DQS_DP(1)
 174 M_M_DQS_DN<2>  DQS2N @BASEBOARD_FAB2_LIB.BASEBOARD_FAB2(SCH_1):M_M_DQS_DN(2)
 175 M_M_DQS_DP<2>  DQS2P @BASEBOARD_FAB2_LIB.BASEBOARD_FAB2(SCH_1):M_M_DQS_DP(2)
 185 M_M_DQS_DN<3>  DQS3N @BASEBOARD_FAB2_LIB.BASEBOARD_FAB2(SCH_1):M_M_DQS_DN(3)
 186 M_M_DQS_DP<3>  DQS3P @BASEBOARD_FAB2_LIB.BASEBOARD_FAB2(SCH_1):M_M_DQS_DP(3)
 244 M_M_DQS_DN<4>  DQS4N @BASEBOARD_FAB2_LIB.BASEBOARD_FAB2(SCH_1):M_M_DQS_DN(4)
 245 M_M_DQS_DP<4>  DQS4P @BASEBOARD_FAB2_LIB.BASEBOARD_FAB2(SCH_1):M_M_DQS_DP(4)
 255 M_M_DQS_DN<5>  DQS5N @BASEBOARD_FAB2_LIB.BASEBOARD_FAB2(SCH_1):M_M_DQS_DN(5)
 256 M_M_DQS_DP<5>  DQS5P @BASEBOARD_FAB2_LIB.BASEBOARD_FAB2(SCH_1):M_M_DQS_DP(5)
 266 M_M_DQS_DN<6>  DQS6N @BASEBOARD_FAB2_LIB.BASEBOARD_FAB2(SCH_1):M_M_DQS_DN(6)
 267 M_M_DQS_DP<6>  DQS6P @BASEBOARD_FAB2_LIB.BASEBOARD_FAB2(SCH_1):M_M_DQS_DP(6)
 277 M_M_DQS_DN<7>  DQS7N @BASEBOARD_FAB2_LIB.BASEBOARD_FAB2(SCH_1):M_M_DQS_DN(7)
 278 M_M_DQS_DP<7>  DQS7P @BASEBOARD_FAB2_LIB.BASEBOARD_FAB2(SCH_1):M_M_DQS_DP(7)
 196 M_M_DQS_DN<8>  DQS8N @BASEBOARD_FAB2_LIB.BASEBOARD_FAB2(SCH_1):M_M_DQS_DN(8)
 197 M_M_DQS_DP<8>  DQS8P @BASEBOARD_FAB2_LIB.BASEBOARD_FAB2(SCH_1):M_M_DQS_DP(8)
   8 M_M_DQS_DN<9>  DQS9N @BASEBOARD_FAB2_LIB.BASEBOARD_FAB2(SCH_1):M_M_DQS_DN(9)
   7 M_M_DQS_DP<9>  DQS9P @BASEBOARD_FAB2_LIB.BASEBOARD_FAB2(SCH_1):M_M_DQS_DP(9)


DRAWING: @BASEBOARD_FAB2_LIB.BASEBOARD_FAB2(SCH_1):PAGE88 

SCONN288_H44441003_PIP-SCONN,HA  I25  J9L1
   2    GND VSS<93> @BASEBOARD_FAB2_LIB.BASEBOARD_FAB2(SCH_1):GND
   4    GND VSS<92> @BASEBOARD_FAB2_LIB.BASEBOARD_FAB2(SCH_1):GND
   6    GND VSS<91> @BASEBOARD_FAB2_LIB.BASEBOARD_FAB2(SCH_1):GND
   9    GND VSS<90> @BASEBOARD_FAB2_LIB.BASEBOARD_FAB2(SCH_1):GND
  11    GND VSS<89> @BASEBOARD_FAB2_LIB.BASEBOARD_FAB2(SCH_1):GND
  13    GND VSS<88> @BASEBOARD_FAB2_LIB.BASEBOARD_FAB2(SCH_1):GND
  15    GND VSS<87> @BASEBOARD_FAB2_LIB.BASEBOARD_FAB2(SCH_1):GND
  17    GND VSS<86> @BASEBOARD_FAB2_LIB.BASEBOARD_FAB2(SCH_1):GND
  20    GND VSS<85> @BASEBOARD_FAB2_LIB.BASEBOARD_FAB2(SCH_1):GND
  22    GND VSS<84> @BASEBOARD_FAB2_LIB.BASEBOARD_FAB2(SCH_1):GND
  24    GND VSS<83> @BASEBOARD_FAB2_LIB.BASEBOARD_FAB2(SCH_1):GND
  26    GND VSS<82> @BASEBOARD_FAB2_LIB.BASEBOARD_FAB2(SCH_1):GND
  28    GND VSS<81> @BASEBOARD_FAB2_LIB.BASEBOARD_FAB2(SCH_1):GND
  31    GND VSS<80> @BASEBOARD_FAB2_LIB.BASEBOARD_FAB2(SCH_1):GND
  33    GND VSS<79> @BASEBOARD_FAB2_LIB.BASEBOARD_FAB2(SCH_1):GND
  35    GND VSS<78> @BASEBOARD_FAB2_LIB.BASEBOARD_FAB2(SCH_1):GND
  37    GND VSS<77> @BASEBOARD_FAB2_LIB.BASEBOARD_FAB2(SCH_1):GND
  39    GND VSS<76> @BASEBOARD_FAB2_LIB.BASEBOARD_FAB2(SCH_1):GND
  42    GND VSS<75> @BASEBOARD_FAB2_LIB.BASEBOARD_FAB2(SCH_1):GND
  44    GND VSS<74> @BASEBOARD_FAB2_LIB.BASEBOARD_FAB2(SCH_1):GND
  46    GND VSS<73> @BASEBOARD_FAB2_LIB.BASEBOARD_FAB2(SCH_1):GND
  48    GND VSS<72> @BASEBOARD_FAB2_LIB.BASEBOARD_FAB2(SCH_1):GND
  50    GND VSS<71> @BASEBOARD_FAB2_LIB.BASEBOARD_FAB2(SCH_1):GND
  53    GND VSS<70> @BASEBOARD_FAB2_LIB.BASEBOARD_FAB2(SCH_1):GND
  55    GND VSS<69> @BASEBOARD_FAB2_LIB.BASEBOARD_FAB2(SCH_1):GND
  57    GND VSS<68> @BASEBOARD_FAB2_LIB.BASEBOARD_FAB2(SCH_1):GND
  94    GND VSS<67> @BASEBOARD_FAB2_LIB.BASEBOARD_FAB2(SCH_1):GND
  96    GND VSS<66> @BASEBOARD_FAB2_LIB.BASEBOARD_FAB2(SCH_1):GND
  98    GND VSS<65> @BASEBOARD_FAB2_LIB.BASEBOARD_FAB2(SCH_1):GND
 101    GND VSS<64> @BASEBOARD_FAB2_LIB.BASEBOARD_FAB2(SCH_1):GND
 103    GND VSS<63> @BASEBOARD_FAB2_LIB.BASEBOARD_FAB2(SCH_1):GND
 105    GND VSS<62> @BASEBOARD_FAB2_LIB.BASEBOARD_FAB2(SCH_1):GND
 107    GND VSS<61> @BASEBOARD_FAB2_LIB.BASEBOARD_FAB2(SCH_1):GND
 109    GND VSS<60> @BASEBOARD_FAB2_LIB.BASEBOARD_FAB2(SCH_1):GND
 112    GND VSS<59> @BASEBOARD_FAB2_LIB.BASEBOARD_FAB2(SCH_1):GND
 114    GND VSS<58> @BASEBOARD_FAB2_LIB.BASEBOARD_FAB2(SCH_1):GND
 116    GND VSS<57> @BASEBOARD_FAB2_LIB.BASEBOARD_FAB2(SCH_1):GND
 118    GND VSS<56> @BASEBOARD_FAB2_LIB.BASEBOARD_FAB2(SCH_1):GND
 120    GND VSS<55> @BASEBOARD_FAB2_LIB.BASEBOARD_FAB2(SCH_1):GND
 123    GND VSS<54> @BASEBOARD_FAB2_LIB.BASEBOARD_FAB2(SCH_1):GND
 125    GND VSS<53> @BASEBOARD_FAB2_LIB.BASEBOARD_FAB2(SCH_1):GND
 127    GND VSS<52> @BASEBOARD_FAB2_LIB.BASEBOARD_FAB2(SCH_1):GND
 129    GND VSS<51> @BASEBOARD_FAB2_LIB.BASEBOARD_FAB2(SCH_1):GND
 131    GND VSS<50> @BASEBOARD_FAB2_LIB.BASEBOARD_FAB2(SCH_1):GND
 134    GND VSS<49> @BASEBOARD_FAB2_LIB.BASEBOARD_FAB2(SCH_1):GND
 136    GND VSS<48> @BASEBOARD_FAB2_LIB.BASEBOARD_FAB2(SCH_1):GND
 138    GND VSS<47> @BASEBOARD_FAB2_LIB.BASEBOARD_FAB2(SCH_1):GND
 147    GND VSS<46> @BASEBOARD_FAB2_LIB.BASEBOARD_FAB2(SCH_1):GND
 149    GND VSS<45> @BASEBOARD_FAB2_LIB.BASEBOARD_FAB2(SCH_1):GND
 151    GND VSS<44> @BASEBOARD_FAB2_LIB.BASEBOARD_FAB2(SCH_1):GND
 154    GND VSS<43> @BASEBOARD_FAB2_LIB.BASEBOARD_FAB2(SCH_1):GND
 156    GND VSS<42> @BASEBOARD_FAB2_LIB.BASEBOARD_FAB2(SCH_1):GND
 158    GND VSS<41> @BASEBOARD_FAB2_LIB.BASEBOARD_FAB2(SCH_1):GND
 160    GND VSS<40> @BASEBOARD_FAB2_LIB.BASEBOARD_FAB2(SCH_1):GND
 162    GND VSS<39> @BASEBOARD_FAB2_LIB.BASEBOARD_FAB2(SCH_1):GND
 165    GND VSS<38> @BASEBOARD_FAB2_LIB.BASEBOARD_FAB2(SCH_1):GND
 167    GND VSS<37> @BASEBOARD_FAB2_LIB.BASEBOARD_FAB2(SCH_1):GND
 169    GND VSS<36> @BASEBOARD_FAB2_LIB.BASEBOARD_FAB2(SCH_1):GND
 171    GND VSS<35> @BASEBOARD_FAB2_LIB.BASEBOARD_FAB2(SCH_1):GND
 173    GND VSS<34> @BASEBOARD_FAB2_LIB.BASEBOARD_FAB2(SCH_1):GND
 176    GND VSS<33> @BASEBOARD_FAB2_LIB.BASEBOARD_FAB2(SCH_1):GND
 178    GND VSS<32> @BASEBOARD_FAB2_LIB.BASEBOARD_FAB2(SCH_1):GND
 180    GND VSS<31> @BASEBOARD_FAB2_LIB.BASEBOARD_FAB2(SCH_1):GND
 182    GND VSS<30> @BASEBOARD_FAB2_LIB.BASEBOARD_FAB2(SCH_1):GND
 184    GND VSS<29> @BASEBOARD_FAB2_LIB.BASEBOARD_FAB2(SCH_1):GND
 187    GND VSS<28> @BASEBOARD_FAB2_LIB.BASEBOARD_FAB2(SCH_1):GND
 189    GND VSS<27> @BASEBOARD_FAB2_LIB.BASEBOARD_FAB2(SCH_1):GND
 191    GND VSS<26> @BASEBOARD_FAB2_LIB.BASEBOARD_FAB2(SCH_1):GND
 193    GND VSS<25> @BASEBOARD_FAB2_LIB.BASEBOARD_FAB2(SCH_1):GND
 195    GND VSS<24> @BASEBOARD_FAB2_LIB.BASEBOARD_FAB2(SCH_1):GND
 198    GND VSS<23> @BASEBOARD_FAB2_LIB.BASEBOARD_FAB2(SCH_1):GND
 200    GND VSS<22> @BASEBOARD_FAB2_LIB.BASEBOARD_FAB2(SCH_1):GND
 202    GND VSS<21> @BASEBOARD_FAB2_LIB.BASEBOARD_FAB2(SCH_1):GND
 239    GND VSS<20> @BASEBOARD_FAB2_LIB.BASEBOARD_FAB2(SCH_1):GND
 241    GND VSS<19> @BASEBOARD_FAB2_LIB.BASEBOARD_FAB2(SCH_1):GND
 243    GND VSS<18> @BASEBOARD_FAB2_LIB.BASEBOARD_FAB2(SCH_1):GND
 246    GND VSS<17> @BASEBOARD_FAB2_LIB.BASEBOARD_FAB2(SCH_1):GND
 248    GND VSS<16> @BASEBOARD_FAB2_LIB.BASEBOARD_FAB2(SCH_1):GND
 250    GND VSS<15> @BASEBOARD_FAB2_LIB.BASEBOARD_FAB2(SCH_1):GND
 252    GND VSS<14> @BASEBOARD_FAB2_LIB.BASEBOARD_FAB2(SCH_1):GND
 254    GND VSS<13> @BASEBOARD_FAB2_LIB.BASEBOARD_FAB2(SCH_1):GND
 257    GND VSS<12> @BASEBOARD_FAB2_LIB.BASEBOARD_FAB2(SCH_1):GND
 259    GND VSS<11> @BASEBOARD_FAB2_LIB.BASEBOARD_FAB2(SCH_1):GND
 261    GND VSS<10> @BASEBOARD_FAB2_LIB.BASEBOARD_FAB2(SCH_1):GND
 263    GND VSS<9> @BASEBOARD_FAB2_LIB.BASEBOARD_FAB2(SCH_1):GND
 265    GND VSS<8> @BASEBOARD_FAB2_LIB.BASEBOARD_FAB2(SCH_1):GND
 268    GND VSS<7> @BASEBOARD_FAB2_LIB.BASEBOARD_FAB2(SCH_1):GND
 270    GND VSS<6> @BASEBOARD_FAB2_LIB.BASEBOARD_FAB2(SCH_1):GND
 272    GND VSS<5> @BASEBOARD_FAB2_LIB.BASEBOARD_FAB2(SCH_1):GND
 274    GND VSS<4> @BASEBOARD_FAB2_LIB.BASEBOARD_FAB2(SCH_1):GND
 276    GND VSS<3> @BASEBOARD_FAB2_LIB.BASEBOARD_FAB2(SCH_1):GND
 279    GND VSS<2> @BASEBOARD_FAB2_LIB.BASEBOARD_FAB2(SCH_1):GND
 281    GND VSS<1> @BASEBOARD_FAB2_LIB.BASEBOARD_FAB2(SCH_1):GND
 283    GND VSS<0> @BASEBOARD_FAB2_LIB.BASEBOARD_FAB2(SCH_1):GND

SCONN288_H44441003_PIP-SCONN,HA  I87  J9L1
 152 M_M_DQS_DN<0>  DQS0N @BASEBOARD_FAB2_LIB.BASEBOARD_FAB2(SCH_1):M_M_DQS_DN(0)
 153 M_M_DQS_DP<0>  DQS0P @BASEBOARD_FAB2_LIB.BASEBOARD_FAB2(SCH_1):M_M_DQS_DP(0)
  19 M_M_DQS_DN<10> DQS10N @BASEBOARD_FAB2_LIB.BASEBOARD_FAB2(SCH_1):M_M_DQS_DN(10)
  18 M_M_DQS_DP<10> DQS10P @BASEBOARD_FAB2_LIB.BASEBOARD_FAB2(SCH_1):M_M_DQS_DP(10)
  30 M_M_DQS_DN<11> DQS11N @BASEBOARD_FAB2_LIB.BASEBOARD_FAB2(SCH_1):M_M_DQS_DN(11)
  29 M_M_DQS_DP<11> DQS11P @BASEBOARD_FAB2_LIB.BASEBOARD_FAB2(SCH_1):M_M_DQS_DP(11)
  41 M_M_DQS_DN<12> DQS12N @BASEBOARD_FAB2_LIB.BASEBOARD_FAB2(SCH_1):M_M_DQS_DN(12)
  40 M_M_DQS_DP<12> DQS12P @BASEBOARD_FAB2_LIB.BASEBOARD_FAB2(SCH_1):M_M_DQS_DP(12)
 100 M_M_DQS_DN<13> DQS13N @BASEBOARD_FAB2_LIB.BASEBOARD_FAB2(SCH_1):M_M_DQS_DN(13)
  99 M_M_DQS_DP<13> DQS13P @BASEBOARD_FAB2_LIB.BASEBOARD_FAB2(SCH_1):M_M_DQS_DP(13)
 111 M_M_DQS_DN<14> DQS14N @BASEBOARD_FAB2_LIB.BASEBOARD_FAB2(SCH_1):M_M_DQS_DN(14)
 110 M_M_DQS_DP<14> DQS14P @BASEBOARD_FAB2_LIB.BASEBOARD_FAB2(SCH_1):M_M_DQS_DP(14)
 122 M_M_DQS_DN<15> DQS15N @BASEBOARD_FAB2_LIB.BASEBOARD_FAB2(SCH_1):M_M_DQS_DN(15)
 121 M_M_DQS_DP<15> DQS15P @BASEBOARD_FAB2_LIB.BASEBOARD_FAB2(SCH_1):M_M_DQS_DP(15)
 133 M_M_DQS_DN<16> DQS16N @BASEBOARD_FAB2_LIB.BASEBOARD_FAB2(SCH_1):M_M_DQS_DN(16)
 132 M_M_DQS_DP<16> DQS16P @BASEBOARD_FAB2_LIB.BASEBOARD_FAB2(SCH_1):M_M_DQS_DP(16)
  52 M_M_DQS_DN<17> DQS17N @BASEBOARD_FAB2_LIB.BASEBOARD_FAB2(SCH_1):M_M_DQS_DN(17)
  51 M_M_DQS_DP<17> DQS17P @BASEBOARD_FAB2_LIB.BASEBOARD_FAB2(SCH_1):M_M_DQS_DP(17)
 163 M_M_DQS_DN<1>  DQS1N @BASEBOARD_FAB2_LIB.BASEBOARD_FAB2(SCH_1):M_M_DQS_DN(1)
 164 M_M_DQS_DP<1>  DQS1P @BASEBOARD_FAB2_LIB.BASEBOARD_FAB2(SCH_1):M_M_DQS_DP(1)
 174 M_M_DQS_DN<2>  DQS2N @BASEBOARD_FAB2_LIB.BASEBOARD_FAB2(SCH_1):M_M_DQS_DN(2)
 175 M_M_DQS_DP<2>  DQS2P @BASEBOARD_FAB2_LIB.BASEBOARD_FAB2(SCH_1):M_M_DQS_DP(2)
 185 M_M_DQS_DN<3>  DQS3N @BASEBOARD_FAB2_LIB.BASEBOARD_FAB2(SCH_1):M_M_DQS_DN(3)
 186 M_M_DQS_DP<3>  DQS3P @BASEBOARD_FAB2_LIB.BASEBOARD_FAB2(SCH_1):M_M_DQS_DP(3)
 244 M_M_DQS_DN<4>  DQS4N @BASEBOARD_FAB2_LIB.BASEBOARD_FAB2(SCH_1):M_M_DQS_DN(4)
 245 M_M_DQS_DP<4>  DQS4P @BASEBOARD_FAB2_LIB.BASEBOARD_FAB2(SCH_1):M_M_DQS_DP(4)
 255 M_M_DQS_DN<5>  DQS5N @BASEBOARD_FAB2_LIB.BASEBOARD_FAB2(SCH_1):M_M_DQS_DN(5)
 256 M_M_DQS_DP<5>  DQS5P @BASEBOARD_FAB2_LIB.BASEBOARD_FAB2(SCH_1):M_M_DQS_DP(5)
 266 M_M_DQS_DN<6>  DQS6N @BASEBOARD_FAB2_LIB.BASEBOARD_FAB2(SCH_1):M_M_DQS_DN(6)
 267 M_M_DQS_DP<6>  DQS6P @BASEBOARD_FAB2_LIB.BASEBOARD_FAB2(SCH_1):M_M_DQS_DP(6)
 277 M_M_DQS_DN<7>  DQS7N @BASEBOARD_FAB2_LIB.BASEBOARD_FAB2(SCH_1):M_M_DQS_DN(7)
 278 M_M_DQS_DP<7>  DQS7P @BASEBOARD_FAB2_LIB.BASEBOARD_FAB2(SCH_1):M_M_DQS_DP(7)
 196 M_M_DQS_DN<8>  DQS8N @BASEBOARD_FAB2_LIB.BASEBOARD_FAB2(SCH_1):M_M_DQS_DN(8)
 197 M_M_DQS_DP<8>  DQS8P @BASEBOARD_FAB2_LIB.BASEBOARD_FAB2(SCH_1):M_M_DQS_DP(8)
   8 M_M_DQS_DN<9>  DQS9N @BASEBOARD_FAB2_LIB.BASEBOARD_FAB2(SCH_1):M_M_DQS_DN(9)
   7 M_M_DQS_DP<9>  DQS9P @BASEBOARD_FAB2_LIB.BASEBOARD_FAB2(SCH_1):M_M_DQS_DP(9)

SCONN288_H44441003_PIP-SCONN,HA  I111  J9L1
  79 M_M_MA<0>     A0 @BASEBOARD_FAB2_LIB.BASEBOARD_FAB2(SCH_1):M_M_MA(0)
  72 M_M_MA<1>     A1 @BASEBOARD_FAB2_LIB.BASEBOARD_FAB2(SCH_1):M_M_MA(1)
 225 M_M_MA<10>    A10 @BASEBOARD_FAB2_LIB.BASEBOARD_FAB2(SCH_1):M_M_MA(10)
 210 M_M_MA<11>    A11 @BASEBOARD_FAB2_LIB.BASEBOARD_FAB2(SCH_1):M_M_MA(11)
  65 M_M_MA<12>    A12 @BASEBOARD_FAB2_LIB.BASEBOARD_FAB2(SCH_1):M_M_MA(12)
 232 M_M_MA<13>    A13 @BASEBOARD_FAB2_LIB.BASEBOARD_FAB2(SCH_1):M_M_MA(13)
 228 M_M_MA<14> A14_WE_N @BASEBOARD_FAB2_LIB.BASEBOARD_FAB2(SCH_1):M_M_MA(14)
  86 M_M_MA<15> A15_CAS_N @BASEBOARD_FAB2_LIB.BASEBOARD_FAB2(SCH_1):M_M_MA(15)
  82 M_M_MA<16> A16_RAS_N @BASEBOARD_FAB2_LIB.BASEBOARD_FAB2(SCH_1):M_M_MA(16)
 234 M_M_MA<17>    A17 @BASEBOARD_FAB2_LIB.BASEBOARD_FAB2(SCH_1):M_M_MA(17)
 216 M_M_MA<2>     A2 @BASEBOARD_FAB2_LIB.BASEBOARD_FAB2(SCH_1):M_M_MA(2)
  71 M_M_MA<3>     A3 @BASEBOARD_FAB2_LIB.BASEBOARD_FAB2(SCH_1):M_M_MA(3)
 214 M_M_MA<4>     A4 @BASEBOARD_FAB2_LIB.BASEBOARD_FAB2(SCH_1):M_M_MA(4)
 213 M_M_MA<5>     A5 @BASEBOARD_FAB2_LIB.BASEBOARD_FAB2(SCH_1):M_M_MA(5)
  69 M_M_MA<6>     A6 @BASEBOARD_FAB2_LIB.BASEBOARD_FAB2(SCH_1):M_M_MA(6)
 211 M_M_MA<7>     A7 @BASEBOARD_FAB2_LIB.BASEBOARD_FAB2(SCH_1):M_M_MA(7)
  68 M_M_MA<8>     A8 @BASEBOARD_FAB2_LIB.BASEBOARD_FAB2(SCH_1):M_M_MA(8)
  66 M_M_MA<9>     A9 @BASEBOARD_FAB2_LIB.BASEBOARD_FAB2(SCH_1):M_M_MA(9)
  62 M_M_ACT_N  ACT_N @BASEBOARD_FAB2_LIB.BASEBOARD_FAB2(SCH_1):M_M_ACT_N
 208 M_M_ALERT_N ALERT_N @BASEBOARD_FAB2_LIB.BASEBOARD_FAB2(SCH_1):M_M_ALERT_N
 224 M_M_BA<1>  BA<1> @BASEBOARD_FAB2_LIB.BASEBOARD_FAB2(SCH_1):M_M_BA(1)
  81 M_M_BA<0>  BA<0> @BASEBOARD_FAB2_LIB.BASEBOARD_FAB2(SCH_1):M_M_BA(0)
 207 M_M_BG<1>  BG<1> @BASEBOARD_FAB2_LIB.BASEBOARD_FAB2(SCH_1):M_M_BG(1)
  63 M_M_BG<0>  BG<0> @BASEBOARD_FAB2_LIB.BASEBOARD_FAB2(SCH_1):M_M_BG(0)
 235 M_M_C<2>   C<2> @BASEBOARD_FAB2_LIB.BASEBOARD_FAB2(SCH_1):M_M_C(2)
 199 M_M_ECC<7>  CB<7> @BASEBOARD_FAB2_LIB.BASEBOARD_FAB2(SCH_1):M_M_ECC(7)
  54 M_M_ECC<6>  CB<6> @BASEBOARD_FAB2_LIB.BASEBOARD_FAB2(SCH_1):M_M_ECC(6)
 192 M_M_ECC<5>  CB<5> @BASEBOARD_FAB2_LIB.BASEBOARD_FAB2(SCH_1):M_M_ECC(5)
  47 M_M_ECC<4>  CB<4> @BASEBOARD_FAB2_LIB.BASEBOARD_FAB2(SCH_1):M_M_ECC(4)
 201 M_M_ECC<3>  CB<3> @BASEBOARD_FAB2_LIB.BASEBOARD_FAB2(SCH_1):M_M_ECC(3)
  56 M_M_ECC<2>  CB<2> @BASEBOARD_FAB2_LIB.BASEBOARD_FAB2(SCH_1):M_M_ECC(2)
 194 M_M_ECC<1>  CB<1> @BASEBOARD_FAB2_LIB.BASEBOARD_FAB2(SCH_1):M_M_ECC(1)
  49 M_M_ECC<0>  CB<0> @BASEBOARD_FAB2_LIB.BASEBOARD_FAB2(SCH_1):M_M_ECC(0)
  75 M_M_CLK_DN<2>   CK0N @BASEBOARD_FAB2_LIB.BASEBOARD_FAB2(SCH_1):M_M_CLK_DN(2)
  74 M_M_CLK_DP<2>   CK0P @BASEBOARD_FAB2_LIB.BASEBOARD_FAB2(SCH_1):M_M_CLK_DP(2)
 219 M_M_CLK_DN<3>   CK1N @BASEBOARD_FAB2_LIB.BASEBOARD_FAB2(SCH_1):M_M_CLK_DN(3)
 218 M_M_CLK_DP<3>   CK1P @BASEBOARD_FAB2_LIB.BASEBOARD_FAB2(SCH_1):M_M_CLK_DP(3)
 203 M_M_CKE<3> CKE<1> @BASEBOARD_FAB2_LIB.BASEBOARD_FAB2(SCH_1):M_M_CKE(3)
  60 M_M_CKE<2> CKE<0> @BASEBOARD_FAB2_LIB.BASEBOARD_FAB2(SCH_1):M_M_CKE(2)
 280 M_M_DQ<63> DQ<63> @BASEBOARD_FAB2_LIB.BASEBOARD_FAB2(SCH_1):M_M_DQ(63)
 135 M_M_DQ<62> DQ<62> @BASEBOARD_FAB2_LIB.BASEBOARD_FAB2(SCH_1):M_M_DQ(62)
 273 M_M_DQ<61> DQ<61> @BASEBOARD_FAB2_LIB.BASEBOARD_FAB2(SCH_1):M_M_DQ(61)
 128 M_M_DQ<60> DQ<60> @BASEBOARD_FAB2_LIB.BASEBOARD_FAB2(SCH_1):M_M_DQ(60)
 282 M_M_DQ<59> DQ<59> @BASEBOARD_FAB2_LIB.BASEBOARD_FAB2(SCH_1):M_M_DQ(59)
 137 M_M_DQ<58> DQ<58> @BASEBOARD_FAB2_LIB.BASEBOARD_FAB2(SCH_1):M_M_DQ(58)
 275 M_M_DQ<57> DQ<57> @BASEBOARD_FAB2_LIB.BASEBOARD_FAB2(SCH_1):M_M_DQ(57)
 130 M_M_DQ<56> DQ<56> @BASEBOARD_FAB2_LIB.BASEBOARD_FAB2(SCH_1):M_M_DQ(56)
 269 M_M_DQ<55> DQ<55> @BASEBOARD_FAB2_LIB.BASEBOARD_FAB2(SCH_1):M_M_DQ(55)
 124 M_M_DQ<54> DQ<54> @BASEBOARD_FAB2_LIB.BASEBOARD_FAB2(SCH_1):M_M_DQ(54)
 262 M_M_DQ<53> DQ<53> @BASEBOARD_FAB2_LIB.BASEBOARD_FAB2(SCH_1):M_M_DQ(53)
 117 M_M_DQ<52> DQ<52> @BASEBOARD_FAB2_LIB.BASEBOARD_FAB2(SCH_1):M_M_DQ(52)
 271 M_M_DQ<51> DQ<51> @BASEBOARD_FAB2_LIB.BASEBOARD_FAB2(SCH_1):M_M_DQ(51)
 126 M_M_DQ<50> DQ<50> @BASEBOARD_FAB2_LIB.BASEBOARD_FAB2(SCH_1):M_M_DQ(50)
 264 M_M_DQ<49> DQ<49> @BASEBOARD_FAB2_LIB.BASEBOARD_FAB2(SCH_1):M_M_DQ(49)
 119 M_M_DQ<48> DQ<48> @BASEBOARD_FAB2_LIB.BASEBOARD_FAB2(SCH_1):M_M_DQ(48)
 258 M_M_DQ<47> DQ<47> @BASEBOARD_FAB2_LIB.BASEBOARD_FAB2(SCH_1):M_M_DQ(47)
 113 M_M_DQ<46> DQ<46> @BASEBOARD_FAB2_LIB.BASEBOARD_FAB2(SCH_1):M_M_DQ(46)
 251 M_M_DQ<45> DQ<45> @BASEBOARD_FAB2_LIB.BASEBOARD_FAB2(SCH_1):M_M_DQ(45)
 106 M_M_DQ<44> DQ<44> @BASEBOARD_FAB2_LIB.BASEBOARD_FAB2(SCH_1):M_M_DQ(44)
 260 M_M_DQ<43> DQ<43> @BASEBOARD_FAB2_LIB.BASEBOARD_FAB2(SCH_1):M_M_DQ(43)
 115 M_M_DQ<42> DQ<42> @BASEBOARD_FAB2_LIB.BASEBOARD_FAB2(SCH_1):M_M_DQ(42)
 253 M_M_DQ<41> DQ<41> @BASEBOARD_FAB2_LIB.BASEBOARD_FAB2(SCH_1):M_M_DQ(41)
 108 M_M_DQ<40> DQ<40> @BASEBOARD_FAB2_LIB.BASEBOARD_FAB2(SCH_1):M_M_DQ(40)
 247 M_M_DQ<39> DQ<39> @BASEBOARD_FAB2_LIB.BASEBOARD_FAB2(SCH_1):M_M_DQ(39)
 102 M_M_DQ<38> DQ<38> @BASEBOARD_FAB2_LIB.BASEBOARD_FAB2(SCH_1):M_M_DQ(38)
 240 M_M_DQ<37> DQ<37> @BASEBOARD_FAB2_LIB.BASEBOARD_FAB2(SCH_1):M_M_DQ(37)
  95 M_M_DQ<36> DQ<36> @BASEBOARD_FAB2_LIB.BASEBOARD_FAB2(SCH_1):M_M_DQ(36)
 249 M_M_DQ<35> DQ<35> @BASEBOARD_FAB2_LIB.BASEBOARD_FAB2(SCH_1):M_M_DQ(35)
 104 M_M_DQ<34> DQ<34> @BASEBOARD_FAB2_LIB.BASEBOARD_FAB2(SCH_1):M_M_DQ(34)
 242 M_M_DQ<33> DQ<33> @BASEBOARD_FAB2_LIB.BASEBOARD_FAB2(SCH_1):M_M_DQ(33)
  97 M_M_DQ<32> DQ<32> @BASEBOARD_FAB2_LIB.BASEBOARD_FAB2(SCH_1):M_M_DQ(32)
 188 M_M_DQ<31> DQ<31> @BASEBOARD_FAB2_LIB.BASEBOARD_FAB2(SCH_1):M_M_DQ(31)
  43 M_M_DQ<30> DQ<30> @BASEBOARD_FAB2_LIB.BASEBOARD_FAB2(SCH_1):M_M_DQ(30)
 181 M_M_DQ<29> DQ<29> @BASEBOARD_FAB2_LIB.BASEBOARD_FAB2(SCH_1):M_M_DQ(29)
  36 M_M_DQ<28> DQ<28> @BASEBOARD_FAB2_LIB.BASEBOARD_FAB2(SCH_1):M_M_DQ(28)
 190 M_M_DQ<27> DQ<27> @BASEBOARD_FAB2_LIB.BASEBOARD_FAB2(SCH_1):M_M_DQ(27)
  45 M_M_DQ<26> DQ<26> @BASEBOARD_FAB2_LIB.BASEBOARD_FAB2(SCH_1):M_M_DQ(26)
 183 M_M_DQ<25> DQ<25> @BASEBOARD_FAB2_LIB.BASEBOARD_FAB2(SCH_1):M_M_DQ(25)
  38 M_M_DQ<24> DQ<24> @BASEBOARD_FAB2_LIB.BASEBOARD_FAB2(SCH_1):M_M_DQ(24)
 177 M_M_DQ<23> DQ<23> @BASEBOARD_FAB2_LIB.BASEBOARD_FAB2(SCH_1):M_M_DQ(23)
  32 M_M_DQ<22> DQ<22> @BASEBOARD_FAB2_LIB.BASEBOARD_FAB2(SCH_1):M_M_DQ(22)
 170 M_M_DQ<21> DQ<21> @BASEBOARD_FAB2_LIB.BASEBOARD_FAB2(SCH_1):M_M_DQ(21)
  25 M_M_DQ<20> DQ<20> @BASEBOARD_FAB2_LIB.BASEBOARD_FAB2(SCH_1):M_M_DQ(20)
 179 M_M_DQ<19> DQ<19> @BASEBOARD_FAB2_LIB.BASEBOARD_FAB2(SCH_1):M_M_DQ(19)
  34 M_M_DQ<18> DQ<18> @BASEBOARD_FAB2_LIB.BASEBOARD_FAB2(SCH_1):M_M_DQ(18)
 172 M_M_DQ<17> DQ<17> @BASEBOARD_FAB2_LIB.BASEBOARD_FAB2(SCH_1):M_M_DQ(17)
  27 M_M_DQ<16> DQ<16> @BASEBOARD_FAB2_LIB.BASEBOARD_FAB2(SCH_1):M_M_DQ(16)
 166 M_M_DQ<15> DQ<15> @BASEBOARD_FAB2_LIB.BASEBOARD_FAB2(SCH_1):M_M_DQ(15)
  21 M_M_DQ<14> DQ<14> @BASEBOARD_FAB2_LIB.BASEBOARD_FAB2(SCH_1):M_M_DQ(14)
 159 M_M_DQ<13> DQ<13> @BASEBOARD_FAB2_LIB.BASEBOARD_FAB2(SCH_1):M_M_DQ(13)
  14 M_M_DQ<12> DQ<12> @BASEBOARD_FAB2_LIB.BASEBOARD_FAB2(SCH_1):M_M_DQ(12)
 168 M_M_DQ<11> DQ<11> @BASEBOARD_FAB2_LIB.BASEBOARD_FAB2(SCH_1):M_M_DQ(11)
  23 M_M_DQ<10> DQ<10> @BASEBOARD_FAB2_LIB.BASEBOARD_FAB2(SCH_1):M_M_DQ(10)
 161 M_M_DQ<9>  DQ<9> @BASEBOARD_FAB2_LIB.BASEBOARD_FAB2(SCH_1):M_M_DQ(9)
  16 M_M_DQ<8>  DQ<8> @BASEBOARD_FAB2_LIB.BASEBOARD_FAB2(SCH_1):M_M_DQ(8)
 155 M_M_DQ<7>  DQ<7> @BASEBOARD_FAB2_LIB.BASEBOARD_FAB2(SCH_1):M_M_DQ(7)
  10 M_M_DQ<6>  DQ<6> @BASEBOARD_FAB2_LIB.BASEBOARD_FAB2(SCH_1):M_M_DQ(6)
 148 M_M_DQ<5>  DQ<5> @BASEBOARD_FAB2_LIB.BASEBOARD_FAB2(SCH_1):M_M_DQ(5)
   3 M_M_DQ<4>  DQ<4> @BASEBOARD_FAB2_LIB.BASEBOARD_FAB2(SCH_1):M_M_DQ(4)
 157 M_M_DQ<3>  DQ<3> @BASEBOARD_FAB2_LIB.BASEBOARD_FAB2(SCH_1):M_M_DQ(3)
  12 M_M_DQ<2>  DQ<2> @BASEBOARD_FAB2_LIB.BASEBOARD_FAB2(SCH_1):M_M_DQ(2)
 150 M_M_DQ<1>  DQ<1> @BASEBOARD_FAB2_LIB.BASEBOARD_FAB2(SCH_1):M_M_DQ(1)
   5 M_M_DQ<0>  DQ<0> @BASEBOARD_FAB2_LIB.BASEBOARD_FAB2(SCH_1):M_M_DQ(0)
  78 FM_DIMM_EVENT_COD_N EVENT_N @BASEBOARD_FAB2_LIB.BASEBOARD_FAB2(SCH_1):FM_DIMM_EVENT_COD_N
  91 M_M_ODT<3> ODT<1> @BASEBOARD_FAB2_LIB.BASEBOARD_FAB2(SCH_1):M_M_ODT(3)
  87 M_M_ODT<2> ODT<0> @BASEBOARD_FAB2_LIB.BASEBOARD_FAB2(SCH_1):M_M_ODT(2)
 222 M_M_PAR    PAR @BASEBOARD_FAB2_LIB.BASEBOARD_FAB2(SCH_1):M_M_PAR
  58 M_KLM_RST_N RESET_N @BASEBOARD_FAB2_LIB.BASEBOARD_FAB2(SCH_1):M_KLM_RST_N
 144 TP_CH_M_DIMM_M1_RFU_2 RFU<2> @BASEBOARD_FAB2_LIB.BASEBOARD_FAB2(SCH_1):TP_CH_M_DIMM_M1_RFU_2
 227 TP_CH_M_DIMM_M1_RFU_1 RFU<1> @BASEBOARD_FAB2_LIB.BASEBOARD_FAB2(SCH_1):TP_CH_M_DIMM_M1_RFU_1
 205 TP_CH_M_DIMM_M1_RFU_0 RFU<0> @BASEBOARD_FAB2_LIB.BASEBOARD_FAB2(SCH_1):TP_CH_M_DIMM_M1_RFU_0
  84 M_M_CS_N<4>   S0_N @BASEBOARD_FAB2_LIB.BASEBOARD_FAB2(SCH_1):M_M_CS_N(4)
  89 M_M_CS_N<5>   S1_N @BASEBOARD_FAB2_LIB.BASEBOARD_FAB2(SCH_1):M_M_CS_N(5)
  93 M_M_CS_N<6> S2_N_C<0> @BASEBOARD_FAB2_LIB.BASEBOARD_FAB2(SCH_1):M_M_CS_N(6)
 237 M_M_CS_N<7> S3_N_C<1> @BASEBOARD_FAB2_LIB.BASEBOARD_FAB2(SCH_1):M_M_CS_N(7)
 238 PVPP_KLM  SA<2> @BASEBOARD_FAB2_LIB.BASEBOARD_FAB2(SCH_1):PVPP_KLM
 140    GND  SA<1> @BASEBOARD_FAB2_LIB.BASEBOARD_FAB2(SCH_1):GND
 139 PVPP_KLM  SA<0> @BASEBOARD_FAB2_LIB.BASEBOARD_FAB2(SCH_1):PVPP_KLM
 230 FM_ADR_COMPLETE_KLM_N SAVE_N_NC @BASEBOARD_FAB2_LIB.BASEBOARD_FAB2(SCH_1):FM_ADR_COMPLETE_KLM_N
 141 SMB_DDR_KLM_VPP_SCL    SCL @BASEBOARD_FAB2_LIB.BASEBOARD_FAB2(SCH_1):SMB_DDR_KLM_VPP_SCL
 285 SMB_DDR_KLM_VPP_SDA    SDA @BASEBOARD_FAB2_LIB.BASEBOARD_FAB2(SCH_1):SMB_DDR_KLM_VPP_SDA
 284 PVPP_KLM VDDSPD @BASEBOARD_FAB2_LIB.BASEBOARD_FAB2(SCH_1):PVPP_KLM
 146 M_M_VREF VREFCA @BASEBOARD_FAB2_LIB.BASEBOARD_FAB2(SCH_1):M_M_VREF

SCONN288_H44441003_PIP-SCONN,HA  I168  J9L1
   1 P12V_NVDIMM_KLM 12V<1> @BASEBOARD_FAB2_LIB.BASEBOARD_FAB2(SCH_1):P12V_NVDIMM_KLM
 145 P12V_NVDIMM_KLM 12V<0> @BASEBOARD_FAB2_LIB.BASEBOARD_FAB2(SCH_1):P12V_NVDIMM_KLM
  59 PVDDQ_KLM VDD<25> @BASEBOARD_FAB2_LIB.BASEBOARD_FAB2(SCH_1):PVDDQ_KLM
  61 PVDDQ_KLM VDD<24> @BASEBOARD_FAB2_LIB.BASEBOARD_FAB2(SCH_1):PVDDQ_KLM
  64 PVDDQ_KLM VDD<23> @BASEBOARD_FAB2_LIB.BASEBOARD_FAB2(SCH_1):PVDDQ_KLM
  67 PVDDQ_KLM VDD<22> @BASEBOARD_FAB2_LIB.BASEBOARD_FAB2(SCH_1):PVDDQ_KLM
  70 PVDDQ_KLM VDD<21> @BASEBOARD_FAB2_LIB.BASEBOARD_FAB2(SCH_1):PVDDQ_KLM
  73 PVDDQ_KLM VDD<20> @BASEBOARD_FAB2_LIB.BASEBOARD_FAB2(SCH_1):PVDDQ_KLM
  76 PVDDQ_KLM VDD<19> @BASEBOARD_FAB2_LIB.BASEBOARD_FAB2(SCH_1):PVDDQ_KLM
  80 PVDDQ_KLM VDD<18> @BASEBOARD_FAB2_LIB.BASEBOARD_FAB2(SCH_1):PVDDQ_KLM
  83 PVDDQ_KLM VDD<17> @BASEBOARD_FAB2_LIB.BASEBOARD_FAB2(SCH_1):PVDDQ_KLM
  85 PVDDQ_KLM VDD<16> @BASEBOARD_FAB2_LIB.BASEBOARD_FAB2(SCH_1):PVDDQ_KLM
  88 PVDDQ_KLM VDD<15> @BASEBOARD_FAB2_LIB.BASEBOARD_FAB2(SCH_1):PVDDQ_KLM
  90 PVDDQ_KLM VDD<14> @BASEBOARD_FAB2_LIB.BASEBOARD_FAB2(SCH_1):PVDDQ_KLM
  92 PVDDQ_KLM VDD<13> @BASEBOARD_FAB2_LIB.BASEBOARD_FAB2(SCH_1):PVDDQ_KLM
 204 PVDDQ_KLM VDD<12> @BASEBOARD_FAB2_LIB.BASEBOARD_FAB2(SCH_1):PVDDQ_KLM
 206 PVDDQ_KLM VDD<11> @BASEBOARD_FAB2_LIB.BASEBOARD_FAB2(SCH_1):PVDDQ_KLM
 209 PVDDQ_KLM VDD<10> @BASEBOARD_FAB2_LIB.BASEBOARD_FAB2(SCH_1):PVDDQ_KLM
 212 PVDDQ_KLM VDD<9> @BASEBOARD_FAB2_LIB.BASEBOARD_FAB2(SCH_1):PVDDQ_KLM
 215 PVDDQ_KLM VDD<8> @BASEBOARD_FAB2_LIB.BASEBOARD_FAB2(SCH_1):PVDDQ_KLM
 217 PVDDQ_KLM VDD<7> @BASEBOARD_FAB2_LIB.BASEBOARD_FAB2(SCH_1):PVDDQ_KLM
 220 PVDDQ_KLM VDD<6> @BASEBOARD_FAB2_LIB.BASEBOARD_FAB2(SCH_1):PVDDQ_KLM
 223 PVDDQ_KLM VDD<5> @BASEBOARD_FAB2_LIB.BASEBOARD_FAB2(SCH_1):PVDDQ_KLM
 226 PVDDQ_KLM VDD<4> @BASEBOARD_FAB2_LIB.BASEBOARD_FAB2(SCH_1):PVDDQ_KLM
 229 PVDDQ_KLM VDD<3> @BASEBOARD_FAB2_LIB.BASEBOARD_FAB2(SCH_1):PVDDQ_KLM
 231 PVDDQ_KLM VDD<2> @BASEBOARD_FAB2_LIB.BASEBOARD_FAB2(SCH_1):PVDDQ_KLM
 233 PVDDQ_KLM VDD<1> @BASEBOARD_FAB2_LIB.BASEBOARD_FAB2(SCH_1):PVDDQ_KLM
 236 PVDDQ_KLM VDD<0> @BASEBOARD_FAB2_LIB.BASEBOARD_FAB2(SCH_1):PVDDQ_KLM
 142 PVPP_KLM VPP<4> @BASEBOARD_FAB2_LIB.BASEBOARD_FAB2(SCH_1):PVPP_KLM
 143 PVPP_KLM VPP<3> @BASEBOARD_FAB2_LIB.BASEBOARD_FAB2(SCH_1):PVPP_KLM
 288 PVPP_KLM VPP<2> @BASEBOARD_FAB2_LIB.BASEBOARD_FAB2(SCH_1):PVPP_KLM
 286 PVPP_KLM VPP<1> @BASEBOARD_FAB2_LIB.BASEBOARD_FAB2(SCH_1):PVPP_KLM
 287 PVPP_KLM VPP<0> @BASEBOARD_FAB2_LIB.BASEBOARD_FAB2(SCH_1):PVPP_KLM
  77 PVTT_KLM VTT<1> @BASEBOARD_FAB2_LIB.BASEBOARD_FAB2(SCH_1):PVTT_KLM
 221 PVTT_KLM VTT<0> @BASEBOARD_FAB2_LIB.BASEBOARD_FAB2(SCH_1):PVTT_KLM

CAP_A_0402V-0.01UF,25V,10%,X7RA  I177  C9L1
   1 M_M_VREF      A @BASEBOARD_FAB2_LIB.BASEBOARD_FAB2(SCH_1):M_M_VREF
   2    GND      B @BASEBOARD_FAB2_LIB.BASEBOARD_FAB2(SCH_1):GND


DRAWING: @BASEBOARD_FAB2_LIB.BASEBOARD_FAB2(SCH_1):PAGE89 

RES_0402-0.0,5%,1/16W,EMPTY,G2A  I1  R4T2
   1 FM_ADR_COMPLETE      A @BASEBOARD_FAB2_LIB.BASEBOARD_FAB2(SCH_1):FM_ADR_COMPLETE
   2 FM_ADR_COMPLETE_R      B @BASEBOARD_FAB2_LIB.BASEBOARD_FAB2(SCH_1):FM_ADR_COMPLETE_R

RES_0402-0.0,5%,1/16W,CHIP,G21A  I2  R4T1
   1 FM_ADR_COMPLETE_DLY      A @BASEBOARD_FAB2_LIB.BASEBOARD_FAB2(SCH_1):FM_ADR_COMPLETE_DLY
   2 FM_ADR_COMPLETE_R      B @BASEBOARD_FAB2_LIB.BASEBOARD_FAB2(SCH_1):FM_ADR_COMPLETE_R

RES_0402-49.9,1%,1/16W,CHIP,G2A  I3  R6F4
   1 IRQ_DIMM_SAVE_N      A @BASEBOARD_FAB2_LIB.BASEBOARD_FAB2(SCH_1):IRQ_DIMM_SAVE_N
   2 FM_ADR_COMPLETE_ABC_N      B @BASEBOARD_FAB2_LIB.BASEBOARD_FAB2(SCH_1):FM_ADR_COMPLETE_ABC_N

RES_0402-49.9,1%,1/16W,CHIP,G2A  I4  R6F1
   1 IRQ_DIMM_SAVE_N      A @BASEBOARD_FAB2_LIB.BASEBOARD_FAB2(SCH_1):IRQ_DIMM_SAVE_N
   2 FM_ADR_COMPLETE_DEF_N      B @BASEBOARD_FAB2_LIB.BASEBOARD_FAB2(SCH_1):FM_ADR_COMPLETE_DEF_N

RES_0402-49.9,1%,1/16W,CHIP,G2A  I5  R6F5
   1 IRQ_DIMM_SAVE_N      A @BASEBOARD_FAB2_LIB.BASEBOARD_FAB2(SCH_1):IRQ_DIMM_SAVE_N
   2 FM_ADR_COMPLETE_GHJ_N      B @BASEBOARD_FAB2_LIB.BASEBOARD_FAB2(SCH_1):FM_ADR_COMPLETE_GHJ_N

RES_0402-49.9,1%,1/16W,CHIP,G2A  I6  R6F2
   1 IRQ_DIMM_SAVE_N      A @BASEBOARD_FAB2_LIB.BASEBOARD_FAB2(SCH_1):IRQ_DIMM_SAVE_N
   2 FM_ADR_COMPLETE_KLM_N      B @BASEBOARD_FAB2_LIB.BASEBOARD_FAB2(SCH_1):FM_ADR_COMPLETE_KLM_N

RES_0402-10.0K,1%,1/16W,CHIP,GA  I7  R6F3
   1 PVPP_ABC      A @BASEBOARD_FAB2_LIB.BASEBOARD_FAB2(SCH_1):PVPP_ABC
   2 IRQ_DIMM_SAVE_N      B @BASEBOARD_FAB2_LIB.BASEBOARD_FAB2(SCH_1):IRQ_DIMM_SAVE_N

FET_N_SOT23-2N7002,FET,C79254-A  I18  Q6F1
   1 FM_ADR_COMPLETE_R   GATE @BASEBOARD_FAB2_LIB.BASEBOARD_FAB2(SCH_1):FM_ADR_COMPLETE_R
   2    GND    SRC @BASEBOARD_FAB2_LIB.BASEBOARD_FAB2(SCH_1):GND
   3 IRQ_DIMM_SAVE_N    DRN @BASEBOARD_FAB2_LIB.BASEBOARD_FAB2(SCH_1):IRQ_DIMM_SAVE_N

RES_0402-0.0,5%,1/16W,EMPTY,G2A  I23  R2P12
   1 IRQ_DIMM_SAVE_LVT3_N      A @BASEBOARD_FAB2_LIB.BASEBOARD_FAB2(SCH_1):IRQ_DIMM_SAVE_LVT3_N
   2 FM_ADR_SMI_GPIO_N      B @BASEBOARD_FAB2_LIB.BASEBOARD_FAB2(SCH_1):FM_ADR_SMI_GPIO_N

RES_0402-4.75K,1%,1/16W,CHIP,GA  I26  R8D29
   1 P3V3_STBY      A @BASEBOARD_FAB2_LIB.BASEBOARD_FAB2(SCH_1):P3V3_STBY
   2 IRQ_DIMM_SAVE_LVT3      B @BASEBOARD_FAB2_LIB.BASEBOARD_FAB2(SCH_1):IRQ_DIMM_SAVE_LVT3

RES_0402-4.75K,1%,1/16W,CHIP,GA  I27  R8D31
   1 P3V3_STBY      A @BASEBOARD_FAB2_LIB.BASEBOARD_FAB2(SCH_1):P3V3_STBY
   2 IRQ_DIMM_SAVE_LVT3_N      B @BASEBOARD_FAB2_LIB.BASEBOARD_FAB2(SCH_1):IRQ_DIMM_SAVE_LVT3_N

RES_0402-10.0K,1%,1/16W,CHIP,GA  I34  R8D30
   1 IRQ_DIMM_SAVE_N      A @BASEBOARD_FAB2_LIB.BASEBOARD_FAB2(SCH_1):IRQ_DIMM_SAVE_N
   2 IRQ_DIMM_SAVE_R_N      B @BASEBOARD_FAB2_LIB.BASEBOARD_FAB2(SCH_1):IRQ_DIMM_SAVE_R_N

NPN_DUAL_SSOPLF-MBT3904,XSTR,CA  I35  Q8D1
   5 IRQ_DIMM_SAVE_R_N   B<0> @BASEBOARD_FAB2_LIB.BASEBOARD_FAB2(SCH_1):IRQ_DIMM_SAVE_R_N
   3 IRQ_DIMM_SAVE_LVT3   C<0> @BASEBOARD_FAB2_LIB.BASEBOARD_FAB2(SCH_1):IRQ_DIMM_SAVE_LVT3
   4    GND   E<0> @BASEBOARD_FAB2_LIB.BASEBOARD_FAB2(SCH_1):GND

NPN_DUAL_SSOPLF-MBT3904,XSTR,CA  I36  Q8D1
   2 IRQ_DIMM_SAVE_LVT3   B<0> @BASEBOARD_FAB2_LIB.BASEBOARD_FAB2(SCH_1):IRQ_DIMM_SAVE_LVT3
   6 IRQ_DIMM_SAVE_LVT3_N   C<0> @BASEBOARD_FAB2_LIB.BASEBOARD_FAB2(SCH_1):IRQ_DIMM_SAVE_LVT3_N
   1    GND   E<0> @BASEBOARD_FAB2_LIB.BASEBOARD_FAB2(SCH_1):GND


DRAWING: @BASEBOARD_FAB2_LIB.BASEBOARD_FAB2(SCH_1):PAGE90 

RES_0402-240,1.0%,1/16W,CHIP,GA  I3  R6D6
   1    GND      A @BASEBOARD_FAB2_LIB.BASEBOARD_FAB2(SCH_1):GND
   2 PD_CPU0_TXT_PLTEN      B @BASEBOARD_FAB2_LIB.BASEBOARD_FAB2(SCH_1):PD_CPU0_TXT_PLTEN

RES_0402-240,1.0%,1/16W,EMPTY,A  I4  R4P1
   1    GND      A @BASEBOARD_FAB2_LIB.BASEBOARD_FAB2(SCH_1):GND
   2 PD_CPU0_BIST_ENABLE      B @BASEBOARD_FAB2_LIB.BASEBOARD_FAB2(SCH_1):PD_CPU0_BIST_ENABLE

RES_0402-240,1.0%,1/16W,CHIP,GA  I11  R3D12
   1    GND      A @BASEBOARD_FAB2_LIB.BASEBOARD_FAB2(SCH_1):GND
   2 PD_CPU1_TXT_PLTEN      B @BASEBOARD_FAB2_LIB.BASEBOARD_FAB2(SCH_1):PD_CPU1_TXT_PLTEN

RES_0402-240,1.0%,1/16W,EMPTY,A  I12  R3D13
   1    GND      A @BASEBOARD_FAB2_LIB.BASEBOARD_FAB2(SCH_1):GND
   2 PD_CPU1_BIST_ENABLE      B @BASEBOARD_FAB2_LIB.BASEBOARD_FAB2(SCH_1):PD_CPU1_BIST_ENABLE

RES_0402-240,1.0%,1/16W,EMPTY,A  I17  R3D22
   1 PVCCIO_CPU1      A @BASEBOARD_FAB2_LIB.BASEBOARD_FAB2(SCH_1):PVCCIO_CPU1
   2 PU_CPU1_FRMAGENT      B @BASEBOARD_FAB2_LIB.BASEBOARD_FAB2(SCH_1):PU_CPU1_FRMAGENT

RES_0402-240,1.0%,1/16W,EMPTY,A  I24  R3D16
   1 PVCCIO_CPU1      A @BASEBOARD_FAB2_LIB.BASEBOARD_FAB2(SCH_1):PVCCIO_CPU1
   2 H_CPU1_BMCINIT      B @BASEBOARD_FAB2_LIB.BASEBOARD_FAB2(SCH_1):H_CPU1_BMCINIT

RES_0402-240,1.0%,1/16W,EMPTY,A  I25  R3D23
   1 PVCCIO_CPU1      A @BASEBOARD_FAB2_LIB.BASEBOARD_FAB2(SCH_1):PVCCIO_CPU1
   2 PU_CPU1_TXT_AGENT      B @BASEBOARD_FAB2_LIB.BASEBOARD_FAB2(SCH_1):PU_CPU1_TXT_AGENT

RES_0402-240,1.0%,1/16W,EMPTY,A  I28  R3D26
   1 PVCCIO_CPU1      A @BASEBOARD_FAB2_LIB.BASEBOARD_FAB2(SCH_1):PVCCIO_CPU1
   2 PU_CPU1_SAFE_MODE_BOOT      B @BASEBOARD_FAB2_LIB.BASEBOARD_FAB2(SCH_1):PU_CPU1_SAFE_MODE_BOOT

RES_0402-240,1.0%,1/16W,CHIP,GA  I29  R5D3
   1 PVCCIO_CPU0      A @BASEBOARD_FAB2_LIB.BASEBOARD_FAB2(SCH_1):PVCCIO_CPU0
   2 PU_CPU0_FRMAGENT      B @BASEBOARD_FAB2_LIB.BASEBOARD_FAB2(SCH_1):PU_CPU0_FRMAGENT

RES_0402-240,1.0%,1/16W,EMPTY,A  I31  R6D7
   1 PVCCIO_CPU0      A @BASEBOARD_FAB2_LIB.BASEBOARD_FAB2(SCH_1):PVCCIO_CPU0
   2 H_CPU0_BMCINIT      B @BASEBOARD_FAB2_LIB.BASEBOARD_FAB2(SCH_1):H_CPU0_BMCINIT

RES_0402-240,1.0%,1/16W,EMPTY,A  I32  R5D4
   1 PVCCIO_CPU0      A @BASEBOARD_FAB2_LIB.BASEBOARD_FAB2(SCH_1):PVCCIO_CPU0
   2 PU_CPU0_TXT_AGENT      B @BASEBOARD_FAB2_LIB.BASEBOARD_FAB2(SCH_1):PU_CPU0_TXT_AGENT

RES_0402-240,1.0%,1/16W,EMPTY,A  I33  R6D13
   1 PVCCIO_CPU0      A @BASEBOARD_FAB2_LIB.BASEBOARD_FAB2(SCH_1):PVCCIO_CPU0
   2 PU_CPU0_SAFE_MODE_BOOT      B @BASEBOARD_FAB2_LIB.BASEBOARD_FAB2(SCH_1):PU_CPU0_SAFE_MODE_BOOT

RES_0402-240,1.0%,1/16W,EMPTY,A  I48  R6D15
   1 PVCCIO_CPU0      A @BASEBOARD_FAB2_LIB.BASEBOARD_FAB2(SCH_1):PVCCIO_CPU0
   2 PU_CPU0_SOCKET_ID_0      B @BASEBOARD_FAB2_LIB.BASEBOARD_FAB2(SCH_1):PU_CPU0_SOCKET_ID_0

RES_0402-240,1.0%,1/16W,EMPTY,A  I49  R6D10
   1 PVCCIO_CPU0      A @BASEBOARD_FAB2_LIB.BASEBOARD_FAB2(SCH_1):PVCCIO_CPU0
   2 PU_CPU0_SOCKET_ID_1      B @BASEBOARD_FAB2_LIB.BASEBOARD_FAB2(SCH_1):PU_CPU0_SOCKET_ID_1

RES_0402-240,1.0%,1/16W,EMPTY,A  I52  R6D14
   1 PVCCIO_CPU0      A @BASEBOARD_FAB2_LIB.BASEBOARD_FAB2(SCH_1):PVCCIO_CPU0
   2 PU_CPU0_EAR_N      B @BASEBOARD_FAB2_LIB.BASEBOARD_FAB2(SCH_1):PU_CPU0_EAR_N

RES_0402-240,1.0%,1/16W,CHIP,GA  I53  R4P14
   1 PVCCIO_CPU0      A @BASEBOARD_FAB2_LIB.BASEBOARD_FAB2(SCH_1):PVCCIO_CPU0
   2 PU_CPU0_LEGACY_SKT      B @BASEBOARD_FAB2_LIB.BASEBOARD_FAB2(SCH_1):PU_CPU0_LEGACY_SKT

RES_0402-240,1.0%,1/16W,CHIP,GA  I59  R3D24
   1 PVCCIO_CPU1      A @BASEBOARD_FAB2_LIB.BASEBOARD_FAB2(SCH_1):PVCCIO_CPU1
   2 PU_CPU1_SOCKET_ID_0      B @BASEBOARD_FAB2_LIB.BASEBOARD_FAB2(SCH_1):PU_CPU1_SOCKET_ID_0

RES_0402-240,1.0%,1/16W,EMPTY,A  I60  R3D17
   1 PVCCIO_CPU1      A @BASEBOARD_FAB2_LIB.BASEBOARD_FAB2(SCH_1):PVCCIO_CPU1
   2 PU_CPU1_SOCKET_ID_1      B @BASEBOARD_FAB2_LIB.BASEBOARD_FAB2(SCH_1):PU_CPU1_SOCKET_ID_1

RES_0402-240,1.0%,1/16W,EMPTY,A  I66  R3D25
   1 PVCCIO_CPU1      A @BASEBOARD_FAB2_LIB.BASEBOARD_FAB2(SCH_1):PVCCIO_CPU1
   2 PU_CPU1_EAR_N      B @BASEBOARD_FAB2_LIB.BASEBOARD_FAB2(SCH_1):PU_CPU1_EAR_N

RES_0402-240,1.0%,1/16W,EMPTY,A  I68  R4P6
   1    GND      A @BASEBOARD_FAB2_LIB.BASEBOARD_FAB2(SCH_1):GND
   2 PD_CPU0_DMIMODE_OVERRIDE      B @BASEBOARD_FAB2_LIB.BASEBOARD_FAB2(SCH_1):PD_CPU0_DMIMODE_OVERRIDE

RES_0402-240,1.0%,1/16W,CHIP,GA  I70  R7P14
   1    GND      A @BASEBOARD_FAB2_LIB.BASEBOARD_FAB2(SCH_1):GND
   2 PD_CPU1_DMIMODE_OVERRIDE      B @BASEBOARD_FAB2_LIB.BASEBOARD_FAB2(SCH_1):PD_CPU1_DMIMODE_OVERRIDE

RES_0402-240,1.0%,1/16W,EMPTY,A  I72  R4P7
   1    GND      A @BASEBOARD_FAB2_LIB.BASEBOARD_FAB2(SCH_1):GND
   2 PD_CPU0_KSFC_DIS      B @BASEBOARD_FAB2_LIB.BASEBOARD_FAB2(SCH_1):PD_CPU0_KSFC_DIS

RES_0402-240,1.0%,1/16W,EMPTY,A  I74  R7P15
   1    GND      A @BASEBOARD_FAB2_LIB.BASEBOARD_FAB2(SCH_1):GND
   2 PD_CPU1_KSFC_DIS      B @BASEBOARD_FAB2_LIB.BASEBOARD_FAB2(SCH_1):PD_CPU1_KSFC_DIS

RES_0402-240,1.0%,1/16W,EMPTY,A  I76  R7P22
   1 PVCCIO_CPU1      A @BASEBOARD_FAB2_LIB.BASEBOARD_FAB2(SCH_1):PVCCIO_CPU1
   2 PU_CPU1_LEGACY_SKT      B @BASEBOARD_FAB2_LIB.BASEBOARD_FAB2(SCH_1):PU_CPU1_LEGACY_SKT

RES_0402-49.9,1%,1/16W,CHIP,G2A  I79  R5P2
   1 PD_CPU0_TEST14      A @BASEBOARD_FAB2_LIB.BASEBOARD_FAB2(SCH_1):PD_CPU0_TEST14
   2    GND      B @BASEBOARD_FAB2_LIB.BASEBOARD_FAB2(SCH_1):GND

RES_0402-49.9,1%,1/16W,CHIP,G2A  I80  R5P3
   1 PD_CPU0_TEST13      A @BASEBOARD_FAB2_LIB.BASEBOARD_FAB2(SCH_1):PD_CPU0_TEST13
   2    GND      B @BASEBOARD_FAB2_LIB.BASEBOARD_FAB2(SCH_1):GND

RES_0402-49.9,1%,1/16W,CHIP,G2A  I81  R6D5
   1 PD_CPU0_TEST12      A @BASEBOARD_FAB2_LIB.BASEBOARD_FAB2(SCH_1):PD_CPU0_TEST12
   2    GND      B @BASEBOARD_FAB2_LIB.BASEBOARD_FAB2(SCH_1):GND

RES_0402-49.9,1%,1/16W,CHIP,G2A  I85  R8P1
   1 PD_CPU1_TEST14      A @BASEBOARD_FAB2_LIB.BASEBOARD_FAB2(SCH_1):PD_CPU1_TEST14
   2    GND      B @BASEBOARD_FAB2_LIB.BASEBOARD_FAB2(SCH_1):GND

RES_0402-49.9,1%,1/16W,CHIP,G2A  I86  R8P2
   1 PD_CPU1_TEST13      A @BASEBOARD_FAB2_LIB.BASEBOARD_FAB2(SCH_1):PD_CPU1_TEST13
   2    GND      B @BASEBOARD_FAB2_LIB.BASEBOARD_FAB2(SCH_1):GND

RES_0402-49.9,1%,1/16W,CHIP,G2A  I88  R3D9
   1 PD_CPU1_TEST12      A @BASEBOARD_FAB2_LIB.BASEBOARD_FAB2(SCH_1):PD_CPU1_TEST12
   2    GND      B @BASEBOARD_FAB2_LIB.BASEBOARD_FAB2(SCH_1):GND


DRAWING: @BASEBOARD_FAB2_LIB.BASEBOARD_FAB2(SCH_1):PAGE91 

SCONN24_H46321001_SM-SCONN,H46A  I1  J8B1
   1    GND    IO1 @BASEBOARD_FAB2_LIB.BASEBOARD_FAB2(SCH_1):GND
  10 SMB_HFI1_CPU0_LVC2_SCL   IO10 @BASEBOARD_FAB2_LIB.BASEBOARD_FAB2(SCH_1):SMB_HFI1_CPU0_LVC2_SCL
  11 FM_MODPRST_HFI1_CPU0_LVT2_N   IO11 @BASEBOARD_FAB2_LIB.BASEBOARD_FAB2(SCH_1):FM_MODPRST_HFI1_CPU0_LVT2_N
  12 SMB_HFI1_CPU0_LVC2_SDA   IO12 @BASEBOARD_FAB2_LIB.BASEBOARD_FAB2(SCH_1):SMB_HFI1_CPU0_LVC2_SDA
  13 LED_HFI1_CPU0_N   IO13 @BASEBOARD_FAB2_LIB.BASEBOARD_FAB2(SCH_1):LED_HFI1_CPU0_N
  14 RST_HFI1_CPU0_LVT2_N   IO14 @BASEBOARD_FAB2_LIB.BASEBOARD_FAB2(SCH_1):RST_HFI1_CPU0_LVT2_N
  15    GND   IO15 @BASEBOARD_FAB2_LIB.BASEBOARD_FAB2(SCH_1):GND
  16 IRQ_HFI1_CPU0_LVT2_N   IO16 @BASEBOARD_FAB2_LIB.BASEBOARD_FAB2(SCH_1):IRQ_HFI1_CPU0_LVT2_N
  17 TP_HFI_IO_CONN0_RSVD_17   IO17 @BASEBOARD_FAB2_LIB.BASEBOARD_FAB2(SCH_1):TP_HFI_IO_CONN0_RSVD_17
  18   P3V3   IO18 @BASEBOARD_FAB2_LIB.BASEBOARD_FAB2(SCH_1):P3V3
  19 PWRGD_PVPP_ABC   IO19 @BASEBOARD_FAB2_LIB.BASEBOARD_FAB2(SCH_1):PWRGD_PVPP_ABC
   2 SMB_HFI0_CPU0_LVC2_SCL    IO2 @BASEBOARD_FAB2_LIB.BASEBOARD_FAB2(SCH_1):SMB_HFI0_CPU0_LVC2_SCL
  20   P3V3   IO20 @BASEBOARD_FAB2_LIB.BASEBOARD_FAB2(SCH_1):P3V3
  21 PVPP_ABC   IO21 @BASEBOARD_FAB2_LIB.BASEBOARD_FAB2(SCH_1):PVPP_ABC
  22 SMB_OCP_FRU_STBY_LVC3_SCL   IO22 @BASEBOARD_FAB2_LIB.BASEBOARD_FAB2(SCH_1):SMB_OCP_FRU_STBY_LVC3_SCL
  23    GND   IO23 @BASEBOARD_FAB2_LIB.BASEBOARD_FAB2(SCH_1):GND
  24 SMB_OCP_FRU_STBY_LVC3_SDA   IO24 @BASEBOARD_FAB2_LIB.BASEBOARD_FAB2(SCH_1):SMB_OCP_FRU_STBY_LVC3_SDA
   3 FM_MODPRST_HFI0_CPU0_LVT2_N    IO3 @BASEBOARD_FAB2_LIB.BASEBOARD_FAB2(SCH_1):FM_MODPRST_HFI0_CPU0_LVT2_N
   4 SMB_HFI0_CPU0_LVC2_SDA    IO4 @BASEBOARD_FAB2_LIB.BASEBOARD_FAB2(SCH_1):SMB_HFI0_CPU0_LVC2_SDA
   5 LED_HFI0_CPU0_N    IO5 @BASEBOARD_FAB2_LIB.BASEBOARD_FAB2(SCH_1):LED_HFI0_CPU0_N
   6 RST_HFI0_CPU0_LVT2_N    IO6 @BASEBOARD_FAB2_LIB.BASEBOARD_FAB2(SCH_1):RST_HFI0_CPU0_LVT2_N
   7    GND    IO7 @BASEBOARD_FAB2_LIB.BASEBOARD_FAB2(SCH_1):GND
   8 IRQ_HFI0_CPU0_LVT2_N    IO8 @BASEBOARD_FAB2_LIB.BASEBOARD_FAB2(SCH_1):IRQ_HFI0_CPU0_LVT2_N
   9    GND    IO9 @BASEBOARD_FAB2_LIB.BASEBOARD_FAB2(SCH_1):GND
 MP1    GND    MP1 @BASEBOARD_FAB2_LIB.BASEBOARD_FAB2(SCH_1):GND
 MP2    GND    MP2 @BASEBOARD_FAB2_LIB.BASEBOARD_FAB2(SCH_1):GND

RES_0402-4.75K,1%,1/16W,CHIP,GA  I14  R8B8
   1 PVPP_ABC      A @BASEBOARD_FAB2_LIB.BASEBOARD_FAB2(SCH_1):PVPP_ABC
   2 RST_HFI0_CPU0_LVT2_N      B @BASEBOARD_FAB2_LIB.BASEBOARD_FAB2(SCH_1):RST_HFI0_CPU0_LVT2_N

RES_0402-4.75K,1%,1/16W,CHIP,GA  I16  R8B10
   1 PVPP_ABC      A @BASEBOARD_FAB2_LIB.BASEBOARD_FAB2(SCH_1):PVPP_ABC
   2 IRQ_HFI0_CPU0_LVT2_N      B @BASEBOARD_FAB2_LIB.BASEBOARD_FAB2(SCH_1):IRQ_HFI0_CPU0_LVT2_N

RES_0402-4.75K,1%,1/16W,CHIP,GA  I17  R8B16
   1 PVPP_ABC      A @BASEBOARD_FAB2_LIB.BASEBOARD_FAB2(SCH_1):PVPP_ABC
   2 RST_HFI1_CPU0_LVT2_N      B @BASEBOARD_FAB2_LIB.BASEBOARD_FAB2(SCH_1):RST_HFI1_CPU0_LVT2_N

RES_0402-4.75K,1%,1/16W,CHIP,GA  I18  R8B17
   1 PVPP_ABC      A @BASEBOARD_FAB2_LIB.BASEBOARD_FAB2(SCH_1):PVPP_ABC
   2 IRQ_HFI1_CPU0_LVT2_N      B @BASEBOARD_FAB2_LIB.BASEBOARD_FAB2(SCH_1):IRQ_HFI1_CPU0_LVT2_N

RES_0402-4.75K,1%,1/16W,CHIP,GA  I20  R8B18
   1 PVPP_ABC      A @BASEBOARD_FAB2_LIB.BASEBOARD_FAB2(SCH_1):PVPP_ABC
   2 LED_HFI1_CPU0_N      B @BASEBOARD_FAB2_LIB.BASEBOARD_FAB2(SCH_1):LED_HFI1_CPU0_N

RES_0402-4.75K,1%,1/16W,CHIP,GA  I21  R8B19
   1 PVPP_ABC      A @BASEBOARD_FAB2_LIB.BASEBOARD_FAB2(SCH_1):PVPP_ABC
   2 FM_MODPRST_HFI1_CPU0_LVT2_N      B @BASEBOARD_FAB2_LIB.BASEBOARD_FAB2(SCH_1):FM_MODPRST_HFI1_CPU0_LVT2_N

RES_0402-4.75K,1%,1/16W,CHIP,GA  I22  R8B5
   1 PVPP_ABC      A @BASEBOARD_FAB2_LIB.BASEBOARD_FAB2(SCH_1):PVPP_ABC
   2 LED_HFI0_CPU0_N      B @BASEBOARD_FAB2_LIB.BASEBOARD_FAB2(SCH_1):LED_HFI0_CPU0_N

RES_0402-4.75K,1%,1/16W,CHIP,GA  I24  R8B3
   1 PVPP_ABC      A @BASEBOARD_FAB2_LIB.BASEBOARD_FAB2(SCH_1):PVPP_ABC
   2 FM_MODPRST_HFI0_CPU0_LVT2_N      B @BASEBOARD_FAB2_LIB.BASEBOARD_FAB2(SCH_1):FM_MODPRST_HFI0_CPU0_LVT2_N

RES_0402-1.8K,1%,1/16W,CHIP,G2A  I34  R8B13
   1 PVPP_ABC      A @BASEBOARD_FAB2_LIB.BASEBOARD_FAB2(SCH_1):PVPP_ABC
   2 SMB_HFI1_CPU0_LVC2_SDA      B @BASEBOARD_FAB2_LIB.BASEBOARD_FAB2(SCH_1):SMB_HFI1_CPU0_LVC2_SDA

RES_0402-1.8K,1%,1/16W,CHIP,G2A  I35  R8B11
   1 PVPP_ABC      A @BASEBOARD_FAB2_LIB.BASEBOARD_FAB2(SCH_1):PVPP_ABC
   2 SMB_HFI1_CPU0_LVC2_SCL      B @BASEBOARD_FAB2_LIB.BASEBOARD_FAB2(SCH_1):SMB_HFI1_CPU0_LVC2_SCL

RES_0402-1.8K,1%,1/16W,CHIP,G2A  I36  R8B7
   1 PVPP_ABC      A @BASEBOARD_FAB2_LIB.BASEBOARD_FAB2(SCH_1):PVPP_ABC
   2 SMB_HFI0_CPU0_LVC2_SDA      B @BASEBOARD_FAB2_LIB.BASEBOARD_FAB2(SCH_1):SMB_HFI0_CPU0_LVC2_SDA

RES_0402-1.8K,1%,1/16W,CHIP,G2A  I37  R8B6
   1 PVPP_ABC      A @BASEBOARD_FAB2_LIB.BASEBOARD_FAB2(SCH_1):PVPP_ABC
   2 SMB_HFI0_CPU0_LVC2_SCL      B @BASEBOARD_FAB2_LIB.BASEBOARD_FAB2(SCH_1):SMB_HFI0_CPU0_LVC2_SCL


DRAWING: @BASEBOARD_FAB2_LIB.BASEBOARD_FAB2(SCH_1):PAGE92 

GTL2014_SM-IC,D66151-001  I1  U3P2
  13 PWRGD_CPUPWRGD_R1     A0 @BASEBOARD_FAB2_LIB.BASEBOARD_FAB2(SCH_1):PWRGD_CPUPWRGD_R1
  12 FM_CPU1_FIVR_FAULT_R_LVT3     A1 @BASEBOARD_FAB2_LIB.BASEBOARD_FAB2(SCH_1):FM_CPU1_FIVR_FAULT_R_LVT3
  10 FM_CPU_CATERR_LVT3_R2_N     A2 @BASEBOARD_FAB2_LIB.BASEBOARD_FAB2(SCH_1):FM_CPU_CATERR_LVT3_R2_N
   9 FM_CPU1_THERMTRIP_LVT3_R_N     A3 @BASEBOARD_FAB2_LIB.BASEBOARD_FAB2(SCH_1):FM_CPU1_THERMTRIP_LVT3_R_N
   2 PWRGD_CPUPWRGD_GTL     B0 @BASEBOARD_FAB2_LIB.BASEBOARD_FAB2(SCH_1):PWRGD_CPUPWRGD_GTL
   3 H_CPU1_FIVR_FAULT_G     B1 @BASEBOARD_FAB2_LIB.BASEBOARD_FAB2(SCH_1):H_CPU1_FIVR_FAULT_G
   5 H_CPU_CATERR_G_N     B2 @BASEBOARD_FAB2_LIB.BASEBOARD_FAB2(SCH_1):H_CPU_CATERR_G_N
   6 H_CPU1_THERMTRIP_G_N     B3 @BASEBOARD_FAB2_LIB.BASEBOARD_FAB2(SCH_1):H_CPU1_THERMTRIP_G_N
   1 PD_GTL2104_DIR_1    DIR @BASEBOARD_FAB2_LIB.BASEBOARD_FAB2(SCH_1):PD_GTL2104_DIR_1
  11    GND GND<2> @BASEBOARD_FAB2_LIB.BASEBOARD_FAB2(SCH_1):GND
   8    GND GND<1> @BASEBOARD_FAB2_LIB.BASEBOARD_FAB2(SCH_1):GND
   7    GND GND<0> @BASEBOARD_FAB2_LIB.BASEBOARD_FAB2(SCH_1):GND
  14   P3V3    VCC @BASEBOARD_FAB2_LIB.BASEBOARD_FAB2(SCH_1):P3V3
   4 P0V7_GTL2104_VREF_1   VREF @BASEBOARD_FAB2_LIB.BASEBOARD_FAB2(SCH_1):P0V7_GTL2104_VREF_1

RES_0402-75,1.0%,1/16W,CHIP,G2A  I9  R3P41
   1 PVCCIO_CPU1      A @BASEBOARD_FAB2_LIB.BASEBOARD_FAB2(SCH_1):PVCCIO_CPU1
   2 H_CPU1_THERMTRIP_G_N      B @BASEBOARD_FAB2_LIB.BASEBOARD_FAB2(SCH_1):H_CPU1_THERMTRIP_G_N

RES_0402-33.2,1%,1/16W,CHIP,G2A  I12  R3P46
   1 FM_CPU1_FIVR_FAULT_R_LVT3      A @BASEBOARD_FAB2_LIB.BASEBOARD_FAB2(SCH_1):FM_CPU1_FIVR_FAULT_R_LVT3
   2 FM_CPU1_FIVR_FAULT_LVT3      B @BASEBOARD_FAB2_LIB.BASEBOARD_FAB2(SCH_1):FM_CPU1_FIVR_FAULT_LVT3

RES_0402-33.2,1%,1/16W,CHIP,G2A  I13  R3P43
   1 FM_CPU_CATERR_LVT3_R2_N      A @BASEBOARD_FAB2_LIB.BASEBOARD_FAB2(SCH_1):FM_CPU_CATERR_LVT3_R2_N
   2 FM_CPU_CATERR_LVT3_N      B @BASEBOARD_FAB2_LIB.BASEBOARD_FAB2(SCH_1):FM_CPU_CATERR_LVT3_N

RES_0402-33.2,1%,1/16W,CHIP,G2A  I14  R3P42
   1 FM_CPU1_THERMTRIP_LVT3_R_N      A @BASEBOARD_FAB2_LIB.BASEBOARD_FAB2(SCH_1):FM_CPU1_THERMTRIP_LVT3_R_N
   2 FM_CPU1_THERMTRIP_LVT3_N      B @BASEBOARD_FAB2_LIB.BASEBOARD_FAB2(SCH_1):FM_CPU1_THERMTRIP_LVT3_N

RES_0402-75,1.0%,1/16W,CHIP,G2A  I19  R7E2
   1 PVCCIO_CPU0      A @BASEBOARD_FAB2_LIB.BASEBOARD_FAB2(SCH_1):PVCCIO_CPU0
   2 H_CPU0_THERMTRIP_G_N      B @BASEBOARD_FAB2_LIB.BASEBOARD_FAB2(SCH_1):H_CPU0_THERMTRIP_G_N

RES_0402-33.2,1%,1/16W,CHIP,G2A  I24  R7D34
   1 FM_CPU0_THERMTRIP_LVT3_R_N      A @BASEBOARD_FAB2_LIB.BASEBOARD_FAB2(SCH_1):FM_CPU0_THERMTRIP_LVT3_R_N
   2 FM_CPU0_THERMTRIP_LVT3_N      B @BASEBOARD_FAB2_LIB.BASEBOARD_FAB2(SCH_1):FM_CPU0_THERMTRIP_LVT3_N

RES_0402-33.2,1%,1/16W,CHIP,G2A  I29  R7D31
   1 FM_CPU_ERR2_LVT3_R_N      A @BASEBOARD_FAB2_LIB.BASEBOARD_FAB2(SCH_1):FM_CPU_ERR2_LVT3_R_N
   2 FM_CPU_ERR2_LVT3_N      B @BASEBOARD_FAB2_LIB.BASEBOARD_FAB2(SCH_1):FM_CPU_ERR2_LVT3_N

RES_0402-33.2,1%,1/16W,CHIP,G2A  I30  R7D29
   1 FM_CPU0_FIVR_FAULT_R_LVT3      A @BASEBOARD_FAB2_LIB.BASEBOARD_FAB2(SCH_1):FM_CPU0_FIVR_FAULT_R_LVT3
   2 FM_CPU0_FIVR_FAULT_LVT3      B @BASEBOARD_FAB2_LIB.BASEBOARD_FAB2(SCH_1):FM_CPU0_FIVR_FAULT_LVT3

GTL2014_SM-IC,D66151-001  I32  U7D2
  13 FM_CPU_MSMI_LVT3_R_N     A0 @BASEBOARD_FAB2_LIB.BASEBOARD_FAB2(SCH_1):FM_CPU_MSMI_LVT3_R_N
  12 FM_CPU0_FIVR_FAULT_R_LVT3     A1 @BASEBOARD_FAB2_LIB.BASEBOARD_FAB2(SCH_1):FM_CPU0_FIVR_FAULT_R_LVT3
  10 FM_CPU_ERR2_LVT3_R_N     A2 @BASEBOARD_FAB2_LIB.BASEBOARD_FAB2(SCH_1):FM_CPU_ERR2_LVT3_R_N
   9 FM_CPU0_THERMTRIP_LVT3_R_N     A3 @BASEBOARD_FAB2_LIB.BASEBOARD_FAB2(SCH_1):FM_CPU0_THERMTRIP_LVT3_R_N
   2 H_CPU_MSMI_G_N     B0 @BASEBOARD_FAB2_LIB.BASEBOARD_FAB2(SCH_1):H_CPU_MSMI_G_N
   3 H_CPU0_FIVR_FAULT_G     B1 @BASEBOARD_FAB2_LIB.BASEBOARD_FAB2(SCH_1):H_CPU0_FIVR_FAULT_G
   5 H_CPU_ERR2_GTL_N     B2 @BASEBOARD_FAB2_LIB.BASEBOARD_FAB2(SCH_1):H_CPU_ERR2_GTL_N
   6 H_CPU0_THERMTRIP_G_N     B3 @BASEBOARD_FAB2_LIB.BASEBOARD_FAB2(SCH_1):H_CPU0_THERMTRIP_G_N
   1 PD_GTL2104_DIR_0    DIR @BASEBOARD_FAB2_LIB.BASEBOARD_FAB2(SCH_1):PD_GTL2104_DIR_0
  11    GND GND<2> @BASEBOARD_FAB2_LIB.BASEBOARD_FAB2(SCH_1):GND
   8    GND GND<1> @BASEBOARD_FAB2_LIB.BASEBOARD_FAB2(SCH_1):GND
   7    GND GND<0> @BASEBOARD_FAB2_LIB.BASEBOARD_FAB2(SCH_1):GND
  14   P3V3    VCC @BASEBOARD_FAB2_LIB.BASEBOARD_FAB2(SCH_1):P3V3
   4 P0V7_GTL2104_VREF_0   VREF @BASEBOARD_FAB2_LIB.BASEBOARD_FAB2(SCH_1):P0V7_GTL2104_VREF_0

CAP_A_0402V-0.1UF,16V,10%,X7R,A  I37  C3P49
   1 P0V7_GTL2104_VREF_1      A @BASEBOARD_FAB2_LIB.BASEBOARD_FAB2(SCH_1):P0V7_GTL2104_VREF_1
   2    GND      B @BASEBOARD_FAB2_LIB.BASEBOARD_FAB2(SCH_1):GND

RES_0402-100.0,1%,1/16W,CHIP,GA  I38  R3P49
   1 P0V7_GTL2104_VREF_1      A @BASEBOARD_FAB2_LIB.BASEBOARD_FAB2(SCH_1):P0V7_GTL2104_VREF_1
   2    GND      B @BASEBOARD_FAB2_LIB.BASEBOARD_FAB2(SCH_1):GND

RES_0402-49.9,1%,1/16W,CHIP,G2A  I39  R3P45
   1 PVCCIO_CPU0      A @BASEBOARD_FAB2_LIB.BASEBOARD_FAB2(SCH_1):PVCCIO_CPU0
   2 P0V7_GTL2104_VREF_1      B @BASEBOARD_FAB2_LIB.BASEBOARD_FAB2(SCH_1):P0V7_GTL2104_VREF_1

RES_0402-1.00K,1%,1/16W,CHIP,GA  I46  R3R1
   1 PD_GTL2104_DIR_1      A @BASEBOARD_FAB2_LIB.BASEBOARD_FAB2(SCH_1):PD_GTL2104_DIR_1
   2    GND      B @BASEBOARD_FAB2_LIB.BASEBOARD_FAB2(SCH_1):GND

RES_0402-100.0,1%,1/16W,CHIP,GA  I48  R7D32
   1 P0V7_GTL2104_VREF_0      A @BASEBOARD_FAB2_LIB.BASEBOARD_FAB2(SCH_1):P0V7_GTL2104_VREF_0
   2    GND      B @BASEBOARD_FAB2_LIB.BASEBOARD_FAB2(SCH_1):GND

RES_0402-49.9,1%,1/16W,CHIP,G2A  I51  R7D33
   1 PVCCIO_CPU0      A @BASEBOARD_FAB2_LIB.BASEBOARD_FAB2(SCH_1):PVCCIO_CPU0
   2 P0V7_GTL2104_VREF_0      B @BASEBOARD_FAB2_LIB.BASEBOARD_FAB2(SCH_1):P0V7_GTL2104_VREF_0

CAP_A_0402V-0.1UF,16V,10%,X7R,A  I52  C7D5
   1 P0V7_GTL2104_VREF_0      A @BASEBOARD_FAB2_LIB.BASEBOARD_FAB2(SCH_1):P0V7_GTL2104_VREF_0
   2    GND      B @BASEBOARD_FAB2_LIB.BASEBOARD_FAB2(SCH_1):GND

RES_0402-1.00K,1%,1/16W,CHIP,GA  I54  R7D26
   1 PD_GTL2104_DIR_0      A @BASEBOARD_FAB2_LIB.BASEBOARD_FAB2(SCH_1):PD_GTL2104_DIR_0
   2    GND      B @BASEBOARD_FAB2_LIB.BASEBOARD_FAB2(SCH_1):GND

RES_0402-33.2,1%,1/16W,CHIP,G2A  I61  R3R3
   1 PWRGD_CPUPWRGD_R1      A @BASEBOARD_FAB2_LIB.BASEBOARD_FAB2(SCH_1):PWRGD_CPUPWRGD_R1
   2 PWRGD_CPUPWRGD      B @BASEBOARD_FAB2_LIB.BASEBOARD_FAB2(SCH_1):PWRGD_CPUPWRGD

RES_0402-150.0,1%,1/16W,CHIP,GA  I64  R6D9
   1 PVCCIO_CPU0      A @BASEBOARD_FAB2_LIB.BASEBOARD_FAB2(SCH_1):PVCCIO_CPU0
   2 H_CPU0_MSMI_G_N      B @BASEBOARD_FAB2_LIB.BASEBOARD_FAB2(SCH_1):H_CPU0_MSMI_G_N

RES_0402-150.0,1%,1/16W,CHIP,GA  I65  R7P27
   1 PVCCIO_CPU0      A @BASEBOARD_FAB2_LIB.BASEBOARD_FAB2(SCH_1):PVCCIO_CPU0
   2 H_CPU1_MSMI_G_N      B @BASEBOARD_FAB2_LIB.BASEBOARD_FAB2(SCH_1):H_CPU1_MSMI_G_N

RES_0402-0.0,5%,1/16W,CHIP,G21A  I67  R7D28
   1 H_CPU1_MSMI_G_N      A @BASEBOARD_FAB2_LIB.BASEBOARD_FAB2(SCH_1):H_CPU1_MSMI_G_N
   2 H_CPU_MSMI_G_N      B @BASEBOARD_FAB2_LIB.BASEBOARD_FAB2(SCH_1):H_CPU_MSMI_G_N

RES_0402-0.0,5%,1/16W,CHIP,G21A  I68  R7D27
   1 H_CPU0_MSMI_G_N      A @BASEBOARD_FAB2_LIB.BASEBOARD_FAB2(SCH_1):H_CPU0_MSMI_G_N
   2 H_CPU_MSMI_G_N      B @BASEBOARD_FAB2_LIB.BASEBOARD_FAB2(SCH_1):H_CPU_MSMI_G_N

RES_0402-33.2,1%,1/16W,CHIP,G2A  I70  R7D25
   1 FM_CPU_MSMI_LVT3_R_N      A @BASEBOARD_FAB2_LIB.BASEBOARD_FAB2(SCH_1):FM_CPU_MSMI_LVT3_R_N
   2 FM_CPU_MSMI_LVT3_N      B @BASEBOARD_FAB2_LIB.BASEBOARD_FAB2(SCH_1):FM_CPU_MSMI_LVT3_N

RES_0402-1.00K,1%,1/16W,CHIP,GA  I75  R3R2
   1 H_CPU1_FIVR_FAULT_G      A @BASEBOARD_FAB2_LIB.BASEBOARD_FAB2(SCH_1):H_CPU1_FIVR_FAULT_G
   2    GND      B @BASEBOARD_FAB2_LIB.BASEBOARD_FAB2(SCH_1):GND

CAP_0402-1.0UF,16V,10%,X6S,D97A  I79  C7D4
   1   P3V3      A @BASEBOARD_FAB2_LIB.BASEBOARD_FAB2(SCH_1):P3V3
   2    GND      B @BASEBOARD_FAB2_LIB.BASEBOARD_FAB2(SCH_1):GND

CAP_0402-1.0UF,16V,10%,X6S,D97A  I84  C3P50
   1   P3V3      A @BASEBOARD_FAB2_LIB.BASEBOARD_FAB2(SCH_1):P3V3
   2    GND      B @BASEBOARD_FAB2_LIB.BASEBOARD_FAB2(SCH_1):GND

RES_0402-0.0,5%,1/16W,CHIP,G21A  I92  R2T44
   1 H_CPU1_ERR2_G_N      A @BASEBOARD_FAB2_LIB.BASEBOARD_FAB2(SCH_1):H_CPU1_ERR2_G_N
   2 H_CPU_ERR2_G_R_N      B @BASEBOARD_FAB2_LIB.BASEBOARD_FAB2(SCH_1):H_CPU_ERR2_G_R_N

RES_0402-0.0,5%,1/16W,CHIP,G21A  I93  R2T40
   1 H_CPU0_ERR2_G_N      A @BASEBOARD_FAB2_LIB.BASEBOARD_FAB2(SCH_1):H_CPU0_ERR2_G_N
   2 H_CPU_ERR2_G_R_N      B @BASEBOARD_FAB2_LIB.BASEBOARD_FAB2(SCH_1):H_CPU_ERR2_G_R_N

RES_0402-200.0,1%,1/16W,CHIP,GA  I94  R2T37
   1 PVCCIO_CPU0      A @BASEBOARD_FAB2_LIB.BASEBOARD_FAB2(SCH_1):PVCCIO_CPU0
   2 H_CPU_ERR2_G_R_N      B @BASEBOARD_FAB2_LIB.BASEBOARD_FAB2(SCH_1):H_CPU_ERR2_G_R_N

RES_0402-75,1.0%,1/16W,CHIP,G2A  I96  R2T43
   1 H_CPU_ERR2_G_R_N      A @BASEBOARD_FAB2_LIB.BASEBOARD_FAB2(SCH_1):H_CPU_ERR2_G_R_N
   2 H_CPU_ERR2_GTL_N      B @BASEBOARD_FAB2_LIB.BASEBOARD_FAB2(SCH_1):H_CPU_ERR2_GTL_N

RES_0402-0.0,5%,1/16W,CHIP,G21A  I97  R3P59
   1 H_CPU0_CATERR_G_N      A @BASEBOARD_FAB2_LIB.BASEBOARD_FAB2(SCH_1):H_CPU0_CATERR_G_N
   2 H_CPU_CATERR_G_N      B @BASEBOARD_FAB2_LIB.BASEBOARD_FAB2(SCH_1):H_CPU_CATERR_G_N

RES_0402-0.0,5%,1/16W,CHIP,G21A  I98  R3P58
   1 H_CPU1_CATERR_G_N      A @BASEBOARD_FAB2_LIB.BASEBOARD_FAB2(SCH_1):H_CPU1_CATERR_G_N
   2 H_CPU_CATERR_G_N      B @BASEBOARD_FAB2_LIB.BASEBOARD_FAB2(SCH_1):H_CPU_CATERR_G_N

RES_0402-150.0,1%,1/16W,CHIP,GA  I100  R7P18
   1 PVCCIO_CPU0      A @BASEBOARD_FAB2_LIB.BASEBOARD_FAB2(SCH_1):PVCCIO_CPU0
   2 H_CPU1_CATERR_G_N      B @BASEBOARD_FAB2_LIB.BASEBOARD_FAB2(SCH_1):H_CPU1_CATERR_G_N

RES_0402-150.0,1%,1/16W,CHIP,GA  I101  R4R2
   1 PVCCIO_CPU0      A @BASEBOARD_FAB2_LIB.BASEBOARD_FAB2(SCH_1):PVCCIO_CPU0
   2 H_CPU0_CATERR_G_N      B @BASEBOARD_FAB2_LIB.BASEBOARD_FAB2(SCH_1):H_CPU0_CATERR_G_N


DRAWING: @BASEBOARD_FAB2_LIB.BASEBOARD_FAB2(SCH_1):PAGE93 

RES_0402-0.0,5%,1/16W,CHIP,G21A  I13  R2T27
   1 H_CPU1_ERR1_G_N      A @BASEBOARD_FAB2_LIB.BASEBOARD_FAB2(SCH_1):H_CPU1_ERR1_G_N
   2 H_CPU_ERR1_GTL_R_N      B @BASEBOARD_FAB2_LIB.BASEBOARD_FAB2(SCH_1):H_CPU_ERR1_GTL_R_N

RES_0402-0.0,5%,1/16W,CHIP,G21A  I15  R2T32
   1 H_CPU0_ERR1_G_N      A @BASEBOARD_FAB2_LIB.BASEBOARD_FAB2(SCH_1):H_CPU0_ERR1_G_N
   2 H_CPU_ERR1_GTL_R_N      B @BASEBOARD_FAB2_LIB.BASEBOARD_FAB2(SCH_1):H_CPU_ERR1_GTL_R_N

RES_0402-0.0,5%,1/16W,CHIP,G21A  I16  R2T20
   1 H_CPU1_ERR0_G_N      A @BASEBOARD_FAB2_LIB.BASEBOARD_FAB2(SCH_1):H_CPU1_ERR0_G_N
   2 H_CPU_ERR0_GTL_R_N      B @BASEBOARD_FAB2_LIB.BASEBOARD_FAB2(SCH_1):H_CPU_ERR0_GTL_R_N

RES_0402-0.0,5%,1/16W,CHIP,G21A  I23  R2T17
   1 H_CPU0_ERR0_G_N      A @BASEBOARD_FAB2_LIB.BASEBOARD_FAB2(SCH_1):H_CPU0_ERR0_G_N
   2 H_CPU_ERR0_GTL_R_N      B @BASEBOARD_FAB2_LIB.BASEBOARD_FAB2(SCH_1):H_CPU_ERR0_GTL_R_N

GTL2014_SM-IC,D66151-001  I30  U2T4
  13 FM_CPU1_PROCHOT_LVT3_R_N     A0 @BASEBOARD_FAB2_LIB.BASEBOARD_FAB2(SCH_1):FM_CPU1_PROCHOT_LVT3_R_N
  12 FM_CPU0_PROCHOT_LVT3_R_N     A1 @BASEBOARD_FAB2_LIB.BASEBOARD_FAB2(SCH_1):FM_CPU0_PROCHOT_LVT3_R_N
  10 FM_CPU_ERR1_LVT3_R_N     A2 @BASEBOARD_FAB2_LIB.BASEBOARD_FAB2(SCH_1):FM_CPU_ERR1_LVT3_R_N
   9 FM_CPU_ERR0_LVT3_R_N     A3 @BASEBOARD_FAB2_LIB.BASEBOARD_FAB2(SCH_1):FM_CPU_ERR0_LVT3_R_N
   2 H_CPU1_PROCHOT_G_R_N     B0 @BASEBOARD_FAB2_LIB.BASEBOARD_FAB2(SCH_1):H_CPU1_PROCHOT_G_R_N
   3 H_CPU0_PROCHOT_G_R_N     B1 @BASEBOARD_FAB2_LIB.BASEBOARD_FAB2(SCH_1):H_CPU0_PROCHOT_G_R_N
   5 H_CPU_ERR1_GTL_N     B2 @BASEBOARD_FAB2_LIB.BASEBOARD_FAB2(SCH_1):H_CPU_ERR1_GTL_N
   6 H_CPU_ERR0_GTL_N     B3 @BASEBOARD_FAB2_LIB.BASEBOARD_FAB2(SCH_1):H_CPU_ERR0_GTL_N
   1 PD_GTL2104_4_DIR    DIR @BASEBOARD_FAB2_LIB.BASEBOARD_FAB2(SCH_1):PD_GTL2104_4_DIR
  11    GND GND<2> @BASEBOARD_FAB2_LIB.BASEBOARD_FAB2(SCH_1):GND
   8    GND GND<1> @BASEBOARD_FAB2_LIB.BASEBOARD_FAB2(SCH_1):GND
   7    GND GND<0> @BASEBOARD_FAB2_LIB.BASEBOARD_FAB2(SCH_1):GND
  14   P3V3    VCC @BASEBOARD_FAB2_LIB.BASEBOARD_FAB2(SCH_1):P3V3
   4 P0V7_GTL2104_5_VREF   VREF @BASEBOARD_FAB2_LIB.BASEBOARD_FAB2(SCH_1):P0V7_GTL2104_5_VREF

RES_0402-33.2,1%,1/16W,CHIP,G2A  I39  R2T38
   1 FM_CPU0_PROCHOT_LVT3_K_N      A @BASEBOARD_FAB2_LIB.BASEBOARD_FAB2(SCH_1):FM_CPU0_PROCHOT_LVT3_K_N
   2 FM_CPU0_PROCHOT_LVT3_N      B @BASEBOARD_FAB2_LIB.BASEBOARD_FAB2(SCH_1):FM_CPU0_PROCHOT_LVT3_N

RES_0402-33.2,1%,1/16W,CHIP,G2A  I40  R2T33
   1 FM_CPU_ERR1_LVT3_K_N      A @BASEBOARD_FAB2_LIB.BASEBOARD_FAB2(SCH_1):FM_CPU_ERR1_LVT3_K_N
   2 FM_CPU_ERR1_LVT3_N      B @BASEBOARD_FAB2_LIB.BASEBOARD_FAB2(SCH_1):FM_CPU_ERR1_LVT3_N

RES_0402-33.2,1%,1/16W,CHIP,G2A  I42  R2T30
   1 FM_CPU_ERR0_LVT3_K_N      A @BASEBOARD_FAB2_LIB.BASEBOARD_FAB2(SCH_1):FM_CPU_ERR0_LVT3_K_N
   2 FM_CPU_ERR0_LVT3_N      B @BASEBOARD_FAB2_LIB.BASEBOARD_FAB2(SCH_1):FM_CPU_ERR0_LVT3_N

RES_0402-33.2,1%,1/16W,CHIP,G2A  I62  R7D24
   1 FM_CPU1_PROCHOT_LVT3_K_N      A @BASEBOARD_FAB2_LIB.BASEBOARD_FAB2(SCH_1):FM_CPU1_PROCHOT_LVT3_K_N
   2 FM_CPU1_PROCHOT_LVT3_N      B @BASEBOARD_FAB2_LIB.BASEBOARD_FAB2(SCH_1):FM_CPU1_PROCHOT_LVT3_N

RES_0402-200.0,1%,1/16W,CHIP,GA  I63  R2T19
   1 PVCCIO_CPU0      A @BASEBOARD_FAB2_LIB.BASEBOARD_FAB2(SCH_1):PVCCIO_CPU0
   2 H_CPU_ERR0_GTL_R_N      B @BASEBOARD_FAB2_LIB.BASEBOARD_FAB2(SCH_1):H_CPU_ERR0_GTL_R_N

RES_0402-75,1.0%,1/16W,CHIP,G2A  I67  R2T16
   1 H_CPU_ERR0_GTL_R_N      A @BASEBOARD_FAB2_LIB.BASEBOARD_FAB2(SCH_1):H_CPU_ERR0_GTL_R_N
   2 H_CPU_ERR0_GTL_N      B @BASEBOARD_FAB2_LIB.BASEBOARD_FAB2(SCH_1):H_CPU_ERR0_GTL_N

RES_0402-75,1.0%,1/16W,CHIP,G2A  I68  R2T31
   1 H_CPU_ERR1_GTL_R_N      A @BASEBOARD_FAB2_LIB.BASEBOARD_FAB2(SCH_1):H_CPU_ERR1_GTL_R_N
   2 H_CPU_ERR1_GTL_N      B @BASEBOARD_FAB2_LIB.BASEBOARD_FAB2(SCH_1):H_CPU_ERR1_GTL_N

CAP_A_0402V-1.0UF,6.3V,10%,X6SA  I72  C2T33
   1   P3V3      A @BASEBOARD_FAB2_LIB.BASEBOARD_FAB2(SCH_1):P3V3
   2    GND      B @BASEBOARD_FAB2_LIB.BASEBOARD_FAB2(SCH_1):GND

RES_0402-150.0,1%,1/16W,CHIP,GA  I79  R4R3
   1 PVCCIO_CPU0      A @BASEBOARD_FAB2_LIB.BASEBOARD_FAB2(SCH_1):PVCCIO_CPU0
   2 H_CPU0_PROCHOT_G_N      B @BASEBOARD_FAB2_LIB.BASEBOARD_FAB2(SCH_1):H_CPU0_PROCHOT_G_N

RES_0402-200.0,1%,1/16W,CHIP,GA  I87  R2T26
   1 PVCCIO_CPU0      A @BASEBOARD_FAB2_LIB.BASEBOARD_FAB2(SCH_1):PVCCIO_CPU0
   2 H_CPU_ERR1_GTL_R_N      B @BASEBOARD_FAB2_LIB.BASEBOARD_FAB2(SCH_1):H_CPU_ERR1_GTL_R_N

RES_0402-0.0,5%,1/16W,EMPTY,G2A  I88  R2T57
   1 H_CPU_ERR0_PCH_N      A @BASEBOARD_FAB2_LIB.BASEBOARD_FAB2(SCH_1):H_CPU_ERR0_PCH_N
   2 H_CPU_ERR0_GTL_R_N      B @BASEBOARD_FAB2_LIB.BASEBOARD_FAB2(SCH_1):H_CPU_ERR0_GTL_R_N

RES_0402-0.0,5%,1/16W,EMPTY,G2A  I89  R2T61
   1 H_CPU_ERR1_PCH_N      A @BASEBOARD_FAB2_LIB.BASEBOARD_FAB2(SCH_1):H_CPU_ERR1_PCH_N
   2 H_CPU_ERR1_GTL_R_N      B @BASEBOARD_FAB2_LIB.BASEBOARD_FAB2(SCH_1):H_CPU_ERR1_GTL_R_N

RES_0402-0.0,5%,1/16W,EMPTY,G2A  I93  R2T62
   1 H_CPU_ERR1_PCH_N      A @BASEBOARD_FAB2_LIB.BASEBOARD_FAB2(SCH_1):H_CPU_ERR1_PCH_N
   2 FM_CPU_ERR1_LVT3_K_N      B @BASEBOARD_FAB2_LIB.BASEBOARD_FAB2(SCH_1):FM_CPU_ERR1_LVT3_K_N

RES_0402-0.0,5%,1/16W,EMPTY,G2A  I94  R2T58
   1 H_CPU_ERR0_PCH_N      A @BASEBOARD_FAB2_LIB.BASEBOARD_FAB2(SCH_1):H_CPU_ERR0_PCH_N
   2 FM_CPU_ERR0_LVT3_K_N      B @BASEBOARD_FAB2_LIB.BASEBOARD_FAB2(SCH_1):FM_CPU_ERR0_LVT3_K_N

CAP_A_0402V-0.1UF,16V,10%,X7R,A  I95  C2T32
   1 P0V7_GTL2104_5_VREF      A @BASEBOARD_FAB2_LIB.BASEBOARD_FAB2(SCH_1):P0V7_GTL2104_5_VREF
   2    GND      B @BASEBOARD_FAB2_LIB.BASEBOARD_FAB2(SCH_1):GND

RES_0402-49.9,1%,1/16W,CHIP,G2A  I97  R2T36
   1 PVCCIO_CPU0      A @BASEBOARD_FAB2_LIB.BASEBOARD_FAB2(SCH_1):PVCCIO_CPU0
   2 P0V7_GTL2104_5_VREF      B @BASEBOARD_FAB2_LIB.BASEBOARD_FAB2(SCH_1):P0V7_GTL2104_5_VREF

RES_0402-100.0,1%,1/16W,CHIP,GA  I98  R2T39
   1 P0V7_GTL2104_5_VREF      A @BASEBOARD_FAB2_LIB.BASEBOARD_FAB2(SCH_1):P0V7_GTL2104_5_VREF
   2    GND      B @BASEBOARD_FAB2_LIB.BASEBOARD_FAB2(SCH_1):GND

RES_0402-0.0,5%,1/16W,CHIP,G21A  I102  R2T68
   1 H_CPU1_PROCHOT_G_N      A @BASEBOARD_FAB2_LIB.BASEBOARD_FAB2(SCH_1):H_CPU1_PROCHOT_G_N
   2 H_CPU1_PROCHOT_G_R_N      B @BASEBOARD_FAB2_LIB.BASEBOARD_FAB2(SCH_1):H_CPU1_PROCHOT_G_R_N

RES_0402-0.0,5%,1/16W,CHIP,G21A  I103  R2T60
   1 H_CPU0_PROCHOT_G_N      A @BASEBOARD_FAB2_LIB.BASEBOARD_FAB2(SCH_1):H_CPU0_PROCHOT_G_N
   2 H_CPU0_PROCHOT_G_R_N      B @BASEBOARD_FAB2_LIB.BASEBOARD_FAB2(SCH_1):H_CPU0_PROCHOT_G_R_N

RES_0402-150.0,1%,1/16W,CHIP,GA  I106  R7P28
   1 PVCCIO_CPU1      A @BASEBOARD_FAB2_LIB.BASEBOARD_FAB2(SCH_1):PVCCIO_CPU1
   2 H_CPU1_PROCHOT_G_N      B @BASEBOARD_FAB2_LIB.BASEBOARD_FAB2(SCH_1):H_CPU1_PROCHOT_G_N

RES_0402-0.0,5%,1/16W,EMPTY,G2A  I107  R2T59
   1 H_CPU0_PROCHOT_G_N      A @BASEBOARD_FAB2_LIB.BASEBOARD_FAB2(SCH_1):H_CPU0_PROCHOT_G_N
   2 H_CPU0_PROCHOT_G_PCH_N      B @BASEBOARD_FAB2_LIB.BASEBOARD_FAB2(SCH_1):H_CPU0_PROCHOT_G_PCH_N

RES_0402-0.0,5%,1/16W,EMPTY,G2A  I108  R2T69
   1 H_CPU1_PROCHOT_G_N      A @BASEBOARD_FAB2_LIB.BASEBOARD_FAB2(SCH_1):H_CPU1_PROCHOT_G_N
   2 H_CPU1_PROCHOT_G_PCH_N      B @BASEBOARD_FAB2_LIB.BASEBOARD_FAB2(SCH_1):H_CPU1_PROCHOT_G_PCH_N

RES_0402-0.0,5%,1/16W,EMPTY,G2A  I109  R2T71
   1 FM_CPU0_PROCHOT_LVT3_K_N      A @BASEBOARD_FAB2_LIB.BASEBOARD_FAB2(SCH_1):FM_CPU0_PROCHOT_LVT3_K_N
   2 H_CPU0_PROCHOT_G_PCH_N      B @BASEBOARD_FAB2_LIB.BASEBOARD_FAB2(SCH_1):H_CPU0_PROCHOT_G_PCH_N

RES_0402-0.0,5%,1/16W,EMPTY,G2A  I110  R7D43
   1 FM_CPU1_PROCHOT_LVT3_K_N      A @BASEBOARD_FAB2_LIB.BASEBOARD_FAB2(SCH_1):FM_CPU1_PROCHOT_LVT3_K_N
   2 H_CPU1_PROCHOT_G_PCH_N      B @BASEBOARD_FAB2_LIB.BASEBOARD_FAB2(SCH_1):H_CPU1_PROCHOT_G_PCH_N

RES_0402-0.0,5%,1/16W,CHIP,G21A  I111  R2T65
   1 FM_CPU_ERR0_LVT3_R_N      A @BASEBOARD_FAB2_LIB.BASEBOARD_FAB2(SCH_1):FM_CPU_ERR0_LVT3_R_N
   2 FM_CPU_ERR0_LVT3_K_N      B @BASEBOARD_FAB2_LIB.BASEBOARD_FAB2(SCH_1):FM_CPU_ERR0_LVT3_K_N

RES_0402-0.0,5%,1/16W,CHIP,G21A  I112  R2T66
   1 FM_CPU_ERR1_LVT3_R_N      A @BASEBOARD_FAB2_LIB.BASEBOARD_FAB2(SCH_1):FM_CPU_ERR1_LVT3_R_N
   2 FM_CPU_ERR1_LVT3_K_N      B @BASEBOARD_FAB2_LIB.BASEBOARD_FAB2(SCH_1):FM_CPU_ERR1_LVT3_K_N

RES_0402-0.0,5%,1/16W,CHIP,G21A  I113  R2T67
   1 FM_CPU0_PROCHOT_LVT3_R_N      A @BASEBOARD_FAB2_LIB.BASEBOARD_FAB2(SCH_1):FM_CPU0_PROCHOT_LVT3_R_N
   2 FM_CPU0_PROCHOT_LVT3_K_N      B @BASEBOARD_FAB2_LIB.BASEBOARD_FAB2(SCH_1):FM_CPU0_PROCHOT_LVT3_K_N

RES_0402-0.0,5%,1/16W,CHIP,G21A  I114  R7D41
   1 FM_CPU1_PROCHOT_LVT3_R_N      A @BASEBOARD_FAB2_LIB.BASEBOARD_FAB2(SCH_1):FM_CPU1_PROCHOT_LVT3_R_N
   2 FM_CPU1_PROCHOT_LVT3_K_N      B @BASEBOARD_FAB2_LIB.BASEBOARD_FAB2(SCH_1):FM_CPU1_PROCHOT_LVT3_K_N

RES_0402-0.0,5%,1/16W,CHIP,G21A  I119  R8F38
   1 FM_CPU_ERR0_LVT3_N      A @BASEBOARD_FAB2_LIB.BASEBOARD_FAB2(SCH_1):FM_CPU_ERR0_LVT3_N
   2 FM_CPU_ERR0_LVT3_BMC_N      B @BASEBOARD_FAB2_LIB.BASEBOARD_FAB2(SCH_1):FM_CPU_ERR0_LVT3_BMC_N

RES_0402-0.0,5%,1/16W,CHIP,G21A  I121  R2T64
   1 FM_CPU_ERR1_LVT3_N      A @BASEBOARD_FAB2_LIB.BASEBOARD_FAB2(SCH_1):FM_CPU_ERR1_LVT3_N
   2 FM_CPU_ERR1_LVT3_BMC_N      B @BASEBOARD_FAB2_LIB.BASEBOARD_FAB2(SCH_1):FM_CPU_ERR1_LVT3_BMC_N

RES_0402-0.0,5%,1/16W,CHIP,G21A  I122  R1T36
   1 FM_CPU0_PROCHOT_LVT3_N      A @BASEBOARD_FAB2_LIB.BASEBOARD_FAB2(SCH_1):FM_CPU0_PROCHOT_LVT3_N
   2 FM_CPU0_PROCHOT_LVT3_BMC_N      B @BASEBOARD_FAB2_LIB.BASEBOARD_FAB2(SCH_1):FM_CPU0_PROCHOT_LVT3_BMC_N

RES_0402-0.0,5%,1/16W,CHIP,G21A  I123  R1T37
   1 FM_CPU1_PROCHOT_LVT3_N      A @BASEBOARD_FAB2_LIB.BASEBOARD_FAB2(SCH_1):FM_CPU1_PROCHOT_LVT3_N
   2 FM_CPU1_PROCHOT_LVT3_BMC_N      B @BASEBOARD_FAB2_LIB.BASEBOARD_FAB2(SCH_1):FM_CPU1_PROCHOT_LVT3_BMC_N

RES_0402-1.00K,1%,1/16W,CHIP,GA  I127  R2T50
   1 PD_GTL2104_4_DIR      A @BASEBOARD_FAB2_LIB.BASEBOARD_FAB2(SCH_1):PD_GTL2104_4_DIR
   2    GND      B @BASEBOARD_FAB2_LIB.BASEBOARD_FAB2(SCH_1):GND

RES_0402-0.0,5%,1/16W,EMPTY,G2A  I131  R8F37
   1 FM_CPU_ERR0_LVT3_N      A @BASEBOARD_FAB2_LIB.BASEBOARD_FAB2(SCH_1):FM_CPU_ERR0_LVT3_N
   2 FM_CPU_ERR0_PCH_N      B @BASEBOARD_FAB2_LIB.BASEBOARD_FAB2(SCH_1):FM_CPU_ERR0_PCH_N

RES_0402-0.0,5%,1/16W,EMPTY,G2A  I133  R2T63
   1 FM_CPU_ERR1_LVT3_N      A @BASEBOARD_FAB2_LIB.BASEBOARD_FAB2(SCH_1):FM_CPU_ERR1_LVT3_N
   2 FM_CPU_ERR1_PCH_N      B @BASEBOARD_FAB2_LIB.BASEBOARD_FAB2(SCH_1):FM_CPU_ERR1_PCH_N

RES_0402-0.0,5%,1/16W,EMPTY,G2A  I135  R1T35
   1 FM_CPU0_PROCHOT_LVT3_N      A @BASEBOARD_FAB2_LIB.BASEBOARD_FAB2(SCH_1):FM_CPU0_PROCHOT_LVT3_N
   2 FM_CPU0_PROCHOT_PCH_N      B @BASEBOARD_FAB2_LIB.BASEBOARD_FAB2(SCH_1):FM_CPU0_PROCHOT_PCH_N

RES_0402-0.0,5%,1/16W,EMPTY,G2A  I137  R1T38
   1 FM_CPU1_PROCHOT_LVT3_N      A @BASEBOARD_FAB2_LIB.BASEBOARD_FAB2(SCH_1):FM_CPU1_PROCHOT_LVT3_N
   2 FM_CPU1_PROCHOT_PCH_N      B @BASEBOARD_FAB2_LIB.BASEBOARD_FAB2(SCH_1):FM_CPU1_PROCHOT_PCH_N

RES_0402-150.0,1%,1/16W,CHIP,GA  I143  R2T72
   1 PVCCIO_CPU0      A @BASEBOARD_FAB2_LIB.BASEBOARD_FAB2(SCH_1):PVCCIO_CPU0
   2 H_CPU0_PROCHOT_G_N      B @BASEBOARD_FAB2_LIB.BASEBOARD_FAB2(SCH_1):H_CPU0_PROCHOT_G_N

RES_0402-150.0,1%,1/16W,CHIP,GA  I144  R2T73
   1 PVCCIO_CPU1      A @BASEBOARD_FAB2_LIB.BASEBOARD_FAB2(SCH_1):PVCCIO_CPU1
   2 H_CPU1_PROCHOT_G_N      B @BASEBOARD_FAB2_LIB.BASEBOARD_FAB2(SCH_1):H_CPU1_PROCHOT_G_N


DRAWING: @BASEBOARD_FAB2_LIB.BASEBOARD_FAB2(SCH_1):PAGE94 

FET_N_DUAL_SMLF-NTJD4001N,FET,A  I49  Q3U1
   2 IRQ_PVDDQ_ABC_VRHOT_LVT3_N GATE<0> @BASEBOARD_FAB2_LIB.BASEBOARD_FAB2(SCH_1):IRQ_PVDDQ_ABC_VRHOT_LVT3_N
   1    GND SOURCE<0> @BASEBOARD_FAB2_LIB.BASEBOARD_FAB2(SCH_1):GND
   6 H_CPU0_MEMABC_MEMHOT DRAIN<0> @BASEBOARD_FAB2_LIB.BASEBOARD_FAB2(SCH_1):H_CPU0_MEMABC_MEMHOT

RES_0402-4.75K,1%,1/16W,CHIP,GA  I51  R7G7
   1   P3V3      A @BASEBOARD_FAB2_LIB.BASEBOARD_FAB2(SCH_1):P3V3
   2 H_CPU0_MEMABC_MEMHOT      B @BASEBOARD_FAB2_LIB.BASEBOARD_FAB2(SCH_1):H_CPU0_MEMABC_MEMHOT

FET_N_DUAL_SMLF-NTJD4001N,FET,A  I60  Q7E1
   2 IRQ_PVDDQ_DEF_VRHOT_LVT3_N GATE<0> @BASEBOARD_FAB2_LIB.BASEBOARD_FAB2(SCH_1):IRQ_PVDDQ_DEF_VRHOT_LVT3_N
   1    GND SOURCE<0> @BASEBOARD_FAB2_LIB.BASEBOARD_FAB2(SCH_1):GND
   6 H_CPU0_MEMDEF_MEMHOT DRAIN<0> @BASEBOARD_FAB2_LIB.BASEBOARD_FAB2(SCH_1):H_CPU0_MEMDEF_MEMHOT

FET_N_DUAL_SMLF-NTJD4001N,FET,A  I64  Q7E1
   5 H_CPU0_MEMDEF_MEMHOT GATE<0> @BASEBOARD_FAB2_LIB.BASEBOARD_FAB2(SCH_1):H_CPU0_MEMDEF_MEMHOT
   4    GND SOURCE<0> @BASEBOARD_FAB2_LIB.BASEBOARD_FAB2(SCH_1):GND
   3 H_CPU0_MEMDEF_MEMHOT_G_N DRAIN<0> @BASEBOARD_FAB2_LIB.BASEBOARD_FAB2(SCH_1):H_CPU0_MEMDEF_MEMHOT_G_N

RES_0402-4.75K,1%,1/16W,CHIP,GA  I66  R3R4
   1   P3V3      A @BASEBOARD_FAB2_LIB.BASEBOARD_FAB2(SCH_1):P3V3
   2 H_CPU0_MEMDEF_MEMHOT      B @BASEBOARD_FAB2_LIB.BASEBOARD_FAB2(SCH_1):H_CPU0_MEMDEF_MEMHOT

FET_N_DUAL_SMLF-NTJD4001N,FET,A  I69  Q7E2
   2 IRQ_PVDDQ_GHJ_VRHOT_LVT3_N GATE<0> @BASEBOARD_FAB2_LIB.BASEBOARD_FAB2(SCH_1):IRQ_PVDDQ_GHJ_VRHOT_LVT3_N
   1    GND SOURCE<0> @BASEBOARD_FAB2_LIB.BASEBOARD_FAB2(SCH_1):GND
   6 H_CPU1_MEMGHJ_MEMHOT DRAIN<0> @BASEBOARD_FAB2_LIB.BASEBOARD_FAB2(SCH_1):H_CPU1_MEMGHJ_MEMHOT

FET_N_DUAL_SMLF-NTJD4001N,FET,A  I75  Q7E2
   5 H_CPU1_MEMGHJ_MEMHOT GATE<0> @BASEBOARD_FAB2_LIB.BASEBOARD_FAB2(SCH_1):H_CPU1_MEMGHJ_MEMHOT
   4    GND SOURCE<0> @BASEBOARD_FAB2_LIB.BASEBOARD_FAB2(SCH_1):GND
   3 H_CPU1_MEMGHJ_MEMHOT_G_N DRAIN<0> @BASEBOARD_FAB2_LIB.BASEBOARD_FAB2(SCH_1):H_CPU1_MEMGHJ_MEMHOT_G_N

FET_N_DUAL_SMLF-NTJD4001N,FET,A  I77  Q4B1
   5 H_CPU1_MEMKLM_MEMHOT GATE<0> @BASEBOARD_FAB2_LIB.BASEBOARD_FAB2(SCH_1):H_CPU1_MEMKLM_MEMHOT
   4    GND SOURCE<0> @BASEBOARD_FAB2_LIB.BASEBOARD_FAB2(SCH_1):GND
   3 H_CPU1_MEMKLM_MEMHOT_G_N DRAIN<0> @BASEBOARD_FAB2_LIB.BASEBOARD_FAB2(SCH_1):H_CPU1_MEMKLM_MEMHOT_G_N

RES_0402-4.75K,1%,1/16W,CHIP,GA  I79  R3R10
   1   P3V3      A @BASEBOARD_FAB2_LIB.BASEBOARD_FAB2(SCH_1):P3V3
   2 H_CPU1_MEMGHJ_MEMHOT      B @BASEBOARD_FAB2_LIB.BASEBOARD_FAB2(SCH_1):H_CPU1_MEMGHJ_MEMHOT

RES_0402-4.75K,1%,1/16W,CHIP,GA  I82  R6M4
   1   P3V3      A @BASEBOARD_FAB2_LIB.BASEBOARD_FAB2(SCH_1):P3V3
   2 H_CPU1_MEMKLM_MEMHOT      B @BASEBOARD_FAB2_LIB.BASEBOARD_FAB2(SCH_1):H_CPU1_MEMKLM_MEMHOT

FET_N_DUAL_SMLF-NTJD4001N,FET,A  I84  Q4B1
   2 IRQ_PVDDQ_KLM_VRHOT_LVT3_N GATE<0> @BASEBOARD_FAB2_LIB.BASEBOARD_FAB2(SCH_1):IRQ_PVDDQ_KLM_VRHOT_LVT3_N
   1    GND SOURCE<0> @BASEBOARD_FAB2_LIB.BASEBOARD_FAB2(SCH_1):GND
   6 H_CPU1_MEMKLM_MEMHOT DRAIN<0> @BASEBOARD_FAB2_LIB.BASEBOARD_FAB2(SCH_1):H_CPU1_MEMKLM_MEMHOT

FET_N_DUAL_SMLF-NTJD4001N,FET,A  I89  Q3U1
   5 H_CPU0_MEMABC_MEMHOT GATE<0> @BASEBOARD_FAB2_LIB.BASEBOARD_FAB2(SCH_1):H_CPU0_MEMABC_MEMHOT
   4    GND SOURCE<0> @BASEBOARD_FAB2_LIB.BASEBOARD_FAB2(SCH_1):GND
   3 H_CPU0_MEMABC_MEMHOT_G_N DRAIN<0> @BASEBOARD_FAB2_LIB.BASEBOARD_FAB2(SCH_1):H_CPU0_MEMABC_MEMHOT_G_N

RES_0402-4.75K,1%,1/16W,CHIP,GA  I91  R4U1
   1 P3V3_STBY      A @BASEBOARD_FAB2_LIB.BASEBOARD_FAB2(SCH_1):P3V3_STBY
   2 FM_MEM_THERM_EVENT_LVT3_N      B @BASEBOARD_FAB2_LIB.BASEBOARD_FAB2(SCH_1):FM_MEM_THERM_EVENT_LVT3_N

RES_0402-4.75K,1%,1/16W,CHIP,GA  I94  R4U3
   1 PVPP_ABC      A @BASEBOARD_FAB2_LIB.BASEBOARD_FAB2(SCH_1):PVPP_ABC
   2 FM_DIMM_EVENT_FET      B @BASEBOARD_FAB2_LIB.BASEBOARD_FAB2(SCH_1):FM_DIMM_EVENT_FET

FET_N_DUAL_SMLF-NTJD4001N,FET,A  I98  Q4U1
   2 FM_DIMM_EVENT_COD_N GATE<0> @BASEBOARD_FAB2_LIB.BASEBOARD_FAB2(SCH_1):FM_DIMM_EVENT_COD_N
   1    GND SOURCE<0> @BASEBOARD_FAB2_LIB.BASEBOARD_FAB2(SCH_1):GND
   6 FM_DIMM_EVENT_FET DRAIN<0> @BASEBOARD_FAB2_LIB.BASEBOARD_FAB2(SCH_1):FM_DIMM_EVENT_FET

RES_0402-2.21K,1%,1/16W,CHIP,GA  I100  R4U2
   1 PVPP_ABC      A @BASEBOARD_FAB2_LIB.BASEBOARD_FAB2(SCH_1):PVPP_ABC
   2 FM_DIMM_EVENT_COD_N      B @BASEBOARD_FAB2_LIB.BASEBOARD_FAB2(SCH_1):FM_DIMM_EVENT_COD_N

FET_N_DUAL_SMLF-NTJD4001N,FET,A  I102  Q4U1
   5 FM_DIMM_EVENT_FET GATE<0> @BASEBOARD_FAB2_LIB.BASEBOARD_FAB2(SCH_1):FM_DIMM_EVENT_FET
   4    GND SOURCE<0> @BASEBOARD_FAB2_LIB.BASEBOARD_FAB2(SCH_1):GND
   3 FM_MEM_THERM_EVENT_LVT3_N DRAIN<0> @BASEBOARD_FAB2_LIB.BASEBOARD_FAB2(SCH_1):FM_MEM_THERM_EVENT_LVT3_N

RES_0402-33.0K,5%,1/16W,CHIP,GA  I104  R4U4
   1 FM_DIMM_EVENT_FET      A @BASEBOARD_FAB2_LIB.BASEBOARD_FAB2(SCH_1):FM_DIMM_EVENT_FET
   2    GND      B @BASEBOARD_FAB2_LIB.BASEBOARD_FAB2(SCH_1):GND


DRAWING: @BASEBOARD_FAB2_LIB.BASEBOARD_FAB2(SCH_1):PAGE95 

FET_N_DUAL_SMLF-NTJD4001N,FET,A  I28  Q2U1
   2 FM_SYS_THROTTLE_LVC3 GATE<0> @BASEBOARD_FAB2_LIB.BASEBOARD_FAB2(SCH_1):FM_SYS_THROTTLE_LVC3
   1    GND SOURCE<0> @BASEBOARD_FAB2_LIB.BASEBOARD_FAB2(SCH_1):GND
   6 H_CPU0_MEMABC_MEMHOT_G_N DRAIN<0> @BASEBOARD_FAB2_LIB.BASEBOARD_FAB2(SCH_1):H_CPU0_MEMABC_MEMHOT_G_N

FET_N_DUAL_SMLF-NTJD4001N,FET,A  I32  Q4B2
   2 FM_SYS_THROTTLE_LVC3 GATE<0> @BASEBOARD_FAB2_LIB.BASEBOARD_FAB2(SCH_1):FM_SYS_THROTTLE_LVC3
   1    GND SOURCE<0> @BASEBOARD_FAB2_LIB.BASEBOARD_FAB2(SCH_1):GND
   6 H_CPU1_MEMGHJ_MEMHOT_G_N DRAIN<0> @BASEBOARD_FAB2_LIB.BASEBOARD_FAB2(SCH_1):H_CPU1_MEMGHJ_MEMHOT_G_N

FET_N_DUAL_SMLF-NTJD4001N,FET,A  I33  Q4B2
   5 FM_SYS_THROTTLE_LVC3 GATE<0> @BASEBOARD_FAB2_LIB.BASEBOARD_FAB2(SCH_1):FM_SYS_THROTTLE_LVC3
   4    GND SOURCE<0> @BASEBOARD_FAB2_LIB.BASEBOARD_FAB2(SCH_1):GND
   3 H_CPU1_MEMKLM_MEMHOT_G_N DRAIN<0> @BASEBOARD_FAB2_LIB.BASEBOARD_FAB2(SCH_1):H_CPU1_MEMKLM_MEMHOT_G_N

FET_N_DUAL_SMLF-NTJD4001N,FET,A  I51  Q7E3
   5 FM_SYS_THROTTLE_LVC3 GATE<0> @BASEBOARD_FAB2_LIB.BASEBOARD_FAB2(SCH_1):FM_SYS_THROTTLE_LVC3
   4    GND SOURCE<0> @BASEBOARD_FAB2_LIB.BASEBOARD_FAB2(SCH_1):GND
   3 H_CPU1_PROCHOT_G_N DRAIN<0> @BASEBOARD_FAB2_LIB.BASEBOARD_FAB2(SCH_1):H_CPU1_PROCHOT_G_N

FET_N_DUAL_SMLF-NTJD4001N,FET,A  I52  Q7E3
   2 FM_SYS_THROTTLE_LVC3 GATE<0> @BASEBOARD_FAB2_LIB.BASEBOARD_FAB2(SCH_1):FM_SYS_THROTTLE_LVC3
   1    GND SOURCE<0> @BASEBOARD_FAB2_LIB.BASEBOARD_FAB2(SCH_1):GND
   6 H_CPU0_PROCHOT_G_N DRAIN<0> @BASEBOARD_FAB2_LIB.BASEBOARD_FAB2(SCH_1):H_CPU0_PROCHOT_G_N

FET_N_DUAL_SMLF-NTJD4001N,FET,A  I59  Q7E5
   5 IRQ_CPU0_VRHOT GATE<0> @BASEBOARD_FAB2_LIB.BASEBOARD_FAB2(SCH_1):IRQ_CPU0_VRHOT
   4    GND SOURCE<0> @BASEBOARD_FAB2_LIB.BASEBOARD_FAB2(SCH_1):GND
   3 H_CPU0_PROCHOT_G_N DRAIN<0> @BASEBOARD_FAB2_LIB.BASEBOARD_FAB2(SCH_1):H_CPU0_PROCHOT_G_N

RES_0402-4.75K,1%,1/16W,CHIP,GA  I62  R7E10
   1   P3V3      A @BASEBOARD_FAB2_LIB.BASEBOARD_FAB2(SCH_1):P3V3
   2 IRQ_CPU0_VRHOT      B @BASEBOARD_FAB2_LIB.BASEBOARD_FAB2(SCH_1):IRQ_CPU0_VRHOT

FET_N_DUAL_SMLF-NTJD4001N,FET,A  I69  Q7E6
   5 IRQ_CPU1_VRHOT GATE<0> @BASEBOARD_FAB2_LIB.BASEBOARD_FAB2(SCH_1):IRQ_CPU1_VRHOT
   4    GND SOURCE<0> @BASEBOARD_FAB2_LIB.BASEBOARD_FAB2(SCH_1):GND
   3 H_CPU1_PROCHOT_G_N DRAIN<0> @BASEBOARD_FAB2_LIB.BASEBOARD_FAB2(SCH_1):H_CPU1_PROCHOT_G_N

RES_0402-4.75K,1%,1/16W,CHIP,GA  I72  R7E11
   1   P3V3      A @BASEBOARD_FAB2_LIB.BASEBOARD_FAB2(SCH_1):P3V3
   2 IRQ_CPU1_VRHOT      B @BASEBOARD_FAB2_LIB.BASEBOARD_FAB2(SCH_1):IRQ_CPU1_VRHOT

CAP_A_0402V-0.1UF,16V,10%,X7R,A  I92  C7E3
   1 P3V3_STBY      A @BASEBOARD_FAB2_LIB.BASEBOARD_FAB2(SCH_1):P3V3_STBY
   2    GND      B @BASEBOARD_FAB2_LIB.BASEBOARD_FAB2(SCH_1):GND

FET_N_SOT23-2N7002,FET,C79254-A  I104  Q7E4
   1 FM_THROTTLE_R_N   GATE @BASEBOARD_FAB2_LIB.BASEBOARD_FAB2(SCH_1):FM_THROTTLE_R_N
   2    GND    SRC @BASEBOARD_FAB2_LIB.BASEBOARD_FAB2(SCH_1):GND
   3 FM_SYS_THROTTLE_LVC3    DRN @BASEBOARD_FAB2_LIB.BASEBOARD_FAB2(SCH_1):FM_SYS_THROTTLE_LVC3

RES_0402-4.75K,1%,1/16W,CHIP,GA  I106  R7E7
   1   P3V3      A @BASEBOARD_FAB2_LIB.BASEBOARD_FAB2(SCH_1):P3V3
   2 FM_SYS_THROTTLE_LVC3      B @BASEBOARD_FAB2_LIB.BASEBOARD_FAB2(SCH_1):FM_SYS_THROTTLE_LVC3

RES_0402-0.0,5%,1/16W,CHIP,G21A  I108  R7E9
   1 FM_THROTTLE_N      A @BASEBOARD_FAB2_LIB.BASEBOARD_FAB2(SCH_1):FM_THROTTLE_N
   2 FM_THROTTLE_R_N      B @BASEBOARD_FAB2_LIB.BASEBOARD_FAB2(SCH_1):FM_THROTTLE_R_N

FET_N_DUAL_SMLF-NTJD4001N,FET,A  I111  Q7E5
   2 IRQ_CPU0_PROCHOT_G_N GATE<0> @BASEBOARD_FAB2_LIB.BASEBOARD_FAB2(SCH_1):IRQ_CPU0_PROCHOT_G_N
   1    GND SOURCE<0> @BASEBOARD_FAB2_LIB.BASEBOARD_FAB2(SCH_1):GND
   6 IRQ_CPU0_VRHOT DRAIN<0> @BASEBOARD_FAB2_LIB.BASEBOARD_FAB2(SCH_1):IRQ_CPU0_VRHOT

FET_N_DUAL_SMLF-NTJD4001N,FET,A  I112  Q7E6
   2 IRQ_CPU1_PROCHOT_G_N GATE<0> @BASEBOARD_FAB2_LIB.BASEBOARD_FAB2(SCH_1):IRQ_CPU1_PROCHOT_G_N
   1    GND SOURCE<0> @BASEBOARD_FAB2_LIB.BASEBOARD_FAB2(SCH_1):GND
   6 IRQ_CPU1_VRHOT DRAIN<0> @BASEBOARD_FAB2_LIB.BASEBOARD_FAB2(SCH_1):IRQ_CPU1_VRHOT

FET_N_DUAL_SMLF-NTJD4001N,FET,A  I113  Q2U1
   5 FM_SYS_THROTTLE_LVC3 GATE<0> @BASEBOARD_FAB2_LIB.BASEBOARD_FAB2(SCH_1):FM_SYS_THROTTLE_LVC3
   4    GND SOURCE<0> @BASEBOARD_FAB2_LIB.BASEBOARD_FAB2(SCH_1):GND
   3 H_CPU0_MEMDEF_MEMHOT_G_N DRAIN<0> @BASEBOARD_FAB2_LIB.BASEBOARD_FAB2(SCH_1):H_CPU0_MEMDEF_MEMHOT_G_N

CAP_A_0402V-0.1UF,16V,10%,X7R,A  I115  C7E4
   1 P3V3_STBY      A @BASEBOARD_FAB2_LIB.BASEBOARD_FAB2(SCH_1):P3V3_STBY
   2    GND      B @BASEBOARD_FAB2_LIB.BASEBOARD_FAB2(SCH_1):GND

TTL1G08_SOTLF-NC7SZ08,IC,D1032B  I117  U7E2
   4 IRQ_CPU0_PROCHOT_G_N   Y<0> @BASEBOARD_FAB2_LIB.BASEBOARD_FAB2(SCH_1):IRQ_CPU0_PROCHOT_G_N
   1 FM_PVCCIN_CPU0_PWR_IN_ALERT_N   A<0> @BASEBOARD_FAB2_LIB.BASEBOARD_FAB2(SCH_1):FM_PVCCIN_CPU0_PWR_IN_ALERT_N
   2 IRQ_PVCCIN_CPU0_VRHOT_LVC3_N   B<0> @BASEBOARD_FAB2_LIB.BASEBOARD_FAB2(SCH_1):IRQ_PVCCIN_CPU0_VRHOT_LVC3_N

TTL1G08_SOTLF-NC7SZ08,IC,D1032B  I118  U7E3
   4 IRQ_CPU1_PROCHOT_G_N   Y<0> @BASEBOARD_FAB2_LIB.BASEBOARD_FAB2(SCH_1):IRQ_CPU1_PROCHOT_G_N
   1 FM_PVCCIN_CPU1_PWR_IN_ALERT_N   A<0> @BASEBOARD_FAB2_LIB.BASEBOARD_FAB2(SCH_1):FM_PVCCIN_CPU1_PWR_IN_ALERT_N
   2 IRQ_PVCCIN_CPU1_VRHOT_LVC3_N   B<0> @BASEBOARD_FAB2_LIB.BASEBOARD_FAB2(SCH_1):IRQ_PVCCIN_CPU1_VRHOT_LVC3_N

FET_N_SOT23-2N7002,FET,C79254-A  I119  Q7E8
   1 FM_SYS_THROTTLE_LVC3   GATE @BASEBOARD_FAB2_LIB.BASEBOARD_FAB2(SCH_1):FM_SYS_THROTTLE_LVC3
   2    GND    SRC @BASEBOARD_FAB2_LIB.BASEBOARD_FAB2(SCH_1):GND
   3 FM_PWRBRK_N    DRN @BASEBOARD_FAB2_LIB.BASEBOARD_FAB2(SCH_1):FM_PWRBRK_N


DRAWING: @BASEBOARD_FAB2_LIB.BASEBOARD_FAB2(SCH_1):PAGE96 

RES_0402-49.9,1%,1/16W,CHIP,G2A  I2  R6D12
   1 PVCCIO_CPU0      A @BASEBOARD_FAB2_LIB.BASEBOARD_FAB2(SCH_1):PVCCIO_CPU0
   2 RST_CPU0_G_N      B @BASEBOARD_FAB2_LIB.BASEBOARD_FAB2(SCH_1):RST_CPU0_G_N

RES_0402-49.9,1%,1/16W,CHIP,G2A  I3  R6D8
   1 PVCCIO_CPU0      A @BASEBOARD_FAB2_LIB.BASEBOARD_FAB2(SCH_1):PVCCIO_CPU0
   2 PWRGD_CPU0_G      B @BASEBOARD_FAB2_LIB.BASEBOARD_FAB2(SCH_1):PWRGD_CPU0_G

RES_0402-64.9,1.0%,1/16W,CHIP,A  I5  R3P29
   1 PVDDQ_DEF      A @BASEBOARD_FAB2_LIB.BASEBOARD_FAB2(SCH_1):PVDDQ_DEF
   2 PWRGD_CPU0_DRAMPWROK_DEF_G      B @BASEBOARD_FAB2_LIB.BASEBOARD_FAB2(SCH_1):PWRGD_CPU0_DRAMPWROK_DEF_G

RES_0402-64.9,1.0%,1/16W,CHIP,A  I7  R3P38
   1 PVDDQ_ABC      A @BASEBOARD_FAB2_LIB.BASEBOARD_FAB2(SCH_1):PVDDQ_ABC
   2 PWRGD_CPU0_DRAMPWROK_ABC_G      B @BASEBOARD_FAB2_LIB.BASEBOARD_FAB2(SCH_1):PWRGD_CPU0_DRAMPWROK_ABC_G

RES_0402-49.9,1%,1/16W,CHIP,G2A  I25  R3D20
   1 PVCCIO_CPU1      A @BASEBOARD_FAB2_LIB.BASEBOARD_FAB2(SCH_1):PVCCIO_CPU1
   2 RST_CPU1_G_N      B @BASEBOARD_FAB2_LIB.BASEBOARD_FAB2(SCH_1):RST_CPU1_G_N

RES_0402-49.9,1%,1/16W,CHIP,G2A  I26  R3D15
   1 PVCCIO_CPU1      A @BASEBOARD_FAB2_LIB.BASEBOARD_FAB2(SCH_1):PVCCIO_CPU1
   2 PWRGD_CPU1_G      B @BASEBOARD_FAB2_LIB.BASEBOARD_FAB2(SCH_1):PWRGD_CPU1_G

RES_0402-64.9,1.0%,1/16W,CHIP,A  I28  R7M9
   1 PVDDQ_KLM      A @BASEBOARD_FAB2_LIB.BASEBOARD_FAB2(SCH_1):PVDDQ_KLM
   2 PWRGD_CPU1_DRAMPWROK_KLM_G      B @BASEBOARD_FAB2_LIB.BASEBOARD_FAB2(SCH_1):PWRGD_CPU1_DRAMPWROK_KLM_G

RES_0402-64.9,1.0%,1/16W,CHIP,A  I30  R3D21
   1 PVDDQ_GHJ      A @BASEBOARD_FAB2_LIB.BASEBOARD_FAB2(SCH_1):PVDDQ_GHJ
   2 PWRGD_CPU1_DRAMPWROK_GHJ_G      B @BASEBOARD_FAB2_LIB.BASEBOARD_FAB2(SCH_1):PWRGD_CPU1_DRAMPWROK_GHJ_G

RES_0402-1.00K,1%,1/16W,CHIP,GA  I36  R3P36
   1 P3V3_STBY      A @BASEBOARD_FAB2_LIB.BASEBOARD_FAB2(SCH_1):P3V3_STBY
   2 PU_GTL2014_1_DIR      B @BASEBOARD_FAB2_LIB.BASEBOARD_FAB2(SCH_1):PU_GTL2014_1_DIR

GTL2014_SM-IC,D66151-001  I42  U3P1
  13 PWRGD_DRAMPWRGD     A0 @BASEBOARD_FAB2_LIB.BASEBOARD_FAB2(SCH_1):PWRGD_DRAMPWRGD
  12 PWRGD_DRAMPWRGD     A1 @BASEBOARD_FAB2_LIB.BASEBOARD_FAB2(SCH_1):PWRGD_DRAMPWRGD
  10 RST_CPU0_LVC3_N     A2 @BASEBOARD_FAB2_LIB.BASEBOARD_FAB2(SCH_1):RST_CPU0_LVC3_N
   9 PWRGD_CPU0_LVC3     A3 @BASEBOARD_FAB2_LIB.BASEBOARD_FAB2(SCH_1):PWRGD_CPU0_LVC3
   2 PWRGD_CPU0_DRAMPWROK_DEF_G     B0 @BASEBOARD_FAB2_LIB.BASEBOARD_FAB2(SCH_1):PWRGD_CPU0_DRAMPWROK_DEF_G
   3 PWRGD_CPU0_DRAMPWROK_ABC_G     B1 @BASEBOARD_FAB2_LIB.BASEBOARD_FAB2(SCH_1):PWRGD_CPU0_DRAMPWROK_ABC_G
   5 RST_CPU0_G_N     B2 @BASEBOARD_FAB2_LIB.BASEBOARD_FAB2(SCH_1):RST_CPU0_G_N
   6 PWRGD_CPU0_G     B3 @BASEBOARD_FAB2_LIB.BASEBOARD_FAB2(SCH_1):PWRGD_CPU0_G
   1 PU_GTL2014_1_DIR    DIR @BASEBOARD_FAB2_LIB.BASEBOARD_FAB2(SCH_1):PU_GTL2014_1_DIR
  11    GND GND<2> @BASEBOARD_FAB2_LIB.BASEBOARD_FAB2(SCH_1):GND
   8    GND GND<1> @BASEBOARD_FAB2_LIB.BASEBOARD_FAB2(SCH_1):GND
   7    GND GND<0> @BASEBOARD_FAB2_LIB.BASEBOARD_FAB2(SCH_1):GND
  14 P3V3_STBY    VCC @BASEBOARD_FAB2_LIB.BASEBOARD_FAB2(SCH_1):P3V3_STBY
   4 PD_GTL2014_1_VREF   VREF @BASEBOARD_FAB2_LIB.BASEBOARD_FAB2(SCH_1):PD_GTL2014_1_VREF

GTL2014_SM-IC,D66151-001  I46  U4C2
  13 PWRGD_DRAMPWRGD     A0 @BASEBOARD_FAB2_LIB.BASEBOARD_FAB2(SCH_1):PWRGD_DRAMPWRGD
  12 PWRGD_DRAMPWRGD     A1 @BASEBOARD_FAB2_LIB.BASEBOARD_FAB2(SCH_1):PWRGD_DRAMPWRGD
  10 RST_CPU1_LVC3_N     A2 @BASEBOARD_FAB2_LIB.BASEBOARD_FAB2(SCH_1):RST_CPU1_LVC3_N
   9 PWRGD_CPU1_LVC3     A3 @BASEBOARD_FAB2_LIB.BASEBOARD_FAB2(SCH_1):PWRGD_CPU1_LVC3
   2 PWRGD_CPU1_DRAMPWROK_KLM_G     B0 @BASEBOARD_FAB2_LIB.BASEBOARD_FAB2(SCH_1):PWRGD_CPU1_DRAMPWROK_KLM_G
   3 PWRGD_CPU1_DRAMPWROK_GHJ_G     B1 @BASEBOARD_FAB2_LIB.BASEBOARD_FAB2(SCH_1):PWRGD_CPU1_DRAMPWROK_GHJ_G
   5 RST_CPU1_G_N     B2 @BASEBOARD_FAB2_LIB.BASEBOARD_FAB2(SCH_1):RST_CPU1_G_N
   6 PWRGD_CPU1_G     B3 @BASEBOARD_FAB2_LIB.BASEBOARD_FAB2(SCH_1):PWRGD_CPU1_G
   1 PU_GTL2014_2_DIR    DIR @BASEBOARD_FAB2_LIB.BASEBOARD_FAB2(SCH_1):PU_GTL2014_2_DIR
  11    GND GND<2> @BASEBOARD_FAB2_LIB.BASEBOARD_FAB2(SCH_1):GND
   8    GND GND<1> @BASEBOARD_FAB2_LIB.BASEBOARD_FAB2(SCH_1):GND
   7    GND GND<0> @BASEBOARD_FAB2_LIB.BASEBOARD_FAB2(SCH_1):GND
  14 P3V3_STBY    VCC @BASEBOARD_FAB2_LIB.BASEBOARD_FAB2(SCH_1):P3V3_STBY
   4 PD_GTL2014_2_VREF   VREF @BASEBOARD_FAB2_LIB.BASEBOARD_FAB2(SCH_1):PD_GTL2014_2_VREF

RES_0402-1.00K,1%,1/16W,CHIP,GA  I55  R4C8
   1 P3V3_STBY      A @BASEBOARD_FAB2_LIB.BASEBOARD_FAB2(SCH_1):P3V3_STBY
   2 PU_GTL2014_2_DIR      B @BASEBOARD_FAB2_LIB.BASEBOARD_FAB2(SCH_1):PU_GTL2014_2_DIR

RES_0402-1.00K,1%,1/16W,CHIP,GA  I69  R4C9
   1    GND      A @BASEBOARD_FAB2_LIB.BASEBOARD_FAB2(SCH_1):GND
   2 PD_GTL2014_2_VREF      B @BASEBOARD_FAB2_LIB.BASEBOARD_FAB2(SCH_1):PD_GTL2014_2_VREF

RES_0402-1.00K,1%,1/16W,CHIP,GA  I71  R3P32
   1    GND      A @BASEBOARD_FAB2_LIB.BASEBOARD_FAB2(SCH_1):GND
   2 PD_GTL2014_1_VREF      B @BASEBOARD_FAB2_LIB.BASEBOARD_FAB2(SCH_1):PD_GTL2014_1_VREF

CAP_A_0402V-1.0UF,6.3V,10%,X6SA  I73  C3P42
   1 P3V3_STBY      A @BASEBOARD_FAB2_LIB.BASEBOARD_FAB2(SCH_1):P3V3_STBY
   2    GND      B @BASEBOARD_FAB2_LIB.BASEBOARD_FAB2(SCH_1):GND

CAP_A_0402V-1.0UF,6.3V,10%,X6SA  I75  C4C3
   1 P3V3_STBY      A @BASEBOARD_FAB2_LIB.BASEBOARD_FAB2(SCH_1):P3V3_STBY
   2    GND      B @BASEBOARD_FAB2_LIB.BASEBOARD_FAB2(SCH_1):GND


DRAWING: @BASEBOARD_FAB2_LIB.BASEBOARD_FAB2(SCH_1):PAGE97 

RES_0402-0.0,5%,1/16W,CHIP,G21A  I33  R3D18
   1 H_CPU0_FAST_WAKE_N      A @BASEBOARD_FAB2_LIB.BASEBOARD_FAB2(SCH_1):H_CPU0_FAST_WAKE_N
   2 H_CPU1_FAST_WAKE_N      B @BASEBOARD_FAB2_LIB.BASEBOARD_FAB2(SCH_1):H_CPU1_FAST_WAKE_N

RES_0402-150.0,1%,1/16W,CHIP,GA  I42  R4R4
   1 PVCCIO_CPU0      A @BASEBOARD_FAB2_LIB.BASEBOARD_FAB2(SCH_1):PVCCIO_CPU0
   2 H_CPU0_FAST_WAKE_N      B @BASEBOARD_FAB2_LIB.BASEBOARD_FAB2(SCH_1):H_CPU0_FAST_WAKE_N

RES_0402-150.0,1%,1/16W,CHIP,GA  I44  R7P20
   1 PVCCIO_CPU0      A @BASEBOARD_FAB2_LIB.BASEBOARD_FAB2(SCH_1):PVCCIO_CPU0
   2 H_CPU1_FAST_WAKE_N      B @BASEBOARD_FAB2_LIB.BASEBOARD_FAB2(SCH_1):H_CPU1_FAST_WAKE_N

RES_0402-240,1.0%,1/16W,CHIP,GA  I72  R4P21
   1 PVCCIO_CPU0      A @BASEBOARD_FAB2_LIB.BASEBOARD_FAB2(SCH_1):PVCCIO_CPU0
   2 PU_CPU0_TSC_SYNC      B @BASEBOARD_FAB2_LIB.BASEBOARD_FAB2(SCH_1):PU_CPU0_TSC_SYNC

RES_0402-240,1.0%,1/16W,CHIP,GA  I76  R4C10
   1 PVCCIO_CPU1      A @BASEBOARD_FAB2_LIB.BASEBOARD_FAB2(SCH_1):PVCCIO_CPU1
   2 PU_CPU1_TSC_SYNC      B @BASEBOARD_FAB2_LIB.BASEBOARD_FAB2(SCH_1):PU_CPU1_TSC_SYNC

RES_0402-10.0K,1%,1/16W,CHIP,GA  I80  R4P5
   1    GND      A @BASEBOARD_FAB2_LIB.BASEBOARD_FAB2(SCH_1):GND
   2 PD_CPU0_MCP01_DMON      B @BASEBOARD_FAB2_LIB.BASEBOARD_FAB2(SCH_1):PD_CPU0_MCP01_DMON

RES_0402-10.0K,1%,1/16W,CHIP,GA  I81  R7P13
   1    GND      A @BASEBOARD_FAB2_LIB.BASEBOARD_FAB2(SCH_1):GND
   2 PD_CPU1_MCP01_DMON      B @BASEBOARD_FAB2_LIB.BASEBOARD_FAB2(SCH_1):PD_CPU1_MCP01_DMON


DRAWING: @BASEBOARD_FAB2_LIB.BASEBOARD_FAB2(SCH_1):PAGE98 

RES_0402-1.00K,1%,1/16W,CHIP,GA  I4  R4F5
   1 M_A_VREF      A @BASEBOARD_FAB2_LIB.BASEBOARD_FAB2(SCH_1):M_A_VREF
   2    GND      B @BASEBOARD_FAB2_LIB.BASEBOARD_FAB2(SCH_1):GND

RES_0402-2,1.0%,1/16W,CHIP,G21A  I5  R4F3
   1 M_A_CPU_VREF      A @BASEBOARD_FAB2_LIB.BASEBOARD_FAB2(SCH_1):M_A_CPU_VREF
   2 M_A_VREF      B @BASEBOARD_FAB2_LIB.BASEBOARD_FAB2(SCH_1):M_A_VREF

CAP_A_0402V-0.01UF,25V,10%,X7RA  I7  C4F9
   1 M_A_CPU_VREF      A @BASEBOARD_FAB2_LIB.BASEBOARD_FAB2(SCH_1):M_A_CPU_VREF
   2    GND      B @BASEBOARD_FAB2_LIB.BASEBOARD_FAB2(SCH_1):GND

RES_0402-1.00K,1%,1/16W,CHIP,GA  I9  R6M1
   1 PVDDQ_DEF      A @BASEBOARD_FAB2_LIB.BASEBOARD_FAB2(SCH_1):PVDDQ_DEF
   2 M_D_VREF      B @BASEBOARD_FAB2_LIB.BASEBOARD_FAB2(SCH_1):M_D_VREF

RES_0402-1.00K,1%,1/16W,CHIP,GA  I12  R6L16
   1 M_D_VREF      A @BASEBOARD_FAB2_LIB.BASEBOARD_FAB2(SCH_1):M_D_VREF
   2    GND      B @BASEBOARD_FAB2_LIB.BASEBOARD_FAB2(SCH_1):GND

RES_0402-2,1.0%,1/16W,CHIP,G21A  I14  R6M2
   1 M_D_CPU_VREF      A @BASEBOARD_FAB2_LIB.BASEBOARD_FAB2(SCH_1):M_D_CPU_VREF
   2 M_D_VREF      B @BASEBOARD_FAB2_LIB.BASEBOARD_FAB2(SCH_1):M_D_VREF

CAP_A_0402V-0.01UF,25V,10%,X7RA  I33  C6M2
   1 M_D_CPU_VREF      A @BASEBOARD_FAB2_LIB.BASEBOARD_FAB2(SCH_1):M_D_CPU_VREF
   2    GND      B @BASEBOARD_FAB2_LIB.BASEBOARD_FAB2(SCH_1):GND

RES_0402-1.00K,1%,1/16W,CHIP,GA  I36  R4F4
   1 PVDDQ_ABC      A @BASEBOARD_FAB2_LIB.BASEBOARD_FAB2(SCH_1):PVDDQ_ABC
   2 M_A_VREF      B @BASEBOARD_FAB2_LIB.BASEBOARD_FAB2(SCH_1):M_A_VREF

RES_0402-1.00K,1%,1/16W,CHIP,GA  I38  R4G2
   1 PVDDQ_ABC      A @BASEBOARD_FAB2_LIB.BASEBOARD_FAB2(SCH_1):PVDDQ_ABC
   2 M_B_VREF      B @BASEBOARD_FAB2_LIB.BASEBOARD_FAB2(SCH_1):M_B_VREF

RES_0402-1.00K,1%,1/16W,CHIP,GA  I40  R4G3
   1 M_B_VREF      A @BASEBOARD_FAB2_LIB.BASEBOARD_FAB2(SCH_1):M_B_VREF
   2    GND      B @BASEBOARD_FAB2_LIB.BASEBOARD_FAB2(SCH_1):GND

RES_0402-2,1.0%,1/16W,CHIP,G21A  I42  R4G1
   1 M_B_CPU_VREF      A @BASEBOARD_FAB2_LIB.BASEBOARD_FAB2(SCH_1):M_B_CPU_VREF
   2 M_B_VREF      B @BASEBOARD_FAB2_LIB.BASEBOARD_FAB2(SCH_1):M_B_VREF

CAP_A_0402V-0.01UF,25V,10%,X7RA  I43  C4G1
   1 M_B_CPU_VREF      A @BASEBOARD_FAB2_LIB.BASEBOARD_FAB2(SCH_1):M_B_CPU_VREF
   2    GND      B @BASEBOARD_FAB2_LIB.BASEBOARD_FAB2(SCH_1):GND

RES_0402-1.00K,1%,1/16W,CHIP,GA  I46  R4G21
   1 PVDDQ_ABC      A @BASEBOARD_FAB2_LIB.BASEBOARD_FAB2(SCH_1):PVDDQ_ABC
   2 M_C_VREF      B @BASEBOARD_FAB2_LIB.BASEBOARD_FAB2(SCH_1):M_C_VREF

RES_0402-1.00K,1%,1/16W,CHIP,GA  I48  R4G22
   1 M_C_VREF      A @BASEBOARD_FAB2_LIB.BASEBOARD_FAB2(SCH_1):M_C_VREF
   2    GND      B @BASEBOARD_FAB2_LIB.BASEBOARD_FAB2(SCH_1):GND

RES_0402-2,1.0%,1/16W,CHIP,G21A  I50  R4G20
   1 M_C_CPU_VREF      A @BASEBOARD_FAB2_LIB.BASEBOARD_FAB2(SCH_1):M_C_CPU_VREF
   2 M_C_VREF      B @BASEBOARD_FAB2_LIB.BASEBOARD_FAB2(SCH_1):M_C_VREF

CAP_A_0402V-0.01UF,25V,10%,X7RA  I51  C4G17
   1 M_C_CPU_VREF      A @BASEBOARD_FAB2_LIB.BASEBOARD_FAB2(SCH_1):M_C_CPU_VREF
   2    GND      B @BASEBOARD_FAB2_LIB.BASEBOARD_FAB2(SCH_1):GND

RES_0402-1.00K,1%,1/16W,CHIP,GA  I54  R6L13
   1 PVDDQ_DEF      A @BASEBOARD_FAB2_LIB.BASEBOARD_FAB2(SCH_1):PVDDQ_DEF
   2 M_E_VREF      B @BASEBOARD_FAB2_LIB.BASEBOARD_FAB2(SCH_1):M_E_VREF

RES_0402-1.00K,1%,1/16W,CHIP,GA  I56  R6L12
   1 M_E_VREF      A @BASEBOARD_FAB2_LIB.BASEBOARD_FAB2(SCH_1):M_E_VREF
   2    GND      B @BASEBOARD_FAB2_LIB.BASEBOARD_FAB2(SCH_1):GND

RES_0402-2,1.0%,1/16W,CHIP,G21A  I58  R6L14
   1 M_E_CPU_VREF      A @BASEBOARD_FAB2_LIB.BASEBOARD_FAB2(SCH_1):M_E_CPU_VREF
   2 M_E_VREF      B @BASEBOARD_FAB2_LIB.BASEBOARD_FAB2(SCH_1):M_E_VREF

CAP_A_0402V-0.01UF,25V,10%,X7RA  I59  C6L7
   1 M_E_CPU_VREF      A @BASEBOARD_FAB2_LIB.BASEBOARD_FAB2(SCH_1):M_E_CPU_VREF
   2    GND      B @BASEBOARD_FAB2_LIB.BASEBOARD_FAB2(SCH_1):GND

RES_0402-1.00K,1%,1/16W,CHIP,GA  I62  R6L2
   1 PVDDQ_DEF      A @BASEBOARD_FAB2_LIB.BASEBOARD_FAB2(SCH_1):PVDDQ_DEF
   2 M_F_VREF      B @BASEBOARD_FAB2_LIB.BASEBOARD_FAB2(SCH_1):M_F_VREF

RES_0402-1.00K,1%,1/16W,CHIP,GA  I64  R6L1
   1 M_F_VREF      A @BASEBOARD_FAB2_LIB.BASEBOARD_FAB2(SCH_1):M_F_VREF
   2    GND      B @BASEBOARD_FAB2_LIB.BASEBOARD_FAB2(SCH_1):GND

RES_0402-2,1.0%,1/16W,CHIP,G21A  I66  R6L3
   1 M_F_CPU_VREF      A @BASEBOARD_FAB2_LIB.BASEBOARD_FAB2(SCH_1):M_F_CPU_VREF
   2 M_F_VREF      B @BASEBOARD_FAB2_LIB.BASEBOARD_FAB2(SCH_1):M_F_VREF

CAP_A_0402V-0.01UF,25V,10%,X7RA  I67  C6L2
   1 M_F_CPU_VREF      A @BASEBOARD_FAB2_LIB.BASEBOARD_FAB2(SCH_1):M_F_CPU_VREF
   2    GND      B @BASEBOARD_FAB2_LIB.BASEBOARD_FAB2(SCH_1):GND


DRAWING: @BASEBOARD_FAB2_LIB.BASEBOARD_FAB2(SCH_1):PAGE99 

CAP_A_0402V-0.1UF,16V,10%,X7R,A  I2  C6F2
   1 PVCCIO_CPU0      A @BASEBOARD_FAB2_LIB.BASEBOARD_FAB2(SCH_1):PVCCIO_CPU0
   2    GND      B @BASEBOARD_FAB2_LIB.BASEBOARD_FAB2(SCH_1):GND

CAP_A_0402V-0.1UF,16V,10%,X7R,A  I7  C6F3
   1 PVPP_ABC      A @BASEBOARD_FAB2_LIB.BASEBOARD_FAB2(SCH_1):PVPP_ABC
   2    GND      B @BASEBOARD_FAB2_LIB.BASEBOARD_FAB2(SCH_1):GND

RES_0402-20.0,1%,1/16W,CHIP,G2A  I9  R4T9
   1 SMB_DDR_ABC_VPP_SCL_R      A @BASEBOARD_FAB2_LIB.BASEBOARD_FAB2(SCH_1):SMB_DDR_ABC_VPP_SCL_R
   2 SMB_DDR_ABC_VPP_SCL      B @BASEBOARD_FAB2_LIB.BASEBOARD_FAB2(SCH_1):SMB_DDR_ABC_VPP_SCL

RES_0402-20.0,1%,1/16W,CHIP,G2A  I10  R4T10
   1 SMB_DDR_ABC_VPP_SDA_R      A @BASEBOARD_FAB2_LIB.BASEBOARD_FAB2(SCH_1):SMB_DDR_ABC_VPP_SDA_R
   2 SMB_DDR_ABC_VPP_SDA      B @BASEBOARD_FAB2_LIB.BASEBOARD_FAB2(SCH_1):SMB_DDR_ABC_VPP_SDA

RES_0402-665,1.0%,1/16W,CHIP,GA  I11  R4T8
   1 PVPP_ABC      A @BASEBOARD_FAB2_LIB.BASEBOARD_FAB2(SCH_1):PVPP_ABC
   2 SMB_DDR_ABC_VPP_SDA_R      B @BASEBOARD_FAB2_LIB.BASEBOARD_FAB2(SCH_1):SMB_DDR_ABC_VPP_SDA_R

RES_0402-665,1.0%,1/16W,CHIP,GA  I13  R4T7
   1 PVPP_ABC      A @BASEBOARD_FAB2_LIB.BASEBOARD_FAB2(SCH_1):PVPP_ABC
   2 SMB_DDR_ABC_VPP_SCL_R      B @BASEBOARD_FAB2_LIB.BASEBOARD_FAB2(SCH_1):SMB_DDR_ABC_VPP_SCL_R

PCA9617_SSOP-IC,G81764-001-GNDA  I15  U6F1
   5 TP_SMB_DDR_ABC_EN     EN @BASEBOARD_FAB2_LIB.BASEBOARD_FAB2(SCH_1):TP_SMB_DDR_ABC_EN
   2 SMB_DDR_ABC_SCL_G   SCLA @BASEBOARD_FAB2_LIB.BASEBOARD_FAB2(SCH_1):SMB_DDR_ABC_SCL_G
   7 SMB_DDR_ABC_VPP_SCL_R   SCLB @BASEBOARD_FAB2_LIB.BASEBOARD_FAB2(SCH_1):SMB_DDR_ABC_VPP_SCL_R
   3 SMB_DDR_ABC_SDA_G   SDAA @BASEBOARD_FAB2_LIB.BASEBOARD_FAB2(SCH_1):SMB_DDR_ABC_SDA_G
   6 SMB_DDR_ABC_VPP_SDA_R   SDAB @BASEBOARD_FAB2_LIB.BASEBOARD_FAB2(SCH_1):SMB_DDR_ABC_VPP_SDA_R
   1 PVCCIO_CPU0   VCCA @BASEBOARD_FAB2_LIB.BASEBOARD_FAB2(SCH_1):PVCCIO_CPU0
   8 PVPP_ABC   VCCB @BASEBOARD_FAB2_LIB.BASEBOARD_FAB2(SCH_1):PVPP_ABC

RES_0402-240,1.0%,1/16W,CHIP,GA  I17  R4T6
   1 PVCCIO_CPU0      A @BASEBOARD_FAB2_LIB.BASEBOARD_FAB2(SCH_1):PVCCIO_CPU0
   2 SMB_DDR_ABC_SDA_G      B @BASEBOARD_FAB2_LIB.BASEBOARD_FAB2(SCH_1):SMB_DDR_ABC_SDA_G

RES_0402-240,1.0%,1/16W,CHIP,GA  I19  R4T5
   1 PVCCIO_CPU0      A @BASEBOARD_FAB2_LIB.BASEBOARD_FAB2(SCH_1):PVCCIO_CPU0
   2 SMB_DDR_ABC_SCL_G      B @BASEBOARD_FAB2_LIB.BASEBOARD_FAB2(SCH_1):SMB_DDR_ABC_SCL_G

RES_0402-10.0,1%,1/16W,CHIP,G2A  I20  R4T4
   1 SMB_DDR_ABC_SDA_G_R      A @BASEBOARD_FAB2_LIB.BASEBOARD_FAB2(SCH_1):SMB_DDR_ABC_SDA_G_R
   2 SMB_DDR_ABC_SDA_G      B @BASEBOARD_FAB2_LIB.BASEBOARD_FAB2(SCH_1):SMB_DDR_ABC_SDA_G

CAP_A_0402V-0.1UF,16V,10%,X7R,A  I23  C7E1
   1 PVCCIO_CPU0      A @BASEBOARD_FAB2_LIB.BASEBOARD_FAB2(SCH_1):PVCCIO_CPU0
   2    GND      B @BASEBOARD_FAB2_LIB.BASEBOARD_FAB2(SCH_1):GND

CAP_A_0402V-0.1UF,16V,10%,X7R,A  I27  C4G22
   1 PVCCIO_CPU1      A @BASEBOARD_FAB2_LIB.BASEBOARD_FAB2(SCH_1):PVCCIO_CPU1
   2    GND      B @BASEBOARD_FAB2_LIB.BASEBOARD_FAB2(SCH_1):GND

CAP_A_0402V-0.1UF,16V,10%,X7R,A  I32  C7E2
   1 PVPP_DEF      A @BASEBOARD_FAB2_LIB.BASEBOARD_FAB2(SCH_1):PVPP_DEF
   2    GND      B @BASEBOARD_FAB2_LIB.BASEBOARD_FAB2(SCH_1):GND

RES_0402-20.0,1%,1/16W,CHIP,G2A  I34  R3R9
   1 SMB_DDR_DEF_VPP_SDA_R      A @BASEBOARD_FAB2_LIB.BASEBOARD_FAB2(SCH_1):SMB_DDR_DEF_VPP_SDA_R
   2 SMB_DDR_DEF_VPP_SDA      B @BASEBOARD_FAB2_LIB.BASEBOARD_FAB2(SCH_1):SMB_DDR_DEF_VPP_SDA

RES_0402-20.0,1%,1/16W,CHIP,G2A  I35  R3R8
   1 SMB_DDR_DEF_VPP_SCL_R      A @BASEBOARD_FAB2_LIB.BASEBOARD_FAB2(SCH_1):SMB_DDR_DEF_VPP_SCL_R
   2 SMB_DDR_DEF_VPP_SCL      B @BASEBOARD_FAB2_LIB.BASEBOARD_FAB2(SCH_1):SMB_DDR_DEF_VPP_SCL

CAP_A_0402V-0.1UF,16V,10%,X7R,A  I41  C4G25
   1 PVPP_GHJ      A @BASEBOARD_FAB2_LIB.BASEBOARD_FAB2(SCH_1):PVPP_GHJ
   2    GND      B @BASEBOARD_FAB2_LIB.BASEBOARD_FAB2(SCH_1):GND

RES_0402-20.0,1%,1/16W,CHIP,G2A  I42  R6U13
   1 SMB_DDR_GHJ_VPP_SCL_R      A @BASEBOARD_FAB2_LIB.BASEBOARD_FAB2(SCH_1):SMB_DDR_GHJ_VPP_SCL_R
   2 SMB_DDR_GHJ_VPP_SCL      B @BASEBOARD_FAB2_LIB.BASEBOARD_FAB2(SCH_1):SMB_DDR_GHJ_VPP_SCL

RES_0402-20.0,1%,1/16W,CHIP,G2A  I43  R6U14
   1 SMB_DDR_GHJ_VPP_SDA_R      A @BASEBOARD_FAB2_LIB.BASEBOARD_FAB2(SCH_1):SMB_DDR_GHJ_VPP_SDA_R
   2 SMB_DDR_GHJ_VPP_SDA      B @BASEBOARD_FAB2_LIB.BASEBOARD_FAB2(SCH_1):SMB_DDR_GHJ_VPP_SDA

CAP_A_0402V-0.1UF,16V,10%,X7R,A  I47  C3B4
   1 PVCCIO_CPU1      A @BASEBOARD_FAB2_LIB.BASEBOARD_FAB2(SCH_1):PVCCIO_CPU1
   2    GND      B @BASEBOARD_FAB2_LIB.BASEBOARD_FAB2(SCH_1):GND

CAP_A_0402V-0.1UF,16V,10%,X7R,A  I53  C3B5
   1 PVPP_KLM      A @BASEBOARD_FAB2_LIB.BASEBOARD_FAB2(SCH_1):PVPP_KLM
   2    GND      B @BASEBOARD_FAB2_LIB.BASEBOARD_FAB2(SCH_1):GND

RES_0402-20.0,1%,1/16W,CHIP,G2A  I55  R7M5
   1 SMB_DDR_KLM_VPP_SDA_R      A @BASEBOARD_FAB2_LIB.BASEBOARD_FAB2(SCH_1):SMB_DDR_KLM_VPP_SDA_R
   2 SMB_DDR_KLM_VPP_SDA      B @BASEBOARD_FAB2_LIB.BASEBOARD_FAB2(SCH_1):SMB_DDR_KLM_VPP_SDA

RES_0402-20.0,1%,1/16W,CHIP,G2A  I56  R7M4
   1 SMB_DDR_KLM_VPP_SCL_R      A @BASEBOARD_FAB2_LIB.BASEBOARD_FAB2(SCH_1):SMB_DDR_KLM_VPP_SCL_R
   2 SMB_DDR_KLM_VPP_SCL      B @BASEBOARD_FAB2_LIB.BASEBOARD_FAB2(SCH_1):SMB_DDR_KLM_VPP_SCL

PCA9617_SSOP-IC,G81764-001-GNDA  I61  U7E1
   5 TP_SMB_DDR_DEF_EN     EN @BASEBOARD_FAB2_LIB.BASEBOARD_FAB2(SCH_1):TP_SMB_DDR_DEF_EN
   2 SMB_DDR_DEF_SCL_G   SCLA @BASEBOARD_FAB2_LIB.BASEBOARD_FAB2(SCH_1):SMB_DDR_DEF_SCL_G
   7 SMB_DDR_DEF_VPP_SCL_R   SCLB @BASEBOARD_FAB2_LIB.BASEBOARD_FAB2(SCH_1):SMB_DDR_DEF_VPP_SCL_R
   3 SMB_DDR_DEF_SDA_G   SDAA @BASEBOARD_FAB2_LIB.BASEBOARD_FAB2(SCH_1):SMB_DDR_DEF_SDA_G
   6 SMB_DDR_DEF_VPP_SDA_R   SDAB @BASEBOARD_FAB2_LIB.BASEBOARD_FAB2(SCH_1):SMB_DDR_DEF_VPP_SDA_R
   1 PVCCIO_CPU0   VCCA @BASEBOARD_FAB2_LIB.BASEBOARD_FAB2(SCH_1):PVCCIO_CPU0
   8 PVPP_DEF   VCCB @BASEBOARD_FAB2_LIB.BASEBOARD_FAB2(SCH_1):PVPP_DEF

PCA9617_SSOP-IC,G81764-001-GNDA  I63  U4G1
   5 TP_SMB_DDR_GHJ_EN     EN @BASEBOARD_FAB2_LIB.BASEBOARD_FAB2(SCH_1):TP_SMB_DDR_GHJ_EN
   2 SMB_DDR_GHJ_SCL_G   SCLA @BASEBOARD_FAB2_LIB.BASEBOARD_FAB2(SCH_1):SMB_DDR_GHJ_SCL_G
   7 SMB_DDR_GHJ_VPP_SCL_R   SCLB @BASEBOARD_FAB2_LIB.BASEBOARD_FAB2(SCH_1):SMB_DDR_GHJ_VPP_SCL_R
   3 SMB_DDR_GHJ_SDA_G   SDAA @BASEBOARD_FAB2_LIB.BASEBOARD_FAB2(SCH_1):SMB_DDR_GHJ_SDA_G
   6 SMB_DDR_GHJ_VPP_SDA_R   SDAB @BASEBOARD_FAB2_LIB.BASEBOARD_FAB2(SCH_1):SMB_DDR_GHJ_VPP_SDA_R
   1 PVCCIO_CPU1   VCCA @BASEBOARD_FAB2_LIB.BASEBOARD_FAB2(SCH_1):PVCCIO_CPU1
   8 PVPP_GHJ   VCCB @BASEBOARD_FAB2_LIB.BASEBOARD_FAB2(SCH_1):PVPP_GHJ

RES_0402-240,1.0%,1/16W,CHIP,GA  I65  R3R13
   1 PVCCIO_CPU0      A @BASEBOARD_FAB2_LIB.BASEBOARD_FAB2(SCH_1):PVCCIO_CPU0
   2 SMB_DDR_DEF_SDA_G      B @BASEBOARD_FAB2_LIB.BASEBOARD_FAB2(SCH_1):SMB_DDR_DEF_SDA_G

RES_0402-240,1.0%,1/16W,CHIP,GA  I67  R3P60
   1 PVCCIO_CPU0      A @BASEBOARD_FAB2_LIB.BASEBOARD_FAB2(SCH_1):PVCCIO_CPU0
   2 SMB_DDR_DEF_SCL_G      B @BASEBOARD_FAB2_LIB.BASEBOARD_FAB2(SCH_1):SMB_DDR_DEF_SCL_G

RES_0402-240,1.0%,1/16W,CHIP,GA  I70  R6T1
   1 PVCCIO_CPU1      A @BASEBOARD_FAB2_LIB.BASEBOARD_FAB2(SCH_1):PVCCIO_CPU1
   2 SMB_DDR_GHJ_SDA_G      B @BASEBOARD_FAB2_LIB.BASEBOARD_FAB2(SCH_1):SMB_DDR_GHJ_SDA_G

RES_0402-240,1.0%,1/16W,CHIP,GA  I72  R6T2
   1 PVCCIO_CPU1      A @BASEBOARD_FAB2_LIB.BASEBOARD_FAB2(SCH_1):PVCCIO_CPU1
   2 SMB_DDR_GHJ_SCL_G      B @BASEBOARD_FAB2_LIB.BASEBOARD_FAB2(SCH_1):SMB_DDR_GHJ_SCL_G

PCA9617_SSOP-IC,G81764-001-GNDA  I75  U3B1
   5 TP_SMB_DDR_KLM_EN     EN @BASEBOARD_FAB2_LIB.BASEBOARD_FAB2(SCH_1):TP_SMB_DDR_KLM_EN
   2 SMB_DDR_KLM_SCL_G   SCLA @BASEBOARD_FAB2_LIB.BASEBOARD_FAB2(SCH_1):SMB_DDR_KLM_SCL_G
   7 SMB_DDR_KLM_VPP_SCL_R   SCLB @BASEBOARD_FAB2_LIB.BASEBOARD_FAB2(SCH_1):SMB_DDR_KLM_VPP_SCL_R
   3 SMB_DDR_KLM_SDA_G   SDAA @BASEBOARD_FAB2_LIB.BASEBOARD_FAB2(SCH_1):SMB_DDR_KLM_SDA_G
   6 SMB_DDR_KLM_VPP_SDA_R   SDAB @BASEBOARD_FAB2_LIB.BASEBOARD_FAB2(SCH_1):SMB_DDR_KLM_VPP_SDA_R
   1 PVCCIO_CPU1   VCCA @BASEBOARD_FAB2_LIB.BASEBOARD_FAB2(SCH_1):PVCCIO_CPU1
   8 PVPP_KLM   VCCB @BASEBOARD_FAB2_LIB.BASEBOARD_FAB2(SCH_1):PVPP_KLM

RES_0402-240,1.0%,1/16W,CHIP,GA  I77  R7M7
   1 PVCCIO_CPU1      A @BASEBOARD_FAB2_LIB.BASEBOARD_FAB2(SCH_1):PVCCIO_CPU1
   2 SMB_DDR_KLM_SDA_G      B @BASEBOARD_FAB2_LIB.BASEBOARD_FAB2(SCH_1):SMB_DDR_KLM_SDA_G

RES_0402-240,1.0%,1/16W,CHIP,GA  I79  R7M2
   1 PVCCIO_CPU1      A @BASEBOARD_FAB2_LIB.BASEBOARD_FAB2(SCH_1):PVCCIO_CPU1
   2 SMB_DDR_KLM_SCL_G      B @BASEBOARD_FAB2_LIB.BASEBOARD_FAB2(SCH_1):SMB_DDR_KLM_SCL_G

RES_0402-10.0,1%,1/16W,CHIP,G2A  I83  R4T3
   1 SMB_DDR_ABC_SCL_G_R      A @BASEBOARD_FAB2_LIB.BASEBOARD_FAB2(SCH_1):SMB_DDR_ABC_SCL_G_R
   2 SMB_DDR_ABC_SCL_G      B @BASEBOARD_FAB2_LIB.BASEBOARD_FAB2(SCH_1):SMB_DDR_ABC_SCL_G

RES_0402-10.0,1%,1/16W,CHIP,G2A  I88  R3R7
   1 SMB_DDR_DEF_SCL_G_R      A @BASEBOARD_FAB2_LIB.BASEBOARD_FAB2(SCH_1):SMB_DDR_DEF_SCL_G_R
   2 SMB_DDR_DEF_SCL_G      B @BASEBOARD_FAB2_LIB.BASEBOARD_FAB2(SCH_1):SMB_DDR_DEF_SCL_G

RES_0402-10.0,1%,1/16W,CHIP,G2A  I92  R6T3
   1 SMB_DDR_GHJ_SCL_G_R      A @BASEBOARD_FAB2_LIB.BASEBOARD_FAB2(SCH_1):SMB_DDR_GHJ_SCL_G_R
   2 SMB_DDR_GHJ_SCL_G      B @BASEBOARD_FAB2_LIB.BASEBOARD_FAB2(SCH_1):SMB_DDR_GHJ_SCL_G

RES_0402-10.0,1%,1/16W,CHIP,G2A  I98  R7M3
   1 SMB_DDR_KLM_SCL_G_R      A @BASEBOARD_FAB2_LIB.BASEBOARD_FAB2(SCH_1):SMB_DDR_KLM_SCL_G_R
   2 SMB_DDR_KLM_SCL_G      B @BASEBOARD_FAB2_LIB.BASEBOARD_FAB2(SCH_1):SMB_DDR_KLM_SCL_G

RES_0402-665,1.0%,1/16W,CHIP,GA  I101  R3R12
   1 PVPP_DEF      A @BASEBOARD_FAB2_LIB.BASEBOARD_FAB2(SCH_1):PVPP_DEF
   2 SMB_DDR_DEF_VPP_SDA_R      B @BASEBOARD_FAB2_LIB.BASEBOARD_FAB2(SCH_1):SMB_DDR_DEF_VPP_SDA_R

RES_0402-665,1.0%,1/16W,CHIP,GA  I103  R3R5
   1 PVPP_DEF      A @BASEBOARD_FAB2_LIB.BASEBOARD_FAB2(SCH_1):PVPP_DEF
   2 SMB_DDR_DEF_VPP_SCL_R      B @BASEBOARD_FAB2_LIB.BASEBOARD_FAB2(SCH_1):SMB_DDR_DEF_VPP_SCL_R

RES_0402-665,1.0%,1/16W,CHIP,GA  I104  R6U18
   1 PVPP_GHJ      A @BASEBOARD_FAB2_LIB.BASEBOARD_FAB2(SCH_1):PVPP_GHJ
   2 SMB_DDR_GHJ_VPP_SDA_R      B @BASEBOARD_FAB2_LIB.BASEBOARD_FAB2(SCH_1):SMB_DDR_GHJ_VPP_SDA_R

RES_0402-665,1.0%,1/16W,CHIP,GA  I106  R6U17
   1 PVPP_GHJ      A @BASEBOARD_FAB2_LIB.BASEBOARD_FAB2(SCH_1):PVPP_GHJ
   2 SMB_DDR_GHJ_VPP_SCL_R      B @BASEBOARD_FAB2_LIB.BASEBOARD_FAB2(SCH_1):SMB_DDR_GHJ_VPP_SCL_R

RES_0402-665,1.0%,1/16W,CHIP,GA  I107  R7M6
   1 PVPP_KLM      A @BASEBOARD_FAB2_LIB.BASEBOARD_FAB2(SCH_1):PVPP_KLM
   2 SMB_DDR_KLM_VPP_SDA_R      B @BASEBOARD_FAB2_LIB.BASEBOARD_FAB2(SCH_1):SMB_DDR_KLM_VPP_SDA_R

RES_0402-665,1.0%,1/16W,CHIP,GA  I109  R7M1
   1 PVPP_KLM      A @BASEBOARD_FAB2_LIB.BASEBOARD_FAB2(SCH_1):PVPP_KLM
   2 SMB_DDR_KLM_VPP_SCL_R      B @BASEBOARD_FAB2_LIB.BASEBOARD_FAB2(SCH_1):SMB_DDR_KLM_VPP_SCL_R

RES_0402-10.0,1%,1/16W,CHIP,G2A  I110  R3R14
   1 SMB_DDR_DEF_SDA_G_R      A @BASEBOARD_FAB2_LIB.BASEBOARD_FAB2(SCH_1):SMB_DDR_DEF_SDA_G_R
   2 SMB_DDR_DEF_SDA_G      B @BASEBOARD_FAB2_LIB.BASEBOARD_FAB2(SCH_1):SMB_DDR_DEF_SDA_G

RES_0402-10.0,1%,1/16W,CHIP,G2A  I111  R6T4
   1 SMB_DDR_GHJ_SDA_G_R      A @BASEBOARD_FAB2_LIB.BASEBOARD_FAB2(SCH_1):SMB_DDR_GHJ_SDA_G_R
   2 SMB_DDR_GHJ_SDA_G      B @BASEBOARD_FAB2_LIB.BASEBOARD_FAB2(SCH_1):SMB_DDR_GHJ_SDA_G

RES_0402-10.0,1%,1/16W,CHIP,G2A  I112  R7M8
   1 SMB_DDR_KLM_SDA_G_R      A @BASEBOARD_FAB2_LIB.BASEBOARD_FAB2(SCH_1):SMB_DDR_KLM_SDA_G_R
   2 SMB_DDR_KLM_SDA_G      B @BASEBOARD_FAB2_LIB.BASEBOARD_FAB2(SCH_1):SMB_DDR_KLM_SDA_G


DRAWING: @BASEBOARD_FAB2_LIB.BASEBOARD_FAB2(SCH_1):PAGE100 

RES_0402-1.00K,1%,1/16W,CHIP,GA  I2  R1F6
   1 M_G_VREF      A @BASEBOARD_FAB2_LIB.BASEBOARD_FAB2(SCH_1):M_G_VREF
   2    GND      B @BASEBOARD_FAB2_LIB.BASEBOARD_FAB2(SCH_1):GND

RES_0402-1.00K,1%,1/16W,CHIP,GA  I4  R9L11
   1 M_K_VREF      A @BASEBOARD_FAB2_LIB.BASEBOARD_FAB2(SCH_1):M_K_VREF
   2    GND      B @BASEBOARD_FAB2_LIB.BASEBOARD_FAB2(SCH_1):GND

RES_0402-1.00K,1%,1/16W,CHIP,GA  I6  R1F5
   1 PVDDQ_GHJ      A @BASEBOARD_FAB2_LIB.BASEBOARD_FAB2(SCH_1):PVDDQ_GHJ
   2 M_G_VREF      B @BASEBOARD_FAB2_LIB.BASEBOARD_FAB2(SCH_1):M_G_VREF

RES_0402-2,1.0%,1/16W,CHIP,G21A  I7  R1F4
   1 M_G_CPU_VREF      A @BASEBOARD_FAB2_LIB.BASEBOARD_FAB2(SCH_1):M_G_CPU_VREF
   2 M_G_VREF      B @BASEBOARD_FAB2_LIB.BASEBOARD_FAB2(SCH_1):M_G_VREF

CAP_A_0402V-0.01UF,25V,10%,X7RA  I8  C1F19
   1 M_G_CPU_VREF      A @BASEBOARD_FAB2_LIB.BASEBOARD_FAB2(SCH_1):M_G_CPU_VREF
   2    GND      B @BASEBOARD_FAB2_LIB.BASEBOARD_FAB2(SCH_1):GND

RES_0402-1.00K,1%,1/16W,CHIP,GA  I11  R9M1
   1 PVDDQ_KLM      A @BASEBOARD_FAB2_LIB.BASEBOARD_FAB2(SCH_1):PVDDQ_KLM
   2 M_K_VREF      B @BASEBOARD_FAB2_LIB.BASEBOARD_FAB2(SCH_1):M_K_VREF

RES_0402-2,1.0%,1/16W,CHIP,G21A  I13  R9M2
   1 M_K_CPU_VREF      A @BASEBOARD_FAB2_LIB.BASEBOARD_FAB2(SCH_1):M_K_CPU_VREF
   2 M_K_VREF      B @BASEBOARD_FAB2_LIB.BASEBOARD_FAB2(SCH_1):M_K_VREF

CAP_A_0402V-0.01UF,25V,10%,X7RA  I15  C9M2
   1 M_K_CPU_VREF      A @BASEBOARD_FAB2_LIB.BASEBOARD_FAB2(SCH_1):M_K_CPU_VREF
   2    GND      B @BASEBOARD_FAB2_LIB.BASEBOARD_FAB2(SCH_1):GND

RES_0402-1.00K,1%,1/16W,CHIP,GA  I19  R1G2
   1 PVDDQ_GHJ      A @BASEBOARD_FAB2_LIB.BASEBOARD_FAB2(SCH_1):PVDDQ_GHJ
   2 M_H_VREF      B @BASEBOARD_FAB2_LIB.BASEBOARD_FAB2(SCH_1):M_H_VREF

RES_0402-1.00K,1%,1/16W,CHIP,GA  I20  R1G3
   1 M_H_VREF      A @BASEBOARD_FAB2_LIB.BASEBOARD_FAB2(SCH_1):M_H_VREF
   2    GND      B @BASEBOARD_FAB2_LIB.BASEBOARD_FAB2(SCH_1):GND

RES_0402-1.00K,1%,1/16W,CHIP,GA  I22  R9L7
   1 PVDDQ_KLM      A @BASEBOARD_FAB2_LIB.BASEBOARD_FAB2(SCH_1):PVDDQ_KLM
   2 M_L_VREF      B @BASEBOARD_FAB2_LIB.BASEBOARD_FAB2(SCH_1):M_L_VREF

RES_0402-1.00K,1%,1/16W,CHIP,GA  I24  R9L6
   1 M_L_VREF      A @BASEBOARD_FAB2_LIB.BASEBOARD_FAB2(SCH_1):M_L_VREF
   2    GND      B @BASEBOARD_FAB2_LIB.BASEBOARD_FAB2(SCH_1):GND

RES_0402-2,1.0%,1/16W,CHIP,G21A  I25  R1G1
   1 M_H_CPU_VREF      A @BASEBOARD_FAB2_LIB.BASEBOARD_FAB2(SCH_1):M_H_CPU_VREF
   2 M_H_VREF      B @BASEBOARD_FAB2_LIB.BASEBOARD_FAB2(SCH_1):M_H_VREF

CAP_A_0402V-0.01UF,25V,10%,X7RA  I26  C1G8
   1 M_H_CPU_VREF      A @BASEBOARD_FAB2_LIB.BASEBOARD_FAB2(SCH_1):M_H_CPU_VREF
   2    GND      B @BASEBOARD_FAB2_LIB.BASEBOARD_FAB2(SCH_1):GND

RES_0402-2,1.0%,1/16W,CHIP,G21A  I29  R9L8
   1 M_L_CPU_VREF      A @BASEBOARD_FAB2_LIB.BASEBOARD_FAB2(SCH_1):M_L_CPU_VREF
   2 M_L_VREF      B @BASEBOARD_FAB2_LIB.BASEBOARD_FAB2(SCH_1):M_L_VREF

CAP_A_0402V-0.01UF,25V,10%,X7RA  I30  C9L8
   1 M_L_CPU_VREF      A @BASEBOARD_FAB2_LIB.BASEBOARD_FAB2(SCH_1):M_L_CPU_VREF
   2    GND      B @BASEBOARD_FAB2_LIB.BASEBOARD_FAB2(SCH_1):GND

RES_0402-1.00K,1%,1/16W,CHIP,GA  I35  R1G15
   1 PVDDQ_GHJ      A @BASEBOARD_FAB2_LIB.BASEBOARD_FAB2(SCH_1):PVDDQ_GHJ
   2 M_J_VREF      B @BASEBOARD_FAB2_LIB.BASEBOARD_FAB2(SCH_1):M_J_VREF

RES_0402-1.00K,1%,1/16W,CHIP,GA  I36  R1G17
   1 M_J_VREF      A @BASEBOARD_FAB2_LIB.BASEBOARD_FAB2(SCH_1):M_J_VREF
   2    GND      B @BASEBOARD_FAB2_LIB.BASEBOARD_FAB2(SCH_1):GND

RES_0402-1.00K,1%,1/16W,CHIP,GA  I38  R9L2
   1 PVDDQ_KLM      A @BASEBOARD_FAB2_LIB.BASEBOARD_FAB2(SCH_1):PVDDQ_KLM
   2 M_M_VREF      B @BASEBOARD_FAB2_LIB.BASEBOARD_FAB2(SCH_1):M_M_VREF

RES_0402-1.00K,1%,1/16W,CHIP,GA  I40  R9L1
   1 M_M_VREF      A @BASEBOARD_FAB2_LIB.BASEBOARD_FAB2(SCH_1):M_M_VREF
   2    GND      B @BASEBOARD_FAB2_LIB.BASEBOARD_FAB2(SCH_1):GND

RES_0402-2,1.0%,1/16W,CHIP,G21A  I41  R1G14
   1 M_J_CPU_VREF      A @BASEBOARD_FAB2_LIB.BASEBOARD_FAB2(SCH_1):M_J_CPU_VREF
   2 M_J_VREF      B @BASEBOARD_FAB2_LIB.BASEBOARD_FAB2(SCH_1):M_J_VREF

CAP_A_0402V-0.01UF,25V,10%,X7RA  I42  C1G18
   1 M_J_CPU_VREF      A @BASEBOARD_FAB2_LIB.BASEBOARD_FAB2(SCH_1):M_J_CPU_VREF
   2    GND      B @BASEBOARD_FAB2_LIB.BASEBOARD_FAB2(SCH_1):GND

RES_0402-2,1.0%,1/16W,CHIP,G21A  I45  R9L3
   1 M_M_CPU_VREF      A @BASEBOARD_FAB2_LIB.BASEBOARD_FAB2(SCH_1):M_M_CPU_VREF
   2 M_M_VREF      B @BASEBOARD_FAB2_LIB.BASEBOARD_FAB2(SCH_1):M_M_VREF

CAP_A_0402V-0.01UF,25V,10%,X7RA  I46  C9L3
   1 M_M_CPU_VREF      A @BASEBOARD_FAB2_LIB.BASEBOARD_FAB2(SCH_1):M_M_CPU_VREF
   2    GND      B @BASEBOARD_FAB2_LIB.BASEBOARD_FAB2(SCH_1):GND


DRAWING: @BASEBOARD_FAB2_LIB.BASEBOARD_FAB2(SCH_1):PAGE101 

RES_0402-33.2,1%,1/16W,CHIP,G2A  I20  R8F29
   1 CLK_25M_BMC_R      A @BASEBOARD_FAB2_LIB.BASEBOARD_FAB2(SCH_1):CLK_25M_BMC_R
   2 CLK_25M_BMC      B @BASEBOARD_FAB2_LIB.BASEBOARD_FAB2(SCH_1):CLK_25M_BMC

RES_0402-475.0,1%,1/16W,CHIP,GA  I28  R8F25
   1 A_COMP_CKMNG      A @BASEBOARD_FAB2_LIB.BASEBOARD_FAB2(SCH_1):A_COMP_CKMNG
   2    GND      B @BASEBOARD_FAB2_LIB.BASEBOARD_FAB2(SCH_1):GND

ICS9FGP204_MLFP-IC,E95226-001  I34  EU8F2
  12 P3V3_STBY_MNG VDD32K @BASEBOARD_FAB2_LIB.BASEBOARD_FAB2(SCH_1):P3V3_STBY_MNG
  13 CLK_32K_SUSCLK_PLD_R  32KHZ @BASEBOARD_FAB2_LIB.BASEBOARD_FAB2(SCH_1):CLK_32K_SUSCLK_PLD_R
  14    GND GND32K @BASEBOARD_FAB2_LIB.BASEBOARD_FAB2(SCH_1):GND
  16 CLK_25M_BMC_R 25MHZ_0 @BASEBOARD_FAB2_LIB.BASEBOARD_FAB2(SCH_1):CLK_25M_BMC_R
  17 CLK_25M_CPLD_R 25MHZ_1 @BASEBOARD_FAB2_LIB.BASEBOARD_FAB2(SCH_1):CLK_25M_CPLD_R
  32 CLK_50M_CKMNG_BMC_1_R RMII<1> @BASEBOARD_FAB2_LIB.BASEBOARD_FAB2(SCH_1):CLK_50M_CKMNG_BMC_1_R
  29 CLK_50M_CKMNG_BMC_2_R RMII<2> @BASEBOARD_FAB2_LIB.BASEBOARD_FAB2(SCH_1):CLK_50M_CKMNG_BMC_2_R
  24 TP_CLK5_50M_CKMNG RMII<5> @BASEBOARD_FAB2_LIB.BASEBOARD_FAB2(SCH_1):TP_CLK5_50M_CKMNG
  25 CLK_50M_CKMNG_PCH_10GBE_R RMII<4> @BASEBOARD_FAB2_LIB.BASEBOARD_FAB2(SCH_1):CLK_50M_CKMNG_PCH_10GBE_R
  28 CLK_50M_CKMNG_SPRVLLE_R RMII<3> @BASEBOARD_FAB2_LIB.BASEBOARD_FAB2(SCH_1):CLK_50M_CKMNG_SPRVLLE_R
  33 CLK_50M_CKMNG_OCP_R RMII<0> @BASEBOARD_FAB2_LIB.BASEBOARD_FAB2(SCH_1):CLK_50M_CKMNG_OCP_R
  41    GND GND<1> @BASEBOARD_FAB2_LIB.BASEBOARD_FAB2(SCH_1):GND
  21    GND  GND33 @BASEBOARD_FAB2_LIB.BASEBOARD_FAB2(SCH_1):GND
   1    GND GND<0> @BASEBOARD_FAB2_LIB.BASEBOARD_FAB2(SCH_1):GND
   4 TP_CLK_96M_CKMNG_N DOT96SSC @BASEBOARD_FAB2_LIB.BASEBOARD_FAB2(SCH_1):TP_CLK_96M_CKMNG_N
   3 TP_CLK_96M_CKMNG_P DOT96SST @BASEBOARD_FAB2_LIB.BASEBOARD_FAB2(SCH_1):TP_CLK_96M_CKMNG_P
   8 TP_CLK_100M_R_DN CPUCLKC0 @BASEBOARD_FAB2_LIB.BASEBOARD_FAB2(SCH_1):TP_CLK_100M_R_DN
  18    GND GNDREF @BASEBOARD_FAB2_LIB.BASEBOARD_FAB2(SCH_1):GND
   7 TP_CLK_100M_R_DP CPUCLKT0 @BASEBOARD_FAB2_LIB.BASEBOARD_FAB2(SCH_1):TP_CLK_100M_R_DP
  15 P3V3_STBY_MNG VDDREF @BASEBOARD_FAB2_LIB.BASEBOARD_FAB2(SCH_1):P3V3_STBY_MNG
  11 A_COMP_CKMNG   IREF @BASEBOARD_FAB2_LIB.BASEBOARD_FAB2(SCH_1):A_COMP_CKMNG
  19 XTAL_CK_MNG_IN  X1_25 @BASEBOARD_FAB2_LIB.BASEBOARD_FAB2(SCH_1):XTAL_CK_MNG_IN
  27    GND GNDRMII<0> @BASEBOARD_FAB2_LIB.BASEBOARD_FAB2(SCH_1):GND
  26 P3V3_STBY_MNG_RMII VDDRMII<0> @BASEBOARD_FAB2_LIB.BASEBOARD_FAB2(SCH_1):P3V3_STBY_MNG_RMII
  31 P3V3_STBY_MNG_RMII VDDRMII<1> @BASEBOARD_FAB2_LIB.BASEBOARD_FAB2(SCH_1):P3V3_STBY_MNG_RMII
  30    GND GNDRMII<1> @BASEBOARD_FAB2_LIB.BASEBOARD_FAB2(SCH_1):GND
  22 TP_33P_33M_SMBADR 33MHZ_SMBADR @BASEBOARD_FAB2_LIB.BASEBOARD_FAB2(SCH_1):TP_33P_33M_SMBADR
  23 P3V3_STBY_MNG  VDD33 @BASEBOARD_FAB2_LIB.BASEBOARD_FAB2(SCH_1):P3V3_STBY_MNG
   5 PD_CKMNG_OE  OE_96 @BASEBOARD_FAB2_LIB.BASEBOARD_FAB2(SCH_1):PD_CKMNG_OE
   2 P3V3_STBY_MNG  VDD96 @BASEBOARD_FAB2_LIB.BASEBOARD_FAB2(SCH_1):P3V3_STBY_MNG
   6 PD_CKMNG_OE OE_CPU @BASEBOARD_FAB2_LIB.BASEBOARD_FAB2(SCH_1):PD_CKMNG_OE
  10    GND GNDCPU @BASEBOARD_FAB2_LIB.BASEBOARD_FAB2(SCH_1):GND
   9 P3V3_STBY_MNG_CPU VDDCPU @BASEBOARD_FAB2_LIB.BASEBOARD_FAB2(SCH_1):P3V3_STBY_MNG_CPU
  40 PWRGD_P3V3_STBY VTTPWR_GD_PD_N @BASEBOARD_FAB2_LIB.BASEBOARD_FAB2(SCH_1):PWRGD_P3V3_STBY
  38 SMB_HOST_STBY_LVC3_SCL SMBCLK @BASEBOARD_FAB2_LIB.BASEBOARD_FAB2(SCH_1):SMB_HOST_STBY_LVC3_SCL
  20 XTAL_CK_MNG_OUT  X2_25 @BASEBOARD_FAB2_LIB.BASEBOARD_FAB2(SCH_1):XTAL_CK_MNG_OUT
  39 SMB_HOST_STBY_LVC3_SDA SMBDAT @BASEBOARD_FAB2_LIB.BASEBOARD_FAB2(SCH_1):SMB_HOST_STBY_LVC3_SDA
  34 P3V3_STBY_MNG_RGMII VDD_RGMII @BASEBOARD_FAB2_LIB.BASEBOARD_FAB2(SCH_1):P3V3_STBY_MNG_RGMII
  35    GND GND_RGMII @BASEBOARD_FAB2_LIB.BASEBOARD_FAB2(SCH_1):GND
  37 TP_CLK_125M_BMCA RGMII<0> @BASEBOARD_FAB2_LIB.BASEBOARD_FAB2(SCH_1):TP_CLK_125M_BMCA
  36 TP_CLK_125M RGMII<1> @BASEBOARD_FAB2_LIB.BASEBOARD_FAB2(SCH_1):TP_CLK_125M

RES_0402-1.00K,1%,1/16W,CHIP,GA  I48  R2T25
   1 PD_CKMNG_OE      A @BASEBOARD_FAB2_LIB.BASEBOARD_FAB2(SCH_1):PD_CKMNG_OE
   2    GND      B @BASEBOARD_FAB2_LIB.BASEBOARD_FAB2(SCH_1):GND

CAP_0402LF-27.0PF,50V,5%,COG,AA  I49  C8F18
   1 XTAL_CK_MNG_IN      A @BASEBOARD_FAB2_LIB.BASEBOARD_FAB2(SCH_1):XTAL_CK_MNG_IN
   2    GND      B @BASEBOARD_FAB2_LIB.BASEBOARD_FAB2(SCH_1):GND

CRYSTAL_2013LF-25.000MHZ,IC,D7B  I52  Y8F1
   1 XTAL_CK_MNG_IN      A @BASEBOARD_FAB2_LIB.BASEBOARD_FAB2(SCH_1):XTAL_CK_MNG_IN
   3 XTAL_CK_MNG_OUT      B @BASEBOARD_FAB2_LIB.BASEBOARD_FAB2(SCH_1):XTAL_CK_MNG_OUT

CAP_0402LF-27.0PF,50V,5%,COG,AA  I53  C8F19
   1 XTAL_CK_MNG_OUT      A @BASEBOARD_FAB2_LIB.BASEBOARD_FAB2(SCH_1):XTAL_CK_MNG_OUT
   2    GND      B @BASEBOARD_FAB2_LIB.BASEBOARD_FAB2(SCH_1):GND

CAP_A_0402V-1.0UF,6.3V,10%,X6SA  I89  C2T31
   1 P3V3_STBY_MNG_RGMII      A @BASEBOARD_FAB2_LIB.BASEBOARD_FAB2(SCH_1):P3V3_STBY_MNG_RGMII
   2    GND      B @BASEBOARD_FAB2_LIB.BASEBOARD_FAB2(SCH_1):GND

CAP_A_0402V-0.01UF,25V,10%,X7RA  I90  C2T27
   1 P3V3_STBY_MNG_RGMII      A @BASEBOARD_FAB2_LIB.BASEBOARD_FAB2(SCH_1):P3V3_STBY_MNG_RGMII
   2    GND      B @BASEBOARD_FAB2_LIB.BASEBOARD_FAB2(SCH_1):GND

RES_0603-2.2,1.0%,1/10W,CHIP,GA  I94  R2T23
   1 P3V3_STBY_MNG      A @BASEBOARD_FAB2_LIB.BASEBOARD_FAB2(SCH_1):P3V3_STBY_MNG
   2 P3V3_STBY_MNG_RGMII      B @BASEBOARD_FAB2_LIB.BASEBOARD_FAB2(SCH_1):P3V3_STBY_MNG_RGMII

RES_0603-2.2,1.0%,1/10W,CHIP,GA  I95  R2T52
   1 P3V3_STBY_MNG      A @BASEBOARD_FAB2_LIB.BASEBOARD_FAB2(SCH_1):P3V3_STBY_MNG
   2 P3V3_STBY_MNG_RMII      B @BASEBOARD_FAB2_LIB.BASEBOARD_FAB2(SCH_1):P3V3_STBY_MNG_RMII

CAP_A_0402V-1.0UF,6.3V,10%,X6SA  I97  C2T38
   1 P3V3_STBY_MNG_RMII      A @BASEBOARD_FAB2_LIB.BASEBOARD_FAB2(SCH_1):P3V3_STBY_MNG_RMII
   2    GND      B @BASEBOARD_FAB2_LIB.BASEBOARD_FAB2(SCH_1):GND

CAP_A_0402V-0.01UF,25V,10%,X7RA  I99  C2T37
   1 P3V3_STBY_MNG_RMII      A @BASEBOARD_FAB2_LIB.BASEBOARD_FAB2(SCH_1):P3V3_STBY_MNG_RMII
   2    GND      B @BASEBOARD_FAB2_LIB.BASEBOARD_FAB2(SCH_1):GND

CAP_A_0402V-0.01UF,25V,10%,X7RA  I104  C2T18
   1 P3V3_STBY_MNG_CPU      A @BASEBOARD_FAB2_LIB.BASEBOARD_FAB2(SCH_1):P3V3_STBY_MNG_CPU
   2    GND      B @BASEBOARD_FAB2_LIB.BASEBOARD_FAB2(SCH_1):GND

RES_0603-2.2,1.0%,1/10W,CHIP,GA  I105  R2T21
   1 P3V3_STBY_MNG      A @BASEBOARD_FAB2_LIB.BASEBOARD_FAB2(SCH_1):P3V3_STBY_MNG
   2 P3V3_STBY_MNG_CPU      B @BASEBOARD_FAB2_LIB.BASEBOARD_FAB2(SCH_1):P3V3_STBY_MNG_CPU

CAP_A_0402V-1.0UF,6.3V,10%,X6SA  I106  C2T19
   1 P3V3_STBY_MNG_CPU      A @BASEBOARD_FAB2_LIB.BASEBOARD_FAB2(SCH_1):P3V3_STBY_MNG_CPU
   2    GND      B @BASEBOARD_FAB2_LIB.BASEBOARD_FAB2(SCH_1):GND

CAP_A_0402V-0.1UF,16V,10%,X7R,A  I109  C2T34
   1 P3V3_STBY_MNG      A @BASEBOARD_FAB2_LIB.BASEBOARD_FAB2(SCH_1):P3V3_STBY_MNG
   2    GND      B @BASEBOARD_FAB2_LIB.BASEBOARD_FAB2(SCH_1):GND

CAP_A_0402V-0.1UF,16V,10%,X7R,A  I110  C2T30
   1 P3V3_STBY_MNG      A @BASEBOARD_FAB2_LIB.BASEBOARD_FAB2(SCH_1):P3V3_STBY_MNG
   2    GND      B @BASEBOARD_FAB2_LIB.BASEBOARD_FAB2(SCH_1):GND

CAP_A_0402V-0.1UF,16V,10%,X7R,A  I111  C2T25
   1 P3V3_STBY_MNG      A @BASEBOARD_FAB2_LIB.BASEBOARD_FAB2(SCH_1):P3V3_STBY_MNG
   2    GND      B @BASEBOARD_FAB2_LIB.BASEBOARD_FAB2(SCH_1):GND

CAP_A_0402V-0.1UF,16V,10%,X7R,A  I112  C2T17
   1 P3V3_STBY_MNG      A @BASEBOARD_FAB2_LIB.BASEBOARD_FAB2(SCH_1):P3V3_STBY_MNG
   2    GND      B @BASEBOARD_FAB2_LIB.BASEBOARD_FAB2(SCH_1):GND

CAP_0805-10UF,16V,10%,X6S,C953A  I113  C2T22
   1 P3V3_STBY_MNG      A @BASEBOARD_FAB2_LIB.BASEBOARD_FAB2(SCH_1):P3V3_STBY_MNG
   2    GND      B @BASEBOARD_FAB2_LIB.BASEBOARD_FAB2(SCH_1):GND

FERRITE_SMLF-600,FB,656554-043  I114  FB2T2
   1 P3V3_STBY      A @BASEBOARD_FAB2_LIB.BASEBOARD_FAB2(SCH_1):P3V3_STBY
   2 P3V3_STBY_MNG      B @BASEBOARD_FAB2_LIB.BASEBOARD_FAB2(SCH_1):P3V3_STBY_MNG

CAP_A_0402V-1.0UF,6.3V,10%,X6SA  I116  C2T28
   1 P3V3_STBY      A @BASEBOARD_FAB2_LIB.BASEBOARD_FAB2(SCH_1):P3V3_STBY
   2    GND      B @BASEBOARD_FAB2_LIB.BASEBOARD_FAB2(SCH_1):GND

RES_0402-22.1,1.0%,1/16W,CHIP,A  I124  R2T42
   1 CLK_50M_CKMNG_OCP_R      A @BASEBOARD_FAB2_LIB.BASEBOARD_FAB2(SCH_1):CLK_50M_CKMNG_OCP_R
   2 CLK_50M_CKMNG_OCP      B @BASEBOARD_FAB2_LIB.BASEBOARD_FAB2(SCH_1):CLK_50M_CKMNG_OCP

RES_0402-22.1,1.0%,1/16W,CHIP,A  I125  R2T46
   1 CLK_50M_CKMNG_BMC_1_R      A @BASEBOARD_FAB2_LIB.BASEBOARD_FAB2(SCH_1):CLK_50M_CKMNG_BMC_1_R
   2 CLK_50M_CKMNG_BMC_1      B @BASEBOARD_FAB2_LIB.BASEBOARD_FAB2(SCH_1):CLK_50M_CKMNG_BMC_1

RES_0402-22.1,1.0%,1/16W,CHIP,A  I129  R8F27
   1 CLK_32K_SUSCLK_PLD_R      A @BASEBOARD_FAB2_LIB.BASEBOARD_FAB2(SCH_1):CLK_32K_SUSCLK_PLD_R
   2 CLK_32K_SUSCLK_PLD      B @BASEBOARD_FAB2_LIB.BASEBOARD_FAB2(SCH_1):CLK_32K_SUSCLK_PLD

RES_0402-33.2,1%,1/16W,CHIP,G2A  I130  R2T47
   1 CLK_25M_CPLD_R      A @BASEBOARD_FAB2_LIB.BASEBOARD_FAB2(SCH_1):CLK_25M_CPLD_R
   2 CLK_25M_CPLD      B @BASEBOARD_FAB2_LIB.BASEBOARD_FAB2(SCH_1):CLK_25M_CPLD

RES_0402-33.2,1%,1/16W,CHIP,G2A  I131  R8G25
   1 CLK_50M_CKMNG_SPRVLLE_R      A @BASEBOARD_FAB2_LIB.BASEBOARD_FAB2(SCH_1):CLK_50M_CKMNG_SPRVLLE_R
   2 CLK_50M_CKMNG_SPRVLLE      B @BASEBOARD_FAB2_LIB.BASEBOARD_FAB2(SCH_1):CLK_50M_CKMNG_SPRVLLE

RES_0402-33.2,1%,1/16W,CHIP,G2A  I132  R8G24
   1 CLK_50M_CKMNG_PCH_10GBE_R      A @BASEBOARD_FAB2_LIB.BASEBOARD_FAB2(SCH_1):CLK_50M_CKMNG_PCH_10GBE_R
   2 CLK_50M_CKMNG_PCH_10GBE      B @BASEBOARD_FAB2_LIB.BASEBOARD_FAB2(SCH_1):CLK_50M_CKMNG_PCH_10GBE

RES_0402-33.2,1%,1/16W,CHIP,G2A  I133  R8G1
   1 CLK_50M_CKMNG_BMC_2_R      A @BASEBOARD_FAB2_LIB.BASEBOARD_FAB2(SCH_1):CLK_50M_CKMNG_BMC_2_R
   2 CLK_50M_CKMNG_BMC_2      B @BASEBOARD_FAB2_LIB.BASEBOARD_FAB2(SCH_1):CLK_50M_CKMNG_BMC_2


DRAWING: @BASEBOARD_FAB2_LIB.BASEBOARD_FAB2(SCH_1):PAGE102 

NB3W1200L_LCC-IC,H13585-001  I1  EU4D2
   1 P3V3_DB1200_A   VDDA @BASEBOARD_FAB2_LIB.BASEBOARD_FAB2(SCH_1):P3V3_DB1200_A
   2    GND   GNDA @BASEBOARD_FAB2_LIB.BASEBOARD_FAB2(SCH_1):GND
   3 NC_DB1200ZL<0>  NC<0> @BASEBOARD_FAB2_LIB.BASEBOARD_FAB2(SCH_1):NC_DB1200ZL(0)
   4 FM_100M_N 100M_133M_N @BASEBOARD_FAB2_LIB.BASEBOARD_FAB2(SCH_1):FM_100M_N
   5 FM_HBW_BYPASS_LOWBW_N HBW_BYPASS_LOBW_N @BASEBOARD_FAB2_LIB.BASEBOARD_FAB2(SCH_1):FM_HBW_BYPASS_LOWBW_N
   6 FM_DB1200_PWRGD PWRGD_PWRDN_N @BASEBOARD_FAB2_LIB.BASEBOARD_FAB2(SCH_1):FM_DB1200_PWRGD
   7    GND GND<0> @BASEBOARD_FAB2_LIB.BASEBOARD_FAB2(SCH_1):GND
   8 P3V3_DB1200_R   VDDR @BASEBOARD_FAB2_LIB.BASEBOARD_FAB2(SCH_1):P3V3_DB1200_R
   9 CLK_100M_DB1200_DP CLK_INP @BASEBOARD_FAB2_LIB.BASEBOARD_FAB2(SCH_1):CLK_100M_DB1200_DP
  10 CLK_100M_DB1200_DN CLK_INN @BASEBOARD_FAB2_LIB.BASEBOARD_FAB2(SCH_1):CLK_100M_DB1200_DN
  11 FM_DB1200_SMB_SA0   SA_0 @BASEBOARD_FAB2_LIB.BASEBOARD_FAB2(SCH_1):FM_DB1200_SMB_SA0
  12 SMB_HOST_STBY_LVC3_SDA_R2    SDA @BASEBOARD_FAB2_LIB.BASEBOARD_FAB2(SCH_1):SMB_HOST_STBY_LVC3_SDA_R2
  13 SMB_HOST_STBY_LVC3_SCL_R2    SCL @BASEBOARD_FAB2_LIB.BASEBOARD_FAB2(SCH_1):SMB_HOST_STBY_LVC3_SCL_R2
  14 FM_DB1200_SMB_SA1   SA_1 @BASEBOARD_FAB2_LIB.BASEBOARD_FAB2(SCH_1):FM_DB1200_SMB_SA1
  15 NC_DB1200ZL<2>  NC<2> @BASEBOARD_FAB2_LIB.BASEBOARD_FAB2(SCH_1):NC_DB1200ZL(2)
  16 NC_DB1200ZL<1>  NC<1> @BASEBOARD_FAB2_LIB.BASEBOARD_FAB2(SCH_1):NC_DB1200ZL(1)
  17 CLK_100M_CPU0_BCLK0_R_DP DIF_0P @BASEBOARD_FAB2_LIB.BASEBOARD_FAB2(SCH_1):CLK_100M_CPU0_BCLK0_R_DP
  18 CLK_100M_CPU0_BCLK0_R_DN DIF_0N @BASEBOARD_FAB2_LIB.BASEBOARD_FAB2(SCH_1):CLK_100M_CPU0_BCLK0_R_DN
  19 FM_DB1200ZL_BCLKS_EN_N OE_0_N @BASEBOARD_FAB2_LIB.BASEBOARD_FAB2(SCH_1):FM_DB1200ZL_BCLKS_EN_N
  20 FM_DB1200ZL_BCLKS_EN_N OE_1_N @BASEBOARD_FAB2_LIB.BASEBOARD_FAB2(SCH_1):FM_DB1200ZL_BCLKS_EN_N
  21 CLK_100M_CPU0_BCLK1_R_DP DIF_1P @BASEBOARD_FAB2_LIB.BASEBOARD_FAB2(SCH_1):CLK_100M_CPU0_BCLK1_R_DP
  22 CLK_100M_CPU0_BCLK1_R_DN DIF_1N @BASEBOARD_FAB2_LIB.BASEBOARD_FAB2(SCH_1):CLK_100M_CPU0_BCLK1_R_DN
  23    GND GND<1> @BASEBOARD_FAB2_LIB.BASEBOARD_FAB2(SCH_1):GND
  24 P3V3_DB1200 VDD<0> @BASEBOARD_FAB2_LIB.BASEBOARD_FAB2(SCH_1):P3V3_DB1200
  25 P3V3_DB1200 VDDIO<0> @BASEBOARD_FAB2_LIB.BASEBOARD_FAB2(SCH_1):P3V3_DB1200
  26 CLK_100M_CPU0_BCLK2_R_DP DIF_2P @BASEBOARD_FAB2_LIB.BASEBOARD_FAB2(SCH_1):CLK_100M_CPU0_BCLK2_R_DP
  27 CLK_100M_CPU0_BCLK2_R_DN DIF_2N @BASEBOARD_FAB2_LIB.BASEBOARD_FAB2(SCH_1):CLK_100M_CPU0_BCLK2_R_DN
  28 FM_DB1200ZL_BCLKS_EN_N OE_2_N @BASEBOARD_FAB2_LIB.BASEBOARD_FAB2(SCH_1):FM_DB1200ZL_BCLKS_EN_N
  29 FM_CPU0_MCP_CLK_EN_N OE_3_N @BASEBOARD_FAB2_LIB.BASEBOARD_FAB2(SCH_1):FM_CPU0_MCP_CLK_EN_N
  30 CLK_100M_CPU0_PE_REFCLK_R_DP DIF_3P @BASEBOARD_FAB2_LIB.BASEBOARD_FAB2(SCH_1):CLK_100M_CPU0_PE_REFCLK_R_DP
  31 CLK_100M_CPU0_PE_REFCLK_R_DN DIF_3N @BASEBOARD_FAB2_LIB.BASEBOARD_FAB2(SCH_1):CLK_100M_CPU0_PE_REFCLK_R_DN
  32 P3V3_DB1200 VDDIO<1> @BASEBOARD_FAB2_LIB.BASEBOARD_FAB2(SCH_1):P3V3_DB1200
  33    GND GND<2> @BASEBOARD_FAB2_LIB.BASEBOARD_FAB2(SCH_1):GND
  34 CLK_100M_CPU0_RC_REFCLK0_R_DP DIF_4P @BASEBOARD_FAB2_LIB.BASEBOARD_FAB2(SCH_1):CLK_100M_CPU0_RC_REFCLK0_R_DP
  35 CLK_100M_CPU0_RC_REFCLK0_R_DN DIF_4N @BASEBOARD_FAB2_LIB.BASEBOARD_FAB2(SCH_1):CLK_100M_CPU0_RC_REFCLK0_R_DN
  36 FM_CPU0_MCP_CLK_EN_N OE_4_N @BASEBOARD_FAB2_LIB.BASEBOARD_FAB2(SCH_1):FM_CPU0_MCP_CLK_EN_N
  37 FM_CPU0_MCP_CLK_EN_N OE_5_N @BASEBOARD_FAB2_LIB.BASEBOARD_FAB2(SCH_1):FM_CPU0_MCP_CLK_EN_N
  38 CLK_100M_CPU0_RC_REFCLK1_R_DP DIF_5P @BASEBOARD_FAB2_LIB.BASEBOARD_FAB2(SCH_1):CLK_100M_CPU0_RC_REFCLK1_R_DP
  39 CLK_100M_CPU0_RC_REFCLK1_R_DN DIF_5N @BASEBOARD_FAB2_LIB.BASEBOARD_FAB2(SCH_1):CLK_100M_CPU0_RC_REFCLK1_R_DN
  40 P3V3_DB1200 VDD<1> @BASEBOARD_FAB2_LIB.BASEBOARD_FAB2(SCH_1):P3V3_DB1200
  41    GND GND<3> @BASEBOARD_FAB2_LIB.BASEBOARD_FAB2(SCH_1):GND
  42 CLK_100M_CPU1_BCLK0_R_DP DIF_6P @BASEBOARD_FAB2_LIB.BASEBOARD_FAB2(SCH_1):CLK_100M_CPU1_BCLK0_R_DP
  43 CLK_100M_CPU1_BCLK0_R_DN DIF_6N @BASEBOARD_FAB2_LIB.BASEBOARD_FAB2(SCH_1):CLK_100M_CPU1_BCLK0_R_DN
  44 FM_DB1200ZL_BCLKS_EN_N OE_6_N @BASEBOARD_FAB2_LIB.BASEBOARD_FAB2(SCH_1):FM_DB1200ZL_BCLKS_EN_N
  45 FM_DB1200ZL_BCLKS_EN_N OE_7_N @BASEBOARD_FAB2_LIB.BASEBOARD_FAB2(SCH_1):FM_DB1200ZL_BCLKS_EN_N
  46 CLK_100M_CPU1_BCLK1_R_DP DIF_7P @BASEBOARD_FAB2_LIB.BASEBOARD_FAB2(SCH_1):CLK_100M_CPU1_BCLK1_R_DP
  47 CLK_100M_CPU1_BCLK1_R_DN DIF_7N @BASEBOARD_FAB2_LIB.BASEBOARD_FAB2(SCH_1):CLK_100M_CPU1_BCLK1_R_DN
  48    GND GND<4> @BASEBOARD_FAB2_LIB.BASEBOARD_FAB2(SCH_1):GND
  49 P3V3_DB1200 VDDIO<2> @BASEBOARD_FAB2_LIB.BASEBOARD_FAB2(SCH_1):P3V3_DB1200
  50 CLK_100M_CPU1_BCLK2_R_DP DIF_8P @BASEBOARD_FAB2_LIB.BASEBOARD_FAB2(SCH_1):CLK_100M_CPU1_BCLK2_R_DP
  51 CLK_100M_CPU1_BCLK2_R_DN DIF_8N @BASEBOARD_FAB2_LIB.BASEBOARD_FAB2(SCH_1):CLK_100M_CPU1_BCLK2_R_DN
  52 FM_DB1200ZL_BCLKS_EN_N OE_8_N @BASEBOARD_FAB2_LIB.BASEBOARD_FAB2(SCH_1):FM_DB1200ZL_BCLKS_EN_N
  53 FM_CPU1_MCP_CLK_EN_N OE_9_N @BASEBOARD_FAB2_LIB.BASEBOARD_FAB2(SCH_1):FM_CPU1_MCP_CLK_EN_N
  54 CLK_100M_CPU1_PE_REFCLK_R_DP DIF_9P @BASEBOARD_FAB2_LIB.BASEBOARD_FAB2(SCH_1):CLK_100M_CPU1_PE_REFCLK_R_DP
  55 CLK_100M_CPU1_PE_REFCLK_R_DN DIF_9N @BASEBOARD_FAB2_LIB.BASEBOARD_FAB2(SCH_1):CLK_100M_CPU1_PE_REFCLK_R_DN
  56 P3V3_DB1200 VDDIO<3> @BASEBOARD_FAB2_LIB.BASEBOARD_FAB2(SCH_1):P3V3_DB1200
  57 P3V3_DB1200 VDD<2> @BASEBOARD_FAB2_LIB.BASEBOARD_FAB2(SCH_1):P3V3_DB1200
  58    GND GND<5> @BASEBOARD_FAB2_LIB.BASEBOARD_FAB2(SCH_1):GND
  59 CLK_100M_CPU1_RC_REFCLK0_R_DP DIF_10P @BASEBOARD_FAB2_LIB.BASEBOARD_FAB2(SCH_1):CLK_100M_CPU1_RC_REFCLK0_R_DP
  60 CLK_100M_CPU1_RC_REFCLK0_R_DN DIF_10N @BASEBOARD_FAB2_LIB.BASEBOARD_FAB2(SCH_1):CLK_100M_CPU1_RC_REFCLK0_R_DN
  61 FM_CPU1_MCP_CLK_EN_N OE_10_N @BASEBOARD_FAB2_LIB.BASEBOARD_FAB2(SCH_1):FM_CPU1_MCP_CLK_EN_N
  62 FM_CPU1_MCP_CLK_EN_N OE_11_N @BASEBOARD_FAB2_LIB.BASEBOARD_FAB2(SCH_1):FM_CPU1_MCP_CLK_EN_N
  63 CLK_100M_CPU1_RC_REFCLK1_R_DP DIF_11P @BASEBOARD_FAB2_LIB.BASEBOARD_FAB2(SCH_1):CLK_100M_CPU1_RC_REFCLK1_R_DP
  64 CLK_100M_CPU1_RC_REFCLK1_R_DN DIF_11N @BASEBOARD_FAB2_LIB.BASEBOARD_FAB2(SCH_1):CLK_100M_CPU1_RC_REFCLK1_R_DN
  65    GND  THPAD @BASEBOARD_FAB2_LIB.BASEBOARD_FAB2(SCH_1):GND

FERRITE_SMLF-600,FB,656554-043  I8  FB6P1
   1   P3V3      A @BASEBOARD_FAB2_LIB.BASEBOARD_FAB2(SCH_1):P3V3
   2 P3V3_DB1200      B @BASEBOARD_FAB2_LIB.BASEBOARD_FAB2(SCH_1):P3V3_DB1200

CAP_0805-10UF,16V,10%,X7R,G106A  I10  C3D22
   1 P3V3_DB1200      A @BASEBOARD_FAB2_LIB.BASEBOARD_FAB2(SCH_1):P3V3_DB1200
   2    GND      B @BASEBOARD_FAB2_LIB.BASEBOARD_FAB2(SCH_1):GND

CAP_A_0402V-0.1UF,16V,10%,X7R,A  I11  C6P4
   1 P3V3_DB1200      A @BASEBOARD_FAB2_LIB.BASEBOARD_FAB2(SCH_1):P3V3_DB1200
   2    GND      B @BASEBOARD_FAB2_LIB.BASEBOARD_FAB2(SCH_1):GND

CAP_A_0402V-0.1UF,16V,10%,X7R,A  I12  C6P6
   1 P3V3_DB1200      A @BASEBOARD_FAB2_LIB.BASEBOARD_FAB2(SCH_1):P3V3_DB1200
   2    GND      B @BASEBOARD_FAB2_LIB.BASEBOARD_FAB2(SCH_1):GND

CAP_A_0402V-0.1UF,16V,10%,X7R,A  I13  C6P10
   1 P3V3_DB1200      A @BASEBOARD_FAB2_LIB.BASEBOARD_FAB2(SCH_1):P3V3_DB1200
   2    GND      B @BASEBOARD_FAB2_LIB.BASEBOARD_FAB2(SCH_1):GND

CAP_A_0402V-0.1UF,16V,10%,X7R,A  I14  C6P5
   1 P3V3_DB1200      A @BASEBOARD_FAB2_LIB.BASEBOARD_FAB2(SCH_1):P3V3_DB1200
   2    GND      B @BASEBOARD_FAB2_LIB.BASEBOARD_FAB2(SCH_1):GND

CAP_A_0402V-0.1UF,16V,10%,X7R,A  I15  C6P12
   1 P3V3_DB1200      A @BASEBOARD_FAB2_LIB.BASEBOARD_FAB2(SCH_1):P3V3_DB1200
   2    GND      B @BASEBOARD_FAB2_LIB.BASEBOARD_FAB2(SCH_1):GND

CAP_A_0402V-0.1UF,16V,10%,X7R,A  I16  C6P11
   1 P3V3_DB1200      A @BASEBOARD_FAB2_LIB.BASEBOARD_FAB2(SCH_1):P3V3_DB1200
   2    GND      B @BASEBOARD_FAB2_LIB.BASEBOARD_FAB2(SCH_1):GND

CAP_A_0402V-0.1UF,16V,10%,X7R,A  I18  C4D24
   1 P3V3_DB1200_A      A @BASEBOARD_FAB2_LIB.BASEBOARD_FAB2(SCH_1):P3V3_DB1200_A
   2    GND      B @BASEBOARD_FAB2_LIB.BASEBOARD_FAB2(SCH_1):GND

CAP_A_0402V-1.0UF,6.3V,10%,X6SA  I19  C4D23
   1 P3V3_DB1200_A      A @BASEBOARD_FAB2_LIB.BASEBOARD_FAB2(SCH_1):P3V3_DB1200_A
   2    GND      B @BASEBOARD_FAB2_LIB.BASEBOARD_FAB2(SCH_1):GND

RES_0603-2.2,1.0%,1/10W,CHIP,GA  I21  R3D14
   1 P3V3_DB1200      A @BASEBOARD_FAB2_LIB.BASEBOARD_FAB2(SCH_1):P3V3_DB1200
   2 P3V3_DB1200_A      B @BASEBOARD_FAB2_LIB.BASEBOARD_FAB2(SCH_1):P3V3_DB1200_A

RES_0603-2.2,1.0%,1/10W,CHIP,GA  I26  R6P25
   1 P3V3_DB1200      A @BASEBOARD_FAB2_LIB.BASEBOARD_FAB2(SCH_1):P3V3_DB1200
   2 P3V3_DB1200_R      B @BASEBOARD_FAB2_LIB.BASEBOARD_FAB2(SCH_1):P3V3_DB1200_R

CAP_A_0402V-0.1UF,16V,10%,X7R,A  I28  C4D22
   1 P3V3_DB1200_R      A @BASEBOARD_FAB2_LIB.BASEBOARD_FAB2(SCH_1):P3V3_DB1200_R
   2    GND      B @BASEBOARD_FAB2_LIB.BASEBOARD_FAB2(SCH_1):GND

CAP_A_0402V-1.0UF,6.3V,10%,X6SA  I30  C4D27
   1 P3V3_DB1200_R      A @BASEBOARD_FAB2_LIB.BASEBOARD_FAB2(SCH_1):P3V3_DB1200_R
   2    GND      B @BASEBOARD_FAB2_LIB.BASEBOARD_FAB2(SCH_1):GND

RES_0402-10.0K,1%,1/16W,EMPTY,A  I37  R4D38
   1 P3V3_DB1200      A @BASEBOARD_FAB2_LIB.BASEBOARD_FAB2(SCH_1):P3V3_DB1200
   2 FM_DB1200_SMB_SA1      B @BASEBOARD_FAB2_LIB.BASEBOARD_FAB2(SCH_1):FM_DB1200_SMB_SA1

RES_0402-10.0K,1%,1/16W,EMPTY,A  I38  R4D35
   1 P3V3_DB1200      A @BASEBOARD_FAB2_LIB.BASEBOARD_FAB2(SCH_1):P3V3_DB1200
   2 FM_DB1200_SMB_SA0      B @BASEBOARD_FAB2_LIB.BASEBOARD_FAB2(SCH_1):FM_DB1200_SMB_SA0

RES_0402-4.75K,1%,1/16W,CHIP,GA  I45  R4D40
   1 P3V3_DB1200      A @BASEBOARD_FAB2_LIB.BASEBOARD_FAB2(SCH_1):P3V3_DB1200
   2 FM_100M_N      B @BASEBOARD_FAB2_LIB.BASEBOARD_FAB2(SCH_1):FM_100M_N

RES_0402-4.75K,1%,1/16W,EMPTY,A  I46  R6P23
   1 FM_100M_N      A @BASEBOARD_FAB2_LIB.BASEBOARD_FAB2(SCH_1):FM_100M_N
   2    GND      B @BASEBOARD_FAB2_LIB.BASEBOARD_FAB2(SCH_1):GND

RES_0402-4.75K,1%,1/16W,EMPTY,A  I47  R6P22
   1 FM_HBW_BYPASS_LOWBW_N      A @BASEBOARD_FAB2_LIB.BASEBOARD_FAB2(SCH_1):FM_HBW_BYPASS_LOWBW_N
   2    GND      B @BASEBOARD_FAB2_LIB.BASEBOARD_FAB2(SCH_1):GND

RES_0402-4.75K,1%,1/16W,CHIP,GA  I53  R4D41
   1 P3V3_DB1200      A @BASEBOARD_FAB2_LIB.BASEBOARD_FAB2(SCH_1):P3V3_DB1200
   2 FM_HBW_BYPASS_LOWBW_N      B @BASEBOARD_FAB2_LIB.BASEBOARD_FAB2(SCH_1):FM_HBW_BYPASS_LOWBW_N

CAP_A_0402V-0.1UF,16V,10%,X7R,A  I79  C6P9
   1 P3V3_DB1200      A @BASEBOARD_FAB2_LIB.BASEBOARD_FAB2(SCH_1):P3V3_DB1200
   2    GND      B @BASEBOARD_FAB2_LIB.BASEBOARD_FAB2(SCH_1):GND

RES_0402-1.00K,1%,1/16W,CHIP,GA  I80  R6P21
   1 FM_DB1200_SMB_SA0      A @BASEBOARD_FAB2_LIB.BASEBOARD_FAB2(SCH_1):FM_DB1200_SMB_SA0
   2    GND      B @BASEBOARD_FAB2_LIB.BASEBOARD_FAB2(SCH_1):GND

RES_0402-1.00K,1%,1/16W,CHIP,GA  I81  R6P20
   1 FM_DB1200_SMB_SA1      A @BASEBOARD_FAB2_LIB.BASEBOARD_FAB2(SCH_1):FM_DB1200_SMB_SA1
   2    GND      B @BASEBOARD_FAB2_LIB.BASEBOARD_FAB2(SCH_1):GND

RES_0402-33.2,1%,1/16W,CHIP,G2A  I82  R4D36
   1 SMB_HOST_STBY_LVC3_SDA      A @BASEBOARD_FAB2_LIB.BASEBOARD_FAB2(SCH_1):SMB_HOST_STBY_LVC3_SDA
   2 SMB_HOST_STBY_LVC3_SDA_R2      B @BASEBOARD_FAB2_LIB.BASEBOARD_FAB2(SCH_1):SMB_HOST_STBY_LVC3_SDA_R2

RES_0402-33.2,1%,1/16W,CHIP,G2A  I87  R4D37
   1 SMB_HOST_STBY_LVC3_SCL      A @BASEBOARD_FAB2_LIB.BASEBOARD_FAB2(SCH_1):SMB_HOST_STBY_LVC3_SCL
   2 SMB_HOST_STBY_LVC3_SCL_R2      B @BASEBOARD_FAB2_LIB.BASEBOARD_FAB2(SCH_1):SMB_HOST_STBY_LVC3_SCL_R2

RES_0402-4.75K,1%,1/16W,CHIP,GA  I91  R6P48
   1   P3V3      A @BASEBOARD_FAB2_LIB.BASEBOARD_FAB2(SCH_1):P3V3
   2 FM_DB1200ZL_BCLKS_EN_N      B @BASEBOARD_FAB2_LIB.BASEBOARD_FAB2(SCH_1):FM_DB1200ZL_BCLKS_EN_N

RES_0402-4.75K,1%,1/16W,CHIP,GA  I93  R4D69
   1   P3V3      A @BASEBOARD_FAB2_LIB.BASEBOARD_FAB2(SCH_1):P3V3
   2 FM_CPU1_MCP_CLK_EN_N      B @BASEBOARD_FAB2_LIB.BASEBOARD_FAB2(SCH_1):FM_CPU1_MCP_CLK_EN_N

RES_0402-4.75K,1%,1/16W,CHIP,GA  I94  R4D70
   1   P3V3      A @BASEBOARD_FAB2_LIB.BASEBOARD_FAB2(SCH_1):P3V3
   2 FM_CPU0_MCP_CLK_EN_N      B @BASEBOARD_FAB2_LIB.BASEBOARD_FAB2(SCH_1):FM_CPU0_MCP_CLK_EN_N


DRAWING: @BASEBOARD_FAB2_LIB.BASEBOARD_FAB2(SCH_1):PAGE103 

RES_0402-27.4,1%,1/16W,CHIP,G2A  I1  R4D25
   1 CLK_100M_CPU0_BCLK0_R_DN      A @BASEBOARD_FAB2_LIB.BASEBOARD_FAB2(SCH_1):CLK_100M_CPU0_BCLK0_R_DN
   2 CLK_100M_CPU0_BCLK0_DN      B @BASEBOARD_FAB2_LIB.BASEBOARD_FAB2(SCH_1):CLK_100M_CPU0_BCLK0_DN

RES_0402-27.4,1%,1/16W,CHIP,G2A  I9  R4D23
   1 CLK_100M_CPU1_RC_REFCLK1_R_DP      A @BASEBOARD_FAB2_LIB.BASEBOARD_FAB2(SCH_1):CLK_100M_CPU1_RC_REFCLK1_R_DP
   2 CLK_100M_CPU1_RC_REFCLK1_DP      B @BASEBOARD_FAB2_LIB.BASEBOARD_FAB2(SCH_1):CLK_100M_CPU1_RC_REFCLK1_DP

RES_0402-27.4,1%,1/16W,CHIP,G2A  I14  R4D28
   1 CLK_100M_CPU1_RC_REFCLK1_R_DN      A @BASEBOARD_FAB2_LIB.BASEBOARD_FAB2(SCH_1):CLK_100M_CPU1_RC_REFCLK1_R_DN
   2 CLK_100M_CPU1_RC_REFCLK1_DN      B @BASEBOARD_FAB2_LIB.BASEBOARD_FAB2(SCH_1):CLK_100M_CPU1_RC_REFCLK1_DN

RES_0402-27.4,1%,1/16W,CHIP,G2A  I19  R4D19
   1 CLK_100M_CPU1_RC_REFCLK0_R_DP      A @BASEBOARD_FAB2_LIB.BASEBOARD_FAB2(SCH_1):CLK_100M_CPU1_RC_REFCLK0_R_DP
   2 CLK_100M_CPU1_RC_REFCLK0_DP      B @BASEBOARD_FAB2_LIB.BASEBOARD_FAB2(SCH_1):CLK_100M_CPU1_RC_REFCLK0_DP

RES_0402-27.4,1%,1/16W,CHIP,G2A  I24  R4D21
   1 CLK_100M_CPU1_RC_REFCLK0_R_DN      A @BASEBOARD_FAB2_LIB.BASEBOARD_FAB2(SCH_1):CLK_100M_CPU1_RC_REFCLK0_R_DN
   2 CLK_100M_CPU1_RC_REFCLK0_DN      B @BASEBOARD_FAB2_LIB.BASEBOARD_FAB2(SCH_1):CLK_100M_CPU1_RC_REFCLK0_DN

RES_0402-27.4,1%,1/16W,CHIP,G2A  I29  R4D13
   1 CLK_100M_CPU1_PE_REFCLK_R_DP      A @BASEBOARD_FAB2_LIB.BASEBOARD_FAB2(SCH_1):CLK_100M_CPU1_PE_REFCLK_R_DP
   2 CLK_100M_CPU1_PE_REFCLK_DP      B @BASEBOARD_FAB2_LIB.BASEBOARD_FAB2(SCH_1):CLK_100M_CPU1_PE_REFCLK_DP

RES_0402-27.4,1%,1/16W,CHIP,G2A  I34  R4D16
   1 CLK_100M_CPU1_PE_REFCLK_R_DN      A @BASEBOARD_FAB2_LIB.BASEBOARD_FAB2(SCH_1):CLK_100M_CPU1_PE_REFCLK_R_DN
   2 CLK_100M_CPU1_PE_REFCLK_DN      B @BASEBOARD_FAB2_LIB.BASEBOARD_FAB2(SCH_1):CLK_100M_CPU1_PE_REFCLK_DN

RES_0402-27.4,1%,1/16W,CHIP,G2A  I39  R4D9
   1 CLK_100M_CPU1_BCLK2_R_DP      A @BASEBOARD_FAB2_LIB.BASEBOARD_FAB2(SCH_1):CLK_100M_CPU1_BCLK2_R_DP
   2 CLK_100M_CPU1_BCLK2_DP      B @BASEBOARD_FAB2_LIB.BASEBOARD_FAB2(SCH_1):CLK_100M_CPU1_BCLK2_DP

RES_0402-27.4,1%,1/16W,CHIP,G2A  I44  R4D11
   1 CLK_100M_CPU1_BCLK2_R_DN      A @BASEBOARD_FAB2_LIB.BASEBOARD_FAB2(SCH_1):CLK_100M_CPU1_BCLK2_R_DN
   2 CLK_100M_CPU1_BCLK2_DN      B @BASEBOARD_FAB2_LIB.BASEBOARD_FAB2(SCH_1):CLK_100M_CPU1_BCLK2_DN

RES_0402-27.4,1%,1/16W,CHIP,G2A  I49  R4D2
   1 CLK_100M_CPU1_BCLK1_R_DP      A @BASEBOARD_FAB2_LIB.BASEBOARD_FAB2(SCH_1):CLK_100M_CPU1_BCLK1_R_DP
   2 CLK_100M_CPU1_BCLK1_DP      B @BASEBOARD_FAB2_LIB.BASEBOARD_FAB2(SCH_1):CLK_100M_CPU1_BCLK1_DP

RES_0402-27.4,1%,1/16W,CHIP,G2A  I54  R4D1
   1 CLK_100M_CPU1_BCLK1_R_DN      A @BASEBOARD_FAB2_LIB.BASEBOARD_FAB2(SCH_1):CLK_100M_CPU1_BCLK1_R_DN
   2 CLK_100M_CPU1_BCLK1_DN      B @BASEBOARD_FAB2_LIB.BASEBOARD_FAB2(SCH_1):CLK_100M_CPU1_BCLK1_DN

RES_0402-27.4,1%,1/16W,CHIP,G2A  I59  R4D4
   1 CLK_100M_CPU1_BCLK0_R_DP      A @BASEBOARD_FAB2_LIB.BASEBOARD_FAB2(SCH_1):CLK_100M_CPU1_BCLK0_R_DP
   2 CLK_100M_CPU1_BCLK0_DP      B @BASEBOARD_FAB2_LIB.BASEBOARD_FAB2(SCH_1):CLK_100M_CPU1_BCLK0_DP

RES_0402-27.4,1%,1/16W,CHIP,G2A  I64  R4D3
   1 CLK_100M_CPU1_BCLK0_R_DN      A @BASEBOARD_FAB2_LIB.BASEBOARD_FAB2(SCH_1):CLK_100M_CPU1_BCLK0_R_DN
   2 CLK_100M_CPU1_BCLK0_DN      B @BASEBOARD_FAB2_LIB.BASEBOARD_FAB2(SCH_1):CLK_100M_CPU1_BCLK0_DN

RES_0402-27.4,1%,1/16W,CHIP,G2A  I69  R4D29
   1 CLK_100M_CPU0_BCLK0_R_DP      A @BASEBOARD_FAB2_LIB.BASEBOARD_FAB2(SCH_1):CLK_100M_CPU0_BCLK0_R_DP
   2 CLK_100M_CPU0_BCLK0_DP      B @BASEBOARD_FAB2_LIB.BASEBOARD_FAB2(SCH_1):CLK_100M_CPU0_BCLK0_DP

RES_0402-27.4,1%,1/16W,CHIP,G2A  I74  R4D6
   1 CLK_100M_CPU0_RC_REFCLK1_R_DP      A @BASEBOARD_FAB2_LIB.BASEBOARD_FAB2(SCH_1):CLK_100M_CPU0_RC_REFCLK1_R_DP
   2 CLK_100M_CPU0_RC_REFCLK1_DP      B @BASEBOARD_FAB2_LIB.BASEBOARD_FAB2(SCH_1):CLK_100M_CPU0_RC_REFCLK1_DP

RES_0402-27.4,1%,1/16W,CHIP,G2A  I79  R4D5
   1 CLK_100M_CPU0_RC_REFCLK1_R_DN      A @BASEBOARD_FAB2_LIB.BASEBOARD_FAB2(SCH_1):CLK_100M_CPU0_RC_REFCLK1_R_DN
   2 CLK_100M_CPU0_RC_REFCLK1_DN      B @BASEBOARD_FAB2_LIB.BASEBOARD_FAB2(SCH_1):CLK_100M_CPU0_RC_REFCLK1_DN

RES_0402-27.4,1%,1/16W,CHIP,G2A  I84  R4D8
   1 CLK_100M_CPU0_RC_REFCLK0_R_DP      A @BASEBOARD_FAB2_LIB.BASEBOARD_FAB2(SCH_1):CLK_100M_CPU0_RC_REFCLK0_R_DP
   2 CLK_100M_CPU0_RC_REFCLK0_DP      B @BASEBOARD_FAB2_LIB.BASEBOARD_FAB2(SCH_1):CLK_100M_CPU0_RC_REFCLK0_DP

RES_0402-27.4,1%,1/16W,CHIP,G2A  I89  R4D7
   1 CLK_100M_CPU0_RC_REFCLK0_R_DN      A @BASEBOARD_FAB2_LIB.BASEBOARD_FAB2(SCH_1):CLK_100M_CPU0_RC_REFCLK0_R_DN
   2 CLK_100M_CPU0_RC_REFCLK0_DN      B @BASEBOARD_FAB2_LIB.BASEBOARD_FAB2(SCH_1):CLK_100M_CPU0_RC_REFCLK0_DN

RES_0402-27.4,1%,1/16W,CHIP,G2A  I94  R4D12
   1 CLK_100M_CPU0_PE_REFCLK_R_DP      A @BASEBOARD_FAB2_LIB.BASEBOARD_FAB2(SCH_1):CLK_100M_CPU0_PE_REFCLK_R_DP
   2 CLK_100M_CPU0_PE_REFCLK_DP      B @BASEBOARD_FAB2_LIB.BASEBOARD_FAB2(SCH_1):CLK_100M_CPU0_PE_REFCLK_DP

RES_0402-27.4,1%,1/16W,CHIP,G2A  I99  R4D10
   1 CLK_100M_CPU0_PE_REFCLK_R_DN      A @BASEBOARD_FAB2_LIB.BASEBOARD_FAB2(SCH_1):CLK_100M_CPU0_PE_REFCLK_R_DN
   2 CLK_100M_CPU0_PE_REFCLK_DN      B @BASEBOARD_FAB2_LIB.BASEBOARD_FAB2(SCH_1):CLK_100M_CPU0_PE_REFCLK_DN

RES_0402-27.4,1%,1/16W,CHIP,G2A  I104  R4D17
   1 CLK_100M_CPU0_BCLK2_R_DP      A @BASEBOARD_FAB2_LIB.BASEBOARD_FAB2(SCH_1):CLK_100M_CPU0_BCLK2_R_DP
   2 CLK_100M_CPU0_BCLK2_DP      B @BASEBOARD_FAB2_LIB.BASEBOARD_FAB2(SCH_1):CLK_100M_CPU0_BCLK2_DP

RES_0402-27.4,1%,1/16W,CHIP,G2A  I109  R4D14
   1 CLK_100M_CPU0_BCLK2_R_DN      A @BASEBOARD_FAB2_LIB.BASEBOARD_FAB2(SCH_1):CLK_100M_CPU0_BCLK2_R_DN
   2 CLK_100M_CPU0_BCLK2_DN      B @BASEBOARD_FAB2_LIB.BASEBOARD_FAB2(SCH_1):CLK_100M_CPU0_BCLK2_DN

RES_0402-27.4,1%,1/16W,CHIP,G2A  I114  R4D22
   1 CLK_100M_CPU0_BCLK1_R_DP      A @BASEBOARD_FAB2_LIB.BASEBOARD_FAB2(SCH_1):CLK_100M_CPU0_BCLK1_R_DP
   2 CLK_100M_CPU0_BCLK1_DP      B @BASEBOARD_FAB2_LIB.BASEBOARD_FAB2(SCH_1):CLK_100M_CPU0_BCLK1_DP

RES_0402-27.4,1%,1/16W,CHIP,G2A  I119  R4D20
   1 CLK_100M_CPU0_BCLK1_R_DN      A @BASEBOARD_FAB2_LIB.BASEBOARD_FAB2(SCH_1):CLK_100M_CPU0_BCLK1_R_DN
   2 CLK_100M_CPU0_BCLK1_DN      B @BASEBOARD_FAB2_LIB.BASEBOARD_FAB2(SCH_1):CLK_100M_CPU0_BCLK1_DN

RES_0402-42.2,1.0%,1/16W,EMPTYA  I121  R7P9
   1 CLK_100M_CPU1_RC_REFCLK1_DP      A @BASEBOARD_FAB2_LIB.BASEBOARD_FAB2(SCH_1):CLK_100M_CPU1_RC_REFCLK1_DP
   2    GND      B @BASEBOARD_FAB2_LIB.BASEBOARD_FAB2(SCH_1):GND

RES_0402-42.2,1.0%,1/16W,EMPTYA  I123  R7P12
   1 CLK_100M_CPU1_RC_REFCLK1_DN      A @BASEBOARD_FAB2_LIB.BASEBOARD_FAB2(SCH_1):CLK_100M_CPU1_RC_REFCLK1_DN
   2    GND      B @BASEBOARD_FAB2_LIB.BASEBOARD_FAB2(SCH_1):GND

RES_0402-42.2,1.0%,1/16W,EMPTYA  I125  R7P6
   1 CLK_100M_CPU1_RC_REFCLK0_DP      A @BASEBOARD_FAB2_LIB.BASEBOARD_FAB2(SCH_1):CLK_100M_CPU1_RC_REFCLK0_DP
   2    GND      B @BASEBOARD_FAB2_LIB.BASEBOARD_FAB2(SCH_1):GND

RES_0402-42.2,1.0%,1/16W,EMPTYA  I127  R7P7
   1 CLK_100M_CPU1_RC_REFCLK0_DN      A @BASEBOARD_FAB2_LIB.BASEBOARD_FAB2(SCH_1):CLK_100M_CPU1_RC_REFCLK0_DN
   2    GND      B @BASEBOARD_FAB2_LIB.BASEBOARD_FAB2(SCH_1):GND

RES_0402-42.2,1.0%,1/16W,EMPTYA  I129  R7P3
   1 CLK_100M_CPU1_PE_REFCLK_DP      A @BASEBOARD_FAB2_LIB.BASEBOARD_FAB2(SCH_1):CLK_100M_CPU1_PE_REFCLK_DP
   2    GND      B @BASEBOARD_FAB2_LIB.BASEBOARD_FAB2(SCH_1):GND

RES_0402-42.2,1.0%,1/16W,EMPTYA  I131  R7P4
   1 CLK_100M_CPU1_PE_REFCLK_DN      A @BASEBOARD_FAB2_LIB.BASEBOARD_FAB2(SCH_1):CLK_100M_CPU1_PE_REFCLK_DN
   2    GND      B @BASEBOARD_FAB2_LIB.BASEBOARD_FAB2(SCH_1):GND

RES_0402-42.2,1.0%,1/16W,EMPTYA  I133  R7P1
   1 CLK_100M_CPU1_BCLK2_DP      A @BASEBOARD_FAB2_LIB.BASEBOARD_FAB2(SCH_1):CLK_100M_CPU1_BCLK2_DP
   2    GND      B @BASEBOARD_FAB2_LIB.BASEBOARD_FAB2(SCH_1):GND

RES_0402-42.2,1.0%,1/16W,EMPTYA  I135  R7P2
   1 CLK_100M_CPU1_BCLK2_DN      A @BASEBOARD_FAB2_LIB.BASEBOARD_FAB2(SCH_1):CLK_100M_CPU1_BCLK2_DN
   2    GND      B @BASEBOARD_FAB2_LIB.BASEBOARD_FAB2(SCH_1):GND

RES_0402-42.2,1.0%,1/16W,EMPTYA  I137  R6P7
   1 CLK_100M_CPU1_BCLK1_DP      A @BASEBOARD_FAB2_LIB.BASEBOARD_FAB2(SCH_1):CLK_100M_CPU1_BCLK1_DP
   2    GND      B @BASEBOARD_FAB2_LIB.BASEBOARD_FAB2(SCH_1):GND

RES_0402-42.2,1.0%,1/16W,EMPTYA  I139  R6P8
   1 CLK_100M_CPU1_BCLK1_DN      A @BASEBOARD_FAB2_LIB.BASEBOARD_FAB2(SCH_1):CLK_100M_CPU1_BCLK1_DN
   2    GND      B @BASEBOARD_FAB2_LIB.BASEBOARD_FAB2(SCH_1):GND

RES_0402-42.2,1.0%,1/16W,EMPTYA  I141  R6P5
   1 CLK_100M_CPU1_BCLK0_DP      A @BASEBOARD_FAB2_LIB.BASEBOARD_FAB2(SCH_1):CLK_100M_CPU1_BCLK0_DP
   2    GND      B @BASEBOARD_FAB2_LIB.BASEBOARD_FAB2(SCH_1):GND

RES_0402-42.2,1.0%,1/16W,EMPTYA  I143  R6P6
   1 CLK_100M_CPU1_BCLK0_DN      A @BASEBOARD_FAB2_LIB.BASEBOARD_FAB2(SCH_1):CLK_100M_CPU1_BCLK0_DN
   2    GND      B @BASEBOARD_FAB2_LIB.BASEBOARD_FAB2(SCH_1):GND

RES_0402-42.2,1.0%,1/16W,EMPTYA  I145  R6P3
   1 CLK_100M_CPU0_RC_REFCLK1_DP      A @BASEBOARD_FAB2_LIB.BASEBOARD_FAB2(SCH_1):CLK_100M_CPU0_RC_REFCLK1_DP
   2    GND      B @BASEBOARD_FAB2_LIB.BASEBOARD_FAB2(SCH_1):GND

RES_0402-42.2,1.0%,1/16W,EMPTYA  I147  R6P4
   1 CLK_100M_CPU0_RC_REFCLK1_DN      A @BASEBOARD_FAB2_LIB.BASEBOARD_FAB2(SCH_1):CLK_100M_CPU0_RC_REFCLK1_DN
   2    GND      B @BASEBOARD_FAB2_LIB.BASEBOARD_FAB2(SCH_1):GND

RES_0402-42.2,1.0%,1/16W,EMPTYA  I149  R6P1
   1 CLK_100M_CPU0_RC_REFCLK0_DP      A @BASEBOARD_FAB2_LIB.BASEBOARD_FAB2(SCH_1):CLK_100M_CPU0_RC_REFCLK0_DP
   2    GND      B @BASEBOARD_FAB2_LIB.BASEBOARD_FAB2(SCH_1):GND

RES_0402-42.2,1.0%,1/16W,EMPTYA  I151  R6P2
   1 CLK_100M_CPU0_RC_REFCLK0_DN      A @BASEBOARD_FAB2_LIB.BASEBOARD_FAB2(SCH_1):CLK_100M_CPU0_RC_REFCLK0_DN
   2    GND      B @BASEBOARD_FAB2_LIB.BASEBOARD_FAB2(SCH_1):GND

RES_0402-42.2,1.0%,1/16W,EMPTYA  I153  R6P11
   1 CLK_100M_CPU0_PE_REFCLK_DP      A @BASEBOARD_FAB2_LIB.BASEBOARD_FAB2(SCH_1):CLK_100M_CPU0_PE_REFCLK_DP
   2    GND      B @BASEBOARD_FAB2_LIB.BASEBOARD_FAB2(SCH_1):GND

RES_0402-42.2,1.0%,1/16W,EMPTYA  I155  R6P9
   1 CLK_100M_CPU0_PE_REFCLK_DN      A @BASEBOARD_FAB2_LIB.BASEBOARD_FAB2(SCH_1):CLK_100M_CPU0_PE_REFCLK_DN
   2    GND      B @BASEBOARD_FAB2_LIB.BASEBOARD_FAB2(SCH_1):GND

RES_0402-42.2,1.0%,1/16W,EMPTYA  I157  R6P13
   1 CLK_100M_CPU0_BCLK2_DP      A @BASEBOARD_FAB2_LIB.BASEBOARD_FAB2(SCH_1):CLK_100M_CPU0_BCLK2_DP
   2    GND      B @BASEBOARD_FAB2_LIB.BASEBOARD_FAB2(SCH_1):GND

RES_0402-42.2,1.0%,1/16W,EMPTYA  I159  R6P12
   1 CLK_100M_CPU0_BCLK2_DN      A @BASEBOARD_FAB2_LIB.BASEBOARD_FAB2(SCH_1):CLK_100M_CPU0_BCLK2_DN
   2    GND      B @BASEBOARD_FAB2_LIB.BASEBOARD_FAB2(SCH_1):GND

RES_0402-42.2,1.0%,1/16W,EMPTYA  I161  R4D24
   1 CLK_100M_CPU0_BCLK1_DP      A @BASEBOARD_FAB2_LIB.BASEBOARD_FAB2(SCH_1):CLK_100M_CPU0_BCLK1_DP
   2    GND      B @BASEBOARD_FAB2_LIB.BASEBOARD_FAB2(SCH_1):GND

RES_0402-42.2,1.0%,1/16W,EMPTYA  I163  R4D18
   1 CLK_100M_CPU0_BCLK1_DN      A @BASEBOARD_FAB2_LIB.BASEBOARD_FAB2(SCH_1):CLK_100M_CPU0_BCLK1_DN
   2    GND      B @BASEBOARD_FAB2_LIB.BASEBOARD_FAB2(SCH_1):GND

RES_0402-42.2,1.0%,1/16W,EMPTYA  I165  R6P17
   1 CLK_100M_CPU0_BCLK0_DP      A @BASEBOARD_FAB2_LIB.BASEBOARD_FAB2(SCH_1):CLK_100M_CPU0_BCLK0_DP
   2    GND      B @BASEBOARD_FAB2_LIB.BASEBOARD_FAB2(SCH_1):GND

RES_0402-42.2,1.0%,1/16W,EMPTYA  I167  R6P15
   1 CLK_100M_CPU0_BCLK0_DN      A @BASEBOARD_FAB2_LIB.BASEBOARD_FAB2(SCH_1):CLK_100M_CPU0_BCLK0_DN
   2    GND      B @BASEBOARD_FAB2_LIB.BASEBOARD_FAB2(SCH_1):GND


DRAWING: @BASEBOARD_FAB2_LIB.BASEBOARD_FAB2(SCH_1):PAGE104 

CAP_A_0402V-0.1UF,16V,10%,X7R,A  I25  C6F1
   1   P3V3      A @BASEBOARD_FAB2_LIB.BASEBOARD_FAB2(SCH_1):P3V3
   2    GND      B @BASEBOARD_FAB2_LIB.BASEBOARD_FAB2(SCH_1):GND

CAP_A_0402V-0.1UF,16V,10%,X7R,A  I34  C3F2
   1   P3V3      A @BASEBOARD_FAB2_LIB.BASEBOARD_FAB2(SCH_1):P3V3
   2    GND      B @BASEBOARD_FAB2_LIB.BASEBOARD_FAB2(SCH_1):GND

RES_0402-0.0,5%,1/16W,EMPTY,G2A  I37  R6F8
   1 CLK_322M_156M_CPU0_OSC_VRM_DP      A @BASEBOARD_FAB2_LIB.BASEBOARD_FAB2(SCH_1):CLK_322M_156M_CPU0_OSC_VRM_DP
   2 CLK_156M_OSC_CPU0_HFI_DP      B @BASEBOARD_FAB2_LIB.BASEBOARD_FAB2(SCH_1):CLK_156M_OSC_CPU0_HFI_DP

RES_0402-0.0,5%,1/16W,EMPTY,G2A  I41  R6F6
   1 CLK_322M_156M_CPU0_OSC_VRM_DN      A @BASEBOARD_FAB2_LIB.BASEBOARD_FAB2(SCH_1):CLK_322M_156M_CPU0_OSC_VRM_DN
   2 CLK_156M_OSC_CPU0_HFI_DN      B @BASEBOARD_FAB2_LIB.BASEBOARD_FAB2(SCH_1):CLK_156M_OSC_CPU0_HFI_DN

RES_0402-0.0,5%,1/16W,EMPTY,G2A  I51  R3F1
   1 CLK_322M_156M_CPU1_OSC_VRM_DN      A @BASEBOARD_FAB2_LIB.BASEBOARD_FAB2(SCH_1):CLK_322M_156M_CPU1_OSC_VRM_DN
   2 CLK_156M_OSC_CPU1_HFI_DN      B @BASEBOARD_FAB2_LIB.BASEBOARD_FAB2(SCH_1):CLK_156M_OSC_CPU1_HFI_DN

RES_0402-0.0,5%,1/16W,EMPTY,G2A  I53  R3F3
   1 CLK_322M_156M_CPU1_OSC_VRM_DP      A @BASEBOARD_FAB2_LIB.BASEBOARD_FAB2(SCH_1):CLK_322M_156M_CPU1_OSC_VRM_DP
   2 CLK_156M_OSC_CPU1_HFI_DP      B @BASEBOARD_FAB2_LIB.BASEBOARD_FAB2(SCH_1):CLK_156M_OSC_CPU1_HFI_DP

RES_0402-0.0,5%,1/16W,CHIP,G21A  I67  R6F7
   1 CLK_156M_OSC_BRD_CPU0_DN      A @BASEBOARD_FAB2_LIB.BASEBOARD_FAB2(SCH_1):CLK_156M_OSC_BRD_CPU0_DN
   2 CLK_156M_OSC_CPU0_HFI_DN      B @BASEBOARD_FAB2_LIB.BASEBOARD_FAB2(SCH_1):CLK_156M_OSC_CPU0_HFI_DN

RES_0402-0.0,5%,1/16W,CHIP,G21A  I68  R6F9
   1 CLK_156M_OSC_BRD_CPU0_DP      A @BASEBOARD_FAB2_LIB.BASEBOARD_FAB2(SCH_1):CLK_156M_OSC_BRD_CPU0_DP
   2 CLK_156M_OSC_CPU0_HFI_DP      B @BASEBOARD_FAB2_LIB.BASEBOARD_FAB2(SCH_1):CLK_156M_OSC_CPU0_HFI_DP

RES_0402-0.0,5%,1/16W,CHIP,G21A  I69  R3F2
   1 CLK_156M_OSC_BRD_CPU1_DN      A @BASEBOARD_FAB2_LIB.BASEBOARD_FAB2(SCH_1):CLK_156M_OSC_BRD_CPU1_DN
   2 CLK_156M_OSC_CPU1_HFI_DN      B @BASEBOARD_FAB2_LIB.BASEBOARD_FAB2(SCH_1):CLK_156M_OSC_CPU1_HFI_DN

RES_0402-0.0,5%,1/16W,CHIP,G21A  I70  R3F4
   1 CLK_156M_OSC_BRD_CPU1_DP      A @BASEBOARD_FAB2_LIB.BASEBOARD_FAB2(SCH_1):CLK_156M_OSC_BRD_CPU1_DP
   2 CLK_156M_OSC_CPU1_HFI_DP      B @BASEBOARD_FAB2_LIB.BASEBOARD_FAB2(SCH_1):CLK_156M_OSC_CPU1_HFI_DP

OSC_C_6P10-156.25MHZ,OSC,G6383A  I71  Y6F1
   1 FM_CPU0_STL_BRD_OSC_EN ENABLE_DISABLE @BASEBOARD_FAB2_LIB.BASEBOARD_FAB2(SCH_1):FM_CPU0_STL_BRD_OSC_EN
   2 NC_CLK_156M_CPU0_OSC NC_GND @BASEBOARD_FAB2_LIB.BASEBOARD_FAB2(SCH_1):NC_CLK_156M_CPU0_OSC
   3    GND    GND @BASEBOARD_FAB2_LIB.BASEBOARD_FAB2(SCH_1):GND
   4 CLK_156M_OSC_BRD_CPU0_DP    OUT @BASEBOARD_FAB2_LIB.BASEBOARD_FAB2(SCH_1):CLK_156M_OSC_BRD_CPU0_DP
   5 CLK_156M_OSC_BRD_CPU0_DN  OUT_N @BASEBOARD_FAB2_LIB.BASEBOARD_FAB2(SCH_1):CLK_156M_OSC_BRD_CPU0_DN
   6   P3V3    VCC @BASEBOARD_FAB2_LIB.BASEBOARD_FAB2(SCH_1):P3V3

OSC_C_6P10-156.25MHZ,OSC,G6383A  I72  Y3F1
   1 FM_CPU1_STL_BRD_OSC_EN ENABLE_DISABLE @BASEBOARD_FAB2_LIB.BASEBOARD_FAB2(SCH_1):FM_CPU1_STL_BRD_OSC_EN
   2 NC_CLK_156M_CPU1_OSC NC_GND @BASEBOARD_FAB2_LIB.BASEBOARD_FAB2(SCH_1):NC_CLK_156M_CPU1_OSC
   3    GND    GND @BASEBOARD_FAB2_LIB.BASEBOARD_FAB2(SCH_1):GND
   4 CLK_156M_OSC_BRD_CPU1_DP    OUT @BASEBOARD_FAB2_LIB.BASEBOARD_FAB2(SCH_1):CLK_156M_OSC_BRD_CPU1_DP
   5 CLK_156M_OSC_BRD_CPU1_DN  OUT_N @BASEBOARD_FAB2_LIB.BASEBOARD_FAB2(SCH_1):CLK_156M_OSC_BRD_CPU1_DN
   6   P3V3    VCC @BASEBOARD_FAB2_LIB.BASEBOARD_FAB2(SCH_1):P3V3

RES_0402-0.0,5%,1/16W,EMPTY,G2A  I78  R6F10
   1 CLK_322M_156M_CPU0_OSC_VRM_DN      A @BASEBOARD_FAB2_LIB.BASEBOARD_FAB2(SCH_1):CLK_322M_156M_CPU0_OSC_VRM_DN
   2 CLK_322M_OSC_CPU0_RC_DN      B @BASEBOARD_FAB2_LIB.BASEBOARD_FAB2(SCH_1):CLK_322M_OSC_CPU0_RC_DN

RES_0402-0.0,5%,1/16W,EMPTY,G2A  I79  R6F11
   1 CLK_322M_156M_CPU0_OSC_VRM_DP      A @BASEBOARD_FAB2_LIB.BASEBOARD_FAB2(SCH_1):CLK_322M_156M_CPU0_OSC_VRM_DP
   2 CLK_322M_OSC_CPU0_RC_DP      B @BASEBOARD_FAB2_LIB.BASEBOARD_FAB2(SCH_1):CLK_322M_OSC_CPU0_RC_DP

RES_0402-0.0,5%,1/16W,EMPTY,G2A  I84  R3F5
   1 CLK_322M_156M_CPU1_OSC_VRM_DN      A @BASEBOARD_FAB2_LIB.BASEBOARD_FAB2(SCH_1):CLK_322M_156M_CPU1_OSC_VRM_DN
   2 CLK_322M_OSC_CPU1_RC_DN      B @BASEBOARD_FAB2_LIB.BASEBOARD_FAB2(SCH_1):CLK_322M_OSC_CPU1_RC_DN

RES_0402-0.0,5%,1/16W,EMPTY,G2A  I88  R3F6
   1 CLK_322M_156M_CPU1_OSC_VRM_DP      A @BASEBOARD_FAB2_LIB.BASEBOARD_FAB2(SCH_1):CLK_322M_156M_CPU1_OSC_VRM_DP
   2 CLK_322M_OSC_CPU1_RC_DP      B @BASEBOARD_FAB2_LIB.BASEBOARD_FAB2(SCH_1):CLK_322M_OSC_CPU1_RC_DP

RES_0402-0.0,5%,1/16W,CHIP,G21A  I93  R8D43
   1 FM_156M_CPU0_BRD_OSC_EN      A @BASEBOARD_FAB2_LIB.BASEBOARD_FAB2(SCH_1):FM_156M_CPU0_BRD_OSC_EN
   2 FM_CPU0_STL_BRD_OSC_EN      B @BASEBOARD_FAB2_LIB.BASEBOARD_FAB2(SCH_1):FM_CPU0_STL_BRD_OSC_EN

RES_0402-0.0,5%,1/16W,EMPTY,G2A  I94  R7D40
   1 FM_CPU0_VRM_OSC_EN      A @BASEBOARD_FAB2_LIB.BASEBOARD_FAB2(SCH_1):FM_CPU0_VRM_OSC_EN
   2 FM_CPU0_STL_BRD_OSC_EN      B @BASEBOARD_FAB2_LIB.BASEBOARD_FAB2(SCH_1):FM_CPU0_STL_BRD_OSC_EN

RES_0402-0.0,5%,1/16W,EMPTY,G2A  I95  R7D39
   1 FM_CPU0_VRM_OSC_EN      A @BASEBOARD_FAB2_LIB.BASEBOARD_FAB2(SCH_1):FM_CPU0_VRM_OSC_EN
   2 FM_CPU0_VRM_322M_156M_OSC_EN      B @BASEBOARD_FAB2_LIB.BASEBOARD_FAB2(SCH_1):FM_CPU0_VRM_322M_156M_OSC_EN

RES_0402-0.0,5%,1/16W,CHIP,G21A  I96  R7D36
   1 FM_156M_CPU1_BRD_OSC_EN      A @BASEBOARD_FAB2_LIB.BASEBOARD_FAB2(SCH_1):FM_156M_CPU1_BRD_OSC_EN
   2 FM_CPU1_STL_BRD_OSC_EN      B @BASEBOARD_FAB2_LIB.BASEBOARD_FAB2(SCH_1):FM_CPU1_STL_BRD_OSC_EN

RES_0402-0.0,5%,1/16W,EMPTY,G2A  I97  R7D38
   1 FM_CPU1_VRM_OSC_EN      A @BASEBOARD_FAB2_LIB.BASEBOARD_FAB2(SCH_1):FM_CPU1_VRM_OSC_EN
   2 FM_CPU1_STL_BRD_OSC_EN      B @BASEBOARD_FAB2_LIB.BASEBOARD_FAB2(SCH_1):FM_CPU1_STL_BRD_OSC_EN

RES_0402-0.0,5%,1/16W,EMPTY,G2A  I98  R7D37
   1 FM_CPU1_VRM_OSC_EN      A @BASEBOARD_FAB2_LIB.BASEBOARD_FAB2(SCH_1):FM_CPU1_VRM_OSC_EN
   2 FM_CPU1_VRM_322M_156M_OSC_EN      B @BASEBOARD_FAB2_LIB.BASEBOARD_FAB2(SCH_1):FM_CPU1_VRM_322M_156M_OSC_EN


DRAWING: @BASEBOARD_FAB2_LIB.BASEBOARD_FAB2(SCH_1):PAGE105 

CAP_0402-0.22UF,16V,10%,X7R,A3A  I1  C7G24
   1 P3E_CPU0_PE2_SS_TXN<6>      A @BASEBOARD_FAB2_LIB.BASEBOARD_FAB2(SCH_1):P3E_CPU0_PE2_SS_TXN(6)
   2 P3E_CPU0_PE2_SS_C_TXN<6>      B @BASEBOARD_FAB2_LIB.BASEBOARD_FAB2(SCH_1):P3E_CPU0_PE2_SS_C_TXN(6)

CAP_0402-0.22UF,16V,10%,X7R,A3A  I6  C7G6
   1 P3E_CPU0_PE2_SS_TXN<15>      A @BASEBOARD_FAB2_LIB.BASEBOARD_FAB2(SCH_1):P3E_CPU0_PE2_SS_TXN(15)
   2 P3E_CPU0_PE2_SS_C_TXN<15>      B @BASEBOARD_FAB2_LIB.BASEBOARD_FAB2(SCH_1):P3E_CPU0_PE2_SS_C_TXN(15)

CAP_0402-0.22UF,16V,10%,X7R,A3A  I7  C7G7
   1 P3E_CPU0_PE2_SS_TXN<14>      A @BASEBOARD_FAB2_LIB.BASEBOARD_FAB2(SCH_1):P3E_CPU0_PE2_SS_TXN(14)
   2 P3E_CPU0_PE2_SS_C_TXN<14>      B @BASEBOARD_FAB2_LIB.BASEBOARD_FAB2(SCH_1):P3E_CPU0_PE2_SS_C_TXN(14)

CAP_0402-0.22UF,16V,10%,X7R,A3A  I8  C7G10
   1 P3E_CPU0_PE2_SS_TXN<13>      A @BASEBOARD_FAB2_LIB.BASEBOARD_FAB2(SCH_1):P3E_CPU0_PE2_SS_TXN(13)
   2 P3E_CPU0_PE2_SS_C_TXN<13>      B @BASEBOARD_FAB2_LIB.BASEBOARD_FAB2(SCH_1):P3E_CPU0_PE2_SS_C_TXN(13)

CAP_0402-0.22UF,16V,10%,X7R,A3A  I12  C7G12
   1 P3E_CPU0_PE2_SS_TXN<12>      A @BASEBOARD_FAB2_LIB.BASEBOARD_FAB2(SCH_1):P3E_CPU0_PE2_SS_TXN(12)
   2 P3E_CPU0_PE2_SS_C_TXN<12>      B @BASEBOARD_FAB2_LIB.BASEBOARD_FAB2(SCH_1):P3E_CPU0_PE2_SS_C_TXN(12)

CAP_0402-0.22UF,16V,10%,X7R,A3A  I13  C7G13
   1 P3E_CPU0_PE2_SS_TXN<11>      A @BASEBOARD_FAB2_LIB.BASEBOARD_FAB2(SCH_1):P3E_CPU0_PE2_SS_TXN(11)
   2 P3E_CPU0_PE2_SS_C_TXN<11>      B @BASEBOARD_FAB2_LIB.BASEBOARD_FAB2(SCH_1):P3E_CPU0_PE2_SS_C_TXN(11)

CAP_0402-0.22UF,16V,10%,X7R,A3A  I20  C7G5
   1 P3E_CPU0_PE2_SS_TXP<15>      A @BASEBOARD_FAB2_LIB.BASEBOARD_FAB2(SCH_1):P3E_CPU0_PE2_SS_TXP(15)
   2 P3E_CPU0_PE2_SS_C_TXP<15>      B @BASEBOARD_FAB2_LIB.BASEBOARD_FAB2(SCH_1):P3E_CPU0_PE2_SS_C_TXP(15)

CAP_0402-0.22UF,16V,10%,X7R,A3A  I21  C7G9
   1 P3E_CPU0_PE2_SS_TXP<13>      A @BASEBOARD_FAB2_LIB.BASEBOARD_FAB2(SCH_1):P3E_CPU0_PE2_SS_TXP(13)
   2 P3E_CPU0_PE2_SS_C_TXP<13>      B @BASEBOARD_FAB2_LIB.BASEBOARD_FAB2(SCH_1):P3E_CPU0_PE2_SS_C_TXP(13)

CAP_0402-0.22UF,16V,10%,X7R,A3A  I22  C7G8
   1 P3E_CPU0_PE2_SS_TXP<14>      A @BASEBOARD_FAB2_LIB.BASEBOARD_FAB2(SCH_1):P3E_CPU0_PE2_SS_TXP(14)
   2 P3E_CPU0_PE2_SS_C_TXP<14>      B @BASEBOARD_FAB2_LIB.BASEBOARD_FAB2(SCH_1):P3E_CPU0_PE2_SS_C_TXP(14)

CAP_0402-0.22UF,16V,10%,X7R,A3A  I27  C7G11
   1 P3E_CPU0_PE2_SS_TXP<12>      A @BASEBOARD_FAB2_LIB.BASEBOARD_FAB2(SCH_1):P3E_CPU0_PE2_SS_TXP(12)
   2 P3E_CPU0_PE2_SS_C_TXP<12>      B @BASEBOARD_FAB2_LIB.BASEBOARD_FAB2(SCH_1):P3E_CPU0_PE2_SS_C_TXP(12)

CAP_0402-0.22UF,16V,10%,X7R,A3A  I28  C7G14
   1 P3E_CPU0_PE2_SS_TXP<11>      A @BASEBOARD_FAB2_LIB.BASEBOARD_FAB2(SCH_1):P3E_CPU0_PE2_SS_TXP(11)
   2 P3E_CPU0_PE2_SS_C_TXP<11>      B @BASEBOARD_FAB2_LIB.BASEBOARD_FAB2(SCH_1):P3E_CPU0_PE2_SS_C_TXP(11)

CAP_0402-0.22UF,16V,10%,X7R,A3A  I31  C7G16
   1 P3E_CPU0_PE2_SS_TXN<10>      A @BASEBOARD_FAB2_LIB.BASEBOARD_FAB2(SCH_1):P3E_CPU0_PE2_SS_TXN(10)
   2 P3E_CPU0_PE2_SS_C_TXN<10>      B @BASEBOARD_FAB2_LIB.BASEBOARD_FAB2(SCH_1):P3E_CPU0_PE2_SS_C_TXN(10)

CAP_0402-0.22UF,16V,10%,X7R,A3A  I32  C7G18
   1 P3E_CPU0_PE2_SS_TXN<9>      A @BASEBOARD_FAB2_LIB.BASEBOARD_FAB2(SCH_1):P3E_CPU0_PE2_SS_TXN(9)
   2 P3E_CPU0_PE2_SS_C_TXN<9>      B @BASEBOARD_FAB2_LIB.BASEBOARD_FAB2(SCH_1):P3E_CPU0_PE2_SS_C_TXN(9)

CAP_0402-0.22UF,16V,10%,X7R,A3A  I34  C7G20
   1 P3E_CPU0_PE2_SS_TXN<8>      A @BASEBOARD_FAB2_LIB.BASEBOARD_FAB2(SCH_1):P3E_CPU0_PE2_SS_TXN(8)
   2 P3E_CPU0_PE2_SS_C_TXN<8>      B @BASEBOARD_FAB2_LIB.BASEBOARD_FAB2(SCH_1):P3E_CPU0_PE2_SS_C_TXN(8)

CAP_0402-0.22UF,16V,10%,X7R,A3A  I37  C7G22
   1 P3E_CPU0_PE2_SS_TXN<7>      A @BASEBOARD_FAB2_LIB.BASEBOARD_FAB2(SCH_1):P3E_CPU0_PE2_SS_TXN(7)
   2 P3E_CPU0_PE2_SS_C_TXN<7>      B @BASEBOARD_FAB2_LIB.BASEBOARD_FAB2(SCH_1):P3E_CPU0_PE2_SS_C_TXN(7)

CAP_0402-0.22UF,16V,10%,X7R,A3A  I44  C7G17
   1 P3E_CPU0_PE2_SS_TXP<9>      A @BASEBOARD_FAB2_LIB.BASEBOARD_FAB2(SCH_1):P3E_CPU0_PE2_SS_TXP(9)
   2 P3E_CPU0_PE2_SS_C_TXP<9>      B @BASEBOARD_FAB2_LIB.BASEBOARD_FAB2(SCH_1):P3E_CPU0_PE2_SS_C_TXP(9)

CAP_0402-0.22UF,16V,10%,X7R,A3A  I45  C7G15
   1 P3E_CPU0_PE2_SS_TXP<10>      A @BASEBOARD_FAB2_LIB.BASEBOARD_FAB2(SCH_1):P3E_CPU0_PE2_SS_TXP(10)
   2 P3E_CPU0_PE2_SS_C_TXP<10>      B @BASEBOARD_FAB2_LIB.BASEBOARD_FAB2(SCH_1):P3E_CPU0_PE2_SS_C_TXP(10)

CAP_0402-0.22UF,16V,10%,X7R,A3A  I46  C7G19
   1 P3E_CPU0_PE2_SS_TXP<8>      A @BASEBOARD_FAB2_LIB.BASEBOARD_FAB2(SCH_1):P3E_CPU0_PE2_SS_TXP(8)
   2 P3E_CPU0_PE2_SS_C_TXP<8>      B @BASEBOARD_FAB2_LIB.BASEBOARD_FAB2(SCH_1):P3E_CPU0_PE2_SS_C_TXP(8)

CAP_0402-0.22UF,16V,10%,X7R,A3A  I51  C7G21
   1 P3E_CPU0_PE2_SS_TXP<7>      A @BASEBOARD_FAB2_LIB.BASEBOARD_FAB2(SCH_1):P3E_CPU0_PE2_SS_TXP(7)
   2 P3E_CPU0_PE2_SS_C_TXP<7>      B @BASEBOARD_FAB2_LIB.BASEBOARD_FAB2(SCH_1):P3E_CPU0_PE2_SS_C_TXP(7)

CAP_0402-0.22UF,16V,10%,X7R,A3A  I52  C7G23
   1 P3E_CPU0_PE2_SS_TXP<6>      A @BASEBOARD_FAB2_LIB.BASEBOARD_FAB2(SCH_1):P3E_CPU0_PE2_SS_TXP(6)
   2 P3E_CPU0_PE2_SS_C_TXP<6>      B @BASEBOARD_FAB2_LIB.BASEBOARD_FAB2(SCH_1):P3E_CPU0_PE2_SS_C_TXP(6)

CAP_0402-0.22UF,16V,10%,X7R,A3A  I55  C7G26
   1 P3E_CPU0_PE2_SS_TXN<5>      A @BASEBOARD_FAB2_LIB.BASEBOARD_FAB2(SCH_1):P3E_CPU0_PE2_SS_TXN(5)
   2 P3E_CPU0_PE2_SS_C_TXN<5>      B @BASEBOARD_FAB2_LIB.BASEBOARD_FAB2(SCH_1):P3E_CPU0_PE2_SS_C_TXN(5)

CAP_0402-0.22UF,16V,10%,X7R,A3A  I56  C8G4
   1 P3E_CPU0_PE2_SS_TXN<3>      A @BASEBOARD_FAB2_LIB.BASEBOARD_FAB2(SCH_1):P3E_CPU0_PE2_SS_TXN(3)
   2 P3E_CPU0_PE2_SS_C_TXN<3>      B @BASEBOARD_FAB2_LIB.BASEBOARD_FAB2(SCH_1):P3E_CPU0_PE2_SS_C_TXN(3)

CAP_0402-0.22UF,16V,10%,X7R,A3A  I58  C8G2
   1 P3E_CPU0_PE2_SS_TXN<4>      A @BASEBOARD_FAB2_LIB.BASEBOARD_FAB2(SCH_1):P3E_CPU0_PE2_SS_TXN(4)
   2 P3E_CPU0_PE2_SS_C_TXN<4>      B @BASEBOARD_FAB2_LIB.BASEBOARD_FAB2(SCH_1):P3E_CPU0_PE2_SS_C_TXN(4)

CAP_0402-0.22UF,16V,10%,X7R,A3A  I61  C8G6
   1 P3E_CPU0_PE2_SS_TXN<2>      A @BASEBOARD_FAB2_LIB.BASEBOARD_FAB2(SCH_1):P3E_CPU0_PE2_SS_TXN(2)
   2 P3E_CPU0_PE2_SS_C_TXN<2>      B @BASEBOARD_FAB2_LIB.BASEBOARD_FAB2(SCH_1):P3E_CPU0_PE2_SS_C_TXN(2)

CAP_0402-0.22UF,16V,10%,X7R,A3A  I62  C8G7
   1 P3E_CPU0_PE2_SS_TXN<1>      A @BASEBOARD_FAB2_LIB.BASEBOARD_FAB2(SCH_1):P3E_CPU0_PE2_SS_TXN(1)
   2 P3E_CPU0_PE2_SS_C_TXN<1>      B @BASEBOARD_FAB2_LIB.BASEBOARD_FAB2(SCH_1):P3E_CPU0_PE2_SS_C_TXN(1)

CAP_0402-0.22UF,16V,10%,X7R,A3A  I69  C7G25
   1 P3E_CPU0_PE2_SS_TXP<5>      A @BASEBOARD_FAB2_LIB.BASEBOARD_FAB2(SCH_1):P3E_CPU0_PE2_SS_TXP(5)
   2 P3E_CPU0_PE2_SS_C_TXP<5>      B @BASEBOARD_FAB2_LIB.BASEBOARD_FAB2(SCH_1):P3E_CPU0_PE2_SS_C_TXP(5)

CAP_0402-0.22UF,16V,10%,X7R,A3A  I70  C8G1
   1 P3E_CPU0_PE2_SS_TXP<4>      A @BASEBOARD_FAB2_LIB.BASEBOARD_FAB2(SCH_1):P3E_CPU0_PE2_SS_TXP(4)
   2 P3E_CPU0_PE2_SS_C_TXP<4>      B @BASEBOARD_FAB2_LIB.BASEBOARD_FAB2(SCH_1):P3E_CPU0_PE2_SS_C_TXP(4)

CAP_0402-0.22UF,16V,10%,X7R,A3A  I71  C8G3
   1 P3E_CPU0_PE2_SS_TXP<3>      A @BASEBOARD_FAB2_LIB.BASEBOARD_FAB2(SCH_1):P3E_CPU0_PE2_SS_TXP(3)
   2 P3E_CPU0_PE2_SS_C_TXP<3>      B @BASEBOARD_FAB2_LIB.BASEBOARD_FAB2(SCH_1):P3E_CPU0_PE2_SS_C_TXP(3)

CAP_0402-0.22UF,16V,10%,X7R,A3A  I75  C8G5
   1 P3E_CPU0_PE2_SS_TXP<2>      A @BASEBOARD_FAB2_LIB.BASEBOARD_FAB2(SCH_1):P3E_CPU0_PE2_SS_TXP(2)
   2 P3E_CPU0_PE2_SS_C_TXP<2>      B @BASEBOARD_FAB2_LIB.BASEBOARD_FAB2(SCH_1):P3E_CPU0_PE2_SS_C_TXP(2)

CAP_0402-0.22UF,16V,10%,X7R,A3A  I76  C8G8
   1 P3E_CPU0_PE2_SS_TXP<1>      A @BASEBOARD_FAB2_LIB.BASEBOARD_FAB2(SCH_1):P3E_CPU0_PE2_SS_TXP(1)
   2 P3E_CPU0_PE2_SS_C_TXP<1>      B @BASEBOARD_FAB2_LIB.BASEBOARD_FAB2(SCH_1):P3E_CPU0_PE2_SS_C_TXP(1)

CAP_0402-0.22UF,16V,10%,X7R,A3A  I93  C8G9
   1 P3E_CPU0_PE2_SS_TXP<0>      A @BASEBOARD_FAB2_LIB.BASEBOARD_FAB2(SCH_1):P3E_CPU0_PE2_SS_TXP(0)
   2 P3E_CPU0_PE2_SS_C_TXP<0>      B @BASEBOARD_FAB2_LIB.BASEBOARD_FAB2(SCH_1):P3E_CPU0_PE2_SS_C_TXP(0)

CAP_0402-0.22UF,16V,10%,X7R,A3A  I96  C8G10
   1 P3E_CPU0_PE2_SS_TXN<0>      A @BASEBOARD_FAB2_LIB.BASEBOARD_FAB2(SCH_1):P3E_CPU0_PE2_SS_TXN(0)
   2 P3E_CPU0_PE2_SS_C_TXN<0>      B @BASEBOARD_FAB2_LIB.BASEBOARD_FAB2(SCH_1):P3E_CPU0_PE2_SS_C_TXN(0)

CAP_0402-0.22UF,16V,10%,X7R,A3A  I153  C6B18
   1 P3E_CPU0_PE1_PCH_TXP<9>      A @BASEBOARD_FAB2_LIB.BASEBOARD_FAB2(SCH_1):P3E_CPU0_PE1_PCH_TXP(9)
   2 P3E_CPU0_PE1_PCH_C_TXP<9>      B @BASEBOARD_FAB2_LIB.BASEBOARD_FAB2(SCH_1):P3E_CPU0_PE1_PCH_C_TXP(9)

CAP_0402-0.22UF,16V,10%,X7R,A3A  I160  C6B19
   1 P3E_CPU0_PE1_PCH_TXN<8>      A @BASEBOARD_FAB2_LIB.BASEBOARD_FAB2(SCH_1):P3E_CPU0_PE1_PCH_TXN(8)
   2 P3E_CPU0_PE1_PCH_C_TXN<8>      B @BASEBOARD_FAB2_LIB.BASEBOARD_FAB2(SCH_1):P3E_CPU0_PE1_PCH_C_TXN(8)

CAP_0402-0.22UF,16V,10%,X7R,A3A  I163  C6B15
   1 P3E_CPU0_PE1_PCH_TXN<10>      A @BASEBOARD_FAB2_LIB.BASEBOARD_FAB2(SCH_1):P3E_CPU0_PE1_PCH_TXN(10)
   2 P3E_CPU0_PE1_PCH_C_TXN<10>      B @BASEBOARD_FAB2_LIB.BASEBOARD_FAB2(SCH_1):P3E_CPU0_PE1_PCH_C_TXN(10)

CAP_0402-0.22UF,16V,10%,X7R,A3A  I166  C6B11
   1 P3E_CPU0_PE1_PCH_TXN<12>      A @BASEBOARD_FAB2_LIB.BASEBOARD_FAB2(SCH_1):P3E_CPU0_PE1_PCH_TXN(12)
   2 P3E_CPU0_PE1_PCH_C_TXN<12>      B @BASEBOARD_FAB2_LIB.BASEBOARD_FAB2(SCH_1):P3E_CPU0_PE1_PCH_C_TXN(12)

CAP_0402-0.22UF,16V,10%,X7R,A3A  I169  C6B6
   1 P3E_CPU0_PE1_PCH_TXN<14>      A @BASEBOARD_FAB2_LIB.BASEBOARD_FAB2(SCH_1):P3E_CPU0_PE1_PCH_TXN(14)
   2 P3E_CPU0_PE1_PCH_C_TXN<14>      B @BASEBOARD_FAB2_LIB.BASEBOARD_FAB2(SCH_1):P3E_CPU0_PE1_PCH_C_TXN(14)

CAP_0402-0.22UF,16V,10%,X7R,A3A  I173  C6B20
   1 P3E_CPU0_PE1_PCH_TXP<8>      A @BASEBOARD_FAB2_LIB.BASEBOARD_FAB2(SCH_1):P3E_CPU0_PE1_PCH_TXP(8)
   2 P3E_CPU0_PE1_PCH_C_TXP<8>      B @BASEBOARD_FAB2_LIB.BASEBOARD_FAB2(SCH_1):P3E_CPU0_PE1_PCH_C_TXP(8)

CAP_0402-0.22UF,16V,10%,X7R,A3A  I175  C6B17
   1 P3E_CPU0_PE1_PCH_TXN<9>      A @BASEBOARD_FAB2_LIB.BASEBOARD_FAB2(SCH_1):P3E_CPU0_PE1_PCH_TXN(9)
   2 P3E_CPU0_PE1_PCH_C_TXN<9>      B @BASEBOARD_FAB2_LIB.BASEBOARD_FAB2(SCH_1):P3E_CPU0_PE1_PCH_C_TXN(9)

CAP_0402-0.22UF,16V,10%,X7R,A3A  I180  C6B16
   1 P3E_CPU0_PE1_PCH_TXP<10>      A @BASEBOARD_FAB2_LIB.BASEBOARD_FAB2(SCH_1):P3E_CPU0_PE1_PCH_TXP(10)
   2 P3E_CPU0_PE1_PCH_C_TXP<10>      B @BASEBOARD_FAB2_LIB.BASEBOARD_FAB2(SCH_1):P3E_CPU0_PE1_PCH_C_TXP(10)

CAP_0402-0.22UF,16V,10%,X7R,A3A  I181  C6B14
   1 P3E_CPU0_PE1_PCH_TXN<11>      A @BASEBOARD_FAB2_LIB.BASEBOARD_FAB2(SCH_1):P3E_CPU0_PE1_PCH_TXN(11)
   2 P3E_CPU0_PE1_PCH_C_TXN<11>      B @BASEBOARD_FAB2_LIB.BASEBOARD_FAB2(SCH_1):P3E_CPU0_PE1_PCH_C_TXN(11)

CAP_0402-0.22UF,16V,10%,X7R,A3A  I185  C6B9
   1 P3E_CPU0_PE1_PCH_TXN<13>      A @BASEBOARD_FAB2_LIB.BASEBOARD_FAB2(SCH_1):P3E_CPU0_PE1_PCH_TXN(13)
   2 P3E_CPU0_PE1_PCH_C_TXN<13>      B @BASEBOARD_FAB2_LIB.BASEBOARD_FAB2(SCH_1):P3E_CPU0_PE1_PCH_C_TXN(13)

CAP_0402-0.22UF,16V,10%,X7R,A3A  I187  C6B12
   1 P3E_CPU0_PE1_PCH_TXP<12>      A @BASEBOARD_FAB2_LIB.BASEBOARD_FAB2(SCH_1):P3E_CPU0_PE1_PCH_TXP(12)
   2 P3E_CPU0_PE1_PCH_C_TXP<12>      B @BASEBOARD_FAB2_LIB.BASEBOARD_FAB2(SCH_1):P3E_CPU0_PE1_PCH_C_TXP(12)

CAP_0402-0.22UF,16V,10%,X7R,A3A  I189  C6B13
   1 P3E_CPU0_PE1_PCH_TXP<11>      A @BASEBOARD_FAB2_LIB.BASEBOARD_FAB2(SCH_1):P3E_CPU0_PE1_PCH_TXP(11)
   2 P3E_CPU0_PE1_PCH_C_TXP<11>      B @BASEBOARD_FAB2_LIB.BASEBOARD_FAB2(SCH_1):P3E_CPU0_PE1_PCH_C_TXP(11)

CAP_0402-0.22UF,16V,10%,X7R,A3A  I193  C6B10
   1 P3E_CPU0_PE1_PCH_TXP<13>      A @BASEBOARD_FAB2_LIB.BASEBOARD_FAB2(SCH_1):P3E_CPU0_PE1_PCH_TXP(13)
   2 P3E_CPU0_PE1_PCH_C_TXP<13>      B @BASEBOARD_FAB2_LIB.BASEBOARD_FAB2(SCH_1):P3E_CPU0_PE1_PCH_C_TXP(13)

CAP_0402-0.22UF,16V,10%,X7R,A3A  I196  C6B4
   1 P3E_CPU0_PE1_PCH_TXN<15>      A @BASEBOARD_FAB2_LIB.BASEBOARD_FAB2(SCH_1):P3E_CPU0_PE1_PCH_TXN(15)
   2 P3E_CPU0_PE1_PCH_C_TXN<15>      B @BASEBOARD_FAB2_LIB.BASEBOARD_FAB2(SCH_1):P3E_CPU0_PE1_PCH_C_TXN(15)

CAP_0402-0.22UF,16V,10%,X7R,A3A  I198  C6B8
   1 P3E_CPU0_PE1_PCH_TXP<14>      A @BASEBOARD_FAB2_LIB.BASEBOARD_FAB2(SCH_1):P3E_CPU0_PE1_PCH_TXP(14)
   2 P3E_CPU0_PE1_PCH_C_TXP<14>      B @BASEBOARD_FAB2_LIB.BASEBOARD_FAB2(SCH_1):P3E_CPU0_PE1_PCH_C_TXP(14)

CAP_0402-0.22UF,16V,10%,X7R,A3A  I201  C6B5
   1 P3E_CPU0_PE1_PCH_TXP<15>      A @BASEBOARD_FAB2_LIB.BASEBOARD_FAB2(SCH_1):P3E_CPU0_PE1_PCH_TXP(15)
   2 P3E_CPU0_PE1_PCH_C_TXP<15>      B @BASEBOARD_FAB2_LIB.BASEBOARD_FAB2(SCH_1):P3E_CPU0_PE1_PCH_C_TXP(15)

CAP_0402-0.22UF,16V,10%,X7R,A3A  I205  C3M25
   1 P3E_CPU0_PE1_PCH_R_RXP<11>      A @BASEBOARD_FAB2_LIB.BASEBOARD_FAB2(SCH_1):P3E_CPU0_PE1_PCH_R_RXP(11)
   2 P3E_CPU0_PE1_PCH_RXP<11>      B @BASEBOARD_FAB2_LIB.BASEBOARD_FAB2(SCH_1):P3E_CPU0_PE1_PCH_RXP(11)

CAP_0402-0.22UF,16V,10%,X7R,A3A  I206  C3M34
   1 P3E_CPU0_PE1_PCH_R_RXP<8>      A @BASEBOARD_FAB2_LIB.BASEBOARD_FAB2(SCH_1):P3E_CPU0_PE1_PCH_R_RXP(8)
   2 P3E_CPU0_PE1_PCH_RXP<8>      B @BASEBOARD_FAB2_LIB.BASEBOARD_FAB2(SCH_1):P3E_CPU0_PE1_PCH_RXP(8)

CAP_0402-0.22UF,16V,10%,X7R,A3A  I212  C3M28
   1 P3E_CPU0_PE1_PCH_R_RXP<10>      A @BASEBOARD_FAB2_LIB.BASEBOARD_FAB2(SCH_1):P3E_CPU0_PE1_PCH_R_RXP(10)
   2 P3E_CPU0_PE1_PCH_RXP<10>      B @BASEBOARD_FAB2_LIB.BASEBOARD_FAB2(SCH_1):P3E_CPU0_PE1_PCH_RXP(10)

CAP_0402-0.22UF,16V,10%,X7R,A3A  I217  C3M33
   1 P3E_CPU0_PE1_PCH_R_RXN<8>      A @BASEBOARD_FAB2_LIB.BASEBOARD_FAB2(SCH_1):P3E_CPU0_PE1_PCH_R_RXN(8)
   2 P3E_CPU0_PE1_PCH_RXN<8>      B @BASEBOARD_FAB2_LIB.BASEBOARD_FAB2(SCH_1):P3E_CPU0_PE1_PCH_RXN(8)

CAP_0402-0.22UF,16V,10%,X7R,A3A  I218  C3M36
   1 P3E_CPU0_PE1_PCH_R_RXP<9>      A @BASEBOARD_FAB2_LIB.BASEBOARD_FAB2(SCH_1):P3E_CPU0_PE1_PCH_R_RXP(9)
   2 P3E_CPU0_PE1_PCH_RXP<9>      B @BASEBOARD_FAB2_LIB.BASEBOARD_FAB2(SCH_1):P3E_CPU0_PE1_PCH_RXP(9)

CAP_0402-0.22UF,16V,10%,X7R,A3A  I223  C3M32
   1 P3E_CPU0_PE1_PCH_R_RXN<10>      A @BASEBOARD_FAB2_LIB.BASEBOARD_FAB2(SCH_1):P3E_CPU0_PE1_PCH_R_RXN(10)
   2 P3E_CPU0_PE1_PCH_RXN<10>      B @BASEBOARD_FAB2_LIB.BASEBOARD_FAB2(SCH_1):P3E_CPU0_PE1_PCH_RXN(10)

CAP_0402-0.22UF,16V,10%,X7R,A3A  I225  C3M35
   1 P3E_CPU0_PE1_PCH_R_RXN<9>      A @BASEBOARD_FAB2_LIB.BASEBOARD_FAB2(SCH_1):P3E_CPU0_PE1_PCH_R_RXN(9)
   2 P3E_CPU0_PE1_PCH_RXN<9>      B @BASEBOARD_FAB2_LIB.BASEBOARD_FAB2(SCH_1):P3E_CPU0_PE1_PCH_RXN(9)

CAP_0402-0.22UF,16V,10%,X7R,A3A  I229  C3M26
   1 P3E_CPU0_PE1_PCH_R_RXN<11>      A @BASEBOARD_FAB2_LIB.BASEBOARD_FAB2(SCH_1):P3E_CPU0_PE1_PCH_R_RXN(11)
   2 P3E_CPU0_PE1_PCH_RXN<11>      B @BASEBOARD_FAB2_LIB.BASEBOARD_FAB2(SCH_1):P3E_CPU0_PE1_PCH_RXN(11)

CAP_0402-0.22UF,16V,10%,X7R,A3A  I232  C3M3
   1 P3E_CPU0_PE1_PCH_R_RXP<12>      A @BASEBOARD_FAB2_LIB.BASEBOARD_FAB2(SCH_1):P3E_CPU0_PE1_PCH_R_RXP(12)
   2 P3E_CPU0_PE1_PCH_RXP<12>      B @BASEBOARD_FAB2_LIB.BASEBOARD_FAB2(SCH_1):P3E_CPU0_PE1_PCH_RXP(12)

CAP_0402-0.22UF,16V,10%,X7R,A3A  I234  C3M11
   1 P3E_CPU0_PE1_PCH_R_RXP<14>      A @BASEBOARD_FAB2_LIB.BASEBOARD_FAB2(SCH_1):P3E_CPU0_PE1_PCH_R_RXP(14)
   2 P3E_CPU0_PE1_PCH_RXP<14>      B @BASEBOARD_FAB2_LIB.BASEBOARD_FAB2(SCH_1):P3E_CPU0_PE1_PCH_RXP(14)

CAP_0402-0.22UF,16V,10%,X7R,A3A  I239  C3M13
   1 P3E_CPU0_PE1_PCH_R_RXP<13>      A @BASEBOARD_FAB2_LIB.BASEBOARD_FAB2(SCH_1):P3E_CPU0_PE1_PCH_R_RXP(13)
   2 P3E_CPU0_PE1_PCH_RXP<13>      B @BASEBOARD_FAB2_LIB.BASEBOARD_FAB2(SCH_1):P3E_CPU0_PE1_PCH_RXP(13)

CAP_0402-0.22UF,16V,10%,X7R,A3A  I244  C3M4
   1 P3E_CPU0_PE1_PCH_R_RXN<12>      A @BASEBOARD_FAB2_LIB.BASEBOARD_FAB2(SCH_1):P3E_CPU0_PE1_PCH_R_RXN(12)
   2 P3E_CPU0_PE1_PCH_RXN<12>      B @BASEBOARD_FAB2_LIB.BASEBOARD_FAB2(SCH_1):P3E_CPU0_PE1_PCH_RXN(12)

CAP_0402-0.22UF,16V,10%,X7R,A3A  I246  C3M12
   1 P3E_CPU0_PE1_PCH_R_RXN<14>      A @BASEBOARD_FAB2_LIB.BASEBOARD_FAB2(SCH_1):P3E_CPU0_PE1_PCH_R_RXN(14)
   2 P3E_CPU0_PE1_PCH_RXN<14>      B @BASEBOARD_FAB2_LIB.BASEBOARD_FAB2(SCH_1):P3E_CPU0_PE1_PCH_RXN(14)

CAP_0402-0.22UF,16V,10%,X7R,A3A  I247  C3M2
   1 P3E_CPU0_PE1_PCH_R_RXP<15>      A @BASEBOARD_FAB2_LIB.BASEBOARD_FAB2(SCH_1):P3E_CPU0_PE1_PCH_R_RXP(15)
   2 P3E_CPU0_PE1_PCH_RXP<15>      B @BASEBOARD_FAB2_LIB.BASEBOARD_FAB2(SCH_1):P3E_CPU0_PE1_PCH_RXP(15)

CAP_0402-0.22UF,16V,10%,X7R,A3A  I253  C3M14
   1 P3E_CPU0_PE1_PCH_R_RXN<13>      A @BASEBOARD_FAB2_LIB.BASEBOARD_FAB2(SCH_1):P3E_CPU0_PE1_PCH_R_RXN(13)
   2 P3E_CPU0_PE1_PCH_RXN<13>      B @BASEBOARD_FAB2_LIB.BASEBOARD_FAB2(SCH_1):P3E_CPU0_PE1_PCH_RXN(13)

CAP_0402-0.22UF,16V,10%,X7R,A3A  I255  C3M1
   1 P3E_CPU0_PE1_PCH_R_RXN<15>      A @BASEBOARD_FAB2_LIB.BASEBOARD_FAB2(SCH_1):P3E_CPU0_PE1_PCH_R_RXN(15)
   2 P3E_CPU0_PE1_PCH_RXN<15>      B @BASEBOARD_FAB2_LIB.BASEBOARD_FAB2(SCH_1):P3E_CPU0_PE1_PCH_RXN(15)


DRAWING: @BASEBOARD_FAB2_LIB.BASEBOARD_FAB2(SCH_1):PAGE106 

CAP_0402-0.22UF,16V,10%,X7R,A3A  I10  C1R2
   1 P3E_CPU0_PE3_OCP_TXP<0>      A @BASEBOARD_FAB2_LIB.BASEBOARD_FAB2(SCH_1):P3E_CPU0_PE3_OCP_TXP(0)
   2 P3E_OCP_CPU0_PE3_C_TXP<0>      B @BASEBOARD_FAB2_LIB.BASEBOARD_FAB2(SCH_1):P3E_OCP_CPU0_PE3_C_TXP(0)

CAP_0402-0.22UF,16V,10%,X7R,A3A  I26  C1R4
   1 P3E_CPU0_PE3_OCP_TXP<1>      A @BASEBOARD_FAB2_LIB.BASEBOARD_FAB2(SCH_1):P3E_CPU0_PE3_OCP_TXP(1)
   2 P3E_OCP_CPU0_PE3_C_TXP<1>      B @BASEBOARD_FAB2_LIB.BASEBOARD_FAB2(SCH_1):P3E_OCP_CPU0_PE3_C_TXP(1)

CAP_0402-0.22UF,16V,10%,X7R,A3A  I29  C1R1
   1 P3E_CPU0_PE3_OCP_TXN<0>      A @BASEBOARD_FAB2_LIB.BASEBOARD_FAB2(SCH_1):P3E_CPU0_PE3_OCP_TXN(0)
   2 P3E_OCP_CPU0_PE3_C_TXN<0>      B @BASEBOARD_FAB2_LIB.BASEBOARD_FAB2(SCH_1):P3E_OCP_CPU0_PE3_C_TXN(0)

CAP_0402-0.22UF,16V,10%,X7R,A3A  I37  C1R3
   1 P3E_CPU0_PE3_OCP_TXN<1>      A @BASEBOARD_FAB2_LIB.BASEBOARD_FAB2(SCH_1):P3E_CPU0_PE3_OCP_TXN(1)
   2 P3E_OCP_CPU0_PE3_C_TXN<1>      B @BASEBOARD_FAB2_LIB.BASEBOARD_FAB2(SCH_1):P3E_OCP_CPU0_PE3_C_TXN(1)

CAP_0402-0.22UF,16V,10%,X7R,A3A  I40  C1R6
   1 P3E_CPU0_PE3_OCP_TXP<2>      A @BASEBOARD_FAB2_LIB.BASEBOARD_FAB2(SCH_1):P3E_CPU0_PE3_OCP_TXP(2)
   2 P3E_OCP_CPU0_PE3_C_TXP<2>      B @BASEBOARD_FAB2_LIB.BASEBOARD_FAB2(SCH_1):P3E_OCP_CPU0_PE3_C_TXP(2)

CAP_0402-0.22UF,16V,10%,X7R,A3A  I55  C1R8
   1 P3E_CPU0_PE3_OCP_TXP<3>      A @BASEBOARD_FAB2_LIB.BASEBOARD_FAB2(SCH_1):P3E_CPU0_PE3_OCP_TXP(3)
   2 P3E_OCP_CPU0_PE3_C_TXP<3>      B @BASEBOARD_FAB2_LIB.BASEBOARD_FAB2(SCH_1):P3E_OCP_CPU0_PE3_C_TXP(3)

CAP_0402-0.22UF,16V,10%,X7R,A3A  I59  C1R5
   1 P3E_CPU0_PE3_OCP_TXN<2>      A @BASEBOARD_FAB2_LIB.BASEBOARD_FAB2(SCH_1):P3E_CPU0_PE3_OCP_TXN(2)
   2 P3E_OCP_CPU0_PE3_C_TXN<2>      B @BASEBOARD_FAB2_LIB.BASEBOARD_FAB2(SCH_1):P3E_OCP_CPU0_PE3_C_TXN(2)

CAP_0402-0.22UF,16V,10%,X7R,A3A  I70  C1R7
   1 P3E_CPU0_PE3_OCP_TXN<3>      A @BASEBOARD_FAB2_LIB.BASEBOARD_FAB2(SCH_1):P3E_CPU0_PE3_OCP_TXN(3)
   2 P3E_OCP_CPU0_PE3_C_TXN<3>      B @BASEBOARD_FAB2_LIB.BASEBOARD_FAB2(SCH_1):P3E_OCP_CPU0_PE3_C_TXN(3)

CAP_0402-0.22UF,16V,10%,X7R,A3A  I76  C2M14
   1 P3E_CPU0_PE3_OCP_TXP<8>      A @BASEBOARD_FAB2_LIB.BASEBOARD_FAB2(SCH_1):P3E_CPU0_PE3_OCP_TXP(8)
   2 P3E_OCP_CPU0_PE3_C_TXP<8>      B @BASEBOARD_FAB2_LIB.BASEBOARD_FAB2(SCH_1):P3E_OCP_CPU0_PE3_C_TXP(8)

CAP_0402-0.22UF,16V,10%,X7R,A3A  I78  C1M18
   1 P3E_CPU0_PE3_OCP_TXP<9>      A @BASEBOARD_FAB2_LIB.BASEBOARD_FAB2(SCH_1):P3E_CPU0_PE3_OCP_TXP(9)
   2 P3E_OCP_CPU0_PE3_C_TXP<9>      B @BASEBOARD_FAB2_LIB.BASEBOARD_FAB2(SCH_1):P3E_OCP_CPU0_PE3_C_TXP(9)

CAP_0402-0.22UF,16V,10%,X7R,A3A  I82  C1M16
   1 P3E_CPU0_PE3_OCP_TXP<10>      A @BASEBOARD_FAB2_LIB.BASEBOARD_FAB2(SCH_1):P3E_CPU0_PE3_OCP_TXP(10)
   2 P3E_OCP_CPU0_PE3_C_TXP<10>      B @BASEBOARD_FAB2_LIB.BASEBOARD_FAB2(SCH_1):P3E_OCP_CPU0_PE3_C_TXP(10)

CAP_0402-0.22UF,16V,10%,X7R,A3A  I85  C1M14
   1 P3E_CPU0_PE3_OCP_TXP<11>      A @BASEBOARD_FAB2_LIB.BASEBOARD_FAB2(SCH_1):P3E_CPU0_PE3_OCP_TXP(11)
   2 P3E_OCP_CPU0_PE3_C_TXP<11>      B @BASEBOARD_FAB2_LIB.BASEBOARD_FAB2(SCH_1):P3E_OCP_CPU0_PE3_C_TXP(11)

CAP_0402-0.22UF,16V,10%,X7R,A3A  I86  C2M15
   1 P3E_CPU0_PE3_OCP_TXN<8>      A @BASEBOARD_FAB2_LIB.BASEBOARD_FAB2(SCH_1):P3E_CPU0_PE3_OCP_TXN(8)
   2 P3E_OCP_CPU0_PE3_C_TXN<8>      B @BASEBOARD_FAB2_LIB.BASEBOARD_FAB2(SCH_1):P3E_OCP_CPU0_PE3_C_TXN(8)

CAP_0402-0.22UF,16V,10%,X7R,A3A  I90  C1M19
   1 P3E_CPU0_PE3_OCP_TXN<9>      A @BASEBOARD_FAB2_LIB.BASEBOARD_FAB2(SCH_1):P3E_CPU0_PE3_OCP_TXN(9)
   2 P3E_OCP_CPU0_PE3_C_TXN<9>      B @BASEBOARD_FAB2_LIB.BASEBOARD_FAB2(SCH_1):P3E_OCP_CPU0_PE3_C_TXN(9)

CAP_0402-0.22UF,16V,10%,X7R,A3A  I92  C1M17
   1 P3E_CPU0_PE3_OCP_TXN<10>      A @BASEBOARD_FAB2_LIB.BASEBOARD_FAB2(SCH_1):P3E_CPU0_PE3_OCP_TXN(10)
   2 P3E_OCP_CPU0_PE3_C_TXN<10>      B @BASEBOARD_FAB2_LIB.BASEBOARD_FAB2(SCH_1):P3E_OCP_CPU0_PE3_C_TXN(10)

CAP_0402-0.22UF,16V,10%,X7R,A3A  I95  C1M15
   1 P3E_CPU0_PE3_OCP_TXN<11>      A @BASEBOARD_FAB2_LIB.BASEBOARD_FAB2(SCH_1):P3E_CPU0_PE3_OCP_TXN(11)
   2 P3E_OCP_CPU0_PE3_C_TXN<11>      B @BASEBOARD_FAB2_LIB.BASEBOARD_FAB2(SCH_1):P3E_OCP_CPU0_PE3_C_TXN(11)

CAP_0402-0.22UF,16V,10%,X7R,A3A  I100  C1M12
   1 P3E_CPU0_PE3_OCP_TXP<12>      A @BASEBOARD_FAB2_LIB.BASEBOARD_FAB2(SCH_1):P3E_CPU0_PE3_OCP_TXP(12)
   2 P3E_OCP_CPU0_PE3_C_TXP<12>      B @BASEBOARD_FAB2_LIB.BASEBOARD_FAB2(SCH_1):P3E_OCP_CPU0_PE3_C_TXP(12)

CAP_0402-0.22UF,16V,10%,X7R,A3A  I102  C1M10
   1 P3E_CPU0_PE3_OCP_TXP<13>      A @BASEBOARD_FAB2_LIB.BASEBOARD_FAB2(SCH_1):P3E_CPU0_PE3_OCP_TXP(13)
   2 P3E_OCP_CPU0_PE3_C_TXP<13>      B @BASEBOARD_FAB2_LIB.BASEBOARD_FAB2(SCH_1):P3E_OCP_CPU0_PE3_C_TXP(13)

CAP_0402-0.22UF,16V,10%,X7R,A3A  I105  C1M8
   1 P3E_CPU0_PE3_OCP_TXP<14>      A @BASEBOARD_FAB2_LIB.BASEBOARD_FAB2(SCH_1):P3E_CPU0_PE3_OCP_TXP(14)
   2 P3E_OCP_CPU0_PE3_C_TXP<14>      B @BASEBOARD_FAB2_LIB.BASEBOARD_FAB2(SCH_1):P3E_OCP_CPU0_PE3_C_TXP(14)

CAP_0402-0.22UF,16V,10%,X7R,A3A  I109  C1M6
   1 P3E_CPU0_PE3_OCP_TXP<15>      A @BASEBOARD_FAB2_LIB.BASEBOARD_FAB2(SCH_1):P3E_CPU0_PE3_OCP_TXP(15)
   2 P3E_OCP_CPU0_PE3_C_TXP<15>      B @BASEBOARD_FAB2_LIB.BASEBOARD_FAB2(SCH_1):P3E_OCP_CPU0_PE3_C_TXP(15)

CAP_0402-0.22UF,16V,10%,X7R,A3A  I111  C1M13
   1 P3E_CPU0_PE3_OCP_TXN<12>      A @BASEBOARD_FAB2_LIB.BASEBOARD_FAB2(SCH_1):P3E_CPU0_PE3_OCP_TXN(12)
   2 P3E_OCP_CPU0_PE3_C_TXN<12>      B @BASEBOARD_FAB2_LIB.BASEBOARD_FAB2(SCH_1):P3E_OCP_CPU0_PE3_C_TXN(12)

CAP_0402-0.22UF,16V,10%,X7R,A3A  I114  C1M9
   1 P3E_CPU0_PE3_OCP_TXN<14>      A @BASEBOARD_FAB2_LIB.BASEBOARD_FAB2(SCH_1):P3E_CPU0_PE3_OCP_TXN(14)
   2 P3E_OCP_CPU0_PE3_C_TXN<14>      B @BASEBOARD_FAB2_LIB.BASEBOARD_FAB2(SCH_1):P3E_OCP_CPU0_PE3_C_TXN(14)

CAP_0402-0.22UF,16V,10%,X7R,A3A  I117  C1M11
   1 P3E_CPU0_PE3_OCP_TXN<13>      A @BASEBOARD_FAB2_LIB.BASEBOARD_FAB2(SCH_1):P3E_CPU0_PE3_OCP_TXN(13)
   2 P3E_OCP_CPU0_PE3_C_TXN<13>      B @BASEBOARD_FAB2_LIB.BASEBOARD_FAB2(SCH_1):P3E_OCP_CPU0_PE3_C_TXN(13)

CAP_0402-0.22UF,16V,10%,X7R,A3A  I122  C1M7
   1 P3E_CPU0_PE3_OCP_TXN<15>      A @BASEBOARD_FAB2_LIB.BASEBOARD_FAB2(SCH_1):P3E_CPU0_PE3_OCP_TXN(15)
   2 P3E_OCP_CPU0_PE3_C_TXN<15>      B @BASEBOARD_FAB2_LIB.BASEBOARD_FAB2(SCH_1):P3E_OCP_CPU0_PE3_C_TXN(15)

CAP_0402-0.22UF,16V,10%,X7R,A3A  I123  C2R7
   1 P3E_CPU0_PE3_OCP_TXN<6>      A @BASEBOARD_FAB2_LIB.BASEBOARD_FAB2(SCH_1):P3E_CPU0_PE3_OCP_TXN(6)
   2 P3E_OCP_CPU0_PE3_C_TXN<6>      B @BASEBOARD_FAB2_LIB.BASEBOARD_FAB2(SCH_1):P3E_OCP_CPU0_PE3_C_TXN(6)

CAP_0402-0.22UF,16V,10%,X7R,A3A  I128  C1R10
   1 P3E_CPU0_PE3_OCP_TXP<4>      A @BASEBOARD_FAB2_LIB.BASEBOARD_FAB2(SCH_1):P3E_CPU0_PE3_OCP_TXP(4)
   2 P3E_OCP_CPU0_PE3_C_TXP<4>      B @BASEBOARD_FAB2_LIB.BASEBOARD_FAB2(SCH_1):P3E_OCP_CPU0_PE3_C_TXP(4)

CAP_0402-0.22UF,16V,10%,X7R,A3A  I130  C2R14
   1 P3E_CPU0_PE3_OCP_TXP<5>      A @BASEBOARD_FAB2_LIB.BASEBOARD_FAB2(SCH_1):P3E_CPU0_PE3_OCP_TXP(5)
   2 P3E_OCP_CPU0_PE3_C_TXP<5>      B @BASEBOARD_FAB2_LIB.BASEBOARD_FAB2(SCH_1):P3E_OCP_CPU0_PE3_C_TXP(5)

CAP_0402-0.22UF,16V,10%,X7R,A3A  I134  C1R9
   1 P3E_CPU0_PE3_OCP_TXN<4>      A @BASEBOARD_FAB2_LIB.BASEBOARD_FAB2(SCH_1):P3E_CPU0_PE3_OCP_TXN(4)
   2 P3E_OCP_CPU0_PE3_C_TXN<4>      B @BASEBOARD_FAB2_LIB.BASEBOARD_FAB2(SCH_1):P3E_OCP_CPU0_PE3_C_TXN(4)

CAP_0402-0.22UF,16V,10%,X7R,A3A  I137  C2R13
   1 P3E_CPU0_PE3_OCP_TXN<5>      A @BASEBOARD_FAB2_LIB.BASEBOARD_FAB2(SCH_1):P3E_CPU0_PE3_OCP_TXN(5)
   2 P3E_OCP_CPU0_PE3_C_TXN<5>      B @BASEBOARD_FAB2_LIB.BASEBOARD_FAB2(SCH_1):P3E_OCP_CPU0_PE3_C_TXN(5)

CAP_0402-0.22UF,16V,10%,X7R,A3A  I141  C2R8
   1 P3E_CPU0_PE3_OCP_TXP<6>      A @BASEBOARD_FAB2_LIB.BASEBOARD_FAB2(SCH_1):P3E_CPU0_PE3_OCP_TXP(6)
   2 P3E_OCP_CPU0_PE3_C_TXP<6>      B @BASEBOARD_FAB2_LIB.BASEBOARD_FAB2(SCH_1):P3E_OCP_CPU0_PE3_C_TXP(6)

CAP_0402-0.22UF,16V,10%,X7R,A3A  I142  C2R10
   1 P3E_CPU0_PE3_OCP_TXP<7>      A @BASEBOARD_FAB2_LIB.BASEBOARD_FAB2(SCH_1):P3E_CPU0_PE3_OCP_TXP(7)
   2 P3E_OCP_CPU0_PE3_C_TXP<7>      B @BASEBOARD_FAB2_LIB.BASEBOARD_FAB2(SCH_1):P3E_OCP_CPU0_PE3_C_TXP(7)

CAP_0402-0.22UF,16V,10%,X7R,A3A  I147  C2R9
   1 P3E_CPU0_PE3_OCP_TXN<7>      A @BASEBOARD_FAB2_LIB.BASEBOARD_FAB2(SCH_1):P3E_CPU0_PE3_OCP_TXN(7)
   2 P3E_OCP_CPU0_PE3_C_TXN<7>      B @BASEBOARD_FAB2_LIB.BASEBOARD_FAB2(SCH_1):P3E_OCP_CPU0_PE3_C_TXN(7)


DRAWING: @BASEBOARD_FAB2_LIB.BASEBOARD_FAB2(SCH_1):PAGE107 

CAP_0402-0.22UF,16V,10%,X7R,A3A  I207  C3P13
   1 P3E_CPU0_PE1_SS_TXN<0>      A @BASEBOARD_FAB2_LIB.BASEBOARD_FAB2(SCH_1):P3E_CPU0_PE1_SS_TXN(0)
   2 P3E_CPU0_PE1_PCH_TXN<0>      B @BASEBOARD_FAB2_LIB.BASEBOARD_FAB2(SCH_1):P3E_CPU0_PE1_PCH_TXN(0)

CAP_0402-0.22UF,16V,10%,X7R,A3A  I208  C3P17
   1 P3E_CPU0_PE1_SS_TXN<1>      A @BASEBOARD_FAB2_LIB.BASEBOARD_FAB2(SCH_1):P3E_CPU0_PE1_SS_TXN(1)
   2 P3E_CPU0_PE1_PCH_TXN<1>      B @BASEBOARD_FAB2_LIB.BASEBOARD_FAB2(SCH_1):P3E_CPU0_PE1_PCH_TXN(1)

CAP_0402-0.22UF,16V,10%,X7R,A3A  I212  C3P11
   1 P3E_CPU0_PE1_SS_TXP<0>      A @BASEBOARD_FAB2_LIB.BASEBOARD_FAB2(SCH_1):P3E_CPU0_PE1_SS_TXP(0)
   2 P3E_CPU0_PE1_PCH_TXP<0>      B @BASEBOARD_FAB2_LIB.BASEBOARD_FAB2(SCH_1):P3E_CPU0_PE1_PCH_TXP(0)

CAP_0402-0.22UF,16V,10%,X7R,A3A  I215  C3P20
   1 P3E_CPU0_PE1_SS_TXN<2>      A @BASEBOARD_FAB2_LIB.BASEBOARD_FAB2(SCH_1):P3E_CPU0_PE1_SS_TXN(2)
   2 P3E_CPU0_PE1_PCH_TXN<2>      B @BASEBOARD_FAB2_LIB.BASEBOARD_FAB2(SCH_1):P3E_CPU0_PE1_PCH_TXN(2)

CAP_0402-0.22UF,16V,10%,X7R,A3A  I216  C3P25
   1 P3E_CPU0_PE1_SS_TXN<3>      A @BASEBOARD_FAB2_LIB.BASEBOARD_FAB2(SCH_1):P3E_CPU0_PE1_SS_TXN(3)
   2 P3E_CPU0_PE1_PCH_TXN<3>      B @BASEBOARD_FAB2_LIB.BASEBOARD_FAB2(SCH_1):P3E_CPU0_PE1_PCH_TXN(3)

CAP_0402-0.22UF,16V,10%,X7R,A3A  I219  C3P18
   1 P3E_CPU0_PE1_SS_TXP<2>      A @BASEBOARD_FAB2_LIB.BASEBOARD_FAB2(SCH_1):P3E_CPU0_PE1_SS_TXP(2)
   2 P3E_CPU0_PE1_PCH_TXP<2>      B @BASEBOARD_FAB2_LIB.BASEBOARD_FAB2(SCH_1):P3E_CPU0_PE1_PCH_TXP(2)

CAP_0402-0.22UF,16V,10%,X7R,A3A  I223  C3P27
   1 P3E_CPU0_PE1_SS_TXP<4>      A @BASEBOARD_FAB2_LIB.BASEBOARD_FAB2(SCH_1):P3E_CPU0_PE1_SS_TXP(4)
   2 P3E_CPU0_PE1_PCH_TXP<4>      B @BASEBOARD_FAB2_LIB.BASEBOARD_FAB2(SCH_1):P3E_CPU0_PE1_PCH_TXP(4)

CAP_0402-0.22UF,16V,10%,X7R,A3A  I226  C3P15
   1 P3E_CPU0_PE1_SS_TXP<1>      A @BASEBOARD_FAB2_LIB.BASEBOARD_FAB2(SCH_1):P3E_CPU0_PE1_SS_TXP(1)
   2 P3E_CPU0_PE1_PCH_TXP<1>      B @BASEBOARD_FAB2_LIB.BASEBOARD_FAB2(SCH_1):P3E_CPU0_PE1_PCH_TXP(1)

CAP_0402-0.22UF,16V,10%,X7R,A3A  I229  C3P23
   1 P3E_CPU0_PE1_SS_TXP<3>      A @BASEBOARD_FAB2_LIB.BASEBOARD_FAB2(SCH_1):P3E_CPU0_PE1_SS_TXP(3)
   2 P3E_CPU0_PE1_PCH_TXP<3>      B @BASEBOARD_FAB2_LIB.BASEBOARD_FAB2(SCH_1):P3E_CPU0_PE1_PCH_TXP(3)

CAP_0402-0.22UF,16V,10%,X7R,A3A  I232  C3P28
   1 P3E_CPU0_PE1_SS_TXN<4>      A @BASEBOARD_FAB2_LIB.BASEBOARD_FAB2(SCH_1):P3E_CPU0_PE1_SS_TXN(4)
   2 P3E_CPU0_PE1_PCH_TXN<4>      B @BASEBOARD_FAB2_LIB.BASEBOARD_FAB2(SCH_1):P3E_CPU0_PE1_PCH_TXN(4)

CAP_0402-0.22UF,16V,10%,X7R,A3A  I234  C3P32
   1 P3E_CPU0_PE1_SS_TXN<5>      A @BASEBOARD_FAB2_LIB.BASEBOARD_FAB2(SCH_1):P3E_CPU0_PE1_SS_TXN(5)
   2 P3E_CPU0_PE1_PCH_TXN<5>      B @BASEBOARD_FAB2_LIB.BASEBOARD_FAB2(SCH_1):P3E_CPU0_PE1_PCH_TXN(5)

CAP_0402-0.22UF,16V,10%,X7R,A3A  I235  C3P37
   1 P3E_CPU0_PE1_SS_TXN<6>      A @BASEBOARD_FAB2_LIB.BASEBOARD_FAB2(SCH_1):P3E_CPU0_PE1_SS_TXN(6)
   2 P3E_CPU0_PE1_PCH_TXN<6>      B @BASEBOARD_FAB2_LIB.BASEBOARD_FAB2(SCH_1):P3E_CPU0_PE1_PCH_TXN(6)

CAP_0402-0.22UF,16V,10%,X7R,A3A  I240  C3P35
   1 P3E_CPU0_PE1_SS_TXP<6>      A @BASEBOARD_FAB2_LIB.BASEBOARD_FAB2(SCH_1):P3E_CPU0_PE1_SS_TXP(6)
   2 P3E_CPU0_PE1_PCH_TXP<6>      B @BASEBOARD_FAB2_LIB.BASEBOARD_FAB2(SCH_1):P3E_CPU0_PE1_PCH_TXP(6)

CAP_0402-0.22UF,16V,10%,X7R,A3A  I241  C3P40
   1 P3E_CPU0_PE1_SS_TXN<7>      A @BASEBOARD_FAB2_LIB.BASEBOARD_FAB2(SCH_1):P3E_CPU0_PE1_SS_TXN(7)
   2 P3E_CPU0_PE1_PCH_TXN<7>      B @BASEBOARD_FAB2_LIB.BASEBOARD_FAB2(SCH_1):P3E_CPU0_PE1_PCH_TXN(7)

CAP_0402-0.22UF,16V,10%,X7R,A3A  I245  C3P30
   1 P3E_CPU0_PE1_SS_TXP<5>      A @BASEBOARD_FAB2_LIB.BASEBOARD_FAB2(SCH_1):P3E_CPU0_PE1_SS_TXP(5)
   2 P3E_CPU0_PE1_PCH_TXP<5>      B @BASEBOARD_FAB2_LIB.BASEBOARD_FAB2(SCH_1):P3E_CPU0_PE1_PCH_TXP(5)

CAP_0402-0.22UF,16V,10%,X7R,A3A  I248  C3P39
   1 P3E_CPU0_PE1_SS_TXP<7>      A @BASEBOARD_FAB2_LIB.BASEBOARD_FAB2(SCH_1):P3E_CPU0_PE1_SS_TXP(7)
   2 P3E_CPU0_PE1_PCH_TXP<7>      B @BASEBOARD_FAB2_LIB.BASEBOARD_FAB2(SCH_1):P3E_CPU0_PE1_PCH_TXP(7)

CAP_0402-0.22UF,16V,10%,X7R,A3A  I257  C2U4
   1 P3E_CPU0_PE1_PCH_RXN<0>      A @BASEBOARD_FAB2_LIB.BASEBOARD_FAB2(SCH_1):P3E_CPU0_PE1_PCH_RXN(0)
   2 P3E_CPU0_PE1_SS_RXN<0>      B @BASEBOARD_FAB2_LIB.BASEBOARD_FAB2(SCH_1):P3E_CPU0_PE1_SS_RXN(0)

CAP_0402-0.22UF,16V,10%,X7R,A3A  I260  C2U6
   1 P3E_CPU0_PE1_PCH_RXN<1>      A @BASEBOARD_FAB2_LIB.BASEBOARD_FAB2(SCH_1):P3E_CPU0_PE1_PCH_RXN(1)
   2 P3E_CPU0_PE1_SS_RXN<1>      B @BASEBOARD_FAB2_LIB.BASEBOARD_FAB2(SCH_1):P3E_CPU0_PE1_SS_RXN(1)

CAP_0402-0.22UF,16V,10%,X7R,A3A  I264  C2U8
   1 P3E_CPU0_PE1_PCH_RXN<2>      A @BASEBOARD_FAB2_LIB.BASEBOARD_FAB2(SCH_1):P3E_CPU0_PE1_PCH_RXN(2)
   2 P3E_CPU0_PE1_SS_RXN<2>      B @BASEBOARD_FAB2_LIB.BASEBOARD_FAB2(SCH_1):P3E_CPU0_PE1_SS_RXN(2)

CAP_0402-0.22UF,16V,10%,X7R,A3A  I265  C2U12
   1 P3E_CPU0_PE1_PCH_RXN<4>      A @BASEBOARD_FAB2_LIB.BASEBOARD_FAB2(SCH_1):P3E_CPU0_PE1_PCH_RXN(4)
   2 P3E_CPU0_PE1_SS_RXN<4>      B @BASEBOARD_FAB2_LIB.BASEBOARD_FAB2(SCH_1):P3E_CPU0_PE1_SS_RXN(4)

CAP_0402-0.22UF,16V,10%,X7R,A3A  I267  C2U10
   1 P3E_CPU0_PE1_PCH_RXN<3>      A @BASEBOARD_FAB2_LIB.BASEBOARD_FAB2(SCH_1):P3E_CPU0_PE1_PCH_RXN(3)
   2 P3E_CPU0_PE1_SS_RXN<3>      B @BASEBOARD_FAB2_LIB.BASEBOARD_FAB2(SCH_1):P3E_CPU0_PE1_SS_RXN(3)

CAP_0402-0.22UF,16V,10%,X7R,A3A  I272  C2U3
   1 P3E_CPU0_PE1_PCH_RXP<0>      A @BASEBOARD_FAB2_LIB.BASEBOARD_FAB2(SCH_1):P3E_CPU0_PE1_PCH_RXP(0)
   2 P3E_CPU0_PE1_SS_RXP<0>      B @BASEBOARD_FAB2_LIB.BASEBOARD_FAB2(SCH_1):P3E_CPU0_PE1_SS_RXP(0)

CAP_0402-0.22UF,16V,10%,X7R,A3A  I274  C2U5
   1 P3E_CPU0_PE1_PCH_RXP<1>      A @BASEBOARD_FAB2_LIB.BASEBOARD_FAB2(SCH_1):P3E_CPU0_PE1_PCH_RXP(1)
   2 P3E_CPU0_PE1_SS_RXP<1>      B @BASEBOARD_FAB2_LIB.BASEBOARD_FAB2(SCH_1):P3E_CPU0_PE1_SS_RXP(1)

CAP_0402-0.22UF,16V,10%,X7R,A3A  I277  C2U7
   1 P3E_CPU0_PE1_PCH_RXP<2>      A @BASEBOARD_FAB2_LIB.BASEBOARD_FAB2(SCH_1):P3E_CPU0_PE1_PCH_RXP(2)
   2 P3E_CPU0_PE1_SS_RXP<2>      B @BASEBOARD_FAB2_LIB.BASEBOARD_FAB2(SCH_1):P3E_CPU0_PE1_SS_RXP(2)

CAP_0402-0.22UF,16V,10%,X7R,A3A  I278  C2U11
   1 P3E_CPU0_PE1_PCH_RXP<4>      A @BASEBOARD_FAB2_LIB.BASEBOARD_FAB2(SCH_1):P3E_CPU0_PE1_PCH_RXP(4)
   2 P3E_CPU0_PE1_SS_RXP<4>      B @BASEBOARD_FAB2_LIB.BASEBOARD_FAB2(SCH_1):P3E_CPU0_PE1_SS_RXP(4)

CAP_0402-0.22UF,16V,10%,X7R,A3A  I279  C2U9
   1 P3E_CPU0_PE1_PCH_RXP<3>      A @BASEBOARD_FAB2_LIB.BASEBOARD_FAB2(SCH_1):P3E_CPU0_PE1_PCH_RXP(3)
   2 P3E_CPU0_PE1_SS_RXP<3>      B @BASEBOARD_FAB2_LIB.BASEBOARD_FAB2(SCH_1):P3E_CPU0_PE1_SS_RXP(3)

CAP_0402-0.22UF,16V,10%,X7R,A3A  I286  C2U16
   1 P3E_CPU0_PE1_PCH_RXN<6>      A @BASEBOARD_FAB2_LIB.BASEBOARD_FAB2(SCH_1):P3E_CPU0_PE1_PCH_RXN(6)
   2 P3E_CPU0_PE1_SS_RXN<6>      B @BASEBOARD_FAB2_LIB.BASEBOARD_FAB2(SCH_1):P3E_CPU0_PE1_SS_RXN(6)

CAP_0402-0.22UF,16V,10%,X7R,A3A  I287  C2U14
   1 P3E_CPU0_PE1_PCH_RXN<5>      A @BASEBOARD_FAB2_LIB.BASEBOARD_FAB2(SCH_1):P3E_CPU0_PE1_PCH_RXN(5)
   2 P3E_CPU0_PE1_SS_RXN<5>      B @BASEBOARD_FAB2_LIB.BASEBOARD_FAB2(SCH_1):P3E_CPU0_PE1_SS_RXN(5)

CAP_0402-0.22UF,16V,10%,X7R,A3A  I294  C2U18
   1 P3E_CPU0_PE1_PCH_RXN<7>      A @BASEBOARD_FAB2_LIB.BASEBOARD_FAB2(SCH_1):P3E_CPU0_PE1_PCH_RXN(7)
   2 P3E_CPU0_PE1_SS_RXN<7>      B @BASEBOARD_FAB2_LIB.BASEBOARD_FAB2(SCH_1):P3E_CPU0_PE1_SS_RXN(7)

CAP_0402-0.22UF,16V,10%,X7R,A3A  I296  C2U15
   1 P3E_CPU0_PE1_PCH_RXP<6>      A @BASEBOARD_FAB2_LIB.BASEBOARD_FAB2(SCH_1):P3E_CPU0_PE1_PCH_RXP(6)
   2 P3E_CPU0_PE1_SS_RXP<6>      B @BASEBOARD_FAB2_LIB.BASEBOARD_FAB2(SCH_1):P3E_CPU0_PE1_SS_RXP(6)

CAP_0402-0.22UF,16V,10%,X7R,A3A  I297  C2U13
   1 P3E_CPU0_PE1_PCH_RXP<5>      A @BASEBOARD_FAB2_LIB.BASEBOARD_FAB2(SCH_1):P3E_CPU0_PE1_PCH_RXP(5)
   2 P3E_CPU0_PE1_SS_RXP<5>      B @BASEBOARD_FAB2_LIB.BASEBOARD_FAB2(SCH_1):P3E_CPU0_PE1_SS_RXP(5)

CAP_0402-0.22UF,16V,10%,X7R,A3A  I300  C2U17
   1 P3E_CPU0_PE1_PCH_RXP<7>      A @BASEBOARD_FAB2_LIB.BASEBOARD_FAB2(SCH_1):P3E_CPU0_PE1_PCH_RXP(7)
   2 P3E_CPU0_PE1_SS_RXP<7>      B @BASEBOARD_FAB2_LIB.BASEBOARD_FAB2(SCH_1):P3E_CPU0_PE1_SS_RXP(7)

CAP_0402-0.22UF,16V,10%,EMPTY,A  I415  C3P12
   1 P3E_CPU0_PE1_SS_TXN<0>      A @BASEBOARD_FAB2_LIB.BASEBOARD_FAB2(SCH_1):P3E_CPU0_PE1_SS_TXN(0)
   2 P3E_CPU0_PE1_SS_C_TXN<0>      B @BASEBOARD_FAB2_LIB.BASEBOARD_FAB2(SCH_1):P3E_CPU0_PE1_SS_C_TXN(0)

CAP_0402-0.22UF,16V,10%,EMPTY,A  I417  C3P10
   1 P3E_CPU0_PE1_SS_TXP<0>      A @BASEBOARD_FAB2_LIB.BASEBOARD_FAB2(SCH_1):P3E_CPU0_PE1_SS_TXP(0)
   2 P3E_CPU0_PE1_SS_C_TXP<0>      B @BASEBOARD_FAB2_LIB.BASEBOARD_FAB2(SCH_1):P3E_CPU0_PE1_SS_C_TXP(0)

CAP_0402-0.22UF,16V,10%,EMPTY,A  I422  C3P16
   1 P3E_CPU0_PE1_SS_TXN<1>      A @BASEBOARD_FAB2_LIB.BASEBOARD_FAB2(SCH_1):P3E_CPU0_PE1_SS_TXN(1)
   2 P3E_CPU0_PE1_SS_C_TXN<1>      B @BASEBOARD_FAB2_LIB.BASEBOARD_FAB2(SCH_1):P3E_CPU0_PE1_SS_C_TXN(1)

CAP_0402-0.22UF,16V,10%,EMPTY,A  I423  C3P21
   1 P3E_CPU0_PE1_SS_TXN<2>      A @BASEBOARD_FAB2_LIB.BASEBOARD_FAB2(SCH_1):P3E_CPU0_PE1_SS_TXN(2)
   2 P3E_CPU0_PE1_SS_C_TXN<2>      B @BASEBOARD_FAB2_LIB.BASEBOARD_FAB2(SCH_1):P3E_CPU0_PE1_SS_C_TXN(2)

CAP_0402-0.22UF,16V,10%,EMPTY,A  I424  C3P24
   1 P3E_CPU0_PE1_SS_TXN<3>      A @BASEBOARD_FAB2_LIB.BASEBOARD_FAB2(SCH_1):P3E_CPU0_PE1_SS_TXN(3)
   2 P3E_CPU0_PE1_SS_C_TXN<3>      B @BASEBOARD_FAB2_LIB.BASEBOARD_FAB2(SCH_1):P3E_CPU0_PE1_SS_C_TXN(3)

CAP_0402-0.22UF,16V,10%,EMPTY,A  I427  C3P19
   1 P3E_CPU0_PE1_SS_TXP<2>      A @BASEBOARD_FAB2_LIB.BASEBOARD_FAB2(SCH_1):P3E_CPU0_PE1_SS_TXP(2)
   2 P3E_CPU0_PE1_SS_C_TXP<2>      B @BASEBOARD_FAB2_LIB.BASEBOARD_FAB2(SCH_1):P3E_CPU0_PE1_SS_C_TXP(2)

CAP_0402-0.22UF,16V,10%,EMPTY,A  I431  C3P14
   1 P3E_CPU0_PE1_SS_TXP<1>      A @BASEBOARD_FAB2_LIB.BASEBOARD_FAB2(SCH_1):P3E_CPU0_PE1_SS_TXP(1)
   2 P3E_CPU0_PE1_SS_C_TXP<1>      B @BASEBOARD_FAB2_LIB.BASEBOARD_FAB2(SCH_1):P3E_CPU0_PE1_SS_C_TXP(1)

CAP_0402-0.22UF,16V,10%,EMPTY,A  I435  C3P22
   1 P3E_CPU0_PE1_SS_TXP<3>      A @BASEBOARD_FAB2_LIB.BASEBOARD_FAB2(SCH_1):P3E_CPU0_PE1_SS_TXP(3)
   2 P3E_CPU0_PE1_SS_C_TXP<3>      B @BASEBOARD_FAB2_LIB.BASEBOARD_FAB2(SCH_1):P3E_CPU0_PE1_SS_C_TXP(3)

CAP_0402-0.22UF,16V,10%,EMPTY,A  I437  C3P29
   1 P3E_CPU0_PE1_SS_TXN<4>      A @BASEBOARD_FAB2_LIB.BASEBOARD_FAB2(SCH_1):P3E_CPU0_PE1_SS_TXN(4)
   2 P3E_CPU0_PE1_SS_C_TXN<4>      B @BASEBOARD_FAB2_LIB.BASEBOARD_FAB2(SCH_1):P3E_CPU0_PE1_SS_C_TXN(4)

CAP_0402-0.22UF,16V,10%,EMPTY,A  I438  C3P36
   1 P3E_CPU0_PE1_SS_TXN<6>      A @BASEBOARD_FAB2_LIB.BASEBOARD_FAB2(SCH_1):P3E_CPU0_PE1_SS_TXN(6)
   2 P3E_CPU0_PE1_SS_C_TXN<6>      B @BASEBOARD_FAB2_LIB.BASEBOARD_FAB2(SCH_1):P3E_CPU0_PE1_SS_C_TXN(6)

CAP_0402-0.22UF,16V,10%,EMPTY,A  I439  C3P33
   1 P3E_CPU0_PE1_SS_TXN<5>      A @BASEBOARD_FAB2_LIB.BASEBOARD_FAB2(SCH_1):P3E_CPU0_PE1_SS_TXN(5)
   2 P3E_CPU0_PE1_SS_C_TXN<5>      B @BASEBOARD_FAB2_LIB.BASEBOARD_FAB2(SCH_1):P3E_CPU0_PE1_SS_C_TXN(5)

CAP_0402-0.22UF,16V,10%,EMPTY,A  I444  C3P26
   1 P3E_CPU0_PE1_SS_TXP<4>      A @BASEBOARD_FAB2_LIB.BASEBOARD_FAB2(SCH_1):P3E_CPU0_PE1_SS_TXP(4)
   2 P3E_CPU0_PE1_SS_C_TXP<4>      B @BASEBOARD_FAB2_LIB.BASEBOARD_FAB2(SCH_1):P3E_CPU0_PE1_SS_C_TXP(4)

CAP_0402-0.22UF,16V,10%,EMPTY,A  I447  C3P34
   1 P3E_CPU0_PE1_SS_TXP<6>      A @BASEBOARD_FAB2_LIB.BASEBOARD_FAB2(SCH_1):P3E_CPU0_PE1_SS_TXP(6)
   2 P3E_CPU0_PE1_SS_C_TXP<6>      B @BASEBOARD_FAB2_LIB.BASEBOARD_FAB2(SCH_1):P3E_CPU0_PE1_SS_C_TXP(6)

CAP_0402-0.22UF,16V,10%,EMPTY,A  I448  C3P41
   1 P3E_CPU0_PE1_SS_TXN<7>      A @BASEBOARD_FAB2_LIB.BASEBOARD_FAB2(SCH_1):P3E_CPU0_PE1_SS_TXN(7)
   2 P3E_CPU0_PE1_SS_C_TXN<7>      B @BASEBOARD_FAB2_LIB.BASEBOARD_FAB2(SCH_1):P3E_CPU0_PE1_SS_C_TXN(7)

CAP_0402-0.22UF,16V,10%,EMPTY,A  I452  C3P31
   1 P3E_CPU0_PE1_SS_TXP<5>      A @BASEBOARD_FAB2_LIB.BASEBOARD_FAB2(SCH_1):P3E_CPU0_PE1_SS_TXP(5)
   2 P3E_CPU0_PE1_SS_C_TXP<5>      B @BASEBOARD_FAB2_LIB.BASEBOARD_FAB2(SCH_1):P3E_CPU0_PE1_SS_C_TXP(5)

CAP_0402-0.22UF,16V,10%,EMPTY,A  I455  C3P38
   1 P3E_CPU0_PE1_SS_TXP<7>      A @BASEBOARD_FAB2_LIB.BASEBOARD_FAB2(SCH_1):P3E_CPU0_PE1_SS_TXP(7)
   2 P3E_CPU0_PE1_SS_C_TXP<7>      B @BASEBOARD_FAB2_LIB.BASEBOARD_FAB2(SCH_1):P3E_CPU0_PE1_SS_C_TXP(7)

RES_0402-0.0,5%,1/16W,EMPTY,G2A  I458  R2U29
   1 P3E_CPU0_PE1_SS_R_RXN<7>      A @BASEBOARD_FAB2_LIB.BASEBOARD_FAB2(SCH_1):P3E_CPU0_PE1_SS_R_RXN(7)
   2 P3E_CPU0_PE1_SS_RXN<7>      B @BASEBOARD_FAB2_LIB.BASEBOARD_FAB2(SCH_1):P3E_CPU0_PE1_SS_RXN(7)

RES_0402-0.0,5%,1/16W,EMPTY,G2A  I459  R2U27
   1 P3E_CPU0_PE1_SS_R_RXN<6>      A @BASEBOARD_FAB2_LIB.BASEBOARD_FAB2(SCH_1):P3E_CPU0_PE1_SS_R_RXN(6)
   2 P3E_CPU0_PE1_SS_RXN<6>      B @BASEBOARD_FAB2_LIB.BASEBOARD_FAB2(SCH_1):P3E_CPU0_PE1_SS_RXN(6)

RES_0402-0.0,5%,1/16W,EMPTY,G2A  I460  R2U25
   1 P3E_CPU0_PE1_SS_R_RXN<5>      A @BASEBOARD_FAB2_LIB.BASEBOARD_FAB2(SCH_1):P3E_CPU0_PE1_SS_R_RXN(5)
   2 P3E_CPU0_PE1_SS_RXN<5>      B @BASEBOARD_FAB2_LIB.BASEBOARD_FAB2(SCH_1):P3E_CPU0_PE1_SS_RXN(5)

RES_0402-0.0,5%,1/16W,EMPTY,G2A  I461  R2U23
   1 P3E_CPU0_PE1_SS_R_RXN<4>      A @BASEBOARD_FAB2_LIB.BASEBOARD_FAB2(SCH_1):P3E_CPU0_PE1_SS_R_RXN(4)
   2 P3E_CPU0_PE1_SS_RXN<4>      B @BASEBOARD_FAB2_LIB.BASEBOARD_FAB2(SCH_1):P3E_CPU0_PE1_SS_RXN(4)

RES_0402-0.0,5%,1/16W,EMPTY,G2A  I462  R2U21
   1 P3E_CPU0_PE1_SS_R_RXN<3>      A @BASEBOARD_FAB2_LIB.BASEBOARD_FAB2(SCH_1):P3E_CPU0_PE1_SS_R_RXN(3)
   2 P3E_CPU0_PE1_SS_RXN<3>      B @BASEBOARD_FAB2_LIB.BASEBOARD_FAB2(SCH_1):P3E_CPU0_PE1_SS_RXN(3)

RES_0402-0.0,5%,1/16W,EMPTY,G2A  I463  R2U19
   1 P3E_CPU0_PE1_SS_R_RXN<2>      A @BASEBOARD_FAB2_LIB.BASEBOARD_FAB2(SCH_1):P3E_CPU0_PE1_SS_R_RXN(2)
   2 P3E_CPU0_PE1_SS_RXN<2>      B @BASEBOARD_FAB2_LIB.BASEBOARD_FAB2(SCH_1):P3E_CPU0_PE1_SS_RXN(2)

RES_0402-0.0,5%,1/16W,EMPTY,G2A  I464  R2U17
   1 P3E_CPU0_PE1_SS_R_RXN<1>      A @BASEBOARD_FAB2_LIB.BASEBOARD_FAB2(SCH_1):P3E_CPU0_PE1_SS_R_RXN(1)
   2 P3E_CPU0_PE1_SS_RXN<1>      B @BASEBOARD_FAB2_LIB.BASEBOARD_FAB2(SCH_1):P3E_CPU0_PE1_SS_RXN(1)

RES_0402-0.0,5%,1/16W,EMPTY,G2A  I465  R2U15
   1 P3E_CPU0_PE1_SS_R_RXN<0>      A @BASEBOARD_FAB2_LIB.BASEBOARD_FAB2(SCH_1):P3E_CPU0_PE1_SS_R_RXN(0)
   2 P3E_CPU0_PE1_SS_RXN<0>      B @BASEBOARD_FAB2_LIB.BASEBOARD_FAB2(SCH_1):P3E_CPU0_PE1_SS_RXN(0)

RES_0402-0.0,5%,1/16W,EMPTY,G2A  I466  R2U14
   1 P3E_CPU0_PE1_SS_R_RXP<0>      A @BASEBOARD_FAB2_LIB.BASEBOARD_FAB2(SCH_1):P3E_CPU0_PE1_SS_R_RXP(0)
   2 P3E_CPU0_PE1_SS_RXP<0>      B @BASEBOARD_FAB2_LIB.BASEBOARD_FAB2(SCH_1):P3E_CPU0_PE1_SS_RXP(0)

RES_0402-0.0,5%,1/16W,EMPTY,G2A  I467  R2U16
   1 P3E_CPU0_PE1_SS_R_RXP<1>      A @BASEBOARD_FAB2_LIB.BASEBOARD_FAB2(SCH_1):P3E_CPU0_PE1_SS_R_RXP(1)
   2 P3E_CPU0_PE1_SS_RXP<1>      B @BASEBOARD_FAB2_LIB.BASEBOARD_FAB2(SCH_1):P3E_CPU0_PE1_SS_RXP(1)

RES_0402-0.0,5%,1/16W,EMPTY,G2A  I468  R2U18
   1 P3E_CPU0_PE1_SS_R_RXP<2>      A @BASEBOARD_FAB2_LIB.BASEBOARD_FAB2(SCH_1):P3E_CPU0_PE1_SS_R_RXP(2)
   2 P3E_CPU0_PE1_SS_RXP<2>      B @BASEBOARD_FAB2_LIB.BASEBOARD_FAB2(SCH_1):P3E_CPU0_PE1_SS_RXP(2)

RES_0402-0.0,5%,1/16W,EMPTY,G2A  I469  R2U20
   1 P3E_CPU0_PE1_SS_R_RXP<3>      A @BASEBOARD_FAB2_LIB.BASEBOARD_FAB2(SCH_1):P3E_CPU0_PE1_SS_R_RXP(3)
   2 P3E_CPU0_PE1_SS_RXP<3>      B @BASEBOARD_FAB2_LIB.BASEBOARD_FAB2(SCH_1):P3E_CPU0_PE1_SS_RXP(3)

RES_0402-0.0,5%,1/16W,EMPTY,G2A  I470  R2U22
   1 P3E_CPU0_PE1_SS_R_RXP<4>      A @BASEBOARD_FAB2_LIB.BASEBOARD_FAB2(SCH_1):P3E_CPU0_PE1_SS_R_RXP(4)
   2 P3E_CPU0_PE1_SS_RXP<4>      B @BASEBOARD_FAB2_LIB.BASEBOARD_FAB2(SCH_1):P3E_CPU0_PE1_SS_RXP(4)

RES_0402-0.0,5%,1/16W,EMPTY,G2A  I471  R2U24
   1 P3E_CPU0_PE1_SS_R_RXP<5>      A @BASEBOARD_FAB2_LIB.BASEBOARD_FAB2(SCH_1):P3E_CPU0_PE1_SS_R_RXP(5)
   2 P3E_CPU0_PE1_SS_RXP<5>      B @BASEBOARD_FAB2_LIB.BASEBOARD_FAB2(SCH_1):P3E_CPU0_PE1_SS_RXP(5)

RES_0402-0.0,5%,1/16W,EMPTY,G2A  I472  R2U26
   1 P3E_CPU0_PE1_SS_R_RXP<6>      A @BASEBOARD_FAB2_LIB.BASEBOARD_FAB2(SCH_1):P3E_CPU0_PE1_SS_R_RXP(6)
   2 P3E_CPU0_PE1_SS_RXP<6>      B @BASEBOARD_FAB2_LIB.BASEBOARD_FAB2(SCH_1):P3E_CPU0_PE1_SS_RXP(6)

RES_0402-0.0,5%,1/16W,EMPTY,G2A  I473  R2U28
   1 P3E_CPU0_PE1_SS_R_RXP<7>      A @BASEBOARD_FAB2_LIB.BASEBOARD_FAB2(SCH_1):P3E_CPU0_PE1_SS_R_RXP(7)
   2 P3E_CPU0_PE1_SS_RXP<7>      B @BASEBOARD_FAB2_LIB.BASEBOARD_FAB2(SCH_1):P3E_CPU0_PE1_SS_RXP(7)


DRAWING: @BASEBOARD_FAB2_LIB.BASEBOARD_FAB2(SCH_1):PAGE108 

CAP_A_0402V-0.1UF,16V,10%,X7R,A  I1  C2U20
   1   P12V      A @BASEBOARD_FAB2_LIB.BASEBOARD_FAB2(SCH_1):P12V
   2    GND      B @BASEBOARD_FAB2_LIB.BASEBOARD_FAB2(SCH_1):GND

CAP_A_0402V-0.1UF,16V,10%,X7R,A  I2  C2U24
   1   P12V      A @BASEBOARD_FAB2_LIB.BASEBOARD_FAB2(SCH_1):P12V
   2    GND      B @BASEBOARD_FAB2_LIB.BASEBOARD_FAB2(SCH_1):GND

CAP_A_0402V-0.1UF,16V,10%,X7R,A  I5  C2U21
   1   P3V3      A @BASEBOARD_FAB2_LIB.BASEBOARD_FAB2(SCH_1):P3V3
   2    GND      B @BASEBOARD_FAB2_LIB.BASEBOARD_FAB2(SCH_1):GND

CAP_A_0402V-0.1UF,16V,10%,X7R,A  I7  C2U25
   1   P3V3      A @BASEBOARD_FAB2_LIB.BASEBOARD_FAB2(SCH_1):P3V3
   2    GND      B @BASEBOARD_FAB2_LIB.BASEBOARD_FAB2(SCH_1):GND

RES_0402-0.0,5%,1/16W,CHIP,G21A  I173  R2U37
   1 RST_PCIE_RISER1_PERST_N      A @BASEBOARD_FAB2_LIB.BASEBOARD_FAB2(SCH_1):RST_PCIE_RISER1_PERST_N
   2 RST_PCIE_RISER1_PERST_R_N      B @BASEBOARD_FAB2_LIB.BASEBOARD_FAB2(SCH_1):RST_PCIE_RISER1_PERST_R_N

SCONN200_H68296001_SM-CONN,H68A  I258  J8G1
   1   P12V    IO1 @BASEBOARD_FAB2_LIB.BASEBOARD_FAB2(SCH_1):P12V
   2   P12V    IO2 @BASEBOARD_FAB2_LIB.BASEBOARD_FAB2(SCH_1):P12V
   3   P12V    IO3 @BASEBOARD_FAB2_LIB.BASEBOARD_FAB2(SCH_1):P12V
   4   P12V    IO4 @BASEBOARD_FAB2_LIB.BASEBOARD_FAB2(SCH_1):P12V
   5   P12V    IO5 @BASEBOARD_FAB2_LIB.BASEBOARD_FAB2(SCH_1):P12V
   6   P12V    IO6 @BASEBOARD_FAB2_LIB.BASEBOARD_FAB2(SCH_1):P12V
   7   P12V    IO7 @BASEBOARD_FAB2_LIB.BASEBOARD_FAB2(SCH_1):P12V
   8   P12V    IO8 @BASEBOARD_FAB2_LIB.BASEBOARD_FAB2(SCH_1):P12V
   9   P12V    IO9 @BASEBOARD_FAB2_LIB.BASEBOARD_FAB2(SCH_1):P12V
  10   P12V   IO10 @BASEBOARD_FAB2_LIB.BASEBOARD_FAB2(SCH_1):P12V
  11   P12V   IO11 @BASEBOARD_FAB2_LIB.BASEBOARD_FAB2(SCH_1):P12V
  12   P12V   IO12 @BASEBOARD_FAB2_LIB.BASEBOARD_FAB2(SCH_1):P12V
  13    GND   IO13 @BASEBOARD_FAB2_LIB.BASEBOARD_FAB2(SCH_1):GND
  14    GND   IO14 @BASEBOARD_FAB2_LIB.BASEBOARD_FAB2(SCH_1):GND
  15 SMB_SLOTX24_STBY_LVC3_SDA_R2   IO15 @BASEBOARD_FAB2_LIB.BASEBOARD_FAB2(SCH_1):SMB_SLOTX24_STBY_LVC3_SDA_R2
  16 IRQ_OOB_MGMT_RISER_ALERT_N   IO16 @BASEBOARD_FAB2_LIB.BASEBOARD_FAB2(SCH_1):IRQ_OOB_MGMT_RISER_ALERT_N
  17 SMB_SLOTX24_STBY_LVC3_SCL_R2   IO17 @BASEBOARD_FAB2_LIB.BASEBOARD_FAB2(SCH_1):SMB_SLOTX24_STBY_LVC3_SCL_R2
  18 FM_SLT_CFG1   IO18 @BASEBOARD_FAB2_LIB.BASEBOARD_FAB2(SCH_1):FM_SLT_CFG1
  19 FM_SLT_CFG0   IO19 @BASEBOARD_FAB2_LIB.BASEBOARD_FAB2(SCH_1):FM_SLT_CFG0
  20 FM_PWRBRK_SLOT_N   IO20 @BASEBOARD_FAB2_LIB.BASEBOARD_FAB2(SCH_1):FM_PWRBRK_SLOT_N
  21   P3V3   IO21 @BASEBOARD_FAB2_LIB.BASEBOARD_FAB2(SCH_1):P3V3
  22   P3V3   IO22 @BASEBOARD_FAB2_LIB.BASEBOARD_FAB2(SCH_1):P3V3
  23   P3V3   IO23 @BASEBOARD_FAB2_LIB.BASEBOARD_FAB2(SCH_1):P3V3
  24   P3V3   IO24 @BASEBOARD_FAB2_LIB.BASEBOARD_FAB2(SCH_1):P3V3
  25 P3V3_STBY   IO25 @BASEBOARD_FAB2_LIB.BASEBOARD_FAB2(SCH_1):P3V3_STBY
  26    GND   IO26 @BASEBOARD_FAB2_LIB.BASEBOARD_FAB2(SCH_1):GND
  27 FM_PRSNT_2_1_N   IO27 @BASEBOARD_FAB2_LIB.BASEBOARD_FAB2(SCH_1):FM_PRSNT_2_1_N
  28 FM_PE_SLOTX24_WAKE_N   IO28 @BASEBOARD_FAB2_LIB.BASEBOARD_FAB2(SCH_1):FM_PE_SLOTX24_WAKE_N
  29 RST_PCIE_RISER1_PERST_R_N   IO29 @BASEBOARD_FAB2_LIB.BASEBOARD_FAB2(SCH_1):RST_PCIE_RISER1_PERST_R_N
  30 FM_PRSNT_2_2_N   IO30 @BASEBOARD_FAB2_LIB.BASEBOARD_FAB2(SCH_1):FM_PRSNT_2_2_N
  31    GND   IO31 @BASEBOARD_FAB2_LIB.BASEBOARD_FAB2(SCH_1):GND
  32 FM_PRSNT_2_3_N   IO32 @BASEBOARD_FAB2_LIB.BASEBOARD_FAB2(SCH_1):FM_PRSNT_2_3_N
  33 CLK_100M_PCH_SLOTX24_S5_DP   IO33 @BASEBOARD_FAB2_LIB.BASEBOARD_FAB2(SCH_1):CLK_100M_PCH_SLOTX24_S5_DP
  34    GND   IO34 @BASEBOARD_FAB2_LIB.BASEBOARD_FAB2(SCH_1):GND
  35 CLK_100M_PCH_SLOTX24_S5_DN   IO35 @BASEBOARD_FAB2_LIB.BASEBOARD_FAB2(SCH_1):CLK_100M_PCH_SLOTX24_S5_DN
  36 CLK_100M_PCH_SLOTX24_S4_DP   IO36 @BASEBOARD_FAB2_LIB.BASEBOARD_FAB2(SCH_1):CLK_100M_PCH_SLOTX24_S4_DP
  37    GND   IO37 @BASEBOARD_FAB2_LIB.BASEBOARD_FAB2(SCH_1):GND
  38 CLK_100M_PCH_SLOTX24_S4_DN   IO38 @BASEBOARD_FAB2_LIB.BASEBOARD_FAB2(SCH_1):CLK_100M_PCH_SLOTX24_S4_DN
  39 CLK_100M_PCH_SLOTX24_S0_DP   IO39 @BASEBOARD_FAB2_LIB.BASEBOARD_FAB2(SCH_1):CLK_100M_PCH_SLOTX24_S0_DP
  40    GND   IO40 @BASEBOARD_FAB2_LIB.BASEBOARD_FAB2(SCH_1):GND
  41 CLK_100M_PCH_SLOTX24_S0_DN   IO41 @BASEBOARD_FAB2_LIB.BASEBOARD_FAB2(SCH_1):CLK_100M_PCH_SLOTX24_S0_DN
  42 CLK_100M_PCH_SLOTX24_S1_DP   IO42 @BASEBOARD_FAB2_LIB.BASEBOARD_FAB2(SCH_1):CLK_100M_PCH_SLOTX24_S1_DP
  43    GND   IO43 @BASEBOARD_FAB2_LIB.BASEBOARD_FAB2(SCH_1):GND
  44 CLK_100M_PCH_SLOTX24_S1_DN   IO44 @BASEBOARD_FAB2_LIB.BASEBOARD_FAB2(SCH_1):CLK_100M_PCH_SLOTX24_S1_DN
  45 CLK_100M_PCH_SLOTX24_S3_DP   IO45 @BASEBOARD_FAB2_LIB.BASEBOARD_FAB2(SCH_1):CLK_100M_PCH_SLOTX24_S3_DP
  46    GND   IO46 @BASEBOARD_FAB2_LIB.BASEBOARD_FAB2(SCH_1):GND
  47 CLK_100M_PCH_SLOTX24_S3_DN   IO47 @BASEBOARD_FAB2_LIB.BASEBOARD_FAB2(SCH_1):CLK_100M_PCH_SLOTX24_S3_DN
  48 CLK_100M_PCH_SLOTX24_S2_DP   IO48 @BASEBOARD_FAB2_LIB.BASEBOARD_FAB2(SCH_1):CLK_100M_PCH_SLOTX24_S2_DP
  49    GND   IO49 @BASEBOARD_FAB2_LIB.BASEBOARD_FAB2(SCH_1):GND
  50 CLK_100M_PCH_SLOTX24_S2_DN   IO50 @BASEBOARD_FAB2_LIB.BASEBOARD_FAB2(SCH_1):CLK_100M_PCH_SLOTX24_S2_DN
  51 P3E_CPU0_PE1_PCH_CON_TXN<15>   IO51 @BASEBOARD_FAB2_LIB.BASEBOARD_FAB2(SCH_1):P3E_CPU0_PE1_PCH_CON_TXN(15)
  52    GND   IO52 @BASEBOARD_FAB2_LIB.BASEBOARD_FAB2(SCH_1):GND
  53 P3E_CPU0_PE1_PCH_CON_TXP<15>   IO53 @BASEBOARD_FAB2_LIB.BASEBOARD_FAB2(SCH_1):P3E_CPU0_PE1_PCH_CON_TXP(15)
  54 P3E_CPU0_PE1_PCH_CON_RXN<15>   IO54 @BASEBOARD_FAB2_LIB.BASEBOARD_FAB2(SCH_1):P3E_CPU0_PE1_PCH_CON_RXN(15)
  55    GND   IO55 @BASEBOARD_FAB2_LIB.BASEBOARD_FAB2(SCH_1):GND
  56 P3E_CPU0_PE1_PCH_CON_RXP<15>   IO56 @BASEBOARD_FAB2_LIB.BASEBOARD_FAB2(SCH_1):P3E_CPU0_PE1_PCH_CON_RXP(15)
  57 P3E_CPU0_PE1_PCH_CON_TXP<14>   IO57 @BASEBOARD_FAB2_LIB.BASEBOARD_FAB2(SCH_1):P3E_CPU0_PE1_PCH_CON_TXP(14)
  58    GND   IO58 @BASEBOARD_FAB2_LIB.BASEBOARD_FAB2(SCH_1):GND
  59 P3E_CPU0_PE1_PCH_CON_TXN<14>   IO59 @BASEBOARD_FAB2_LIB.BASEBOARD_FAB2(SCH_1):P3E_CPU0_PE1_PCH_CON_TXN(14)
  60 P3E_CPU0_PE1_PCH_CON_RXN<14>   IO60 @BASEBOARD_FAB2_LIB.BASEBOARD_FAB2(SCH_1):P3E_CPU0_PE1_PCH_CON_RXN(14)
  61    GND   IO61 @BASEBOARD_FAB2_LIB.BASEBOARD_FAB2(SCH_1):GND
  62 P3E_CPU0_PE1_PCH_CON_RXP<14>   IO62 @BASEBOARD_FAB2_LIB.BASEBOARD_FAB2(SCH_1):P3E_CPU0_PE1_PCH_CON_RXP(14)
  63 FM_PRSNT_2_4_N   IO63 @BASEBOARD_FAB2_LIB.BASEBOARD_FAB2(SCH_1):FM_PRSNT_2_4_N
  64    GND   IO64 @BASEBOARD_FAB2_LIB.BASEBOARD_FAB2(SCH_1):GND
  65    GND   IO65 @BASEBOARD_FAB2_LIB.BASEBOARD_FAB2(SCH_1):GND
  66 FM_PRSNT_2_5_N   IO66 @BASEBOARD_FAB2_LIB.BASEBOARD_FAB2(SCH_1):FM_PRSNT_2_5_N
  67 P3E_CPU0_PE1_PCH_CON_TXN<13>   IO67 @BASEBOARD_FAB2_LIB.BASEBOARD_FAB2(SCH_1):P3E_CPU0_PE1_PCH_CON_TXN(13)
  68    GND   IO68 @BASEBOARD_FAB2_LIB.BASEBOARD_FAB2(SCH_1):GND
  69 P3E_CPU0_PE1_PCH_CON_TXP<13>   IO69 @BASEBOARD_FAB2_LIB.BASEBOARD_FAB2(SCH_1):P3E_CPU0_PE1_PCH_CON_TXP(13)
  70 P3E_CPU0_PE1_PCH_CON_RXN<13>   IO70 @BASEBOARD_FAB2_LIB.BASEBOARD_FAB2(SCH_1):P3E_CPU0_PE1_PCH_CON_RXN(13)
  71    GND   IO71 @BASEBOARD_FAB2_LIB.BASEBOARD_FAB2(SCH_1):GND
  72 P3E_CPU0_PE1_PCH_CON_RXP<13>   IO72 @BASEBOARD_FAB2_LIB.BASEBOARD_FAB2(SCH_1):P3E_CPU0_PE1_PCH_CON_RXP(13)
  73 P3E_CPU0_PE1_PCH_CON_TXN<12>   IO73 @BASEBOARD_FAB2_LIB.BASEBOARD_FAB2(SCH_1):P3E_CPU0_PE1_PCH_CON_TXN(12)
  74    GND   IO74 @BASEBOARD_FAB2_LIB.BASEBOARD_FAB2(SCH_1):GND
  75 P3E_CPU0_PE1_PCH_CON_TXP<12>   IO75 @BASEBOARD_FAB2_LIB.BASEBOARD_FAB2(SCH_1):P3E_CPU0_PE1_PCH_CON_TXP(12)
  76 P3E_CPU0_PE1_PCH_CON_RXN<12>   IO76 @BASEBOARD_FAB2_LIB.BASEBOARD_FAB2(SCH_1):P3E_CPU0_PE1_PCH_CON_RXN(12)
  77    GND   IO77 @BASEBOARD_FAB2_LIB.BASEBOARD_FAB2(SCH_1):GND
  78 P3E_CPU0_PE1_PCH_CON_RXP<12>   IO78 @BASEBOARD_FAB2_LIB.BASEBOARD_FAB2(SCH_1):P3E_CPU0_PE1_PCH_CON_RXP(12)
  79 P3E_CPU0_PE1_PCH_CON_TXN<11>   IO79 @BASEBOARD_FAB2_LIB.BASEBOARD_FAB2(SCH_1):P3E_CPU0_PE1_PCH_CON_TXN(11)
  80    GND   IO80 @BASEBOARD_FAB2_LIB.BASEBOARD_FAB2(SCH_1):GND
  81 P3E_CPU0_PE1_PCH_CON_TXP<11>   IO81 @BASEBOARD_FAB2_LIB.BASEBOARD_FAB2(SCH_1):P3E_CPU0_PE1_PCH_CON_TXP(11)
  82 P3E_CPU0_PE1_PCH_CON_RXN<11>   IO82 @BASEBOARD_FAB2_LIB.BASEBOARD_FAB2(SCH_1):P3E_CPU0_PE1_PCH_CON_RXN(11)
  83    GND   IO83 @BASEBOARD_FAB2_LIB.BASEBOARD_FAB2(SCH_1):GND
  84 P3E_CPU0_PE1_PCH_CON_RXP<11>   IO84 @BASEBOARD_FAB2_LIB.BASEBOARD_FAB2(SCH_1):P3E_CPU0_PE1_PCH_CON_RXP(11)
  85 P3E_CPU0_PE1_PCH_CON_TXN<10>   IO85 @BASEBOARD_FAB2_LIB.BASEBOARD_FAB2(SCH_1):P3E_CPU0_PE1_PCH_CON_TXN(10)
  86    GND   IO86 @BASEBOARD_FAB2_LIB.BASEBOARD_FAB2(SCH_1):GND
  87 P3E_CPU0_PE1_PCH_CON_TXP<10>   IO87 @BASEBOARD_FAB2_LIB.BASEBOARD_FAB2(SCH_1):P3E_CPU0_PE1_PCH_CON_TXP(10)
  88 P3E_CPU0_PE1_PCH_CON_RXN<10>   IO88 @BASEBOARD_FAB2_LIB.BASEBOARD_FAB2(SCH_1):P3E_CPU0_PE1_PCH_CON_RXN(10)
  89    GND   IO89 @BASEBOARD_FAB2_LIB.BASEBOARD_FAB2(SCH_1):GND
  90 P3E_CPU0_PE1_PCH_CON_RXP<10>   IO90 @BASEBOARD_FAB2_LIB.BASEBOARD_FAB2(SCH_1):P3E_CPU0_PE1_PCH_CON_RXP(10)
  91 P3E_CPU0_PE1_PCH_CON_TXN<9>   IO91 @BASEBOARD_FAB2_LIB.BASEBOARD_FAB2(SCH_1):P3E_CPU0_PE1_PCH_CON_TXN(9)
  92    GND   IO92 @BASEBOARD_FAB2_LIB.BASEBOARD_FAB2(SCH_1):GND
  93 P3E_CPU0_PE1_PCH_CON_TXP<9>   IO93 @BASEBOARD_FAB2_LIB.BASEBOARD_FAB2(SCH_1):P3E_CPU0_PE1_PCH_CON_TXP(9)
  94 P3E_CPU0_PE1_PCH_CON_RXP<9>   IO94 @BASEBOARD_FAB2_LIB.BASEBOARD_FAB2(SCH_1):P3E_CPU0_PE1_PCH_CON_RXP(9)
  95    GND   IO95 @BASEBOARD_FAB2_LIB.BASEBOARD_FAB2(SCH_1):GND
  96 P3E_CPU0_PE1_PCH_CON_RXN<9>   IO96 @BASEBOARD_FAB2_LIB.BASEBOARD_FAB2(SCH_1):P3E_CPU0_PE1_PCH_CON_RXN(9)
  97 P3E_CPU0_PE1_PCH_CON_TXN<8>   IO97 @BASEBOARD_FAB2_LIB.BASEBOARD_FAB2(SCH_1):P3E_CPU0_PE1_PCH_CON_TXN(8)
  98    GND   IO98 @BASEBOARD_FAB2_LIB.BASEBOARD_FAB2(SCH_1):GND
  99 P3E_CPU0_PE1_PCH_CON_TXP<8>   IO99 @BASEBOARD_FAB2_LIB.BASEBOARD_FAB2(SCH_1):P3E_CPU0_PE1_PCH_CON_TXP(8)
 100 P3E_CPU0_PE1_PCH_CON_RXN<8>  IO100 @BASEBOARD_FAB2_LIB.BASEBOARD_FAB2(SCH_1):P3E_CPU0_PE1_PCH_CON_RXN(8)
 MH1    GND    MH1 @BASEBOARD_FAB2_LIB.BASEBOARD_FAB2(SCH_1):GND
 MH2    GND    MH2 @BASEBOARD_FAB2_LIB.BASEBOARD_FAB2(SCH_1):GND

CAP_A_0402V-0.1UF,16V,10%,X7R,A  I315  C2U23
   1 P3V3_STBY      A @BASEBOARD_FAB2_LIB.BASEBOARD_FAB2(SCH_1):P3V3_STBY
   2    GND      B @BASEBOARD_FAB2_LIB.BASEBOARD_FAB2(SCH_1):GND

CAP_A_0402V-0.1UF,16V,10%,X7R,A  I318  C2U22
   1 P3V3_STBY      A @BASEBOARD_FAB2_LIB.BASEBOARD_FAB2(SCH_1):P3V3_STBY
   2    GND      B @BASEBOARD_FAB2_LIB.BASEBOARD_FAB2(SCH_1):GND

RES_0402-20.0,1%,1/16W,EMPTY,GA  I320  R2U35
   1 SMB_SLOTX24_PCH_STBY_LVC3_SDA      A @BASEBOARD_FAB2_LIB.BASEBOARD_FAB2(SCH_1):SMB_SLOTX24_PCH_STBY_LVC3_SDA
   2 SMB_SLOTX24_STBY_LVC3_SDA_R2      B @BASEBOARD_FAB2_LIB.BASEBOARD_FAB2(SCH_1):SMB_SLOTX24_STBY_LVC3_SDA_R2

RES_0402-20.0,1%,1/16W,CHIP,G2A  I330  R2U31
   1 SMB_SLOTX24_BMC_STBY_LVC3_SDA      A @BASEBOARD_FAB2_LIB.BASEBOARD_FAB2(SCH_1):SMB_SLOTX24_BMC_STBY_LVC3_SDA
   2 SMB_SLOTX24_STBY_LVC3_SDA_R2      B @BASEBOARD_FAB2_LIB.BASEBOARD_FAB2(SCH_1):SMB_SLOTX24_STBY_LVC3_SDA_R2

RES_0402-20.0,1%,1/16W,CHIP,G2A  I339  R2U32
   1 SMB_SLOTX24_BMC_STBY_LVC3_SCL      A @BASEBOARD_FAB2_LIB.BASEBOARD_FAB2(SCH_1):SMB_SLOTX24_BMC_STBY_LVC3_SCL
   2 SMB_SLOTX24_STBY_LVC3_SCL_R2      B @BASEBOARD_FAB2_LIB.BASEBOARD_FAB2(SCH_1):SMB_SLOTX24_STBY_LVC3_SCL_R2

RES_0402-20.0,1%,1/16W,EMPTY,GA  I340  R2U36
   1 SMB_SLOTX24_PCH_STBY_LVC3_SCL      A @BASEBOARD_FAB2_LIB.BASEBOARD_FAB2(SCH_1):SMB_SLOTX24_PCH_STBY_LVC3_SCL
   2 SMB_SLOTX24_STBY_LVC3_SCL_R2      B @BASEBOARD_FAB2_LIB.BASEBOARD_FAB2(SCH_1):SMB_SLOTX24_STBY_LVC3_SCL_R2

RES_0402-0.0,5%,1/16W,CHIP,G21A  I341  R7E22
   1 FM_PWRBRK_N      A @BASEBOARD_FAB2_LIB.BASEBOARD_FAB2(SCH_1):FM_PWRBRK_N
   2 FM_PWRBRK_SLOT_N      B @BASEBOARD_FAB2_LIB.BASEBOARD_FAB2(SCH_1):FM_PWRBRK_SLOT_N

RES_0402-4.75K,1%,1/16W,CHIP,GA  I343  R7E21
   1   P3V3      A @BASEBOARD_FAB2_LIB.BASEBOARD_FAB2(SCH_1):P3V3
   2 FM_PWRBRK_N      B @BASEBOARD_FAB2_LIB.BASEBOARD_FAB2(SCH_1):FM_PWRBRK_N


DRAWING: @BASEBOARD_FAB2_LIB.BASEBOARD_FAB2(SCH_1):PAGE110 

RCC_DFX1940_ID4-EMPTY,N_A  I1  TC9F1
   1    GND    GND @BASEBOARD_FAB2_LIB.BASEBOARD_FAB2(SCH_1):GND
   2 RCC_DFX_1940_3    IO1 @BASEBOARD_FAB2_LIB.BASEBOARD_FAB2(SCH_1):RCC_DFX_1940_3
   3 RCC_DFX_1940_3    IO2 @BASEBOARD_FAB2_LIB.BASEBOARD_FAB2(SCH_1):RCC_DFX_1940_3

RCC_DFX1940_ID4-EMPTY,N_A  I3  TC1G1
   1    GND    GND @BASEBOARD_FAB2_LIB.BASEBOARD_FAB2(SCH_1):GND
   2 RCC_DFX_1940_4    IO1 @BASEBOARD_FAB2_LIB.BASEBOARD_FAB2(SCH_1):RCC_DFX_1940_4
   3 RCC_DFX_1940_4    IO2 @BASEBOARD_FAB2_LIB.BASEBOARD_FAB2(SCH_1):RCC_DFX_1940_4

RCC_DFX1940_ID4-EMPTY,N_A  I7  TC1A1
   1    GND    GND @BASEBOARD_FAB2_LIB.BASEBOARD_FAB2(SCH_1):GND
   2 RCC_DFX_1940_1    IO1 @BASEBOARD_FAB2_LIB.BASEBOARD_FAB2(SCH_1):RCC_DFX_1940_1
   3 RCC_DFX_1940_1    IO2 @BASEBOARD_FAB2_LIB.BASEBOARD_FAB2(SCH_1):RCC_DFX_1940_1

RCC_DFX1940_ID4-EMPTY,N_A  I9  TC9A1
   1    GND    GND @BASEBOARD_FAB2_LIB.BASEBOARD_FAB2(SCH_1):GND
   2 RCC_DFX_1940_2    IO1 @BASEBOARD_FAB2_LIB.BASEBOARD_FAB2(SCH_1):RCC_DFX_1940_2
   3 RCC_DFX_1940_2    IO2 @BASEBOARD_FAB2_LIB.BASEBOARD_FAB2(SCH_1):RCC_DFX_1940_2

SNLABEL_A_LABEL-EMPTY,N_A  I11  LB2F1
SNLABEL_A_LABEL-EMPTY,N_A  I12  LB5F1
SNLABEL_A_LABEL-EMPTY,N_A  I13  LB2B1
SNLABEL_A_LABEL-EMPTY,N_A  I14  LB5B1
SNLABEL_A_LABEL-EMPTY,N_A  I15  LB6T1

DRAWING: @BASEBOARD_FAB2_LIB.BASEBOARD_FAB2(SCH_1):PAGE111 

RES_0402-1.00K,1%,1/16W,CHIP,GA  I6  R1L13
   1 XDP_SYSPWROK      A @BASEBOARD_FAB2_LIB.BASEBOARD_FAB2(SCH_1):XDP_SYSPWROK
   2 P3V3_STBY      B @BASEBOARD_FAB2_LIB.BASEBOARD_FAB2(SCH_1):P3V3_STBY

CAP_A_0402V-0.1UF,16V,10%,X7R,A  I10  C9A2
   1 XDP_SYSPWROK      A @BASEBOARD_FAB2_LIB.BASEBOARD_FAB2(SCH_1):XDP_SYSPWROK
   2    GND      B @BASEBOARD_FAB2_LIB.BASEBOARD_FAB2(SCH_1):GND

RES_0402-1.00K,1%,1/16W,CHIP,GA  I11  R9A14
   1 XDP_RST_CO_N      A @BASEBOARD_FAB2_LIB.BASEBOARD_FAB2(SCH_1):XDP_RST_CO_N
   2 P3V3_STBY      B @BASEBOARD_FAB2_LIB.BASEBOARD_FAB2(SCH_1):P3V3_STBY

CAP_A_0402V-0.1UF,16V,10%,X7R,A  I12  C9A5
   1 XDP_RST_CO_N      A @BASEBOARD_FAB2_LIB.BASEBOARD_FAB2(SCH_1):XDP_RST_CO_N
   2    GND      B @BASEBOARD_FAB2_LIB.BASEBOARD_FAB2(SCH_1):GND

RES_0402-1.00K,1%,1/16W,CHIP,GA  I13  R1L23
   1 XDP_PWRGD_RST_N      A @BASEBOARD_FAB2_LIB.BASEBOARD_FAB2(SCH_1):XDP_PWRGD_RST_N
   2 P3V3_STBY      B @BASEBOARD_FAB2_LIB.BASEBOARD_FAB2(SCH_1):P3V3_STBY

CAP_A_0402V-0.1UF,16V,10%,X7R,A  I14  C1L8
   1 XDP_PWRGD_RST_N      A @BASEBOARD_FAB2_LIB.BASEBOARD_FAB2(SCH_1):XDP_PWRGD_RST_N
   2    GND      B @BASEBOARD_FAB2_LIB.BASEBOARD_FAB2(SCH_1):GND

CAP_A_0402V-1.0UF,6.3V,10%,X6SA  I25  C9A6
   1 P1V05_PCH_STBY      A @BASEBOARD_FAB2_LIB.BASEBOARD_FAB2(SCH_1):P1V05_PCH_STBY
   2    GND      B @BASEBOARD_FAB2_LIB.BASEBOARD_FAB2(SCH_1):GND

SCONN60_C21100002_SMLF-CONN,C2A  I26  J9A3
   1 XDP_DEBUG_CONSENT_N    IO1 @BASEBOARD_FAB2_LIB.BASEBOARD_FAB2(SCH_1):XDP_DEBUG_CONSENT_N
   3 XDP_PREQ_N    IO3 @BASEBOARD_FAB2_LIB.BASEBOARD_FAB2(SCH_1):XDP_PREQ_N
   5 XDP_PRDY_N    IO5 @BASEBOARD_FAB2_LIB.BASEBOARD_FAB2(SCH_1):XDP_PRDY_N
   7    GND    IO7 @BASEBOARD_FAB2_LIB.BASEBOARD_FAB2(SCH_1):GND
   9 TP_XDP_OBSDATA_A0    IO9 @BASEBOARD_FAB2_LIB.BASEBOARD_FAB2(SCH_1):TP_XDP_OBSDATA_A0
  11 TP_XDP_OBSDATA_A1   IO11 @BASEBOARD_FAB2_LIB.BASEBOARD_FAB2(SCH_1):TP_XDP_OBSDATA_A1
  13    GND   IO13 @BASEBOARD_FAB2_LIB.BASEBOARD_FAB2(SCH_1):GND
  15 TP_XDP_OBSDATA_A2   IO15 @BASEBOARD_FAB2_LIB.BASEBOARD_FAB2(SCH_1):TP_XDP_OBSDATA_A2
  17 TP_XDP_OBSDATA_A3   IO17 @BASEBOARD_FAB2_LIB.BASEBOARD_FAB2(SCH_1):TP_XDP_OBSDATA_A3
  19    GND   IO19 @BASEBOARD_FAB2_LIB.BASEBOARD_FAB2(SCH_1):GND
  21 TP_XDP_OBSFN_B0   IO21 @BASEBOARD_FAB2_LIB.BASEBOARD_FAB2(SCH_1):TP_XDP_OBSFN_B0
  23 TP_XDP_OBSFN_B1   IO23 @BASEBOARD_FAB2_LIB.BASEBOARD_FAB2(SCH_1):TP_XDP_OBSFN_B1
  25    GND   IO25 @BASEBOARD_FAB2_LIB.BASEBOARD_FAB2(SCH_1):GND
  27 TP_XDP_OBSDATA_B0   IO27 @BASEBOARD_FAB2_LIB.BASEBOARD_FAB2(SCH_1):TP_XDP_OBSDATA_B0
  29 TP_XDP_OBSDATA_B1   IO29 @BASEBOARD_FAB2_LIB.BASEBOARD_FAB2(SCH_1):TP_XDP_OBSDATA_B1
  31    GND   IO31 @BASEBOARD_FAB2_LIB.BASEBOARD_FAB2(SCH_1):GND
  33 TP_XDP_OBSDATA_B2   IO33 @BASEBOARD_FAB2_LIB.BASEBOARD_FAB2(SCH_1):TP_XDP_OBSDATA_B2
  35 TP_XDP_OBSDATA_B3   IO35 @BASEBOARD_FAB2_LIB.BASEBOARD_FAB2(SCH_1):TP_XDP_OBSDATA_B3
  37    GND   IO37 @BASEBOARD_FAB2_LIB.BASEBOARD_FAB2(SCH_1):GND
  39 XDP_RSMRST_N   IO39 @BASEBOARD_FAB2_LIB.BASEBOARD_FAB2(SCH_1):XDP_RSMRST_N
  41 XDP_PWRGD_RST_N   IO41 @BASEBOARD_FAB2_LIB.BASEBOARD_FAB2(SCH_1):XDP_PWRGD_RST_N
  43 P1V05_PCH_STBY   IO43 @BASEBOARD_FAB2_LIB.BASEBOARD_FAB2(SCH_1):P1V05_PCH_STBY
  45 XDP_CPU_PWR_DEBUG_N   IO45 @BASEBOARD_FAB2_LIB.BASEBOARD_FAB2(SCH_1):XDP_CPU_PWR_DEBUG_N
  47 XDP_SYSPWROK   IO47 @BASEBOARD_FAB2_LIB.BASEBOARD_FAB2(SCH_1):XDP_SYSPWROK
  49    GND   IO49 @BASEBOARD_FAB2_LIB.BASEBOARD_FAB2(SCH_1):GND
   2    GND    IO2 @BASEBOARD_FAB2_LIB.BASEBOARD_FAB2(SCH_1):GND
   4 TP_XDP_CPU_OBSFN_C0    IO4 @BASEBOARD_FAB2_LIB.BASEBOARD_FAB2(SCH_1):TP_XDP_CPU_OBSFN_C0
   6 XDP_SPI_PCH_MOSI_BOOT_HALT_N    IO6 @BASEBOARD_FAB2_LIB.BASEBOARD_FAB2(SCH_1):XDP_SPI_PCH_MOSI_BOOT_HALT_N
   8    GND    IO8 @BASEBOARD_FAB2_LIB.BASEBOARD_FAB2(SCH_1):GND
  10 TP_XDP_CPU_OBSDATA_C0   IO10 @BASEBOARD_FAB2_LIB.BASEBOARD_FAB2(SCH_1):TP_XDP_CPU_OBSDATA_C0
  12 TP_XDP_CPU_OBSDATA_C1   IO12 @BASEBOARD_FAB2_LIB.BASEBOARD_FAB2(SCH_1):TP_XDP_CPU_OBSDATA_C1
  14    GND   IO14 @BASEBOARD_FAB2_LIB.BASEBOARD_FAB2(SCH_1):GND
  16 TP_XDP_CPU_OBSDATA_C2   IO16 @BASEBOARD_FAB2_LIB.BASEBOARD_FAB2(SCH_1):TP_XDP_CPU_OBSDATA_C2
  18 TP_XDP_CPU_OBSDATA_C3   IO18 @BASEBOARD_FAB2_LIB.BASEBOARD_FAB2(SCH_1):TP_XDP_CPU_OBSDATA_C3
  20    GND   IO20 @BASEBOARD_FAB2_LIB.BASEBOARD_FAB2(SCH_1):GND
  22 XDP_OBSFN_B0_MBP6_N   IO22 @BASEBOARD_FAB2_LIB.BASEBOARD_FAB2(SCH_1):XDP_OBSFN_B0_MBP6_N
  24 XDP_OBSFN_B1_MBP7_N   IO24 @BASEBOARD_FAB2_LIB.BASEBOARD_FAB2(SCH_1):XDP_OBSFN_B1_MBP7_N
  26    GND   IO26 @BASEBOARD_FAB2_LIB.BASEBOARD_FAB2(SCH_1):GND
  28 TP_XDP_CPU_OBSDATA_D0   IO28 @BASEBOARD_FAB2_LIB.BASEBOARD_FAB2(SCH_1):TP_XDP_CPU_OBSDATA_D0
  30 TP_XDP_CPU_OBSDATA_D1   IO30 @BASEBOARD_FAB2_LIB.BASEBOARD_FAB2(SCH_1):TP_XDP_CPU_OBSDATA_D1
  32    GND   IO32 @BASEBOARD_FAB2_LIB.BASEBOARD_FAB2(SCH_1):GND
  34 TP_XDP_CPU_OBSDATA_D2   IO34 @BASEBOARD_FAB2_LIB.BASEBOARD_FAB2(SCH_1):TP_XDP_CPU_OBSDATA_D2
  36 TP_XDP_CPU_OBSDATA_D3   IO36 @BASEBOARD_FAB2_LIB.BASEBOARD_FAB2(SCH_1):TP_XDP_CPU_OBSDATA_D3
  38    GND   IO38 @BASEBOARD_FAB2_LIB.BASEBOARD_FAB2(SCH_1):GND
  40 CLK_100M_PCH_XDP_DP   IO40 @BASEBOARD_FAB2_LIB.BASEBOARD_FAB2(SCH_1):CLK_100M_PCH_XDP_DP
  42 CLK_100M_PCH_XDP_DN   IO42 @BASEBOARD_FAB2_LIB.BASEBOARD_FAB2(SCH_1):CLK_100M_PCH_XDP_DN
  44 P1V05_PCH_STBY   IO44 @BASEBOARD_FAB2_LIB.BASEBOARD_FAB2(SCH_1):P1V05_PCH_STBY
  46 XDP_ITP_PMODE   IO46 @BASEBOARD_FAB2_LIB.BASEBOARD_FAB2(SCH_1):XDP_ITP_PMODE
  48 XDP_RST_CO_N   IO48 @BASEBOARD_FAB2_LIB.BASEBOARD_FAB2(SCH_1):XDP_RST_CO_N
  50    GND   IO50 @BASEBOARD_FAB2_LIB.BASEBOARD_FAB2(SCH_1):GND
  51 SMB_HOST_STBY_LVC3_SDA   IO51 @BASEBOARD_FAB2_LIB.BASEBOARD_FAB2(SCH_1):SMB_HOST_STBY_LVC3_SDA
  52 XDP_TDO   IO52 @BASEBOARD_FAB2_LIB.BASEBOARD_FAB2(SCH_1):XDP_TDO
  53 SMB_HOST_STBY_LVC3_SCL   IO53 @BASEBOARD_FAB2_LIB.BASEBOARD_FAB2(SCH_1):SMB_HOST_STBY_LVC3_SCL
  54 XDP_TRST_N   IO54 @BASEBOARD_FAB2_LIB.BASEBOARD_FAB2(SCH_1):XDP_TRST_N
  55 XDP_PCH_TCK1   IO55 @BASEBOARD_FAB2_LIB.BASEBOARD_FAB2(SCH_1):XDP_PCH_TCK1
  56 XDP_TDI   IO56 @BASEBOARD_FAB2_LIB.BASEBOARD_FAB2(SCH_1):XDP_TDI
  57 XDP_CPU_TCK0   IO57 @BASEBOARD_FAB2_LIB.BASEBOARD_FAB2(SCH_1):XDP_CPU_TCK0
  58 XDP_TMS   IO58 @BASEBOARD_FAB2_LIB.BASEBOARD_FAB2(SCH_1):XDP_TMS
  59    GND   IO59 @BASEBOARD_FAB2_LIB.BASEBOARD_FAB2(SCH_1):GND
  60 XDP_PRESENT_N   IO60 @BASEBOARD_FAB2_LIB.BASEBOARD_FAB2(SCH_1):XDP_PRESENT_N

CAP_A_0402V-1.0UF,6.3V,10%,X6SA  I30  C1L5
   1 P1V05_PCH_STBY      A @BASEBOARD_FAB2_LIB.BASEBOARD_FAB2(SCH_1):P1V05_PCH_STBY
   2    GND      B @BASEBOARD_FAB2_LIB.BASEBOARD_FAB2(SCH_1):GND

RES_0402-1.00K,1%,1/16W,CHIP,GA  I37  R2P2
   1 SPI_PCH_IO2      A @BASEBOARD_FAB2_LIB.BASEBOARD_FAB2(SCH_1):SPI_PCH_IO2
   2 XDP_DEBUG_CONSENT_N      B @BASEBOARD_FAB2_LIB.BASEBOARD_FAB2(SCH_1):XDP_DEBUG_CONSENT_N

RES_0402-475.0,1%,1/16W,CHIP,GA  I55  R9A4
   1 XDP_PRESENT_N      A @BASEBOARD_FAB2_LIB.BASEBOARD_FAB2(SCH_1):XDP_PRESENT_N
   2 PVCCIO_CPU0      B @BASEBOARD_FAB2_LIB.BASEBOARD_FAB2(SCH_1):PVCCIO_CPU0

RES_0402-150.0,1%,1/16W,CHIP,GA  I56  R1L17
   1 XDP_CPU_PWR_DEBUG_N      A @BASEBOARD_FAB2_LIB.BASEBOARD_FAB2(SCH_1):XDP_CPU_PWR_DEBUG_N
   2 PVCCIO_CPU0      B @BASEBOARD_FAB2_LIB.BASEBOARD_FAB2(SCH_1):PVCCIO_CPU0

RES_0402-1.00K,1%,1/16W,CHIP,GA  I57  R9A17
   1 XDP_ITP_PMODE      A @BASEBOARD_FAB2_LIB.BASEBOARD_FAB2(SCH_1):XDP_ITP_PMODE
   2 P1V05_PCH_STBY      B @BASEBOARD_FAB2_LIB.BASEBOARD_FAB2(SCH_1):P1V05_PCH_STBY

CAP_A_0402V-0.1UF,16V,10%,X7R,A  I59  C9A4
   1 XDP_CPU_PWR_DEBUG_N      A @BASEBOARD_FAB2_LIB.BASEBOARD_FAB2(SCH_1):XDP_CPU_PWR_DEBUG_N
   2    GND      B @BASEBOARD_FAB2_LIB.BASEBOARD_FAB2(SCH_1):GND

RES_0402-1.00K,1%,1/16W,CHIP,GA  I60  R9A15
   1 RST_RSMRST_N      A @BASEBOARD_FAB2_LIB.BASEBOARD_FAB2(SCH_1):RST_RSMRST_N
   2 XDP_RSMRST_N      B @BASEBOARD_FAB2_LIB.BASEBOARD_FAB2(SCH_1):XDP_RSMRST_N

RES_0402-4.75K,1%,1/16W,CHIP,GA  I66  R1L28
   1 P3V3_STBY      A @BASEBOARD_FAB2_LIB.BASEBOARD_FAB2(SCH_1):P3V3_STBY
   2 FM_DEBUG_RST_BTN_R1_N      B @BASEBOARD_FAB2_LIB.BASEBOARD_FAB2(SCH_1):FM_DEBUG_RST_BTN_R1_N

RES_0402-33.2,1%,1/16W,CHIP,G2A  I68  R1L29
   1 FM_DEBUG_RST_BTN_R1_N      A @BASEBOARD_FAB2_LIB.BASEBOARD_FAB2(SCH_1):FM_DEBUG_RST_BTN_R1_N
   2 FM_DEBUG_RST_BTN_N      B @BASEBOARD_FAB2_LIB.BASEBOARD_FAB2(SCH_1):FM_DEBUG_RST_BTN_N

RES_0402-0.0,5%,1/16W,CHIP,G21A  I74  R9A3
   1 XDP_PCH_CPU_TCK0      A @BASEBOARD_FAB2_LIB.BASEBOARD_FAB2(SCH_1):XDP_PCH_CPU_TCK0
   2 XDP_CPU_TCK0      B @BASEBOARD_FAB2_LIB.BASEBOARD_FAB2(SCH_1):XDP_CPU_TCK0

RES_0402-33.2,1%,1/16W,EMPTY,GA  I83  R9A2
   1 XDP_PCH_CPU_TCK0      A @BASEBOARD_FAB2_LIB.BASEBOARD_FAB2(SCH_1):XDP_PCH_CPU_TCK0
   2 XDP_CPU_GTL_TCK_R2      B @BASEBOARD_FAB2_LIB.BASEBOARD_FAB2(SCH_1):XDP_CPU_GTL_TCK_R2

TTL1G07_A_SOP-74LVC1G07,IC,C88B  I85  U1L4
   2 XDP_RST_CO_N      A @BASEBOARD_FAB2_LIB.BASEBOARD_FAB2(SCH_1):XDP_RST_CO_N
   4 FM_DEBUG_RST_BTN_R1_N      Y @BASEBOARD_FAB2_LIB.BASEBOARD_FAB2(SCH_1):FM_DEBUG_RST_BTN_R1_N

CAP_A_0402V-0.1UF,16V,10%,X7R,A  I87  C1L11
   1 P3V3_STBY      A @BASEBOARD_FAB2_LIB.BASEBOARD_FAB2(SCH_1):P3V3_STBY
   2    GND      B @BASEBOARD_FAB2_LIB.BASEBOARD_FAB2(SCH_1):GND

RES_0402-1.00K,1%,1/16W,CHIP,GA  I89  R8E2
   1 XDP_SPI_PCH_MOSI_BOOT_HALT_N      A @BASEBOARD_FAB2_LIB.BASEBOARD_FAB2(SCH_1):XDP_SPI_PCH_MOSI_BOOT_HALT_N
   2 SPI_PCH_MOSI      B @BASEBOARD_FAB2_LIB.BASEBOARD_FAB2(SCH_1):SPI_PCH_MOSI

NPN_DUAL_SSOPLF-MBT3904,EMPTY,A  I93  Q9A1
   2 XDP_CPU_TCK_BUF   B<0> @BASEBOARD_FAB2_LIB.BASEBOARD_FAB2(SCH_1):XDP_CPU_TCK_BUF
   6 XDP_CPU_TCK_BUF   C<0> @BASEBOARD_FAB2_LIB.BASEBOARD_FAB2(SCH_1):XDP_CPU_TCK_BUF
   1 XDP_CPU_GTL_TCK_R2   E<0> @BASEBOARD_FAB2_LIB.BASEBOARD_FAB2(SCH_1):XDP_CPU_GTL_TCK_R2

NPN_DUAL_SSOPLF-MBT3904,EMPTY,A  I94  Q9A1
   5 XDP_CPU_TCK_BUF   B<0> @BASEBOARD_FAB2_LIB.BASEBOARD_FAB2(SCH_1):XDP_CPU_TCK_BUF
   3   P3V3   C<0> @BASEBOARD_FAB2_LIB.BASEBOARD_FAB2(SCH_1):P3V3
   4 XDP_CPU_TCK0   E<0> @BASEBOARD_FAB2_LIB.BASEBOARD_FAB2(SCH_1):XDP_CPU_TCK0

RES_0402-1.00K,1%,1/16W,EMPTY,A  I95  R9A1
   1   P3V3      A @BASEBOARD_FAB2_LIB.BASEBOARD_FAB2(SCH_1):P3V3
   2 XDP_CPU_TCK_BUF      B @BASEBOARD_FAB2_LIB.BASEBOARD_FAB2(SCH_1):XDP_CPU_TCK_BUF


DRAWING: @BASEBOARD_FAB2_LIB.BASEBOARD_FAB2(SCH_1):PAGE112 

NC7SB3157_SMLF-IC,C99406-001  I40  U1M7
   6 FM_CPU1_SKTOCC_LVT3_N      S @BASEBOARD_FAB2_LIB.BASEBOARD_FAB2(SCH_1):FM_CPU1_SKTOCC_LVT3_N
   3 XDP_CPU1_TDO     B0 @BASEBOARD_FAB2_LIB.BASEBOARD_FAB2(SCH_1):XDP_CPU1_TDO
   1 XDP_CPU0_TDO     B1 @BASEBOARD_FAB2_LIB.BASEBOARD_FAB2(SCH_1):XDP_CPU0_TDO
   4 XDP_CPU_TDO      A @BASEBOARD_FAB2_LIB.BASEBOARD_FAB2(SCH_1):XDP_CPU_TDO
   5 P3V3_STBY    VCC @BASEBOARD_FAB2_LIB.BASEBOARD_FAB2(SCH_1):P3V3_STBY
   2    GND    GND @BASEBOARD_FAB2_LIB.BASEBOARD_FAB2(SCH_1):GND

CAP_A_0402V-0.01UF,25V,10%,X7RA  I42  C1M36
   1 P3V3_STBY      A @BASEBOARD_FAB2_LIB.BASEBOARD_FAB2(SCH_1):P3V3_STBY
   2    GND      B @BASEBOARD_FAB2_LIB.BASEBOARD_FAB2(SCH_1):GND

CAP_A_0402V-1.0UF,6.3V,10%,X6SA  I47  C1M37
   1 P3V3_STBY      A @BASEBOARD_FAB2_LIB.BASEBOARD_FAB2(SCH_1):P3V3_STBY
   2    GND      B @BASEBOARD_FAB2_LIB.BASEBOARD_FAB2(SCH_1):GND

RES_0402-100.0,1%,1/16W,CHIP,GA  I49  R6P46
   1 PVCCIO_CPU0      A @BASEBOARD_FAB2_LIB.BASEBOARD_FAB2(SCH_1):PVCCIO_CPU0
   2 XDP_CPU_MBP1_N      B @BASEBOARD_FAB2_LIB.BASEBOARD_FAB2(SCH_1):XDP_CPU_MBP1_N

RES_0402-100.0,1%,1/16W,CHIP,GA  I50  R7P30
   1 PVCCIO_CPU0      A @BASEBOARD_FAB2_LIB.BASEBOARD_FAB2(SCH_1):PVCCIO_CPU0
   2 XDP_CPU_MBP0_N      B @BASEBOARD_FAB2_LIB.BASEBOARD_FAB2(SCH_1):XDP_CPU_MBP0_N

RES_0402-100.0,1%,1/16W,CHIP,GA  I51  R1M3
   1 PVCCIO_CPU0      A @BASEBOARD_FAB2_LIB.BASEBOARD_FAB2(SCH_1):PVCCIO_CPU0
   2 XDP_CPU_PRDY_N      B @BASEBOARD_FAB2_LIB.BASEBOARD_FAB2(SCH_1):XDP_CPU_PRDY_N

RES_0402-100.0,1%,1/16W,CHIP,GA  I53  R4P15
   1 PVCCIO_CPU0      A @BASEBOARD_FAB2_LIB.BASEBOARD_FAB2(SCH_1):PVCCIO_CPU0
   2 XDP_CPU_MBP1_N      B @BASEBOARD_FAB2_LIB.BASEBOARD_FAB2(SCH_1):XDP_CPU_MBP1_N

RES_0402-100.0,1%,1/16W,CHIP,GA  I54  R1M4
   1 PVCCIO_CPU0      A @BASEBOARD_FAB2_LIB.BASEBOARD_FAB2(SCH_1):PVCCIO_CPU0
   2 XDP_CPU_PREQ_N      B @BASEBOARD_FAB2_LIB.BASEBOARD_FAB2(SCH_1):XDP_CPU_PREQ_N

RES_0402-150.0,1%,1/16W,CHIP,GA  I55  R6T7
   1 PVCCIO_CPU1      A @BASEBOARD_FAB2_LIB.BASEBOARD_FAB2(SCH_1):PVCCIO_CPU1
   2 XDP_CPU1_TDO      B @BASEBOARD_FAB2_LIB.BASEBOARD_FAB2(SCH_1):XDP_CPU1_TDO

RES_0402-150.0,1%,1/16W,CHIP,GA  I56  R6T6
   1 PVCCIO_CPU1      A @BASEBOARD_FAB2_LIB.BASEBOARD_FAB2(SCH_1):PVCCIO_CPU1
   2 XDP_CPU1_TDI      B @BASEBOARD_FAB2_LIB.BASEBOARD_FAB2(SCH_1):XDP_CPU1_TDI

RES_0402-100.0,1%,1/16W,CHIP,GA  I57  R4P12
   1 PVCCIO_CPU0      A @BASEBOARD_FAB2_LIB.BASEBOARD_FAB2(SCH_1):PVCCIO_CPU0
   2 XDP_CPU_MBP0_N      B @BASEBOARD_FAB2_LIB.BASEBOARD_FAB2(SCH_1):XDP_CPU_MBP0_N

RES_0402-150.0,1%,1/16W,CHIP,GA  I58  R4P23
   1 PVCCIO_CPU0      A @BASEBOARD_FAB2_LIB.BASEBOARD_FAB2(SCH_1):PVCCIO_CPU0
   2 XDP_CPU0_TDO      B @BASEBOARD_FAB2_LIB.BASEBOARD_FAB2(SCH_1):XDP_CPU0_TDO

RES_0402-150.0,1%,1/16W,CHIP,GA  I59  R4P24
   1 PVCCIO_CPU0      A @BASEBOARD_FAB2_LIB.BASEBOARD_FAB2(SCH_1):PVCCIO_CPU0
   2 XDP_CPU_TDI      B @BASEBOARD_FAB2_LIB.BASEBOARD_FAB2(SCH_1):XDP_CPU_TDI

RES_0402-150.0,1%,1/16W,CHIP,GA  I60  R1L15
   1 PVCCIO_CPU0      A @BASEBOARD_FAB2_LIB.BASEBOARD_FAB2(SCH_1):PVCCIO_CPU0
   2 XDP_CPU_TMS      B @BASEBOARD_FAB2_LIB.BASEBOARD_FAB2(SCH_1):XDP_CPU_TMS

RES_0402-51.1,1.0%,1/16W,CHIP,A  I61  R7P29
   1 XDP_CPU_TCK0      A @BASEBOARD_FAB2_LIB.BASEBOARD_FAB2(SCH_1):XDP_CPU_TCK0
   2    GND      B @BASEBOARD_FAB2_LIB.BASEBOARD_FAB2(SCH_1):GND

RES_0402-1.00K,1%,1/16W,CHIP,GA  I62  R6T5
   1 XDP_CPU_TRST_N      A @BASEBOARD_FAB2_LIB.BASEBOARD_FAB2(SCH_1):XDP_CPU_TRST_N
   2    GND      B @BASEBOARD_FAB2_LIB.BASEBOARD_FAB2(SCH_1):GND

RES_0402-100.0,1%,1/16W,CHIP,GA  I76  R1L39
   1 P1V05_PCH_STBY      A @BASEBOARD_FAB2_LIB.BASEBOARD_FAB2(SCH_1):P1V05_PCH_STBY
   2 XDP_PRDY_N      B @BASEBOARD_FAB2_LIB.BASEBOARD_FAB2(SCH_1):XDP_PRDY_N

RES_0402-100.0,1%,1/16W,CHIP,GA  I77  R1L41
   1 P1V05_PCH_STBY      A @BASEBOARD_FAB2_LIB.BASEBOARD_FAB2(SCH_1):P1V05_PCH_STBY
   2 XDP_PREQ_N      B @BASEBOARD_FAB2_LIB.BASEBOARD_FAB2(SCH_1):XDP_PREQ_N

RES_0402-150.0,1%,1/16W,CHIP,GA  I78  R9A11
   1 P1V05_PCH_STBY      A @BASEBOARD_FAB2_LIB.BASEBOARD_FAB2(SCH_1):P1V05_PCH_STBY
   2 XDP_TDO      B @BASEBOARD_FAB2_LIB.BASEBOARD_FAB2(SCH_1):XDP_TDO

RES_0402-150.0,1%,1/16W,CHIP,GA  I79  R8A13
   1 P1V05_PCH_STBY      A @BASEBOARD_FAB2_LIB.BASEBOARD_FAB2(SCH_1):P1V05_PCH_STBY
   2 XDP_TDI      B @BASEBOARD_FAB2_LIB.BASEBOARD_FAB2(SCH_1):XDP_TDI

RES_0402-150.0,1%,1/16W,CHIP,GA  I80  R8A14
   1 P1V05_PCH_STBY      A @BASEBOARD_FAB2_LIB.BASEBOARD_FAB2(SCH_1):P1V05_PCH_STBY
   2 XDP_TMS      B @BASEBOARD_FAB2_LIB.BASEBOARD_FAB2(SCH_1):XDP_TMS

RES_0402-1.00K,1%,1/16W,CHIP,GA  I85  R3M10
   1 XDP_PCH_CPU_TCK0      A @BASEBOARD_FAB2_LIB.BASEBOARD_FAB2(SCH_1):XDP_PCH_CPU_TCK0
   2    GND      B @BASEBOARD_FAB2_LIB.BASEBOARD_FAB2(SCH_1):GND

RES_0402-1.00K,1%,1/16W,CHIP,GA  I94  R8B2
   1 XDP_TRST_N      A @BASEBOARD_FAB2_LIB.BASEBOARD_FAB2(SCH_1):XDP_TRST_N
   2    GND      B @BASEBOARD_FAB2_LIB.BASEBOARD_FAB2(SCH_1):GND

RES_0402-51.1,1.0%,1/16W,CHIP,A  I95  R8B1
   1 XDP_PCH_TCK1      A @BASEBOARD_FAB2_LIB.BASEBOARD_FAB2(SCH_1):XDP_PCH_TCK1
   2    GND      B @BASEBOARD_FAB2_LIB.BASEBOARD_FAB2(SCH_1):GND

TTL3126_QFNLF-74CBTLV3126,IC,DB  I108  SIZE=4  Summary of common pins:

  Section:  I108(3) U1L1
   1 PWRGD_PVCCIN_CPU0  OE<3> @BASEBOARD_FAB2_LIB.BASEBOARD_FAB2(SCH_1):PWRGD_PVCCIN_CPU0
   2 XDP_TRST_N   A<3> @BASEBOARD_FAB2_LIB.BASEBOARD_FAB2(SCH_1):XDP_TRST_N
   3 XDP_CPU_TRST_N   B<3> @BASEBOARD_FAB2_LIB.BASEBOARD_FAB2(SCH_1):XDP_CPU_TRST_N

  Section:  I108(2) U1L1
   4 PWRGD_PVCCIN_CPU0  OE<2> @BASEBOARD_FAB2_LIB.BASEBOARD_FAB2(SCH_1):PWRGD_PVCCIN_CPU0
   5 XDP_TMS   A<2> @BASEBOARD_FAB2_LIB.BASEBOARD_FAB2(SCH_1):XDP_TMS
   6 XDP_CPU_TMS   B<2> @BASEBOARD_FAB2_LIB.BASEBOARD_FAB2(SCH_1):XDP_CPU_TMS

  Section:  I108(1) U1L1
  10 PWRGD_PVCCIN_CPU0  OE<1> @BASEBOARD_FAB2_LIB.BASEBOARD_FAB2(SCH_1):PWRGD_PVCCIN_CPU0
   9 XDP_TDO   A<1> @BASEBOARD_FAB2_LIB.BASEBOARD_FAB2(SCH_1):XDP_TDO
   8 XDP_CPU_TDO   B<1> @BASEBOARD_FAB2_LIB.BASEBOARD_FAB2(SCH_1):XDP_CPU_TDO

  Section:  I108 U1L1
  13 PWRGD_PVCCIN_CPU0  OE<0> @BASEBOARD_FAB2_LIB.BASEBOARD_FAB2(SCH_1):PWRGD_PVCCIN_CPU0
  12 XDP_TDI   A<0> @BASEBOARD_FAB2_LIB.BASEBOARD_FAB2(SCH_1):XDP_TDI
  11 XDP_CPU_TDI   B<0> @BASEBOARD_FAB2_LIB.BASEBOARD_FAB2(SCH_1):XDP_CPU_TDI

TTL3126_QFNLF-74CBTLV3126,IC,DB  I109  SIZE=4  Summary of common pins:

  Section:  I109(3) U1L5
   1 PWRGD_PVCCIN_CPU0  OE<3> @BASEBOARD_FAB2_LIB.BASEBOARD_FAB2(SCH_1):PWRGD_PVCCIN_CPU0
   2 XDP_OBSFN_B1_MBP7_N   A<3> @BASEBOARD_FAB2_LIB.BASEBOARD_FAB2(SCH_1):XDP_OBSFN_B1_MBP7_N
   3 XDP_CPU_OBSFN_B1_MBP7_N   B<3> @BASEBOARD_FAB2_LIB.BASEBOARD_FAB2(SCH_1):XDP_CPU_OBSFN_B1_MBP7_N

  Section:  I109(2) U1L5
   4 PWRGD_PVCCIN_CPU0  OE<2> @BASEBOARD_FAB2_LIB.BASEBOARD_FAB2(SCH_1):PWRGD_PVCCIN_CPU0
   5 XDP_OBSFN_B0_MBP6_N   A<2> @BASEBOARD_FAB2_LIB.BASEBOARD_FAB2(SCH_1):XDP_OBSFN_B0_MBP6_N
   6 XDP_CPU_OBSFN_B0_MBP6_N   B<2> @BASEBOARD_FAB2_LIB.BASEBOARD_FAB2(SCH_1):XDP_CPU_OBSFN_B0_MBP6_N

  Section:  I109(1) U1L5
  10 PWRGD_PVCCIN_CPU0  OE<1> @BASEBOARD_FAB2_LIB.BASEBOARD_FAB2(SCH_1):PWRGD_PVCCIN_CPU0
   9 XDP_PRDY_N   A<1> @BASEBOARD_FAB2_LIB.BASEBOARD_FAB2(SCH_1):XDP_PRDY_N
   8 XDP_CPU_PRDY_N   B<1> @BASEBOARD_FAB2_LIB.BASEBOARD_FAB2(SCH_1):XDP_CPU_PRDY_N

  Section:  I109 U1L5
  13 PWRGD_PVCCIN_CPU0  OE<0> @BASEBOARD_FAB2_LIB.BASEBOARD_FAB2(SCH_1):PWRGD_PVCCIN_CPU0
  12 XDP_PREQ_N   A<0> @BASEBOARD_FAB2_LIB.BASEBOARD_FAB2(SCH_1):XDP_PREQ_N
  11 XDP_CPU_PREQ_N   B<0> @BASEBOARD_FAB2_LIB.BASEBOARD_FAB2(SCH_1):XDP_CPU_PREQ_N

RES_0402-100.0,1%,1/16W,CHIP,GA  I120  R6T9
   1 PVCCIO_CPU0      A @BASEBOARD_FAB2_LIB.BASEBOARD_FAB2(SCH_1):PVCCIO_CPU0
   2 XDP_CPU_OBSFN_B1_MBP7_N      B @BASEBOARD_FAB2_LIB.BASEBOARD_FAB2(SCH_1):XDP_CPU_OBSFN_B1_MBP7_N

RES_0402-100.0,1%,1/16W,CHIP,GA  I121  R6T8
   1 PVCCIO_CPU0      A @BASEBOARD_FAB2_LIB.BASEBOARD_FAB2(SCH_1):PVCCIO_CPU0
   2 XDP_CPU_OBSFN_B0_MBP6_N      B @BASEBOARD_FAB2_LIB.BASEBOARD_FAB2(SCH_1):XDP_CPU_OBSFN_B0_MBP6_N

74CBTLV1G125_SMLF-IC,C88177-00A  I127  U1M4
   4 XDP_CPU1_TDI      B @BASEBOARD_FAB2_LIB.BASEBOARD_FAB2(SCH_1):XDP_CPU1_TDI
   1 FM_CPU1_SKTOCC_LVT3_N   OE_N @BASEBOARD_FAB2_LIB.BASEBOARD_FAB2(SCH_1):FM_CPU1_SKTOCC_LVT3_N
   2 XDP_CPU0_TDO      A @BASEBOARD_FAB2_LIB.BASEBOARD_FAB2(SCH_1):XDP_CPU0_TDO

CAP_A_0402V-0.01UF,25V,10%,X7RA  I131  C1M30
   1 P3V3_STBY      A @BASEBOARD_FAB2_LIB.BASEBOARD_FAB2(SCH_1):P3V3_STBY
   2    GND      B @BASEBOARD_FAB2_LIB.BASEBOARD_FAB2(SCH_1):GND

CAP_0402-1.0UF,16V,10%,X6S,D97A  I136  C1L1
   1 P3V3_STBY      A @BASEBOARD_FAB2_LIB.BASEBOARD_FAB2(SCH_1):P3V3_STBY
   2    GND      B @BASEBOARD_FAB2_LIB.BASEBOARD_FAB2(SCH_1):GND

CAP_0402-1.0UF,16V,10%,X6S,D97A  I140  C1L19
   1 P3V3_STBY      A @BASEBOARD_FAB2_LIB.BASEBOARD_FAB2(SCH_1):P3V3_STBY
   2    GND      B @BASEBOARD_FAB2_LIB.BASEBOARD_FAB2(SCH_1):GND


DRAWING: @BASEBOARD_FAB2_LIB.BASEBOARD_FAB2(SCH_1):PAGE113 

NC7SB3157_SMLF-IC,C99406-001  I107  U1M2
   6 FM_CPU1_CD_PRES      S @BASEBOARD_FAB2_LIB.BASEBOARD_FAB2(SCH_1):FM_CPU1_CD_PRES
   3 JTAG_MCP_CPU1_TDO     B0 @BASEBOARD_FAB2_LIB.BASEBOARD_FAB2(SCH_1):JTAG_MCP_CPU1_TDO
   1 JTAG_MCP_CPU0_TDO     B1 @BASEBOARD_FAB2_LIB.BASEBOARD_FAB2(SCH_1):JTAG_MCP_CPU0_TDO
   4 JTAG_MCP_MUX_TDO      A @BASEBOARD_FAB2_LIB.BASEBOARD_FAB2(SCH_1):JTAG_MCP_MUX_TDO
   5 P3V3_STBY    VCC @BASEBOARD_FAB2_LIB.BASEBOARD_FAB2(SCH_1):P3V3_STBY
   2    GND    GND @BASEBOARD_FAB2_LIB.BASEBOARD_FAB2(SCH_1):GND

CAP_A_0402V-0.01UF,25V,10%,X7RA  I116  C1M31
   1 P3V3_STBY      A @BASEBOARD_FAB2_LIB.BASEBOARD_FAB2(SCH_1):P3V3_STBY
   2    GND      B @BASEBOARD_FAB2_LIB.BASEBOARD_FAB2(SCH_1):GND

CAP_A_0402V-1.0UF,6.3V,10%,X6SA  I117  C1M32
   1 P3V3_STBY      A @BASEBOARD_FAB2_LIB.BASEBOARD_FAB2(SCH_1):P3V3_STBY
   2    GND      B @BASEBOARD_FAB2_LIB.BASEBOARD_FAB2(SCH_1):GND

CAP_A_0402V-0.01UF,25V,10%,X7RA  I119  C1M28
   1 P3V3_STBY      A @BASEBOARD_FAB2_LIB.BASEBOARD_FAB2(SCH_1):P3V3_STBY
   2    GND      B @BASEBOARD_FAB2_LIB.BASEBOARD_FAB2(SCH_1):GND

74CBTLV1G125_SMLF-IC,C88177-00A  I127  U1M6
   4 JTAG_MCP_CPU1_TDI      B @BASEBOARD_FAB2_LIB.BASEBOARD_FAB2(SCH_1):JTAG_MCP_CPU1_TDI
   1 FM_CPU0_AND_CPU1_MCP_PRES   OE_N @BASEBOARD_FAB2_LIB.BASEBOARD_FAB2(SCH_1):FM_CPU0_AND_CPU1_MCP_PRES
   2 JTAG_MCP_CPU0_TDO      A @BASEBOARD_FAB2_LIB.BASEBOARD_FAB2(SCH_1):JTAG_MCP_CPU0_TDO

RES_0402-49.9,1%,1/16W,CHIP,G2A  I134  R4R6
   1 JTAG_MCP_CPU0_TDI_R      A @BASEBOARD_FAB2_LIB.BASEBOARD_FAB2(SCH_1):JTAG_MCP_CPU0_TDI_R
   2 JTAG_MCP_CPU0_TDI      B @BASEBOARD_FAB2_LIB.BASEBOARD_FAB2(SCH_1):JTAG_MCP_CPU0_TDI

CAP_A_0402V-0.1UF,16V,10%,X7R,A  I147  C1M29
   1 P1V8_MCP_CPU0      A @BASEBOARD_FAB2_LIB.BASEBOARD_FAB2(SCH_1):P1V8_MCP_CPU0
   2    GND      B @BASEBOARD_FAB2_LIB.BASEBOARD_FAB2(SCH_1):GND

RES_0402-1.00K,1%,1/16W,CHIP,GA  I168  R9B14
   1 PWRGD_CPU0_G      A @BASEBOARD_FAB2_LIB.BASEBOARD_FAB2(SCH_1):PWRGD_CPU0_G
   2 PWRGD_CPU0_G_R      B @BASEBOARD_FAB2_LIB.BASEBOARD_FAB2(SCH_1):PWRGD_CPU0_G_R

SCONN10_C12536004_SMLF-CONN,C1A  I175  J9B4
   1 JTAG_MCP_TCK_R    IO1 @BASEBOARD_FAB2_LIB.BASEBOARD_FAB2(SCH_1):JTAG_MCP_TCK_R
   2    GND    IO2 @BASEBOARD_FAB2_LIB.BASEBOARD_FAB2(SCH_1):GND
   3 JTAG_MCP_MUX_TDO    IO3 @BASEBOARD_FAB2_LIB.BASEBOARD_FAB2(SCH_1):JTAG_MCP_MUX_TDO
   4 P1V8_MCP_CPU0    IO4 @BASEBOARD_FAB2_LIB.BASEBOARD_FAB2(SCH_1):P1V8_MCP_CPU0
   5 JTAG_MCP_TMS_R    IO5 @BASEBOARD_FAB2_LIB.BASEBOARD_FAB2(SCH_1):JTAG_MCP_TMS_R
   6 JTAG_MCP_TRST_N    IO6 @BASEBOARD_FAB2_LIB.BASEBOARD_FAB2(SCH_1):JTAG_MCP_TRST_N
   7 PWRGD_CPU0_G_R    IO7 @BASEBOARD_FAB2_LIB.BASEBOARD_FAB2(SCH_1):PWRGD_CPU0_G_R
   8 TP_JTAG_MCP_IO8_RSVD    IO8 @BASEBOARD_FAB2_LIB.BASEBOARD_FAB2(SCH_1):TP_JTAG_MCP_IO8_RSVD
   9 JTAG_MCP_MUX_TDI    IO9 @BASEBOARD_FAB2_LIB.BASEBOARD_FAB2(SCH_1):JTAG_MCP_MUX_TDI
  10    GND   IO10 @BASEBOARD_FAB2_LIB.BASEBOARD_FAB2(SCH_1):GND

RES_0402-1.00K,1%,1/16W,CHIP,GA  I179  R9B9
   1 JTAG_MCP_TCK      A @BASEBOARD_FAB2_LIB.BASEBOARD_FAB2(SCH_1):JTAG_MCP_TCK
   2    GND      B @BASEBOARD_FAB2_LIB.BASEBOARD_FAB2(SCH_1):GND

RES_0402-49.9,1%,1/16W,CHIP,G2A  I180  R9B10
   1 JTAG_MCP_TCK      A @BASEBOARD_FAB2_LIB.BASEBOARD_FAB2(SCH_1):JTAG_MCP_TCK
   2 JTAG_MCP_TCK_R      B @BASEBOARD_FAB2_LIB.BASEBOARD_FAB2(SCH_1):JTAG_MCP_TCK_R

74CBTLV1G125_SMLF-IC,C88177-00A  I185  U9A5
   4    GND      B @BASEBOARD_FAB2_LIB.BASEBOARD_FAB2(SCH_1):GND
   1 FM_CPU0_OR_CPU1_MCP_PRES   OE_N @BASEBOARD_FAB2_LIB.BASEBOARD_FAB2(SCH_1):FM_CPU0_OR_CPU1_MCP_PRES
   2 JTAG_MCP_TCK_R      A @BASEBOARD_FAB2_LIB.BASEBOARD_FAB2(SCH_1):JTAG_MCP_TCK_R

RES_0402-49.9,1%,1/16W,CHIP,G2A  I188  R6M8
   1 JTAG_MCP_CPU1_TDI_R      A @BASEBOARD_FAB2_LIB.BASEBOARD_FAB2(SCH_1):JTAG_MCP_CPU1_TDI_R
   2 JTAG_MCP_CPU1_TDI      B @BASEBOARD_FAB2_LIB.BASEBOARD_FAB2(SCH_1):JTAG_MCP_CPU1_TDI

74CBTLV1G125_SMLF-IC,C88177-00A  I190  U6M1
   4 JTAG_MCP_CPU1_TDI_R      B @BASEBOARD_FAB2_LIB.BASEBOARD_FAB2(SCH_1):JTAG_MCP_CPU1_TDI_R
   1 FM_CPU1_PKGID1   OE_N @BASEBOARD_FAB2_LIB.BASEBOARD_FAB2(SCH_1):FM_CPU1_PKGID1
   2 P1V8_MCP_CPU1      A @BASEBOARD_FAB2_LIB.BASEBOARD_FAB2(SCH_1):P1V8_MCP_CPU1

RES_0402-49.9,1%,1/16W,CHIP,G2A  I195  R1M22
   1 JTAG_MCP_TMS_R1      A @BASEBOARD_FAB2_LIB.BASEBOARD_FAB2(SCH_1):JTAG_MCP_TMS_R1
   2 JTAG_MCP_TMS      B @BASEBOARD_FAB2_LIB.BASEBOARD_FAB2(SCH_1):JTAG_MCP_TMS

74CBTLV1G125_SMLF-IC,C88177-00A  I196  U1M5
   4 JTAG_MCP_TMS_R1      B @BASEBOARD_FAB2_LIB.BASEBOARD_FAB2(SCH_1):JTAG_MCP_TMS_R1
   1 FM_CPU0_OR_CPU1_MCP_PRES   OE_N @BASEBOARD_FAB2_LIB.BASEBOARD_FAB2(SCH_1):FM_CPU0_OR_CPU1_MCP_PRES
   2 P1V8_MCP_CPU0      A @BASEBOARD_FAB2_LIB.BASEBOARD_FAB2(SCH_1):P1V8_MCP_CPU0

RES_0402-1.00K,1%,1/16W,EMPTY,A  I199  R1M23
   1 JTAG_MCP_TRST_N      A @BASEBOARD_FAB2_LIB.BASEBOARD_FAB2(SCH_1):JTAG_MCP_TRST_N
   2    GND      B @BASEBOARD_FAB2_LIB.BASEBOARD_FAB2(SCH_1):GND

RES_0402-1.00K,1%,1/16W,CHIP,GA  I202  R1M19
   1 P1V8_MCP_CPU0      A @BASEBOARD_FAB2_LIB.BASEBOARD_FAB2(SCH_1):P1V8_MCP_CPU0
   2 JTAG_MCP_TMS      B @BASEBOARD_FAB2_LIB.BASEBOARD_FAB2(SCH_1):JTAG_MCP_TMS

RES_0402-1.00K,1%,1/16W,CHIP,GA  I203  R9B12
   1 P1V8_MCP_CPU0      A @BASEBOARD_FAB2_LIB.BASEBOARD_FAB2(SCH_1):P1V8_MCP_CPU0
   2 JTAG_MCP_MUX_TDO      B @BASEBOARD_FAB2_LIB.BASEBOARD_FAB2(SCH_1):JTAG_MCP_MUX_TDO

RES_0402-1.00K,1%,1/16W,CHIP,GA  I204  R1M20
   1 P1V8_MCP_CPU0      A @BASEBOARD_FAB2_LIB.BASEBOARD_FAB2(SCH_1):P1V8_MCP_CPU0
   2 JTAG_MCP_MUX_TDI      B @BASEBOARD_FAB2_LIB.BASEBOARD_FAB2(SCH_1):JTAG_MCP_MUX_TDI

RES_0402-1.00K,1%,1/16W,CHIP,GA  I205  R1M21
   1 P1V8_MCP_CPU0      A @BASEBOARD_FAB2_LIB.BASEBOARD_FAB2(SCH_1):P1V8_MCP_CPU0
   2 JTAG_MCP_TRST_N      B @BASEBOARD_FAB2_LIB.BASEBOARD_FAB2(SCH_1):JTAG_MCP_TRST_N

74CBTLV1G125_SMLF-IC,C88177-00A  I206  U4R1
   4 JTAG_MCP_CPU0_TDI_R      B @BASEBOARD_FAB2_LIB.BASEBOARD_FAB2(SCH_1):JTAG_MCP_CPU0_TDI_R
   1 FM_CPU0_PKGID1   OE_N @BASEBOARD_FAB2_LIB.BASEBOARD_FAB2(SCH_1):FM_CPU0_PKGID1
   2 P1V8_MCP_CPU0      A @BASEBOARD_FAB2_LIB.BASEBOARD_FAB2(SCH_1):P1V8_MCP_CPU0

RES_0402-0.0,5%,1/16W,CHIP,G21A  I239  R9B11
   1 JTAG_MCP_TCK      A @BASEBOARD_FAB2_LIB.BASEBOARD_FAB2(SCH_1):JTAG_MCP_TCK
   2 JTAG_MCP_TCK_R      B @BASEBOARD_FAB2_LIB.BASEBOARD_FAB2(SCH_1):JTAG_MCP_TCK_R

RES_0402-0.0,5%,1/16W,CHIP,G21A  I240  R9B13
   1 JTAG_MCP_TMS      A @BASEBOARD_FAB2_LIB.BASEBOARD_FAB2(SCH_1):JTAG_MCP_TMS
   2 JTAG_MCP_TMS_R      B @BASEBOARD_FAB2_LIB.BASEBOARD_FAB2(SCH_1):JTAG_MCP_TMS_R

CAP_A_0402V-0.1UF,16V,10%,X7R,A  I246  C4R2
   1 JTAG_MCP_CPU0_TDI_R      A @BASEBOARD_FAB2_LIB.BASEBOARD_FAB2(SCH_1):JTAG_MCP_CPU0_TDI_R
   2    GND      B @BASEBOARD_FAB2_LIB.BASEBOARD_FAB2(SCH_1):GND

CAP_A_0402V-0.1UF,16V,10%,X7R,A  I248  C1M33
   1 JTAG_MCP_TMS_R1      A @BASEBOARD_FAB2_LIB.BASEBOARD_FAB2(SCH_1):JTAG_MCP_TMS_R1
   2    GND      B @BASEBOARD_FAB2_LIB.BASEBOARD_FAB2(SCH_1):GND

CAP_A_0402V-0.1UF,16V,10%,X7R,A  I250  C6M6
   1 JTAG_MCP_CPU1_TDI_R      A @BASEBOARD_FAB2_LIB.BASEBOARD_FAB2(SCH_1):JTAG_MCP_CPU1_TDI_R
   2    GND      B @BASEBOARD_FAB2_LIB.BASEBOARD_FAB2(SCH_1):GND

NC7SB3157_SMLF-IC,C99406-001  I255  U2M1
   6 FM_CPU0_CD_PRES      S @BASEBOARD_FAB2_LIB.BASEBOARD_FAB2(SCH_1):FM_CPU0_CD_PRES
   3 JTAG_MCP_CPU1_TDI     B0 @BASEBOARD_FAB2_LIB.BASEBOARD_FAB2(SCH_1):JTAG_MCP_CPU1_TDI
   1 JTAG_MCP_CPU0_TDI     B1 @BASEBOARD_FAB2_LIB.BASEBOARD_FAB2(SCH_1):JTAG_MCP_CPU0_TDI
   4 JTAG_MCP_MUX_TDI      A @BASEBOARD_FAB2_LIB.BASEBOARD_FAB2(SCH_1):JTAG_MCP_MUX_TDI
   5 P3V3_STBY    VCC @BASEBOARD_FAB2_LIB.BASEBOARD_FAB2(SCH_1):P3V3_STBY
   2    GND    GND @BASEBOARD_FAB2_LIB.BASEBOARD_FAB2(SCH_1):GND

CAP_A_0402V-0.01UF,25V,10%,X7RA  I265  C1M34
   1 P3V3_STBY      A @BASEBOARD_FAB2_LIB.BASEBOARD_FAB2(SCH_1):P3V3_STBY
   2    GND      B @BASEBOARD_FAB2_LIB.BASEBOARD_FAB2(SCH_1):GND

CAP_A_0402V-0.01UF,25V,10%,X7RA  I266  C1M35
   1 P3V3_STBY      A @BASEBOARD_FAB2_LIB.BASEBOARD_FAB2(SCH_1):P3V3_STBY
   2    GND      B @BASEBOARD_FAB2_LIB.BASEBOARD_FAB2(SCH_1):GND

CAP_A_0402V-0.01UF,25V,10%,X7RA  I267  C1L20
   1 P3V3_STBY      A @BASEBOARD_FAB2_LIB.BASEBOARD_FAB2(SCH_1):P3V3_STBY
   2    GND      B @BASEBOARD_FAB2_LIB.BASEBOARD_FAB2(SCH_1):GND


DRAWING: @BASEBOARD_FAB2_LIB.BASEBOARD_FAB2(SCH_1):PAGE114 

LBG_CORE_QAT_EXT_D_BGA1-IC,H91A  I40  U7C1
 A39 CLK_100M_PCH_XDP_DN CLKOUT_ITPXDPN @BASEBOARD_FAB2_LIB.BASEBOARD_FAB2(SCH_1):CLK_100M_PCH_XDP_DN
 C39 CLK_100M_PCH_XDP_DP CLKOUT_ITPXDPP @BASEBOARD_FAB2_LIB.BASEBOARD_FAB2(SCH_1):CLK_100M_PCH_XDP_DP
 A32 TP_CLK_100M_NSSCC0_DN CLKOUT_NSSCCAP0N @BASEBOARD_FAB2_LIB.BASEBOARD_FAB2(SCH_1):TP_CLK_100M_NSSCC0_DN
 C32 TP_CLK_100M_NSSCC0_DP CLKOUT_NSSCCAP0P @BASEBOARD_FAB2_LIB.BASEBOARD_FAB2(SCH_1):TP_CLK_100M_NSSCC0_DP
 B38 TP_CLK_100M_NSSCC1_DN CLKOUT_NSSCCAP1N @BASEBOARD_FAB2_LIB.BASEBOARD_FAB2(SCH_1):TP_CLK_100M_NSSCC1_DN
 D38 TP_CLK_100M_NSSCC1_DP CLKOUT_NSSCCAP1P @BASEBOARD_FAB2_LIB.BASEBOARD_FAB2(SCH_1):TP_CLK_100M_NSSCC1_DP
 B29 CLK_100M_BMC_PE_DN CLKOUT_PLAT0N @BASEBOARD_FAB2_LIB.BASEBOARD_FAB2(SCH_1):CLK_100M_BMC_PE_DN
 D29 CLK_100M_BMC_PE_DP CLKOUT_PLAT0P @BASEBOARD_FAB2_LIB.BASEBOARD_FAB2(SCH_1):CLK_100M_BMC_PE_DP
 B40 TP_CLK_100M_PLAT1_DN CLKOUT_PLAT1N @BASEBOARD_FAB2_LIB.BASEBOARD_FAB2(SCH_1):TP_CLK_100M_PLAT1_DN
 D40 TP_CLK_100M_PLAT1_DP CLKOUT_PLAT1P @BASEBOARD_FAB2_LIB.BASEBOARD_FAB2(SCH_1):TP_CLK_100M_PLAT1_DP
 K27 CLK_100M_M2_DN CLKOUT_SRCN<15> @BASEBOARD_FAB2_LIB.BASEBOARD_FAB2(SCH_1):CLK_100M_M2_DN
 C20 CLK_100M_SPRV_DN CLKOUT_SRCN<14> @BASEBOARD_FAB2_LIB.BASEBOARD_FAB2(SCH_1):CLK_100M_SPRV_DN
 C24 CLK_100M_SRC13_DN CLKOUT_SRCN<13> @BASEBOARD_FAB2_LIB.BASEBOARD_FAB2(SCH_1):CLK_100M_SRC13_DN
 K24 CLK_100M_SRC12_DN CLKOUT_SRCN<12> @BASEBOARD_FAB2_LIB.BASEBOARD_FAB2(SCH_1):CLK_100M_SRC12_DN
 B21 CLK_100M_MEZZ4_DN CLKOUT_SRCN<11> @BASEBOARD_FAB2_LIB.BASEBOARD_FAB2(SCH_1):CLK_100M_MEZZ4_DN
 B23 CLK_100M_MEZZ3_DN CLKOUT_SRCN<10> @BASEBOARD_FAB2_LIB.BASEBOARD_FAB2(SCH_1):CLK_100M_MEZZ3_DN
 J26 CLK_100M_MEZZ2_DN CLKOUT_SRCN<9> @BASEBOARD_FAB2_LIB.BASEBOARD_FAB2(SCH_1):CLK_100M_MEZZ2_DN
 D31 CLK_100M_MEZZ1_DN CLKOUT_SRCN<8> @BASEBOARD_FAB2_LIB.BASEBOARD_FAB2(SCH_1):CLK_100M_MEZZ1_DN
 H31 CLK_100M_PCH_SLOTX24_S5_DN CLKOUT_SRCN<7> @BASEBOARD_FAB2_LIB.BASEBOARD_FAB2(SCH_1):CLK_100M_PCH_SLOTX24_S5_DN
 D33 CLK_100M_PCH_SLOTX24_S4_DN CLKOUT_SRCN<6> @BASEBOARD_FAB2_LIB.BASEBOARD_FAB2(SCH_1):CLK_100M_PCH_SLOTX24_S4_DN
 J40 CLK_100M_PCH_SLOTX24_S3_DN CLKOUT_SRCN<5> @BASEBOARD_FAB2_LIB.BASEBOARD_FAB2(SCH_1):CLK_100M_PCH_SLOTX24_S3_DN
 A28 CLK_100M_PCH_SLOTX24_S2_DN CLKOUT_SRCN<4> @BASEBOARD_FAB2_LIB.BASEBOARD_FAB2(SCH_1):CLK_100M_PCH_SLOTX24_S2_DN
 K42 CLK_100M_PCH_SLOTX24_S1_DN CLKOUT_SRCN<3> @BASEBOARD_FAB2_LIB.BASEBOARD_FAB2(SCH_1):CLK_100M_PCH_SLOTX24_S1_DN
 J33 CLK_100M_PCH_SLOTX24_S0_DN CLKOUT_SRCN<2> @BASEBOARD_FAB2_LIB.BASEBOARD_FAB2(SCH_1):CLK_100M_PCH_SLOTX24_S0_DN
 K35 CLK_100M_DB1200_DN CLKOUT_SRCN<1> @BASEBOARD_FAB2_LIB.BASEBOARD_FAB2(SCH_1):CLK_100M_DB1200_DN
 K38 CLK_100M_AIRMAX8_PE1_DN CLKOUT_SRCN<0> @BASEBOARD_FAB2_LIB.BASEBOARD_FAB2(SCH_1):CLK_100M_AIRMAX8_PE1_DN
 H27 CLK_100M_M2_DP CLKOUT_SRCP<15> @BASEBOARD_FAB2_LIB.BASEBOARD_FAB2(SCH_1):CLK_100M_M2_DP
 A20 CLK_100M_SPRV_DP CLKOUT_SRCP<14> @BASEBOARD_FAB2_LIB.BASEBOARD_FAB2(SCH_1):CLK_100M_SPRV_DP
 A24 CLK_100M_SRC13_DP CLKOUT_SRCP<13> @BASEBOARD_FAB2_LIB.BASEBOARD_FAB2(SCH_1):CLK_100M_SRC13_DP
 H24 CLK_100M_SRC12_DP CLKOUT_SRCP<12> @BASEBOARD_FAB2_LIB.BASEBOARD_FAB2(SCH_1):CLK_100M_SRC12_DP
 D21 CLK_100M_MEZZ4_DP CLKOUT_SRCP<11> @BASEBOARD_FAB2_LIB.BASEBOARD_FAB2(SCH_1):CLK_100M_MEZZ4_DP
 D23 CLK_100M_MEZZ3_DP CLKOUT_SRCP<10> @BASEBOARD_FAB2_LIB.BASEBOARD_FAB2(SCH_1):CLK_100M_MEZZ3_DP
 G26 CLK_100M_MEZZ2_DP CLKOUT_SRCP<9> @BASEBOARD_FAB2_LIB.BASEBOARD_FAB2(SCH_1):CLK_100M_MEZZ2_DP
 B31 CLK_100M_MEZZ1_DP CLKOUT_SRCP<8> @BASEBOARD_FAB2_LIB.BASEBOARD_FAB2(SCH_1):CLK_100M_MEZZ1_DP
 K31 CLK_100M_PCH_SLOTX24_S5_DP CLKOUT_SRCP<7> @BASEBOARD_FAB2_LIB.BASEBOARD_FAB2(SCH_1):CLK_100M_PCH_SLOTX24_S5_DP
 B33 CLK_100M_PCH_SLOTX24_S4_DP CLKOUT_SRCP<6> @BASEBOARD_FAB2_LIB.BASEBOARD_FAB2(SCH_1):CLK_100M_PCH_SLOTX24_S4_DP
 G40 CLK_100M_PCH_SLOTX24_S3_DP CLKOUT_SRCP<5> @BASEBOARD_FAB2_LIB.BASEBOARD_FAB2(SCH_1):CLK_100M_PCH_SLOTX24_S3_DP
 C28 CLK_100M_PCH_SLOTX24_S2_DP CLKOUT_SRCP<4> @BASEBOARD_FAB2_LIB.BASEBOARD_FAB2(SCH_1):CLK_100M_PCH_SLOTX24_S2_DP
 H42 CLK_100M_PCH_SLOTX24_S1_DP CLKOUT_SRCP<3> @BASEBOARD_FAB2_LIB.BASEBOARD_FAB2(SCH_1):CLK_100M_PCH_SLOTX24_S1_DP
 G33 CLK_100M_PCH_SLOTX24_S0_DP CLKOUT_SRCP<2> @BASEBOARD_FAB2_LIB.BASEBOARD_FAB2(SCH_1):CLK_100M_PCH_SLOTX24_S0_DP
 H35 CLK_100M_DB1200_DP CLKOUT_SRCP<1> @BASEBOARD_FAB2_LIB.BASEBOARD_FAB2(SCH_1):CLK_100M_DB1200_DP
 H38 CLK_100M_AIRMAX8_PE1_DP CLKOUT_SRCP<0> @BASEBOARD_FAB2_LIB.BASEBOARD_FAB2(SCH_1):CLK_100M_AIRMAX8_PE1_DP
BW50 CLK_48M_USB_BMC CLOCKSE_BMCCLK @BASEBOARD_FAB2_LIB.BASEBOARD_FAB2(SCH_1):CLK_48M_USB_BMC
BY51 H_PMSYNC_CLK_24M_R CLOCKSE_PMSYNCCLK1 @BASEBOARD_FAB2_LIB.BASEBOARD_FAB2(SCH_1):H_PMSYNC_CLK_24M_R
BV51 TP_CLK_24M_PMSYNC2 CLOCKSE_PMSYNCCLK2 @BASEBOARD_FAB2_LIB.BASEBOARD_FAB2(SCH_1):TP_CLK_24M_PMSYNC2
 A26 TP_PCH_RSVD65 RSVD<65> @BASEBOARD_FAB2_LIB.BASEBOARD_FAB2(SCH_1):TP_PCH_RSVD65
 C26 TP_PCH_RSVD64 RSVD<64> @BASEBOARD_FAB2_LIB.BASEBOARD_FAB2(SCH_1):TP_PCH_RSVD64
 K17 XTAL_33K_RTC1  RTCX1 @BASEBOARD_FAB2_LIB.BASEBOARD_FAB2(SCH_1):XTAL_33K_RTC1
 H17 XTAL_33K_RTC2  RTCX2 @BASEBOARD_FAB2_LIB.BASEBOARD_FAB2(SCH_1):XTAL_33K_RTC2
 G44 A_PCH_XCLK_BIASREF XCLK_BIASREF @BASEBOARD_FAB2_LIB.BASEBOARD_FAB2(SCH_1):A_PCH_XCLK_BIASREF
 B35 XTAL_PCH_48M_IN XTAL_IN @BASEBOARD_FAB2_LIB.BASEBOARD_FAB2(SCH_1):XTAL_PCH_48M_IN
 D35 XTAL_PCH_48M_OUT XTAL_OUT @BASEBOARD_FAB2_LIB.BASEBOARD_FAB2(SCH_1):XTAL_PCH_48M_OUT

CAP_0402LF-18PF,50V,5%,C0G,A36A  I46  C7C15
   1 XTAL_33K_RTC2      A @BASEBOARD_FAB2_LIB.BASEBOARD_FAB2(SCH_1):XTAL_33K_RTC2
   2    GND      B @BASEBOARD_FAB2_LIB.BASEBOARD_FAB2(SCH_1):GND

CAP_0402LF-15.0PF,50V,5%,COG,AA  I47  C7C5
   1 XTAL_PCH_48M_OUT      A @BASEBOARD_FAB2_LIB.BASEBOARD_FAB2(SCH_1):XTAL_PCH_48M_OUT
   2    GND      B @BASEBOARD_FAB2_LIB.BASEBOARD_FAB2(SCH_1):GND

RES_0603-200K,0.1%,1/10W,CHIP,A  I48  R7C1
   1 XTAL_PCH_48M_IN      A @BASEBOARD_FAB2_LIB.BASEBOARD_FAB2(SCH_1):XTAL_PCH_48M_IN
   2 XTAL_PCH_48M_OUT      B @BASEBOARD_FAB2_LIB.BASEBOARD_FAB2(SCH_1):XTAL_PCH_48M_OUT

CRYSTAL_2013-48.000MHZ,IC,D717A  I49  Y7C1
   1 XTAL_PCH_48M_IN      A @BASEBOARD_FAB2_LIB.BASEBOARD_FAB2(SCH_1):XTAL_PCH_48M_IN
   3 XTAL_PCH_48M_OUT      B @BASEBOARD_FAB2_LIB.BASEBOARD_FAB2(SCH_1):XTAL_PCH_48M_OUT

CAP_0402LF-15.0PF,50V,5%,COG,AA  I50  C7C4
   1 XTAL_PCH_48M_IN      A @BASEBOARD_FAB2_LIB.BASEBOARD_FAB2(SCH_1):XTAL_PCH_48M_IN
   2    GND      B @BASEBOARD_FAB2_LIB.BASEBOARD_FAB2(SCH_1):GND

RES_0603-10M,1.0%,1/10W,CHIP,GA  I54  R7C6
   1 XTAL_33K_RTC1      A @BASEBOARD_FAB2_LIB.BASEBOARD_FAB2(SCH_1):XTAL_33K_RTC1
   2 XTAL_33K_RTC2      B @BASEBOARD_FAB2_LIB.BASEBOARD_FAB2(SCH_1):XTAL_33K_RTC2

CRYSTAL_SM-32.768KHZ,IC,C13544A  I55  Y7C2
   1 XTAL_33K_RTC1      A @BASEBOARD_FAB2_LIB.BASEBOARD_FAB2(SCH_1):XTAL_33K_RTC1
   2 XTAL_33K_RTC2      B @BASEBOARD_FAB2_LIB.BASEBOARD_FAB2(SCH_1):XTAL_33K_RTC2

CAP_0402LF-18PF,50V,5%,C0G,A36A  I56  C7C13
   1 XTAL_33K_RTC1      A @BASEBOARD_FAB2_LIB.BASEBOARD_FAB2(SCH_1):XTAL_33K_RTC1
   2    GND      B @BASEBOARD_FAB2_LIB.BASEBOARD_FAB2(SCH_1):GND

RES_0402-10.0,1%,1/16W,CHIP,G2A  I110  R8B20
   1 H_PMSYNC_CLK_24M_R      A @BASEBOARD_FAB2_LIB.BASEBOARD_FAB2(SCH_1):H_PMSYNC_CLK_24M_R
   2 H_PMSYNC_CLK_24M      B @BASEBOARD_FAB2_LIB.BASEBOARD_FAB2(SCH_1):H_PMSYNC_CLK_24M

RES_0402-49.9,1%,1/16W,EMPTY,GA  I124  R8B21
   1 H_PMSYNC_CLK_24M      A @BASEBOARD_FAB2_LIB.BASEBOARD_FAB2(SCH_1):H_PMSYNC_CLK_24M
   2    GND      B @BASEBOARD_FAB2_LIB.BASEBOARD_FAB2(SCH_1):GND

RES_0402-0.0,5%,1/16W,EMPTY,G2A  I141  R7C2
   1 CLK_100M_BMC_PE_R_DN      A @BASEBOARD_FAB2_LIB.BASEBOARD_FAB2(SCH_1):CLK_100M_BMC_PE_R_DN
   2 CLK_100M_BMC_PE_DN      B @BASEBOARD_FAB2_LIB.BASEBOARD_FAB2(SCH_1):CLK_100M_BMC_PE_DN

RES_0402-0.0,5%,1/16W,EMPTY,G2A  I142  R7C4
   1 CLK_100M_BMC_PE_R_DP      A @BASEBOARD_FAB2_LIB.BASEBOARD_FAB2(SCH_1):CLK_100M_BMC_PE_R_DP
   2 CLK_100M_BMC_PE_DP      B @BASEBOARD_FAB2_LIB.BASEBOARD_FAB2(SCH_1):CLK_100M_BMC_PE_DP

RES_0402-169,1.0%,1/16W,CHIP,GA  I149  R3N1
   1 A_PCH_XCLK_BIASREF      A @BASEBOARD_FAB2_LIB.BASEBOARD_FAB2(SCH_1):A_PCH_XCLK_BIASREF
   2    GND      B @BASEBOARD_FAB2_LIB.BASEBOARD_FAB2(SCH_1):GND


DRAWING: @BASEBOARD_FAB2_LIB.BASEBOARD_FAB2(SCH_1):PAGE115 

LBG_CORE_QAT_EXT_D_BGA1-IC,H91A  I74  U7C1
BN68 TP_PCH_RSVD55 RSVD<55> @BASEBOARD_FAB2_LIB.BASEBOARD_FAB2(SCH_1):TP_PCH_RSVD55
BY60 USB2_P01_DN USB2N_1 @BASEBOARD_FAB2_LIB.BASEBOARD_FAB2(SCH_1):USB2_P01_DN
BW65 TP_USB2_P10_DN USB2N_10 @BASEBOARD_FAB2_LIB.BASEBOARD_FAB2(SCH_1):TP_USB2_P10_DN
CA54 TP_USB2_P11_DN USB2N_11 @BASEBOARD_FAB2_LIB.BASEBOARD_FAB2(SCH_1):TP_USB2_P11_DN
BW67 TP_USB2_P12_DN USB2N_12 @BASEBOARD_FAB2_LIB.BASEBOARD_FAB2(SCH_1):TP_USB2_P12_DN
BY53 TP_USB2_P13_DN USB2N_13 @BASEBOARD_FAB2_LIB.BASEBOARD_FAB2(SCH_1):TP_USB2_P13_DN
BW68 TP_USB2_P14_DN USB2N_14 @BASEBOARD_FAB2_LIB.BASEBOARD_FAB2(SCH_1):TP_USB2_P14_DN
CA61 USB2_P02_DN USB2N_2 @BASEBOARD_FAB2_LIB.BASEBOARD_FAB2(SCH_1):USB2_P02_DN
CA59 TP_USB2_P03_DN USB2N_3 @BASEBOARD_FAB2_LIB.BASEBOARD_FAB2(SCH_1):TP_USB2_P03_DN
BY62 USB_PCH_BMC_P4_DN USB2N_4 @BASEBOARD_FAB2_LIB.BASEBOARD_FAB2(SCH_1):USB_PCH_BMC_P4_DN
BY58 USB2_PCH_BMC_P5_DN USB2N_5 @BASEBOARD_FAB2_LIB.BASEBOARD_FAB2(SCH_1):USB2_PCH_BMC_P5_DN
CA63 TP_USB2_P06_DN USB2N_6 @BASEBOARD_FAB2_LIB.BASEBOARD_FAB2(SCH_1):TP_USB2_P06_DN
CA57 TP_USB2_P07_DN USB2N_7 @BASEBOARD_FAB2_LIB.BASEBOARD_FAB2(SCH_1):TP_USB2_P07_DN
BY64 TP_USB2_P8_DN USB2N_8 @BASEBOARD_FAB2_LIB.BASEBOARD_FAB2(SCH_1):TP_USB2_P8_DN
BY55 TP_USB2_P9_DN USB2N_9 @BASEBOARD_FAB2_LIB.BASEBOARD_FAB2(SCH_1):TP_USB2_P9_DN
BV60 USB2_P01_DP USB2P_1 @BASEBOARD_FAB2_LIB.BASEBOARD_FAB2(SCH_1):USB2_P01_DP
BU65 TP_USB2_P10_DP USB2P_10 @BASEBOARD_FAB2_LIB.BASEBOARD_FAB2(SCH_1):TP_USB2_P10_DP
BW54 TP_USB2_P11_DP USB2P_11 @BASEBOARD_FAB2_LIB.BASEBOARD_FAB2(SCH_1):TP_USB2_P11_DP
BV66 TP_USB2_P12_DP USB2P_12 @BASEBOARD_FAB2_LIB.BASEBOARD_FAB2(SCH_1):TP_USB2_P12_DP
BV53 TP_USB2_P13_DP USB2P_13 @BASEBOARD_FAB2_LIB.BASEBOARD_FAB2(SCH_1):TP_USB2_P13_DP
BU67 TP_USB2_P14_DP USB2P_14 @BASEBOARD_FAB2_LIB.BASEBOARD_FAB2(SCH_1):TP_USB2_P14_DP
BW61 USB2_P02_DP USB2P_2 @BASEBOARD_FAB2_LIB.BASEBOARD_FAB2(SCH_1):USB2_P02_DP
BW59 TP_USB2_P03_DP USB2P_3 @BASEBOARD_FAB2_LIB.BASEBOARD_FAB2(SCH_1):TP_USB2_P03_DP
BV62 USB_PCH_BMC_P4_DP USB2P_4 @BASEBOARD_FAB2_LIB.BASEBOARD_FAB2(SCH_1):USB_PCH_BMC_P4_DP
BV58 USB2_PCH_BMC_P5_DP USB2P_5 @BASEBOARD_FAB2_LIB.BASEBOARD_FAB2(SCH_1):USB2_PCH_BMC_P5_DP
BW63 TP_USB2_P06_DP USB2P_6 @BASEBOARD_FAB2_LIB.BASEBOARD_FAB2(SCH_1):TP_USB2_P06_DP
BW57 TP_USB2_P07_DP USB2P_7 @BASEBOARD_FAB2_LIB.BASEBOARD_FAB2(SCH_1):TP_USB2_P07_DP
BV64 TP_USB2_P8_DP USB2P_8 @BASEBOARD_FAB2_LIB.BASEBOARD_FAB2(SCH_1):TP_USB2_P8_DP
BV55 TP_USB2_P9_DP USB2P_9 @BASEBOARD_FAB2_LIB.BASEBOARD_FAB2(SCH_1):TP_USB2_P9_DP
BN70 A_USB2_COMP USB2_COMP @BASEBOARD_FAB2_LIB.BASEBOARD_FAB2(SCH_1):A_USB2_COMP
BR67 A_USB2_VBUS USB2_VBUS @BASEBOARD_FAB2_LIB.BASEBOARD_FAB2(SCH_1):A_USB2_VBUS
BK71 USB3_P01_RXN USB3_1_RXN @BASEBOARD_FAB2_LIB.BASEBOARD_FAB2(SCH_1):USB3_P01_RXN
BK69 USB3_P01_RXP USB3_1_RXP @BASEBOARD_FAB2_LIB.BASEBOARD_FAB2(SCH_1):USB3_P01_RXP
BL52 USB3_P01_TXN USB3_1_TXN @BASEBOARD_FAB2_LIB.BASEBOARD_FAB2(SCH_1):USB3_P01_TXN
BK54 USB3_P01_TXP USB3_1_TXP @BASEBOARD_FAB2_LIB.BASEBOARD_FAB2(SCH_1):USB3_P01_TXP
BJ72 TP_USB3_P02_RXN USB3_2_RXN @BASEBOARD_FAB2_LIB.BASEBOARD_FAB2(SCH_1):TP_USB3_P02_RXN
BJ70 TP_USB3_P02_RXP USB3_2_RXP @BASEBOARD_FAB2_LIB.BASEBOARD_FAB2(SCH_1):TP_USB3_P02_RXP
BL56 TP_USB3_P02_TXN USB3_2_TXN @BASEBOARD_FAB2_LIB.BASEBOARD_FAB2(SCH_1):TP_USB3_P02_TXN
BJ56 TP_USB3_P02_TXP USB3_2_TXP @BASEBOARD_FAB2_LIB.BASEBOARD_FAB2(SCH_1):TP_USB3_P02_TXP
BH71 TP_USB3_P03_RXN USB3_3_RXN @BASEBOARD_FAB2_LIB.BASEBOARD_FAB2(SCH_1):TP_USB3_P03_RXN
BH69 TP_USB3_P03_RXP USB3_3_RXP @BASEBOARD_FAB2_LIB.BASEBOARD_FAB2(SCH_1):TP_USB3_P03_RXP
BM54 TP_USB3_P03_TXN USB3_3_TXN @BASEBOARD_FAB2_LIB.BASEBOARD_FAB2(SCH_1):TP_USB3_P03_TXN
BN56 TP_USB3_P03_TXP USB3_3_TXP @BASEBOARD_FAB2_LIB.BASEBOARD_FAB2(SCH_1):TP_USB3_P03_TXP
BF72 TP_USB3_P04_RXN USB3_4_RXN @BASEBOARD_FAB2_LIB.BASEBOARD_FAB2(SCH_1):TP_USB3_P04_RXN
BF70 TP_USB3_P04_RXP USB3_4_RXP @BASEBOARD_FAB2_LIB.BASEBOARD_FAB2(SCH_1):TP_USB3_P04_RXP
BH58 TP_USB3_P04_TXN USB3_4_TXN @BASEBOARD_FAB2_LIB.BASEBOARD_FAB2(SCH_1):TP_USB3_P04_TXN
BG56 TP_USB3_P04_TXP USB3_4_TXP @BASEBOARD_FAB2_LIB.BASEBOARD_FAB2(SCH_1):TP_USB3_P04_TXP
BE71 TP_USB3_P05_RXN USB3_5_RXN @BASEBOARD_FAB2_LIB.BASEBOARD_FAB2(SCH_1):TP_USB3_P05_RXN
BE69 TP_USB3_P05_RXP USB3_5_RXP @BASEBOARD_FAB2_LIB.BASEBOARD_FAB2(SCH_1):TP_USB3_P05_RXP
BK58 TP_USB3_P05_TXN USB3_5_TXN @BASEBOARD_FAB2_LIB.BASEBOARD_FAB2(SCH_1):TP_USB3_P05_TXN
BJ59 TP_USB3_P05_TXP USB3_5_TXP @BASEBOARD_FAB2_LIB.BASEBOARD_FAB2(SCH_1):TP_USB3_P05_TXP
BD72 TP_USB3_P06_RXN USB3_6_RXN @BASEBOARD_FAB2_LIB.BASEBOARD_FAB2(SCH_1):TP_USB3_P06_RXN
BD70 TP_USB3_P06_RXP USB3_6_RXP @BASEBOARD_FAB2_LIB.BASEBOARD_FAB2(SCH_1):TP_USB3_P06_RXP
BL59 TP_USB3_P06_TXN USB3_6_TXN @BASEBOARD_FAB2_LIB.BASEBOARD_FAB2(SCH_1):TP_USB3_P06_TXN
BM61 TP_USB3_P06_TXP USB3_6_TXP @BASEBOARD_FAB2_LIB.BASEBOARD_FAB2(SCH_1):TP_USB3_P06_TXP

RES_0402-113,1%,1/16W,CHIP,G21A  I90  R8B9
   1 A_USB2_COMP      A @BASEBOARD_FAB2_LIB.BASEBOARD_FAB2(SCH_1):A_USB2_COMP
   2    GND      B @BASEBOARD_FAB2_LIB.BASEBOARD_FAB2(SCH_1):GND

RES_0402-10.0K,1%,1/16W,CHIP,GA  I114  R8B32
   1 A_USB2_VBUS      A @BASEBOARD_FAB2_LIB.BASEBOARD_FAB2(SCH_1):A_USB2_VBUS
   2    GND      B @BASEBOARD_FAB2_LIB.BASEBOARD_FAB2(SCH_1):GND


DRAWING: @BASEBOARD_FAB2_LIB.BASEBOARD_FAB2(SCH_1):PAGE116 

RES_0402-100.0,1%,1/16W,CHIP,GA  I108  R3M11
   1 A_PCIE_RCOMP_P      A @BASEBOARD_FAB2_LIB.BASEBOARD_FAB2(SCH_1):A_PCIE_RCOMP_P
   2 A_PCIE_RCOMP_N      B @BASEBOARD_FAB2_LIB.BASEBOARD_FAB2(SCH_1):A_PCIE_RCOMP_N

RES_0402-100.0,1%,1/16W,CHIP,GA  I181  R3M12
   1 A_PCIEUP_RCOMP_P      A @BASEBOARD_FAB2_LIB.BASEBOARD_FAB2(SCH_1):A_PCIEUP_RCOMP_P
   2 A_PCIEUP_RCOMP_N      B @BASEBOARD_FAB2_LIB.BASEBOARD_FAB2(SCH_1):A_PCIEUP_RCOMP_N

CAP_A_0402V-0.1UF,16V,10%,EMPTA  I182  C2M4
   1 P2E_SSB_BMC_TX_DP      A @BASEBOARD_FAB2_LIB.BASEBOARD_FAB2(SCH_1):P2E_SSB_BMC_TX_DP
   2 P2E_SSB_BMC_TX_C_DP      B @BASEBOARD_FAB2_LIB.BASEBOARD_FAB2(SCH_1):P2E_SSB_BMC_TX_C_DP

CAP_A_0402V-0.1UF,16V,10%,EMPTA  I183  C2M3
   1 P2E_SSB_BMC_TX_DN      A @BASEBOARD_FAB2_LIB.BASEBOARD_FAB2(SCH_1):P2E_SSB_BMC_TX_DN
   2 P2E_SSB_BMC_TX_C_DN      B @BASEBOARD_FAB2_LIB.BASEBOARD_FAB2(SCH_1):P2E_SSB_BMC_TX_C_DN

LBG_CORE_QAT_EXT_D_BGA1-IC,H91A  I220  U7C1
 D66 A_EXTCLKN EXTCLKN @BASEBOARD_FAB2_LIB.BASEBOARD_FAB2(SCH_1):A_EXTCLKN
 E67 A_EXTCLKP EXTCLKP @BASEBOARD_FAB2_LIB.BASEBOARD_FAB2(SCH_1):A_EXTCLKP
AV63 SATA6G_RX_DN<2> PCIE10_SSATA4_RXN @BASEBOARD_FAB2_LIB.BASEBOARD_FAB2(SCH_1):SATA6G_RX_DN(2)
AU65 SATA6G_RX_DP<2> PCIE10_SSATA4_RXP @BASEBOARD_FAB2_LIB.BASEBOARD_FAB2(SCH_1):SATA6G_RX_DP(2)
AD70 SATA6G_TX_DN<2> PCIE10_SSATA4_TXN @BASEBOARD_FAB2_LIB.BASEBOARD_FAB2(SCH_1):SATA6G_TX_DN(2)
AD72 SATA6G_TX_DP<2> PCIE10_SSATA4_TXP @BASEBOARD_FAB2_LIB.BASEBOARD_FAB2(SCH_1):SATA6G_TX_DP(2)
AT66 SATA6G_RX_DN<3> PCIE11_SSATA5_GBE_RXN @BASEBOARD_FAB2_LIB.BASEBOARD_FAB2(SCH_1):SATA6G_RX_DN(3)
AV66 SATA6G_RX_DP<3> PCIE11_SSATA5_GBE_RXP @BASEBOARD_FAB2_LIB.BASEBOARD_FAB2(SCH_1):SATA6G_RX_DP(3)
AC69 SATA6G_TX_DN<3> PCIE11_SSATA5_GBE_TXN @BASEBOARD_FAB2_LIB.BASEBOARD_FAB2(SCH_1):SATA6G_TX_DN(3)
AC71 SATA6G_TX_DP<3> PCIE11_SSATA5_GBE_TXP @BASEBOARD_FAB2_LIB.BASEBOARD_FAB2(SCH_1):SATA6G_TX_DP(3)
AR61 SATA6G_PCH_PCIE_UP_SATA_RXN<0> PCIE12_UP0_SATA0_RXN @BASEBOARD_FAB2_LIB.BASEBOARD_FAB2(SCH_1):SATA6G_PCH_PCIE_UP_SATA_RXN(0)
AT63 SATA6G_PCH_PCIE_UP_SATA_RXP<0> PCIE12_UP0_SATA0_RXP @BASEBOARD_FAB2_LIB.BASEBOARD_FAB2(SCH_1):SATA6G_PCH_PCIE_UP_SATA_RXP(0)
 W69 SATA6G_PCH_PCIE_UP_SATA_TXN<0> PCIE12_UP0_SATA0_TXN @BASEBOARD_FAB2_LIB.BASEBOARD_FAB2(SCH_1):SATA6G_PCH_PCIE_UP_SATA_TXN(0)
 W71 SATA6G_PCH_PCIE_UP_SATA_TXP<0> PCIE12_UP0_SATA0_TXP @BASEBOARD_FAB2_LIB.BASEBOARD_FAB2(SCH_1):SATA6G_PCH_PCIE_UP_SATA_TXP(0)
AL66 SATA6G_PCH_PCIE_UP_SATA_RXN<1> PCIE13_UP1_SATA1_RXN @BASEBOARD_FAB2_LIB.BASEBOARD_FAB2(SCH_1):SATA6G_PCH_PCIE_UP_SATA_RXN(1)
AN65 SATA6G_PCH_PCIE_UP_SATA_RXP<1> PCIE13_UP1_SATA1_RXP @BASEBOARD_FAB2_LIB.BASEBOARD_FAB2(SCH_1):SATA6G_PCH_PCIE_UP_SATA_RXP(1)
 V70 SATA6G_PCH_PCIE_UP_SATA_TXN<1> PCIE13_UP1_SATA1_TXN @BASEBOARD_FAB2_LIB.BASEBOARD_FAB2(SCH_1):SATA6G_PCH_PCIE_UP_SATA_TXN(1)
 V72 SATA6G_PCH_PCIE_UP_SATA_TXP<1> PCIE13_UP1_SATA1_TXP @BASEBOARD_FAB2_LIB.BASEBOARD_FAB2(SCH_1):SATA6G_PCH_PCIE_UP_SATA_TXP(1)
AK65 SATA6G_PCH_PCIE_UP_SATA_RXN<2> PCIE14_UP2_SATA2_RXN @BASEBOARD_FAB2_LIB.BASEBOARD_FAB2(SCH_1):SATA6G_PCH_PCIE_UP_SATA_RXN(2)
AJ63 SATA6G_PCH_PCIE_UP_SATA_RXP<2> PCIE14_UP2_SATA2_RXP @BASEBOARD_FAB2_LIB.BASEBOARD_FAB2(SCH_1):SATA6G_PCH_PCIE_UP_SATA_RXP(2)
 T69 SATA6G_PCH_PCIE_UP_SATA_TXN<2> PCIE14_UP2_SATA2_TXN @BASEBOARD_FAB2_LIB.BASEBOARD_FAB2(SCH_1):SATA6G_PCH_PCIE_UP_SATA_TXN(2)
 T71 SATA6G_PCH_PCIE_UP_SATA_TXP<2> PCIE14_UP2_SATA2_TXP @BASEBOARD_FAB2_LIB.BASEBOARD_FAB2(SCH_1):SATA6G_PCH_PCIE_UP_SATA_TXP(2)
AP63 SATA6G_PCH_PCIE_UP_SATA_RXN<3> PCIE15_UP3_SATA3_RXN @BASEBOARD_FAB2_LIB.BASEBOARD_FAB2(SCH_1):SATA6G_PCH_PCIE_UP_SATA_RXN(3)
AL63 SATA6G_PCH_PCIE_UP_SATA_RXP<3> PCIE15_UP3_SATA3_RXP @BASEBOARD_FAB2_LIB.BASEBOARD_FAB2(SCH_1):SATA6G_PCH_PCIE_UP_SATA_RXP(3)
 R70 SATA6G_PCH_PCIE_UP_SATA_TXN<3> PCIE15_UP3_SATA3_TXN @BASEBOARD_FAB2_LIB.BASEBOARD_FAB2(SCH_1):SATA6G_PCH_PCIE_UP_SATA_TXN(3)
 R72 SATA6G_PCH_PCIE_UP_SATA_TXP<3> PCIE15_UP3_SATA3_TXP @BASEBOARD_FAB2_LIB.BASEBOARD_FAB2(SCH_1):SATA6G_PCH_PCIE_UP_SATA_TXP(3)
AF65 SATA6G_PCH_PCIE_UP_SATA_RXN<4> PCIE16_UP4_SATA4_RXN @BASEBOARD_FAB2_LIB.BASEBOARD_FAB2(SCH_1):SATA6G_PCH_PCIE_UP_SATA_RXN(4)
AH65 SATA6G_PCH_PCIE_UP_SATA_RXP<4> PCIE16_UP4_SATA4_RXP @BASEBOARD_FAB2_LIB.BASEBOARD_FAB2(SCH_1):SATA6G_PCH_PCIE_UP_SATA_RXP(4)
 P69 SATA6G_PCH_PCIE_UP_SATA_TXN<4> PCIE16_UP4_SATA4_TXN @BASEBOARD_FAB2_LIB.BASEBOARD_FAB2(SCH_1):SATA6G_PCH_PCIE_UP_SATA_TXN(4)
 P71 SATA6G_PCH_PCIE_UP_SATA_TXP<4> PCIE16_UP4_SATA4_TXP @BASEBOARD_FAB2_LIB.BASEBOARD_FAB2(SCH_1):SATA6G_PCH_PCIE_UP_SATA_TXP(4)
AH61 SATA6G_PCH_PCIE_UP_SATA_RXN<5> PCIE17_UP5_SATA5_RXN @BASEBOARD_FAB2_LIB.BASEBOARD_FAB2(SCH_1):SATA6G_PCH_PCIE_UP_SATA_RXN(5)
AG63 SATA6G_PCH_PCIE_UP_SATA_RXP<5> PCIE17_UP5_SATA5_RXP @BASEBOARD_FAB2_LIB.BASEBOARD_FAB2(SCH_1):SATA6G_PCH_PCIE_UP_SATA_RXP(5)
 N70 SATA6G_PCH_PCIE_UP_SATA_TXN<5> PCIE17_UP5_SATA5_TXN @BASEBOARD_FAB2_LIB.BASEBOARD_FAB2(SCH_1):SATA6G_PCH_PCIE_UP_SATA_TXN(5)
 N72 SATA6G_PCH_PCIE_UP_SATA_TXP<5> PCIE17_UP5_SATA5_TXP @BASEBOARD_FAB2_LIB.BASEBOARD_FAB2(SCH_1):SATA6G_PCH_PCIE_UP_SATA_TXP(5)
AP59 SATA6G_PCH_PCIE_UP_SATA_RXN<6> PCIE18_UP6_SATA6_RXN @BASEBOARD_FAB2_LIB.BASEBOARD_FAB2(SCH_1):SATA6G_PCH_PCIE_UP_SATA_RXN(6)
AN61 SATA6G_PCH_PCIE_UP_SATA_RXP<6> PCIE18_UP6_SATA6_RXP @BASEBOARD_FAB2_LIB.BASEBOARD_FAB2(SCH_1):SATA6G_PCH_PCIE_UP_SATA_RXP(6)
 M69 SATA6G_PCH_PCIE_UP_SATA_TXN<6> PCIE18_UP6_SATA6_TXN @BASEBOARD_FAB2_LIB.BASEBOARD_FAB2(SCH_1):SATA6G_PCH_PCIE_UP_SATA_TXN(6)
 M71 SATA6G_PCH_PCIE_UP_SATA_TXP<6> PCIE18_UP6_SATA6_TXP @BASEBOARD_FAB2_LIB.BASEBOARD_FAB2(SCH_1):SATA6G_PCH_PCIE_UP_SATA_TXP(6)
AA61 SATA6G_PCH_PCIE_UP_SATA_RXN<7> PCIE19_UP7_SATA7_RXN @BASEBOARD_FAB2_LIB.BASEBOARD_FAB2(SCH_1):SATA6G_PCH_PCIE_UP_SATA_RXN(7)
AD61 SATA6G_PCH_PCIE_UP_SATA_RXP<7> PCIE19_UP7_SATA7_RXP @BASEBOARD_FAB2_LIB.BASEBOARD_FAB2(SCH_1):SATA6G_PCH_PCIE_UP_SATA_RXP(7)
 L70 SATA6G_PCH_PCIE_UP_SATA_TXN<7> PCIE19_UP7_SATA7_TXN @BASEBOARD_FAB2_LIB.BASEBOARD_FAB2(SCH_1):SATA6G_PCH_PCIE_UP_SATA_TXN(7)
 L72 SATA6G_PCH_PCIE_UP_SATA_TXP<7> PCIE19_UP7_SATA7_TXP @BASEBOARD_FAB2_LIB.BASEBOARD_FAB2(SCH_1):SATA6G_PCH_PCIE_UP_SATA_TXP(7)
AN70 P2E_SSB_BMC_RX_C_DN PCIE4_GBE_RXN @BASEBOARD_FAB2_LIB.BASEBOARD_FAB2(SCH_1):P2E_SSB_BMC_RX_C_DN
AN72 P2E_SSB_BMC_RX_C_DP PCIE4_GBE_RXP @BASEBOARD_FAB2_LIB.BASEBOARD_FAB2(SCH_1):P2E_SSB_BMC_RX_C_DP
BG66 P2E_SSB_BMC_TX_DN PCIE4_GBE_TXN @BASEBOARD_FAB2_LIB.BASEBOARD_FAB2(SCH_1):P2E_SSB_BMC_TX_DN
BJ66 P2E_SSB_BMC_TX_DP PCIE4_GBE_TXP @BASEBOARD_FAB2_LIB.BASEBOARD_FAB2(SCH_1):P2E_SSB_BMC_TX_DP
AM69 PE_PCH_SPRV_RX_C_DN PCIE5_GBE_RXN @BASEBOARD_FAB2_LIB.BASEBOARD_FAB2(SCH_1):PE_PCH_SPRV_RX_C_DN
AM71 PE_PCH_SPRV_RX_C_DP PCIE5_GBE_RXP @BASEBOARD_FAB2_LIB.BASEBOARD_FAB2(SCH_1):PE_PCH_SPRV_RX_C_DP
BH65 PE_PCH_SPRV_TX_DN PCIE5_GBE_TXN @BASEBOARD_FAB2_LIB.BASEBOARD_FAB2(SCH_1):PE_PCH_SPRV_TX_DN
BJ63 PE_PCH_SPRV_TX_DP PCIE5_GBE_TXP @BASEBOARD_FAB2_LIB.BASEBOARD_FAB2(SCH_1):PE_PCH_SPRV_TX_DP
BB63 SATA6G_S0_RX_DN PCIE6_SSATA0_RXN @BASEBOARD_FAB2_LIB.BASEBOARD_FAB2(SCH_1):SATA6G_S0_RX_DN
BD61 SATA6G_S0_RX_DP PCIE6_SSATA0_RXP @BASEBOARD_FAB2_LIB.BASEBOARD_FAB2(SCH_1):SATA6G_S0_RX_DP
AJ70 SATA6G_S0_TX_DN PCIE6_SSATA0_TXN @BASEBOARD_FAB2_LIB.BASEBOARD_FAB2(SCH_1):SATA6G_S0_TX_DN
AJ72 SATA6G_S0_TX_DP PCIE6_SSATA0_TXP @BASEBOARD_FAB2_LIB.BASEBOARD_FAB2(SCH_1):SATA6G_S0_TX_DP
AY59 SATA6G_S1_RX_DN PCIE7_SSATA1_RXN @BASEBOARD_FAB2_LIB.BASEBOARD_FAB2(SCH_1):SATA6G_S1_RX_DN
BA61 SATA6G_S1_RX_DP PCIE7_SSATA1_RXP @BASEBOARD_FAB2_LIB.BASEBOARD_FAB2(SCH_1):SATA6G_S1_RX_DP
AH69 SATA6G_S1_TX_DN PCIE7_SSATA1_TXN @BASEBOARD_FAB2_LIB.BASEBOARD_FAB2(SCH_1):SATA6G_S1_TX_DN
AH71 SATA6G_S1_TX_DP PCIE7_SSATA1_TXP @BASEBOARD_FAB2_LIB.BASEBOARD_FAB2(SCH_1):SATA6G_S1_TX_DP
BA65 SATA6G_RX_DN<0> PCIE8_SSATA2_GBE_RXN @BASEBOARD_FAB2_LIB.BASEBOARD_FAB2(SCH_1):SATA6G_RX_DN(0)
BD65 SATA6G_RX_DP<0> PCIE8_SSATA2_GBE_RXP @BASEBOARD_FAB2_LIB.BASEBOARD_FAB2(SCH_1):SATA6G_RX_DP(0)
AF70 SATA6G_TX_DN<0> PCIE8_SSATA2_GBE_TXN @BASEBOARD_FAB2_LIB.BASEBOARD_FAB2(SCH_1):SATA6G_TX_DN(0)
AF72 SATA6G_TX_DP<0> PCIE8_SSATA2_GBE_TXP @BASEBOARD_FAB2_LIB.BASEBOARD_FAB2(SCH_1):SATA6G_TX_DP(0)
AW65 SATA6G_RX_DN<1> PCIE9_SSATA3_RXN @BASEBOARD_FAB2_LIB.BASEBOARD_FAB2(SCH_1):SATA6G_RX_DN(1)
AY66 SATA6G_RX_DP<1> PCIE9_SSATA3_RXP @BASEBOARD_FAB2_LIB.BASEBOARD_FAB2(SCH_1):SATA6G_RX_DP(1)
AE69 SATA6G_TX_DN<1> PCIE9_SSATA3_TXN @BASEBOARD_FAB2_LIB.BASEBOARD_FAB2(SCH_1):SATA6G_TX_DN(1)
AE71 SATA6G_TX_DP<1> PCIE9_SSATA3_TXP @BASEBOARD_FAB2_LIB.BASEBOARD_FAB2(SCH_1):SATA6G_TX_DP(1)
AF58 A_PCIEUP_RCOMP_N PCIEUP_RCOMPN @BASEBOARD_FAB2_LIB.BASEBOARD_FAB2(SCH_1):A_PCIEUP_RCOMP_N
AH58 A_PCIEUP_RCOMP_P PCIEUP_RCOMPP @BASEBOARD_FAB2_LIB.BASEBOARD_FAB2(SCH_1):A_PCIEUP_RCOMP_P
BD58 A_PCIE_RCOMP_N PCIE_RCOMPN @BASEBOARD_FAB2_LIB.BASEBOARD_FAB2(SCH_1):A_PCIE_RCOMP_N
BB56 A_PCIE_RCOMP_P PCIE_RCOMPP @BASEBOARD_FAB2_LIB.BASEBOARD_FAB2(SCH_1):A_PCIE_RCOMP_P
AA71 TP_PCH_RSVD52 RSVD<52> @BASEBOARD_FAB2_LIB.BASEBOARD_FAB2(SCH_1):TP_PCH_RSVD52
AA69 TP_PCH_RSVD51 RSVD<51> @BASEBOARD_FAB2_LIB.BASEBOARD_FAB2(SCH_1):TP_PCH_RSVD51
 H69 TP_PCH_RSVD50 RSVD<50> @BASEBOARD_FAB2_LIB.BASEBOARD_FAB2(SCH_1):TP_PCH_RSVD50
 G67 TP_PCH_RSVD49 RSVD<49> @BASEBOARD_FAB2_LIB.BASEBOARD_FAB2(SCH_1):TP_PCH_RSVD49
AP71 TP_PCH_RSVD48 RSVD<48> @BASEBOARD_FAB2_LIB.BASEBOARD_FAB2(SCH_1):TP_PCH_RSVD48
AP69 TP_PCH_RSVD47 RSVD<47> @BASEBOARD_FAB2_LIB.BASEBOARD_FAB2(SCH_1):TP_PCH_RSVD47
AV72 P3E_PCH_M2_RX_DN<3> USB3_10_PCIE3_GBE_RXN @BASEBOARD_FAB2_LIB.BASEBOARD_FAB2(SCH_1):P3E_PCH_M2_RX_DN(3)
AV70 P3E_PCH_M2_RX_DP<3> USB3_10_PCIE3_GBE_RXP @BASEBOARD_FAB2_LIB.BASEBOARD_FAB2(SCH_1):P3E_PCH_M2_RX_DP(3)
BH61 P3E_PCH_M2_TX_DN<3> USB3_10_PCIE3_GBE_TXN @BASEBOARD_FAB2_LIB.BASEBOARD_FAB2(SCH_1):P3E_PCH_M2_TX_DN(3)
BK61 P3E_PCH_M2_TX_DP<3> USB3_10_PCIE3_GBE_TXP @BASEBOARD_FAB2_LIB.BASEBOARD_FAB2(SCH_1):P3E_PCH_M2_TX_DP(3)
BA71 P3E_PCH_RX_0_DN USB3_7_PCIE0_RXN @BASEBOARD_FAB2_LIB.BASEBOARD_FAB2(SCH_1):P3E_PCH_RX_0_DN
BA69 P3E_PCH_RX_0_DP USB3_7_PCIE0_RXP @BASEBOARD_FAB2_LIB.BASEBOARD_FAB2(SCH_1):P3E_PCH_RX_0_DP
BR61 P3E_PCH_TX_0_DN USB3_7_PCIE0_TXN @BASEBOARD_FAB2_LIB.BASEBOARD_FAB2(SCH_1):P3E_PCH_TX_0_DN
BN63 P3E_PCH_TX_0_DP USB3_7_PCIE0_TXP @BASEBOARD_FAB2_LIB.BASEBOARD_FAB2(SCH_1):P3E_PCH_TX_0_DP
AY72 P3E_PCH_M2_RX_DN<1> USB3_8_PCIE1_RXN @BASEBOARD_FAB2_LIB.BASEBOARD_FAB2(SCH_1):P3E_PCH_M2_RX_DN(1)
AY70 P3E_PCH_M2_RX_DP<1> USB3_8_PCIE1_RXP @BASEBOARD_FAB2_LIB.BASEBOARD_FAB2(SCH_1):P3E_PCH_M2_RX_DP(1)
BM65 P3E_PCH_M2_TX_DN<1> USB3_8_PCIE1_TXN @BASEBOARD_FAB2_LIB.BASEBOARD_FAB2(SCH_1):P3E_PCH_M2_TX_DN(1)
BR65 P3E_PCH_M2_TX_DP<1> USB3_8_PCIE1_TXP @BASEBOARD_FAB2_LIB.BASEBOARD_FAB2(SCH_1):P3E_PCH_M2_TX_DP(1)
AW71 P3E_PCH_M2_RX_DN<2> USB3_9_PCIE2_RXN @BASEBOARD_FAB2_LIB.BASEBOARD_FAB2(SCH_1):P3E_PCH_M2_RX_DN(2)
AW69 P3E_PCH_M2_RX_DP<2> USB3_9_PCIE2_RXP @BASEBOARD_FAB2_LIB.BASEBOARD_FAB2(SCH_1):P3E_PCH_M2_RX_DP(2)
BK65 P3E_PCH_M2_TX_DN<2> USB3_9_PCIE2_TXN @BASEBOARD_FAB2_LIB.BASEBOARD_FAB2(SCH_1):P3E_PCH_M2_TX_DN(2)
BL66 P3E_PCH_M2_TX_DP<2> USB3_9_PCIE2_TXP @BASEBOARD_FAB2_LIB.BASEBOARD_FAB2(SCH_1):P3E_PCH_M2_TX_DP(2)

RES_0402-10.0K,1%,1/16W,EMPTY,A  I229  R7B8
   1 A_EXTCLKN      A @BASEBOARD_FAB2_LIB.BASEBOARD_FAB2(SCH_1):A_EXTCLKN
   2    GND      B @BASEBOARD_FAB2_LIB.BASEBOARD_FAB2(SCH_1):GND

RES_0402-10.0K,1%,1/16W,EMPTY,A  I230  R7B7
   1 A_EXTCLKP      A @BASEBOARD_FAB2_LIB.BASEBOARD_FAB2(SCH_1):A_EXTCLKP
   2    GND      B @BASEBOARD_FAB2_LIB.BASEBOARD_FAB2(SCH_1):GND

RES_0402-100.0K,1%,1/16W,CHIP,A  I234  R3M9
   1 P2E_SSB_BMC_RX_C_DN      A @BASEBOARD_FAB2_LIB.BASEBOARD_FAB2(SCH_1):P2E_SSB_BMC_RX_C_DN
   2    GND      B @BASEBOARD_FAB2_LIB.BASEBOARD_FAB2(SCH_1):GND

RES_0402-100.0K,1%,1/16W,CHIP,A  I235  R3M8
   1 P2E_SSB_BMC_RX_C_DP      A @BASEBOARD_FAB2_LIB.BASEBOARD_FAB2(SCH_1):P2E_SSB_BMC_RX_C_DP
   2    GND      B @BASEBOARD_FAB2_LIB.BASEBOARD_FAB2(SCH_1):GND


DRAWING: @BASEBOARD_FAB2_LIB.BASEBOARD_FAB2(SCH_1):PAGE117 

LBG_CORE_QAT_EXT_D_BGA1-IC,H91A  I9  U7C1
 C45 DMI_CPU0_PCH_TX_C_DN<3> DMI_RXN<3> @BASEBOARD_FAB2_LIB.BASEBOARD_FAB2(SCH_1):DMI_CPU0_PCH_TX_C_DN(3)
 D44 DMI_CPU0_PCH_TX_C_DN<2> DMI_RXN<2> @BASEBOARD_FAB2_LIB.BASEBOARD_FAB2(SCH_1):DMI_CPU0_PCH_TX_C_DN(2)
 C43 DMI_CPU0_PCH_TX_C_DN<1> DMI_RXN<1> @BASEBOARD_FAB2_LIB.BASEBOARD_FAB2(SCH_1):DMI_CPU0_PCH_TX_C_DN(1)
 D42 DMI_CPU0_PCH_TX_C_DN<0> DMI_RXN<0> @BASEBOARD_FAB2_LIB.BASEBOARD_FAB2(SCH_1):DMI_CPU0_PCH_TX_C_DN(0)
 A45 DMI_CPU0_PCH_TX_C_DP<3> DMI_RXP<3> @BASEBOARD_FAB2_LIB.BASEBOARD_FAB2(SCH_1):DMI_CPU0_PCH_TX_C_DP(3)
 B44 DMI_CPU0_PCH_TX_C_DP<2> DMI_RXP<2> @BASEBOARD_FAB2_LIB.BASEBOARD_FAB2(SCH_1):DMI_CPU0_PCH_TX_C_DP(2)
 A43 DMI_CPU0_PCH_TX_C_DP<1> DMI_RXP<1> @BASEBOARD_FAB2_LIB.BASEBOARD_FAB2(SCH_1):DMI_CPU0_PCH_TX_C_DP(1)
 B42 DMI_CPU0_PCH_TX_C_DP<0> DMI_RXP<0> @BASEBOARD_FAB2_LIB.BASEBOARD_FAB2(SCH_1):DMI_CPU0_PCH_TX_C_DP(0)
 P52 DMI_CPU0_PCH_RX_DN<3> DMI_TXN<3> @BASEBOARD_FAB2_LIB.BASEBOARD_FAB2(SCH_1):DMI_CPU0_PCH_RX_DN(3)
 K50 DMI_CPU0_PCH_RX_DN<2> DMI_TXN<2> @BASEBOARD_FAB2_LIB.BASEBOARD_FAB2(SCH_1):DMI_CPU0_PCH_RX_DN(2)
 J48 DMI_CPU0_PCH_RX_DN<1> DMI_TXN<1> @BASEBOARD_FAB2_LIB.BASEBOARD_FAB2(SCH_1):DMI_CPU0_PCH_RX_DN(1)
 H46 DMI_CPU0_PCH_RX_DN<0> DMI_TXN<0> @BASEBOARD_FAB2_LIB.BASEBOARD_FAB2(SCH_1):DMI_CPU0_PCH_RX_DN(0)
 N54 DMI_CPU0_PCH_RX_DP<3> DMI_TXP<3> @BASEBOARD_FAB2_LIB.BASEBOARD_FAB2(SCH_1):DMI_CPU0_PCH_RX_DP(3)
 M52 DMI_CPU0_PCH_RX_DP<2> DMI_TXP<2> @BASEBOARD_FAB2_LIB.BASEBOARD_FAB2(SCH_1):DMI_CPU0_PCH_RX_DP(2)
 H50 DMI_CPU0_PCH_RX_DP<1> DMI_TXP<1> @BASEBOARD_FAB2_LIB.BASEBOARD_FAB2(SCH_1):DMI_CPU0_PCH_RX_DP(1)
 K46 DMI_CPU0_PCH_RX_DP<0> DMI_TXP<0> @BASEBOARD_FAB2_LIB.BASEBOARD_FAB2(SCH_1):DMI_CPU0_PCH_RX_DP(0)
 C48 P3E_CPU0_PE1_PCH_TXN<0> PCIEUP_0_RXN @BASEBOARD_FAB2_LIB.BASEBOARD_FAB2(SCH_1):P3E_CPU0_PE1_PCH_TXN(0)
 A48 P3E_CPU0_PE1_PCH_TXP<0> PCIEUP_0_RXP @BASEBOARD_FAB2_LIB.BASEBOARD_FAB2(SCH_1):P3E_CPU0_PE1_PCH_TXP(0)
 J52 P3E_CPU0_PE1_PCH_RXN<0> PCIEUP_0_TXN @BASEBOARD_FAB2_LIB.BASEBOARD_FAB2(SCH_1):P3E_CPU0_PE1_PCH_RXN(0)
 G52 P3E_CPU0_PE1_PCH_RXP<0> PCIEUP_0_TXP @BASEBOARD_FAB2_LIB.BASEBOARD_FAB2(SCH_1):P3E_CPU0_PE1_PCH_RXP(0)
 C59 P3E_CPU0_PE1_PCH_C_TXP<10> PCIEUP_10_RXN @BASEBOARD_FAB2_LIB.BASEBOARD_FAB2(SCH_1):P3E_CPU0_PE1_PCH_C_TXP(10)
 A59 P3E_CPU0_PE1_PCH_C_TXN<10> PCIEUP_10_RXP @BASEBOARD_FAB2_LIB.BASEBOARD_FAB2(SCH_1):P3E_CPU0_PE1_PCH_C_TXN(10)
 N65 P3E_CPU0_PE1_PCH_R_RXN<10> PCIEUP_10_TXN @BASEBOARD_FAB2_LIB.BASEBOARD_FAB2(SCH_1):P3E_CPU0_PE1_PCH_R_RXN(10)
 P66 P3E_CPU0_PE1_PCH_R_RXP<10> PCIEUP_10_TXP @BASEBOARD_FAB2_LIB.BASEBOARD_FAB2(SCH_1):P3E_CPU0_PE1_PCH_R_RXP(10)
 D60 P3E_CPU0_PE1_PCH_C_TXN<11> PCIEUP_11_RXN @BASEBOARD_FAB2_LIB.BASEBOARD_FAB2(SCH_1):P3E_CPU0_PE1_PCH_C_TXN(11)
 B60 P3E_CPU0_PE1_PCH_C_TXP<11> PCIEUP_11_RXP @BASEBOARD_FAB2_LIB.BASEBOARD_FAB2(SCH_1):P3E_CPU0_PE1_PCH_C_TXP(11)
 T59 P3E_CPU0_PE1_PCH_R_RXN<11> PCIEUP_11_TXN @BASEBOARD_FAB2_LIB.BASEBOARD_FAB2(SCH_1):P3E_CPU0_PE1_PCH_R_RXN(11)
 V59 P3E_CPU0_PE1_PCH_R_RXP<11> PCIEUP_11_TXP @BASEBOARD_FAB2_LIB.BASEBOARD_FAB2(SCH_1):P3E_CPU0_PE1_PCH_R_RXP(11)
 C61 P3E_CPU0_PE1_PCH_C_TXP<12> PCIEUP_12_RXN @BASEBOARD_FAB2_LIB.BASEBOARD_FAB2(SCH_1):P3E_CPU0_PE1_PCH_C_TXP(12)
 A61 P3E_CPU0_PE1_PCH_C_TXN<12> PCIEUP_12_RXP @BASEBOARD_FAB2_LIB.BASEBOARD_FAB2(SCH_1):P3E_CPU0_PE1_PCH_C_TXN(12)
 R65 P3E_CPU0_PE1_PCH_R_RXN<12> PCIEUP_12_TXN @BASEBOARD_FAB2_LIB.BASEBOARD_FAB2(SCH_1):P3E_CPU0_PE1_PCH_R_RXN(12)
 U65 P3E_CPU0_PE1_PCH_R_RXP<12> PCIEUP_12_TXP @BASEBOARD_FAB2_LIB.BASEBOARD_FAB2(SCH_1):P3E_CPU0_PE1_PCH_R_RXP(12)
 D62 P3E_CPU0_PE1_PCH_C_TXP<13> PCIEUP_13_RXN @BASEBOARD_FAB2_LIB.BASEBOARD_FAB2(SCH_1):P3E_CPU0_PE1_PCH_C_TXP(13)
 B62 P3E_CPU0_PE1_PCH_C_TXN<13> PCIEUP_13_RXP @BASEBOARD_FAB2_LIB.BASEBOARD_FAB2(SCH_1):P3E_CPU0_PE1_PCH_C_TXN(13)
 T63 P3E_CPU0_PE1_PCH_R_RXN<13> PCIEUP_13_TXN @BASEBOARD_FAB2_LIB.BASEBOARD_FAB2(SCH_1):P3E_CPU0_PE1_PCH_R_RXN(13)
 U61 P3E_CPU0_PE1_PCH_R_RXP<13> PCIEUP_13_TXP @BASEBOARD_FAB2_LIB.BASEBOARD_FAB2(SCH_1):P3E_CPU0_PE1_PCH_R_RXP(13)
 C63 P3E_CPU0_PE1_PCH_C_TXP<14> PCIEUP_14_RXN @BASEBOARD_FAB2_LIB.BASEBOARD_FAB2(SCH_1):P3E_CPU0_PE1_PCH_C_TXP(14)
 A63 P3E_CPU0_PE1_PCH_C_TXN<14> PCIEUP_14_RXP @BASEBOARD_FAB2_LIB.BASEBOARD_FAB2(SCH_1):P3E_CPU0_PE1_PCH_C_TXN(14)
 W65 P3E_CPU0_PE1_PCH_R_RXN<14> PCIEUP_14_TXN @BASEBOARD_FAB2_LIB.BASEBOARD_FAB2(SCH_1):P3E_CPU0_PE1_PCH_R_RXN(14)
 V63 P3E_CPU0_PE1_PCH_R_RXP<14> PCIEUP_14_TXP @BASEBOARD_FAB2_LIB.BASEBOARD_FAB2(SCH_1):P3E_CPU0_PE1_PCH_R_RXP(14)
 D64 P3E_CPU0_PE1_PCH_C_TXP<15> PCIEUP_15_RXN @BASEBOARD_FAB2_LIB.BASEBOARD_FAB2(SCH_1):P3E_CPU0_PE1_PCH_C_TXP(15)
 B64 P3E_CPU0_PE1_PCH_C_TXN<15> PCIEUP_15_RXP @BASEBOARD_FAB2_LIB.BASEBOARD_FAB2(SCH_1):P3E_CPU0_PE1_PCH_C_TXN(15)
 Y66 P3E_CPU0_PE1_PCH_R_RXN<15> PCIEUP_15_TXN @BASEBOARD_FAB2_LIB.BASEBOARD_FAB2(SCH_1):P3E_CPU0_PE1_PCH_R_RXN(15)
AA65 P3E_CPU0_PE1_PCH_R_RXP<15> PCIEUP_15_TXP @BASEBOARD_FAB2_LIB.BASEBOARD_FAB2(SCH_1):P3E_CPU0_PE1_PCH_R_RXP(15)
 D49 P3E_CPU0_PE1_PCH_TXN<1> PCIEUP_1_RXN @BASEBOARD_FAB2_LIB.BASEBOARD_FAB2(SCH_1):P3E_CPU0_PE1_PCH_TXN(1)
 B49 P3E_CPU0_PE1_PCH_TXP<1> PCIEUP_1_RXP @BASEBOARD_FAB2_LIB.BASEBOARD_FAB2(SCH_1):P3E_CPU0_PE1_PCH_TXP(1)
 P56 P3E_CPU0_PE1_PCH_RXN<1> PCIEUP_1_TXN @BASEBOARD_FAB2_LIB.BASEBOARD_FAB2(SCH_1):P3E_CPU0_PE1_PCH_RXN(1)
 M56 P3E_CPU0_PE1_PCH_RXP<1> PCIEUP_1_TXP @BASEBOARD_FAB2_LIB.BASEBOARD_FAB2(SCH_1):P3E_CPU0_PE1_PCH_RXP(1)
 C50 P3E_CPU0_PE1_PCH_TXN<2> PCIEUP_2_RXN @BASEBOARD_FAB2_LIB.BASEBOARD_FAB2(SCH_1):P3E_CPU0_PE1_PCH_TXN(2)
 A50 P3E_CPU0_PE1_PCH_TXP<2> PCIEUP_2_RXP @BASEBOARD_FAB2_LIB.BASEBOARD_FAB2(SCH_1):P3E_CPU0_PE1_PCH_TXP(2)
 H54 P3E_CPU0_PE1_PCH_RXN<2> PCIEUP_2_TXN @BASEBOARD_FAB2_LIB.BASEBOARD_FAB2(SCH_1):P3E_CPU0_PE1_PCH_RXN(2)
 G56 P3E_CPU0_PE1_PCH_RXP<2> PCIEUP_2_TXP @BASEBOARD_FAB2_LIB.BASEBOARD_FAB2(SCH_1):P3E_CPU0_PE1_PCH_RXP(2)
 D51 P3E_CPU0_PE1_PCH_TXN<3> PCIEUP_3_RXN @BASEBOARD_FAB2_LIB.BASEBOARD_FAB2(SCH_1):P3E_CPU0_PE1_PCH_TXN(3)
 B51 P3E_CPU0_PE1_PCH_TXP<3> PCIEUP_3_RXP @BASEBOARD_FAB2_LIB.BASEBOARD_FAB2(SCH_1):P3E_CPU0_PE1_PCH_TXP(3)
 J56 P3E_CPU0_PE1_PCH_RXN<3> PCIEUP_3_TXN @BASEBOARD_FAB2_LIB.BASEBOARD_FAB2(SCH_1):P3E_CPU0_PE1_PCH_RXN(3)
 K58 P3E_CPU0_PE1_PCH_RXP<3> PCIEUP_3_TXP @BASEBOARD_FAB2_LIB.BASEBOARD_FAB2(SCH_1):P3E_CPU0_PE1_PCH_RXP(3)
 C52 P3E_CPU0_PE1_PCH_TXN<4> PCIEUP_4_RXN @BASEBOARD_FAB2_LIB.BASEBOARD_FAB2(SCH_1):P3E_CPU0_PE1_PCH_TXN(4)
 A52 P3E_CPU0_PE1_PCH_TXP<4> PCIEUP_4_RXP @BASEBOARD_FAB2_LIB.BASEBOARD_FAB2(SCH_1):P3E_CPU0_PE1_PCH_TXP(4)
 N58 P3E_CPU0_PE1_PCH_RXN<4> PCIEUP_4_TXN @BASEBOARD_FAB2_LIB.BASEBOARD_FAB2(SCH_1):P3E_CPU0_PE1_PCH_RXN(4)
 M59 P3E_CPU0_PE1_PCH_RXP<4> PCIEUP_4_TXP @BASEBOARD_FAB2_LIB.BASEBOARD_FAB2(SCH_1):P3E_CPU0_PE1_PCH_RXP(4)
 D53 P3E_CPU0_PE1_PCH_TXN<5> PCIEUP_5_RXN @BASEBOARD_FAB2_LIB.BASEBOARD_FAB2(SCH_1):P3E_CPU0_PE1_PCH_TXN(5)
 B53 P3E_CPU0_PE1_PCH_TXP<5> PCIEUP_5_RXP @BASEBOARD_FAB2_LIB.BASEBOARD_FAB2(SCH_1):P3E_CPU0_PE1_PCH_TXP(5)
 N61 P3E_CPU0_PE1_PCH_RXN<5> PCIEUP_5_TXN @BASEBOARD_FAB2_LIB.BASEBOARD_FAB2(SCH_1):P3E_CPU0_PE1_PCH_RXN(5)
 K61 P3E_CPU0_PE1_PCH_RXP<5> PCIEUP_5_TXP @BASEBOARD_FAB2_LIB.BASEBOARD_FAB2(SCH_1):P3E_CPU0_PE1_PCH_RXP(5)
 C54 P3E_CPU0_PE1_PCH_TXN<6> PCIEUP_6_RXN @BASEBOARD_FAB2_LIB.BASEBOARD_FAB2(SCH_1):P3E_CPU0_PE1_PCH_TXN(6)
 A54 P3E_CPU0_PE1_PCH_TXP<6> PCIEUP_6_RXP @BASEBOARD_FAB2_LIB.BASEBOARD_FAB2(SCH_1):P3E_CPU0_PE1_PCH_TXP(6)
 H61 P3E_CPU0_PE1_PCH_RXN<6> PCIEUP_6_TXN @BASEBOARD_FAB2_LIB.BASEBOARD_FAB2(SCH_1):P3E_CPU0_PE1_PCH_RXN(6)
 J63 P3E_CPU0_PE1_PCH_RXP<6> PCIEUP_6_TXP @BASEBOARD_FAB2_LIB.BASEBOARD_FAB2(SCH_1):P3E_CPU0_PE1_PCH_RXP(6)
 D55 P3E_CPU0_PE1_PCH_TXN<7> PCIEUP_7_RXN @BASEBOARD_FAB2_LIB.BASEBOARD_FAB2(SCH_1):P3E_CPU0_PE1_PCH_TXN(7)
 B55 P3E_CPU0_PE1_PCH_TXP<7> PCIEUP_7_RXP @BASEBOARD_FAB2_LIB.BASEBOARD_FAB2(SCH_1):P3E_CPU0_PE1_PCH_TXP(7)
 P59 P3E_CPU0_PE1_PCH_RXN<7> PCIEUP_7_TXN @BASEBOARD_FAB2_LIB.BASEBOARD_FAB2(SCH_1):P3E_CPU0_PE1_PCH_RXN(7)
 R61 P3E_CPU0_PE1_PCH_RXP<7> PCIEUP_7_TXP @BASEBOARD_FAB2_LIB.BASEBOARD_FAB2(SCH_1):P3E_CPU0_PE1_PCH_RXP(7)
 C57 P3E_CPU0_PE1_PCH_C_TXP<8> PCIEUP_8_RXN @BASEBOARD_FAB2_LIB.BASEBOARD_FAB2(SCH_1):P3E_CPU0_PE1_PCH_C_TXP(8)
 A57 P3E_CPU0_PE1_PCH_C_TXN<8> PCIEUP_8_RXP @BASEBOARD_FAB2_LIB.BASEBOARD_FAB2(SCH_1):P3E_CPU0_PE1_PCH_C_TXN(8)
 K65 P3E_CPU0_PE1_PCH_R_RXN<8> PCIEUP_8_TXN @BASEBOARD_FAB2_LIB.BASEBOARD_FAB2(SCH_1):P3E_CPU0_PE1_PCH_R_RXN(8)
 M63 P3E_CPU0_PE1_PCH_R_RXP<8> PCIEUP_8_TXP @BASEBOARD_FAB2_LIB.BASEBOARD_FAB2(SCH_1):P3E_CPU0_PE1_PCH_R_RXP(8)
 D58 P3E_CPU0_PE1_PCH_C_TXP<9> PCIEUP_9_RXN @BASEBOARD_FAB2_LIB.BASEBOARD_FAB2(SCH_1):P3E_CPU0_PE1_PCH_C_TXP(9)
 B58 P3E_CPU0_PE1_PCH_C_TXN<9> PCIEUP_9_RXP @BASEBOARD_FAB2_LIB.BASEBOARD_FAB2(SCH_1):P3E_CPU0_PE1_PCH_C_TXN(9)
 J66 P3E_CPU0_PE1_PCH_R_RXN<9> PCIEUP_9_TXN @BASEBOARD_FAB2_LIB.BASEBOARD_FAB2(SCH_1):P3E_CPU0_PE1_PCH_R_RXN(9)
 M66 P3E_CPU0_PE1_PCH_R_RXP<9> PCIEUP_9_TXP @BASEBOARD_FAB2_LIB.BASEBOARD_FAB2(SCH_1):P3E_CPU0_PE1_PCH_R_RXP(9)


DRAWING: @BASEBOARD_FAB2_LIB.BASEBOARD_FAB2(SCH_1):PAGE118 

RES_0402-10.0,1%,1/16W,CHIP,G2A  I66  R3N9
   1 H_PM_SYNC1_GTL_R      A @BASEBOARD_FAB2_LIB.BASEBOARD_FAB2(SCH_1):H_PM_SYNC1_GTL_R
   2 H_PM_SYNC_GTL      B @BASEBOARD_FAB2_LIB.BASEBOARD_FAB2(SCH_1):H_PM_SYNC_GTL

RES_0402-49.9,1%,1/16W,EMPTY,GA  I67  R3N14
   1 H_PM_SYNC_GTL      A @BASEBOARD_FAB2_LIB.BASEBOARD_FAB2(SCH_1):H_PM_SYNC_GTL
   2    GND      B @BASEBOARD_FAB2_LIB.BASEBOARD_FAB2(SCH_1):GND

RES_0402-4.75K,1%,1/16W,CHIP,GA  I71  R3N13
   1 P3V3_STBY      A @BASEBOARD_FAB2_LIB.BASEBOARD_FAB2(SCH_1):P3V3_STBY
   2 IRQ_LVC3_WAKE_N      B @BASEBOARD_FAB2_LIB.BASEBOARD_FAB2(SCH_1):IRQ_LVC3_WAKE_N

LBG_CORE_QAT_EXT_D_BGA1-IC,H91A  I73  U7C1
AT56 XDP_TRST_N CPU_TRST_N @BASEBOARD_FAB2_LIB.BASEBOARD_FAB2(SCH_1):XDP_TRST_N
 K13 PWRGD_DSW_PWROK DSW_PWROK @BASEBOARD_FAB2_LIB.BASEBOARD_FAB2(SCH_1):PWRGD_DSW_PWROK
 G15 XDP_PCH_PWR_DEBUG_N   GPD0 @BASEBOARD_FAB2_LIB.BASEBOARD_FAB2(SCH_1):XDP_PCH_PWR_DEBUG_N
 B14 FM_CPU0_RC_ERROR_N GPD10_SLP_S5_N @BASEBOARD_FAB2_LIB.BASEBOARD_FAB2(SCH_1):FM_CPU0_RC_ERROR_N
 A13 FM_GBE_LOM_DISABLE_N GPD11_GBEPHY @BASEBOARD_FAB2_LIB.BASEBOARD_FAB2(SCH_1):FM_GBE_LOM_DISABLE_N
 H13 FM_CPU1_SKTOCC_LVT3_N GPD1_ACPRESENT @BASEBOARD_FAB2_LIB.BASEBOARD_FAB2(SCH_1):FM_CPU1_SKTOCC_LVT3_N
 M11 RST_BMC_SRST_R_N GPD2_GBE_WAKE_N @BASEBOARD_FAB2_LIB.BASEBOARD_FAB2(SCH_1):RST_BMC_SRST_R_N
 C15 FM_PCH_PWRBTN_N GPD3_PWRBTN_N @BASEBOARD_FAB2_LIB.BASEBOARD_FAB2(SCH_1):FM_PCH_PWRBTN_N
 D14 FM_SLPS3_N GPD4_SLP_S3_N @BASEBOARD_FAB2_LIB.BASEBOARD_FAB2(SCH_1):FM_SLPS3_N
 B16 FM_SLPS4_N GPD5_SLP_S4_N @BASEBOARD_FAB2_LIB.BASEBOARD_FAB2(SCH_1):FM_SLPS4_N
 G11 FM_CPU0_SKTOCC_LVT3_N GPD6_SLP_A_N @BASEBOARD_FAB2_LIB.BASEBOARD_FAB2(SCH_1):FM_CPU0_SKTOCC_LVT3_N
  H9 FM_BATTERY_SENSE_EN_N   GPD7 @BASEBOARD_FAB2_LIB.BASEBOARD_FAB2(SCH_1):FM_BATTERY_SENSE_EN_N
 C13 IRQ_SML1_PMBUS_ALERT_N GPD8_SUSCLK @BASEBOARD_FAB2_LIB.BASEBOARD_FAB2(SCH_1):IRQ_SML1_PMBUS_ALERT_N
 A15 FM_BMC_CPLD_MP_RST_N   GPD9 @BASEBOARD_FAB2_LIB.BASEBOARD_FAB2(SCH_1):FM_BMC_CPLD_MP_RST_N
AR54 XDP_ITP_PMODE ITP_PMODE @BASEBOARD_FAB2_LIB.BASEBOARD_FAB2(SCH_1):XDP_ITP_PMODE
AF54 XDP_PCH_CPU_TCK0  JTAGX @BASEBOARD_FAB2_LIB.BASEBOARD_FAB2(SCH_1):XDP_PCH_CPU_TCK0
AL56 XDP_PCH_TCK1 JTAG_TCK @BASEBOARD_FAB2_LIB.BASEBOARD_FAB2(SCH_1):XDP_PCH_TCK1
AN54 XDP_TDI JTAG_TDI @BASEBOARD_FAB2_LIB.BASEBOARD_FAB2(SCH_1):XDP_TDI
AP56 XDP_TDO JTAG_TDO @BASEBOARD_FAB2_LIB.BASEBOARD_FAB2(SCH_1):XDP_TDO
AH54 XDP_TMS JTAG_TMS @BASEBOARD_FAB2_LIB.BASEBOARD_FAB2(SCH_1):XDP_TMS
BB29 A_KR0_RBIAS LAN_RBIAS_0 @BASEBOARD_FAB2_LIB.BASEBOARD_FAB2(SCH_1):A_KR0_RBIAS
BD42 A_KR1_RBIAS LAN_RBIAS_1 @BASEBOARD_FAB2_LIB.BASEBOARD_FAB2(SCH_1):A_KR1_RBIAS
BH31 KR_P0_OCP_RX_C_DN LAN_RX_P0N @BASEBOARD_FAB2_LIB.BASEBOARD_FAB2(SCH_1):KR_P0_OCP_RX_C_DN
BF31 KR_P0_OCP_RX_C_DP LAN_RX_P0P @BASEBOARD_FAB2_LIB.BASEBOARD_FAB2(SCH_1):KR_P0_OCP_RX_C_DP
BG29 KR_P1_OCP_RX_C_DN LAN_RX_P1N @BASEBOARD_FAB2_LIB.BASEBOARD_FAB2(SCH_1):KR_P1_OCP_RX_C_DN
BJ29 KR_P1_OCP_RX_C_DP LAN_RX_P1P @BASEBOARD_FAB2_LIB.BASEBOARD_FAB2(SCH_1):KR_P1_OCP_RX_C_DP
BJ37 KR_P2_OCP_RX_C_DN LAN_RX_P2N @BASEBOARD_FAB2_LIB.BASEBOARD_FAB2(SCH_1):KR_P2_OCP_RX_C_DN
BG37 KR_P2_OCP_RX_C_DP LAN_RX_P2P @BASEBOARD_FAB2_LIB.BASEBOARD_FAB2(SCH_1):KR_P2_OCP_RX_C_DP
BF35 KR_P3_OCP_RX_C_DN LAN_RX_P3N @BASEBOARD_FAB2_LIB.BASEBOARD_FAB2(SCH_1):KR_P3_OCP_RX_C_DN
BH35 KR_P3_OCP_RX_C_DP LAN_RX_P3P @BASEBOARD_FAB2_LIB.BASEBOARD_FAB2(SCH_1):KR_P3_OCP_RX_C_DP
BM27 KR_P0_OCP_TX_DN LAN_TX_P0N @BASEBOARD_FAB2_LIB.BASEBOARD_FAB2(SCH_1):KR_P0_OCP_TX_DN
BR27 KR_P0_OCP_TX_DP LAN_TX_P0P @BASEBOARD_FAB2_LIB.BASEBOARD_FAB2(SCH_1):KR_P0_OCP_TX_DP
BM24 KR_P1_OCP_TX_DN LAN_TX_P1N @BASEBOARD_FAB2_LIB.BASEBOARD_FAB2(SCH_1):KR_P1_OCP_TX_DN
BR24 KR_P1_OCP_TX_DP LAN_TX_P1P @BASEBOARD_FAB2_LIB.BASEBOARD_FAB2(SCH_1):KR_P1_OCP_TX_DP
BM35 KR_P2_OCP_TX_DN LAN_TX_P2N @BASEBOARD_FAB2_LIB.BASEBOARD_FAB2(SCH_1):KR_P2_OCP_TX_DN
BR35 KR_P2_OCP_TX_DP LAN_TX_P2P @BASEBOARD_FAB2_LIB.BASEBOARD_FAB2(SCH_1):KR_P2_OCP_TX_DP
BR31 KR_P3_OCP_TX_DN LAN_TX_P3N @BASEBOARD_FAB2_LIB.BASEBOARD_FAB2(SCH_1):KR_P3_OCP_TX_DN
BM31 KR_P3_OCP_TX_DP LAN_TX_P3P @BASEBOARD_FAB2_LIB.BASEBOARD_FAB2(SCH_1):KR_P3_OCP_TX_DP
BV16 XTAL_KR_25M_IN LAN_XTAL_IN @BASEBOARD_FAB2_LIB.BASEBOARD_FAB2(SCH_1):XTAL_KR_25M_IN
BY16 XTAL_KR_25M_OUT LAN_XTAL_OUT @BASEBOARD_FAB2_LIB.BASEBOARD_FAB2(SCH_1):XTAL_KR_25M_OUT
 R17 PWRGD_PCH_PWROK PCH_PWROK @BASEBOARD_FAB2_LIB.BASEBOARD_FAB2(SCH_1):PWRGD_PCH_PWROK
  U9 PECI_PCH   PECI @BASEBOARD_FAB2_LIB.BASEBOARD_FAB2(SCH_1):PECI_PCH
 U17 TP_PLTRST_CPU_N PLTRST_CPU_N @BASEBOARD_FAB2_LIB.BASEBOARD_FAB2(SCH_1):TP_PLTRST_CPU_N
 U13 H_PM_SYNC1_GTL_R PM_SYNC @BASEBOARD_FAB2_LIB.BASEBOARD_FAB2(SCH_1):H_PM_SYNC1_GTL_R
  V7 TP_PM_SYNC_GTL PM_SYNC2 @BASEBOARD_FAB2_LIB.BASEBOARD_FAB2(SCH_1):TP_PM_SYNC_GTL
AD54 XDP_PRDY_N PRDY_N @BASEBOARD_FAB2_LIB.BASEBOARD_FAB2(SCH_1):XDP_PRDY_N
 U54 XDP_PREQ_N PREQ_N @BASEBOARD_FAB2_LIB.BASEBOARD_FAB2(SCH_1):XDP_PREQ_N
  R9 PWRGD_CPUPWRGD_GTL PROC_PWRGD @BASEBOARD_FAB2_LIB.BASEBOARD_FAB2(SCH_1):PWRGD_CPUPWRGD_GTL
 P15 RST_RSMRST_N RSMRST_N @BASEBOARD_FAB2_LIB.BASEBOARD_FAB2(SCH_1):RST_RSMRST_N
 R24 TP_PCH_RSVD54 RSVD<54> @BASEBOARD_FAB2_LIB.BASEBOARD_FAB2(SCH_1):TP_PCH_RSVD54
 P26 TP_PCH_RSVD53 RSVD<53> @BASEBOARD_FAB2_LIB.BASEBOARD_FAB2(SCH_1):TP_PCH_RSVD53
 P22 TP_PCH_RSVD45 RSVD<45> @BASEBOARD_FAB2_LIB.BASEBOARD_FAB2(SCH_1):TP_PCH_RSVD45
BN33 TP_10GBE_KR1_MON_DP RSVD<44> @BASEBOARD_FAB2_LIB.BASEBOARD_FAB2(SCH_1):TP_10GBE_KR1_MON_DP
BL33 TP_10GBE_KR1_MON_DN RSVD<43> @BASEBOARD_FAB2_LIB.BASEBOARD_FAB2(SCH_1):TP_10GBE_KR1_MON_DN
BG40 TP_PCH_RSVD42 RSVD<42> @BASEBOARD_FAB2_LIB.BASEBOARD_FAB2(SCH_1):TP_PCH_RSVD42
BJ40 TP_PCH_RSVD41 RSVD<41> @BASEBOARD_FAB2_LIB.BASEBOARD_FAB2(SCH_1):TP_PCH_RSVD41
BN26 TP_10GBE_KR0_MON_DP RSVD<40> @BASEBOARD_FAB2_LIB.BASEBOARD_FAB2(SCH_1):TP_10GBE_KR0_MON_DP
BL26 TP_10GBE_KR0_MON_DN RSVD<39> @BASEBOARD_FAB2_LIB.BASEBOARD_FAB2(SCH_1):TP_10GBE_KR0_MON_DN
BL29 TP_PCH_RSVD38 RSVD<38> @BASEBOARD_FAB2_LIB.BASEBOARD_FAB2(SCH_1):TP_PCH_RSVD38
BN29 TP_PCH_RSVD37 RSVD<37> @BASEBOARD_FAB2_LIB.BASEBOARD_FAB2(SCH_1):TP_PCH_RSVD37
AK54 TP_PCH_RSVD36 RSVD<36> @BASEBOARD_FAB2_LIB.BASEBOARD_FAB2(SCH_1):TP_PCH_RSVD36
 W54 TP_PCH_RSVD35 RSVD<35> @BASEBOARD_FAB2_LIB.BASEBOARD_FAB2(SCH_1):TP_PCH_RSVD35
 Y56 TP_PCH_RSVD34 RSVD<34> @BASEBOARD_FAB2_LIB.BASEBOARD_FAB2(SCH_1):TP_PCH_RSVD34
 V56 TP_PCH_RSVD33 RSVD<33> @BASEBOARD_FAB2_LIB.BASEBOARD_FAB2(SCH_1):TP_PCH_RSVD33
AA54 TP_PCH_RSVD32 RSVD<32> @BASEBOARD_FAB2_LIB.BASEBOARD_FAB2(SCH_1):TP_PCH_RSVD32
 M15 TP_SLP_LAN_N SLP_GBE_N @BASEBOARD_FAB2_LIB.BASEBOARD_FAB2(SCH_1):TP_SLP_LAN_N
  P7 FM_SLP_SUS_N SLP_SUS_N @BASEBOARD_FAB2_LIB.BASEBOARD_FAB2(SCH_1):FM_SLP_SUS_N
BY19 PWRGD_SYS_PWROK SYS_PWROK @BASEBOARD_FAB2_LIB.BASEBOARD_FAB2(SCH_1):PWRGD_SYS_PWROK
BV19 RST_BMC_SYSRST_BTN_OUT_B_N SYS_RESET_N @BASEBOARD_FAB2_LIB.BASEBOARD_FAB2(SCH_1):RST_BMC_SYSRST_BTN_OUT_B_N
 V15 FM_PCH_LVC1_THERMTRIP_N THRMTRIP_N @BASEBOARD_FAB2_LIB.BASEBOARD_FAB2(SCH_1):FM_PCH_LVC1_THERMTRIP_N
  M7 TP_CPU_PCH_TRIGGER_IN TRIGGER_IN @BASEBOARD_FAB2_LIB.BASEBOARD_FAB2(SCH_1):TP_CPU_PCH_TRIGGER_IN
 R13 TP_CPU_PCH_TRIGGER_OUT TRIGGER_OUT @BASEBOARD_FAB2_LIB.BASEBOARD_FAB2(SCH_1):TP_CPU_PCH_TRIGGER_OUT
  K9 IRQ_LVC3_WAKE_N WAKE_N @BASEBOARD_FAB2_LIB.BASEBOARD_FAB2(SCH_1):IRQ_LVC3_WAKE_N

CRYSTAL_2013-25.000MHZ,IC,H196A  I76  Y8C1
   1 XTAL_KR_25M_IN      A @BASEBOARD_FAB2_LIB.BASEBOARD_FAB2(SCH_1):XTAL_KR_25M_IN
   3 XTAL_KR_25M_OUT      B @BASEBOARD_FAB2_LIB.BASEBOARD_FAB2(SCH_1):XTAL_KR_25M_OUT

CAP_0402LF-33.0PF,50V,5%,COG,AA  I77  C8C2
   1 XTAL_KR_25M_OUT      A @BASEBOARD_FAB2_LIB.BASEBOARD_FAB2(SCH_1):XTAL_KR_25M_OUT
   2    GND      B @BASEBOARD_FAB2_LIB.BASEBOARD_FAB2(SCH_1):GND

CAP_0402LF-33.0PF,50V,5%,COG,AA  I79  C8C1
   1 XTAL_KR_25M_IN      A @BASEBOARD_FAB2_LIB.BASEBOARD_FAB2(SCH_1):XTAL_KR_25M_IN
   2    GND      B @BASEBOARD_FAB2_LIB.BASEBOARD_FAB2(SCH_1):GND

RES_0402-1.0K,0.1%,1/16W,CHIP,A  I96  R2N4
   1 P1V05_PCH_STBY_KR_PLL      A @BASEBOARD_FAB2_LIB.BASEBOARD_FAB2(SCH_1):P1V05_PCH_STBY_KR_PLL
   2 A_KR0_RBIAS      B @BASEBOARD_FAB2_LIB.BASEBOARD_FAB2(SCH_1):A_KR0_RBIAS

RES_0402-1.0K,0.1%,1/16W,CHIP,A  I99  R2M6
   1 A_KR1_RBIAS      A @BASEBOARD_FAB2_LIB.BASEBOARD_FAB2(SCH_1):A_KR1_RBIAS
   2 P1V05_PCH_STBY_KR_PLL      B @BASEBOARD_FAB2_LIB.BASEBOARD_FAB2(SCH_1):P1V05_PCH_STBY_KR_PLL

RES_0402-0.0,5%,1/16W,CHIP,G21A  I120  R8C24
   1 FM_GBE_LOM_DISABLE_N      A @BASEBOARD_FAB2_LIB.BASEBOARD_FAB2(SCH_1):FM_GBE_LOM_DISABLE_N
   2 FM_1GB_LOM_DISABLE_N      B @BASEBOARD_FAB2_LIB.BASEBOARD_FAB2(SCH_1):FM_1GB_LOM_DISABLE_N

RES_0402-0.0,5%,1/16W,EMPTY,G2A  I125  R8C23
   1 FM_GBE_LOM_DISABLE_N      A @BASEBOARD_FAB2_LIB.BASEBOARD_FAB2(SCH_1):FM_GBE_LOM_DISABLE_N
   2 FM_10GBE_LOM_DISABLE_N      B @BASEBOARD_FAB2_LIB.BASEBOARD_FAB2(SCH_1):FM_10GBE_LOM_DISABLE_N

RES_0402-10.0K,1%,1/16W,CHIP,GA  I128  R2N6
   1 P3V3_STBY      A @BASEBOARD_FAB2_LIB.BASEBOARD_FAB2(SCH_1):P3V3_STBY
   2 FM_GBE_LOM_DISABLE_N      B @BASEBOARD_FAB2_LIB.BASEBOARD_FAB2(SCH_1):FM_GBE_LOM_DISABLE_N

RES_0402-0.0,5%,1/16W,CHIP,G21A  I131  R7D23
   1 RST_BMC_SRST_N      A @BASEBOARD_FAB2_LIB.BASEBOARD_FAB2(SCH_1):RST_BMC_SRST_N
   2 RST_BMC_SRST_R_N      B @BASEBOARD_FAB2_LIB.BASEBOARD_FAB2(SCH_1):RST_BMC_SRST_R_N

CAP_A_0402V-0.1UF,16V,10%,X7R,A  I136  C7D1
   1 P3V3_STBY      A @BASEBOARD_FAB2_LIB.BASEBOARD_FAB2(SCH_1):P3V3_STBY
   2    GND      B @BASEBOARD_FAB2_LIB.BASEBOARD_FAB2(SCH_1):GND

74CBTLV1G125_SMLF-IC,C88177-00A  I142  U7D1
   4 XDP_CPU_PWR_DEBUG_N      B @BASEBOARD_FAB2_LIB.BASEBOARD_FAB2(SCH_1):XDP_CPU_PWR_DEBUG_N
   1 PWRGD_PVCCIO_CPU0   OE_N @BASEBOARD_FAB2_LIB.BASEBOARD_FAB2(SCH_1):PWRGD_PVCCIO_CPU0
   2 XDP_PCH_PWR_DEBUG_N      A @BASEBOARD_FAB2_LIB.BASEBOARD_FAB2(SCH_1):XDP_PCH_PWR_DEBUG_N

RES_0402-10.0K,1%,1/16W,CHIP,GA  I144  R7C23
   1 P3V3_STBY      A @BASEBOARD_FAB2_LIB.BASEBOARD_FAB2(SCH_1):P3V3_STBY
   2 XDP_PCH_PWR_DEBUG_N      B @BASEBOARD_FAB2_LIB.BASEBOARD_FAB2(SCH_1):XDP_PCH_PWR_DEBUG_N


DRAWING: @BASEBOARD_FAB2_LIB.BASEBOARD_FAB2(SCH_1):PAGE119 

LBG_CORE_QAT_EXT_D_BGA1-IC,H91A  I115  U7C1
  N3 PU_FM_RCIN_N GPP_A0_RCIN_N_ESPI_ALERT1_N @BASEBOARD_FAB2_LIB.BASEBOARD_FAB2(SCH_1):PU_FM_RCIN_N
 AA4 IRQ_VM_INT_N GPP_A10_CLKOUT_LPC1 @BASEBOARD_FAB2_LIB.BASEBOARD_FAB2(SCH_1):IRQ_VM_INT_N
 AC2 PU_LPC_PME_N GPP_A11_PME_N @BASEBOARD_FAB2_LIB.BASEBOARD_FAB2(SCH_1):PU_LPC_PME_N
  R1 PU_IRQ_PCH_SCI_WHEA_N GPP_A12_BMBUSY_N_SXEXITHLDOFF_N @BASEBOARD_FAB2_LIB.BASEBOARD_FAB2(SCH_1):PU_IRQ_PCH_SCI_WHEA_N
  T4 FM_MB_SLOT_ID0 GPP_A13_SUSWARN_N_SUSPWRDNACK @BASEBOARD_FAB2_LIB.BASEBOARD_FAB2(SCH_1):FM_MB_SLOT_ID0
 AB3 FM_MB_SLOT_ID1 GPP_A14_ESPI_RESET_N @BASEBOARD_FAB2_LIB.BASEBOARD_FAB2(SCH_1):FM_MB_SLOT_ID1
 AC4 FM_MB_SLOT_ID2 GPP_A15_SUSACK_N @BASEBOARD_FAB2_LIB.BASEBOARD_FAB2(SCH_1):FM_MB_SLOT_ID2
  T2 FM_UART_PRES_N GPP_A16_CLKOUT_LPC2 @BASEBOARD_FAB2_LIB.BASEBOARD_FAB2(SCH_1):FM_UART_PRES_N
 AD1 FM_CPU_BMC_INIT GPP_A17 @BASEBOARD_FAB2_LIB.BASEBOARD_FAB2(SCH_1):FM_CPU_BMC_INIT
 AD3 RST_PCH_SYSRST_BTN_OUT_N GPP_A18 @BASEBOARD_FAB2_LIB.BASEBOARD_FAB2(SCH_1):RST_PCH_SYSRST_BTN_OUT_N
  V3 FM_ME_RECOVER_N GPP_A19 @BASEBOARD_FAB2_LIB.BASEBOARD_FAB2(SCH_1):FM_ME_RECOVER_N
  Y3 LPC_LAD0_IO0 GPP_A1_LAD0_ESPI_IO0 @BASEBOARD_FAB2_LIB.BASEBOARD_FAB2(SCH_1):LPC_LAD0_IO0
  W4 FM_POST_CARD_PRES_BMC_N GPP_A20 @BASEBOARD_FAB2_LIB.BASEBOARD_FAB2(SCH_1):FM_POST_CARD_PRES_BMC_N
 AE2 FM_OCP_MEZZA_PRES_N GPP_A21 @BASEBOARD_FAB2_LIB.BASEBOARD_FAB2(SCH_1):FM_OCP_MEZZA_PRES_N
 AE4 FM_TPM_PRES_N GPP_A22 @BASEBOARD_FAB2_LIB.BASEBOARD_FAB2(SCH_1):FM_TPM_PRES_N
  V1 FM_BMC_READY_N GPP_A23 @BASEBOARD_FAB2_LIB.BASEBOARD_FAB2(SCH_1):FM_BMC_READY_N
  N1 LPC_LAD1_IO1 GPP_A2_LAD1_ESPI_IO1 @BASEBOARD_FAB2_LIB.BASEBOARD_FAB2(SCH_1):LPC_LAD1_IO1
  W2 LPC_LAD2_IO2 GPP_A3_LAD2_ESPI_IO2 @BASEBOARD_FAB2_LIB.BASEBOARD_FAB2(SCH_1):LPC_LAD2_IO2
  Y1 LPC_LAD3_IO3 GPP_A4_LAD3_ESPI_IO3 @BASEBOARD_FAB2_LIB.BASEBOARD_FAB2(SCH_1):LPC_LAD3_IO3
  P4 LPC_LFRAME_N_CS0_N GPP_A5_LFRAME_N_ESPI_CS0_N @BASEBOARD_FAB2_LIB.BASEBOARD_FAB2(SCH_1):LPC_LFRAME_N_CS0_N
  P2 IRQ_LPC_SERIRQ_N GPP_A6_SERIRQ_ESPI_CS1_N @BASEBOARD_FAB2_LIB.BASEBOARD_FAB2(SCH_1):IRQ_LPC_SERIRQ_N
 AA2 IRQ_PIRQA_SPI_TPM_N GPP_A7_PIRQA_N_ESPI_ALERT0_N @BASEBOARD_FAB2_LIB.BASEBOARD_FAB2(SCH_1):IRQ_PIRQA_SPI_TPM_N
 AB1 PU_LPC_CLKRUN_N GPP_A8_CLKRUN_N @BASEBOARD_FAB2_LIB.BASEBOARD_FAB2(SCH_1):PU_LPC_CLKRUN_N
  R3 CLK_24M_BMC_LPC_R GPP_A9_CLKOUT_LPC0_ESPI_CLK @BASEBOARD_FAB2_LIB.BASEBOARD_FAB2(SCH_1):CLK_24M_BMC_LPC_R
 BL7 VID_PCH_CORE_PVNN_AUX_VID_0 GPP_B0_CORE_VID0 @BASEBOARD_FAB2_LIB.BASEBOARD_FAB2(SCH_1):VID_PCH_CORE_PVNN_AUX_VID_0
BL11 RST_SYSTEM_BTN_N GPP_B10_SRCCLKREQ5_N @BASEBOARD_FAB2_LIB.BASEBOARD_FAB2(SCH_1):RST_SYSTEM_BTN_N
 BK9 FM_PMBUS_ALERT_BUF_EN_N GPP_B11 @BASEBOARD_FAB2_LIB.BASEBOARD_FAB2(SCH_1):FM_PMBUS_ALERT_BUF_EN_N
BL18 FM_GLOBAL_RST_WARN_N GPP_B12_GLB_RST_WARN_N @BASEBOARD_FAB2_LIB.BASEBOARD_FAB2(SCH_1):FM_GLOBAL_RST_WARN_N
BN18 RST_PLTRST_N GPP_B13_PLTRST_N @BASEBOARD_FAB2_LIB.BASEBOARD_FAB2(SCH_1):RST_PLTRST_N
BH13 FM_BIOS_TOP_SWAP_SPKR GPP_B14_SPKR @BASEBOARD_FAB2_LIB.BASEBOARD_FAB2(SCH_1):FM_BIOS_TOP_SWAP_SPKR
BK13 FM_UART_ALERT_N GPP_B15 @BASEBOARD_FAB2_LIB.BASEBOARD_FAB2(SCH_1):FM_UART_ALERT_N
BG22 IRQ_PCH_NIC_ALERT_N GPP_B16 @BASEBOARD_FAB2_LIB.BASEBOARD_FAB2(SCH_1):IRQ_PCH_NIC_ALERT_N
BG15 FM_PCH_PWRBTN_OUT_N GPP_B17 @BASEBOARD_FAB2_LIB.BASEBOARD_FAB2(SCH_1):FM_PCH_PWRBTN_OUT_N
BL15 FM_UV_ADR_TRIGGER_EN GPP_B18 @BASEBOARD_FAB2_LIB.BASEBOARD_FAB2(SCH_1):FM_UV_ADR_TRIGGER_EN
BK20 FM_BIOS_PREFRB2_GOOD GPP_B19 @BASEBOARD_FAB2_LIB.BASEBOARD_FAB2(SCH_1):FM_BIOS_PREFRB2_GOOD
 BH9 VID_PCH_CORE_PVNN_AUX_VID_1 GPP_B1_CORE_VID1 @BASEBOARD_FAB2_LIB.BASEBOARD_FAB2(SCH_1):VID_PCH_CORE_PVNN_AUX_VID_1
BN15 PU_IRQ_VRALERT_N GPP_B2 @BASEBOARD_FAB2_LIB.BASEBOARD_FAB2(SCH_1):PU_IRQ_VRALERT_N
BJ22 FM_BIOS_POST_CMPLT_N GPP_B20 @BASEBOARD_FAB2_LIB.BASEBOARD_FAB2(SCH_1):FM_BIOS_POST_CMPLT_N
BH17 FM_FAST_PROCHOT_EN_N GPP_B21 @BASEBOARD_FAB2_LIB.BASEBOARD_FAB2(SCH_1):FM_FAST_PROCHOT_EN_N
BR17 FM_USB_P0_EN_BOOT_BIOS_STRAP_N GPP_B22 @BASEBOARD_FAB2_LIB.BASEBOARD_FAB2(SCH_1):FM_USB_P0_EN_BOOT_BIOS_STRAP_N
BM20 FM_PCH_BMC_THERMTRIP_EXI_STRAP_ GPP_B23_MEIE_SML1ALRT_N_PHOT_N @BASEBOARD_FAB2_LIB.BASEBOARD_FAB2(SCH_1):FM_PCH_BMC_THERMTRIP_EXI_STRAP_N
 BR9 FM_QAT_EN_N GPP_B3_CPU_GP2 @BASEBOARD_FAB2_LIB.BASEBOARD_FAB2(SCH_1):FM_QAT_EN_N
 BN7 IRQ_PVDDQ_ABC_VRHOT_LVT3_N GPP_B4_CPU_GP3 @BASEBOARD_FAB2_LIB.BASEBOARD_FAB2(SCH_1):IRQ_PVDDQ_ABC_VRHOT_LVT3_N
BK17 IRQ_PVDDQ_DEF_VRHOT_LVT3_N GPP_B5_SRCCLKREQ0_N @BASEBOARD_FAB2_LIB.BASEBOARD_FAB2(SCH_1):IRQ_PVDDQ_DEF_VRHOT_LVT3_N
BG18 IRQ_PVDDQ_GHJ_VRHOT_LVT3_N GPP_B6_SRCCLKREQ1_N @BASEBOARD_FAB2_LIB.BASEBOARD_FAB2(SCH_1):IRQ_PVDDQ_GHJ_VRHOT_LVT3_N
BR13 IRQ_PVDDQ_KLM_VRHOT_LVT3_N GPP_B7_SRCCLKREQ2_N @BASEBOARD_FAB2_LIB.BASEBOARD_FAB2(SCH_1):IRQ_PVDDQ_KLM_VRHOT_LVT3_N
BN11 FP_NMI_BTN_N GPP_B8_SRCCLKREQ3_N @BASEBOARD_FAB2_LIB.BASEBOARD_FAB2(SCH_1):FP_NMI_BTN_N
BH20 FM_PWR_BTN_N GPP_B9_SRCCLKREQ4_N @BASEBOARD_FAB2_LIB.BASEBOARD_FAB2(SCH_1):FM_PWR_BTN_N
BW28 SMB_HOST_STBY_LVC3_SCL_R1 GPP_C0_SMBCLK @BASEBOARD_FAB2_LIB.BASEBOARD_FAB2(SCH_1):SMB_HOST_STBY_LVC3_SCL_R1
BV31 FM_PCH_SATA_RAID_KEY GPP_C10 @BASEBOARD_FAB2_LIB.BASEBOARD_FAB2(SCH_1):FM_PCH_SATA_RAID_KEY
BV33 FM_BOARD_REV_ID2 GPP_C11 @BASEBOARD_FAB2_LIB.BASEBOARD_FAB2(SCH_1):FM_BOARD_REV_ID2
CA30 FM_BOARD_REV_ID0 GPP_C12 @BASEBOARD_FAB2_LIB.BASEBOARD_FAB2(SCH_1):FM_BOARD_REV_ID0
BV38 FM_BOARD_REV_ID1 GPP_C13 @BASEBOARD_FAB2_LIB.BASEBOARD_FAB2(SCH_1):FM_BOARD_REV_ID1
BY38 IRQ_BMC_PCH_SCI_LPC_N GPP_C14 @BASEBOARD_FAB2_LIB.BASEBOARD_FAB2(SCH_1):IRQ_BMC_PCH_SCI_LPC_N
CA32 FM_SLT_CFG0 GPP_C15 @BASEBOARD_FAB2_LIB.BASEBOARD_FAB2(SCH_1):FM_SLT_CFG0
BW37 FM_SLT_CFG1 GPP_C16 @BASEBOARD_FAB2_LIB.BASEBOARD_FAB2(SCH_1):FM_SLT_CFG1
BY31 FM_SLT_CFG2_R GPP_C17 @BASEBOARD_FAB2_LIB.BASEBOARD_FAB2(SCH_1):FM_SLT_CFG2_R
BY35 FM_PMBUS_ALERT_BUF_EN_N GPP_C18 @BASEBOARD_FAB2_LIB.BASEBOARD_FAB2(SCH_1):FM_PMBUS_ALERT_BUF_EN_N
BW39 FM_BB_BMC_MP_GPIO GPP_C19 @BASEBOARD_FAB2_LIB.BASEBOARD_FAB2(SCH_1):FM_BB_BMC_MP_GPIO
BV27 SMB_HOST_STBY_LVC3_SDA_R1 GPP_C1_SMBDATA @BASEBOARD_FAB2_LIB.BASEBOARD_FAB2(SCH_1):SMB_HOST_STBY_LVC3_SDA_R1
CA39 FM_THROTTLE_N GPP_C20 @BASEBOARD_FAB2_LIB.BASEBOARD_FAB2(SCH_1):FM_THROTTLE_N
BY33 FM_BIOS_POST_CMPLT_N GPP_C21 @BASEBOARD_FAB2_LIB.BASEBOARD_FAB2(SCH_1):FM_BIOS_POST_CMPLT_N
CA34 IRQ_BMC_PCH_SMI_LPC_N GPP_C22 @BASEBOARD_FAB2_LIB.BASEBOARD_FAB2(SCH_1):IRQ_BMC_PCH_SMI_LPC_N
CA37 FM_CPU_CATERR_DLY_LVT3_R_N GPP_C23 @BASEBOARD_FAB2_LIB.BASEBOARD_FAB2(SCH_1):FM_CPU_CATERR_DLY_LVT3_R_N
BY27 PU_PCH_TLS_ENABLE_STRAP GPP_C2_SMBALERT_N @BASEBOARD_FAB2_LIB.BASEBOARD_FAB2(SCH_1):PU_PCH_TLS_ENABLE_STRAP
BV29 SMB_SMLINK0_STBY_LVC3_SCL_R1 GPP_C3_SML0CLK_IE @BASEBOARD_FAB2_LIB.BASEBOARD_FAB2(SCH_1):SMB_SMLINK0_STBY_LVC3_SCL_R1
BW30 SMB_SMLINK0_STBY_LVC3_SDA_R1 GPP_C4_SML0DATA_IE @BASEBOARD_FAB2_LIB.BASEBOARD_FAB2(SCH_1):SMB_SMLINK0_STBY_LVC3_SDA_R1
BW34 IRQ_SML0_ALERT_N GPP_C5_SML0ALERT_IE_N @BASEBOARD_FAB2_LIB.BASEBOARD_FAB2(SCH_1):IRQ_SML0_ALERT_N
CA28 SMB_PMBUS_BMC_STBY_LVC3_SCL_R1 GPP_C6_SML1CLK_IE @BASEBOARD_FAB2_LIB.BASEBOARD_FAB2(SCH_1):SMB_PMBUS_BMC_STBY_LVC3_SCL_R1
BV35 SMB_PMBUS_BMC_STBY_LVC3_SDA_R1 GPP_C7_SML1DATA_IE @BASEBOARD_FAB2_LIB.BASEBOARD_FAB2(SCH_1):SMB_PMBUS_BMC_STBY_LVC3_SDA_R1
BW32 FM_PASSWORD_CLEAR_N GPP_C8 @BASEBOARD_FAB2_LIB.BASEBOARD_FAB2(SCH_1):FM_PASSWORD_CLEAR_N
BY29 FM_CPU1_RC_EN GPP_C9 @BASEBOARD_FAB2_LIB.BASEBOARD_FAB2(SCH_1):FM_CPU1_RC_EN
BR42 IRQ_BMC_PCH_NMI_STBY_R_N GPP_D0 @BASEBOARD_FAB2_LIB.BASEBOARD_FAB2(SCH_1):IRQ_BMC_PCH_NMI_STBY_R_N
BK46 FM_PWR_LED_N GPP_D1 @BASEBOARD_FAB2_LIB.BASEBOARD_FAB2(SCH_1):FM_PWR_LED_N
BV47 H_CPU0_FAST_WAKE_LVT3_N GPP_D10_SSATA_DEVSLP4 @BASEBOARD_FAB2_LIB.BASEBOARD_FAB2(SCH_1):H_CPU0_FAST_WAKE_LVT3_N
BY47 IRQ_LOM_ALERT_N GPP_D11_SSATA_DEVSLP5 @BASEBOARD_FAB2_LIB.BASEBOARD_FAB2(SCH_1):IRQ_LOM_ALERT_N
BN40 TP_PCH_GPP_D12 GPP_D12_SSATA_SDATAOUT1 @BASEBOARD_FAB2_LIB.BASEBOARD_FAB2(SCH_1):TP_PCH_GPP_D12
BY44 SMB_SLOTX24_STBY_LVC3_SCL_R1 GPP_D13_SML0BCLK_IE @BASEBOARD_FAB2_LIB.BASEBOARD_FAB2(SCH_1):SMB_SLOTX24_STBY_LVC3_SCL_R1
BL44 SMB_SLOTX24_STBY_LVC3_SDA_R1 GPP_D14_SML0BDATA_IE @BASEBOARD_FAB2_LIB.BASEBOARD_FAB2(SCH_1):SMB_SLOTX24_STBY_LVC3_SDA_R1
BW43 SGPIO_PCH_SSATA_DOUT0 GPP_D15_SSATA_SDATAOUT0 @BASEBOARD_FAB2_LIB.BASEBOARD_FAB2(SCH_1):SGPIO_PCH_SSATA_DOUT0
BV42 IRQ_OOB_MGMT_RISER_ALERT_N GPP_D16_SML0BALERT_IE_N @BASEBOARD_FAB2_LIB.BASEBOARD_FAB2(SCH_1):IRQ_OOB_MGMT_RISER_ALERT_N
BW48 FM_XRC_PRESENT_N GPP_D17 @BASEBOARD_FAB2_LIB.BASEBOARD_FAB2(SCH_1):FM_XRC_PRESENT_N
CA41 FM_XRC_READY_N GPP_D18 @BASEBOARD_FAB2_LIB.BASEBOARD_FAB2(SCH_1):FM_XRC_READY_N
CA43 FM_ADR_MODE_SEL_R GPP_D19 @BASEBOARD_FAB2_LIB.BASEBOARD_FAB2(SCH_1):FM_ADR_MODE_SEL_R
BJ44 IRQ_HSC_FAULT_N GPP_D2 @BASEBOARD_FAB2_LIB.BASEBOARD_FAB2(SCH_1):IRQ_HSC_FAULT_N
CA48 FM_BMC_HEARTBEAT_N GPP_D20 @BASEBOARD_FAB2_LIB.BASEBOARD_FAB2(SCH_1):FM_BMC_HEARTBEAT_N
BV44 SP2_BMC_CM_UART_RX GPP_D21_IE_UART_RX @BASEBOARD_FAB2_LIB.BASEBOARD_FAB2(SCH_1):SP2_BMC_CM_UART_RX
BR46 SP2_BMC_CM_UART_TX GPP_D22_IE_UART_TX @BASEBOARD_FAB2_LIB.BASEBOARD_FAB2(SCH_1):SP2_BMC_CM_UART_TX
BN44 FM_CPU0_THERMTRIP_LATCH_LVT3_N GPP_D23 @BASEBOARD_FAB2_LIB.BASEBOARD_FAB2(SCH_1):FM_CPU0_THERMTRIP_LATCH_LVT3_N
BW45 IRQ_MEZZ_LAN_ALERT_N GPP_D3 @BASEBOARD_FAB2_LIB.BASEBOARD_FAB2(SCH_1):IRQ_MEZZ_LAN_ALERT_N
BM42 FM_PCH_PLD_DATA_R GPP_D4 @BASEBOARD_FAB2_LIB.BASEBOARD_FAB2(SCH_1):FM_PCH_PLD_DATA_R
BM38 FM_BMC_ENABLE_N GPP_D5 @BASEBOARD_FAB2_LIB.BASEBOARD_FAB2(SCH_1):FM_BMC_ENABLE_N
BW41 FM_CPLD_BMC_PWRDN_N GPP_D6 @BASEBOARD_FAB2_LIB.BASEBOARD_FAB2(SCH_1):FM_CPLD_BMC_PWRDN_N
CA45 FM_BMC_CPLD_GPO GPP_D7 @BASEBOARD_FAB2_LIB.BASEBOARD_FAB2(SCH_1):FM_BMC_CPLD_GPO
BR38 FM_BMC_FAULT_LED_N GPP_D8 @BASEBOARD_FAB2_LIB.BASEBOARD_FAB2(SCH_1):FM_BMC_FAULT_LED_N
BY42 IRQ_FORCE_NM_THROTTLE_N GPP_D9_SSATA_DEVSLP3 @BASEBOARD_FAB2_LIB.BASEBOARD_FAB2(SCH_1):IRQ_FORCE_NM_THROTTLE_N

RES_0402-33.2,1%,1/16W,CHIP,G2A  I172  R2M3
   1 FM_PCH_PLD_DATA_R      A @BASEBOARD_FAB2_LIB.BASEBOARD_FAB2(SCH_1):FM_PCH_PLD_DATA_R
   2 FM_PCH_PLD_DATA      B @BASEBOARD_FAB2_LIB.BASEBOARD_FAB2(SCH_1):FM_PCH_PLD_DATA

RES_0402-33.2,1%,1/16W,CHIP,G2A  I173  R2N1
   1 FM_CPU_CATERR_DLY_LVT3_R_N      A @BASEBOARD_FAB2_LIB.BASEBOARD_FAB2(SCH_1):FM_CPU_CATERR_DLY_LVT3_R_N
   2 FM_CPU_CATERR_DLY_LVT3_N      B @BASEBOARD_FAB2_LIB.BASEBOARD_FAB2(SCH_1):FM_CPU_CATERR_DLY_LVT3_N

RES_0402-33.2,1%,1/16W,CHIP,G2A  I174  R2M7
   1 FM_ADR_MODE_SEL_R      A @BASEBOARD_FAB2_LIB.BASEBOARD_FAB2(SCH_1):FM_ADR_MODE_SEL_R
   2 FM_ADR_MODE_SEL      B @BASEBOARD_FAB2_LIB.BASEBOARD_FAB2(SCH_1):FM_ADR_MODE_SEL

FET_N_DUAL_SMLF-NTJD4001N,FET,A  I175  Q9A2
   2 FM_PWR_LED_N GATE<0> @BASEBOARD_FAB2_LIB.BASEBOARD_FAB2(SCH_1):FM_PWR_LED_N
   1    GND SOURCE<0> @BASEBOARD_FAB2_LIB.BASEBOARD_FAB2(SCH_1):GND
   6 FM_PWR_LED DRAIN<0> @BASEBOARD_FAB2_LIB.BASEBOARD_FAB2(SCH_1):FM_PWR_LED

RES_0402-221,1.0%,1/16W,CHIP,GA  I178  R9A20
   1 FM_PWR_LED_A      A @BASEBOARD_FAB2_LIB.BASEBOARD_FAB2(SCH_1):FM_PWR_LED_A
   2 P3V3_STBY      B @BASEBOARD_FAB2_LIB.BASEBOARD_FAB2(SCH_1):P3V3_STBY

LED_A1LF-GREEN,IC,C97278-010  I179  DS9A5
   2 FM_PWR_LED_K      C @BASEBOARD_FAB2_LIB.BASEBOARD_FAB2(SCH_1):FM_PWR_LED_K
   1 FM_PWR_LED_A      A @BASEBOARD_FAB2_LIB.BASEBOARD_FAB2(SCH_1):FM_PWR_LED_A

FET_N_DUAL_SMLF-NTJD4001N,FET,A  I180  Q9A2
   5 FM_PWR_LED GATE<0> @BASEBOARD_FAB2_LIB.BASEBOARD_FAB2(SCH_1):FM_PWR_LED
   4    GND SOURCE<0> @BASEBOARD_FAB2_LIB.BASEBOARD_FAB2(SCH_1):GND
   3 FM_PWR_LED_K DRAIN<0> @BASEBOARD_FAB2_LIB.BASEBOARD_FAB2(SCH_1):FM_PWR_LED_K

RES_0402-4.75K,1%,1/16W,CHIP,GA  I183  R9A18
   1 P3V3_STBY      A @BASEBOARD_FAB2_LIB.BASEBOARD_FAB2(SCH_1):P3V3_STBY
   2 FM_PWR_LED      B @BASEBOARD_FAB2_LIB.BASEBOARD_FAB2(SCH_1):FM_PWR_LED

RES_0402-4.75K,1%,1/16W,CHIP,GA  I186  R9A21
   1 P3V3_STBY      A @BASEBOARD_FAB2_LIB.BASEBOARD_FAB2(SCH_1):P3V3_STBY
   2 FM_PWR_LED_N      B @BASEBOARD_FAB2_LIB.BASEBOARD_FAB2(SCH_1):FM_PWR_LED_N

RES_0402-33.2,1%,1/16W,CHIP,G2A  I189  R7C26
   1 CLK_24M_BMC_LPC      A @BASEBOARD_FAB2_LIB.BASEBOARD_FAB2(SCH_1):CLK_24M_BMC_LPC
   2 CLK_24M_BMC_LPC_R      B @BASEBOARD_FAB2_LIB.BASEBOARD_FAB2(SCH_1):CLK_24M_BMC_LPC_R

RES_0402-4.75K,1%,1/16W,CHIP,GA  I213  R2U48
   1 P3V3_STBY      A @BASEBOARD_FAB2_LIB.BASEBOARD_FAB2(SCH_1):P3V3_STBY
   2 FM_SLT_CFG2_R      B @BASEBOARD_FAB2_LIB.BASEBOARD_FAB2(SCH_1):FM_SLT_CFG2_R

RES_0402-0.0,5%,1/16W,EMPTY,G2A  I215  R2U50
   1 FM_SLT_CFG2_R      A @BASEBOARD_FAB2_LIB.BASEBOARD_FAB2(SCH_1):FM_SLT_CFG2_R
   2 FM_PWRBRK_SLOT_N      B @BASEBOARD_FAB2_LIB.BASEBOARD_FAB2(SCH_1):FM_PWRBRK_SLOT_N


DRAWING: @BASEBOARD_FAB2_LIB.BASEBOARD_FAB2(SCH_1):PAGE120 

LBG_CORE_QAT_EXT_D_BGA1-IC,H91A  I147  U7C1
BY25 A_RCOMP_3P3 GPIO_RCOMP_3P3 @BASEBOARD_FAB2_LIB.BASEBOARD_FAB2(SCH_1):A_RCOMP_3P3
BH50 FM_CPU0_RC_ERROR_N GPP_E0_SATAXPCIE0_SATAGP0 @BASEBOARD_FAB2_LIB.BASEBOARD_FAB2(SCH_1):FM_CPU0_RC_ERROR_N
BN48 IRQ_BMC_PCH_SCI_LPC_N GPP_E10_USB2_OC1_N @BASEBOARD_FAB2_LIB.BASEBOARD_FAB2(SCH_1):IRQ_BMC_PCH_SCI_LPC_N
AW54 IRQ_BMC_PCH_SMI_LPC_N GPP_E11_USB2_OC2_N @BASEBOARD_FAB2_LIB.BASEBOARD_FAB2(SCH_1):IRQ_BMC_PCH_SMI_LPC_N
AU58 IRQ_UV_DETECT_N GPP_E12_USB2_OC3_N @BASEBOARD_FAB2_LIB.BASEBOARD_FAB2(SCH_1):IRQ_UV_DETECT_N
AY52 FM_CPU1_RC_ERROR_N GPP_E1_SATAXPCIE1_SATAGP1 @BASEBOARD_FAB2_LIB.BASEBOARD_FAB2(SCH_1):FM_CPU1_RC_ERROR_N
BG52 FM_POST_CARD_PRES_BMC_N GPP_E2_SATAXPCIE2_SATAGP2 @BASEBOARD_FAB2_LIB.BASEBOARD_FAB2(SCH_1):FM_POST_CARD_PRES_BMC_N
BE52 FM_CPLD_ADR_TRIGGER_R_N GPP_E3_CPU_GP0 @BASEBOARD_FAB2_LIB.BASEBOARD_FAB2(SCH_1):FM_CPLD_ADR_TRIGGER_R_N
AV52 FM_CPU_ERR2_LVT3_N GPP_E4_SATA_DEVSLP0 @BASEBOARD_FAB2_LIB.BASEBOARD_FAB2(SCH_1):FM_CPU_ERR2_LVT3_N
AT52 FM_CPU_MSMI_LVT3_N GPP_E5_SATA_DEVSLP1 @BASEBOARD_FAB2_LIB.BASEBOARD_FAB2(SCH_1):FM_CPU_MSMI_LVT3_N
BB52 IRQ_BMC_PCH_NMI_STBY_N GPP_E6_SATA_DEVSLP2 @BASEBOARD_FAB2_LIB.BASEBOARD_FAB2(SCH_1):IRQ_BMC_PCH_NMI_STBY_N
BJ48 FM_ADR_SMI_GPIO_N GPP_E7_CPU_GP1 @BASEBOARD_FAB2_LIB.BASEBOARD_FAB2(SCH_1):FM_ADR_SMI_GPIO_N
AV56 LED_PCH_SATA_HDD_N GPP_E8_SATA_LED_N @BASEBOARD_FAB2_LIB.BASEBOARD_FAB2(SCH_1):LED_PCH_SATA_HDD_N
BL48 FM_OC0_USB_N GPP_E9_USB2_OC0_N @BASEBOARD_FAB2_LIB.BASEBOARD_FAB2(SCH_1):FM_OC0_USB_N
 AG7 IRQ_OC_DETECT_N GPP_F0_SATAXPCIE3_SATAGP3 @BASEBOARD_FAB2_LIB.BASEBOARD_FAB2(SCH_1):IRQ_OC_DETECT_N
 AL7 SGPIO_PCH_SATA_CLOCK GPP_F10_SATA_SCLOCK @BASEBOARD_FAB2_LIB.BASEBOARD_FAB2(SCH_1):SGPIO_PCH_SATA_CLOCK
 AR9 SGPIO_PCH_SATA_LOAD GPP_F11_SATA_SLOAD @BASEBOARD_FAB2_LIB.BASEBOARD_FAB2(SCH_1):SGPIO_PCH_SATA_LOAD
 AP7 TP_PCH_GPP_F12 GPP_F12_SATA_SDATAOUT1 @BASEBOARD_FAB2_LIB.BASEBOARD_FAB2(SCH_1):TP_PCH_GPP_F12
AP11 SGPIO_PCH_SATA_DOUT0 GPP_F13_SATA_SDATAOUT0 @BASEBOARD_FAB2_LIB.BASEBOARD_FAB2(SCH_1):SGPIO_PCH_SATA_DOUT0
AL11 LED_PCH_SSATA_HDD_N GPP_F14_SSATA_LED_N @BASEBOARD_FAB2_LIB.BASEBOARD_FAB2(SCH_1):LED_PCH_SSATA_HDD_N
AR13 FM_FORCE_ADR_N GPP_F15_USB2_OC4_N @BASEBOARD_FAB2_LIB.BASEBOARD_FAB2(SCH_1):FM_FORCE_ADR_N
AU13 FM_IE_DISABLE_N GPP_F16_USB2_OC5_N @BASEBOARD_FAB2_LIB.BASEBOARD_FAB2(SCH_1):FM_IE_DISABLE_N
AP15 FM_BIOS_TOP_SWAP GPP_F17_USB2_OC6_N @BASEBOARD_FAB2_LIB.BASEBOARD_FAB2(SCH_1):FM_BIOS_TOP_SWAP
AL15 FM_MEM_THERM_EVENT_PCH_N GPP_F18_USB2_OC7_N @BASEBOARD_FAB2_LIB.BASEBOARD_FAB2(SCH_1):FM_MEM_THERM_EVENT_PCH_N
 AU9 SMB_LAN_STBY_LVC3_SCL_R2 GPP_F19_LAN_SMBCLK @BASEBOARD_FAB2_LIB.BASEBOARD_FAB2(SCH_1):SMB_LAN_STBY_LVC3_SCL_R2
 AK9 FM_HSC_TIMER_EXP_N GPP_F1_SATAXPCIE4_SATAGP4 @BASEBOARD_FAB2_LIB.BASEBOARD_FAB2(SCH_1):FM_HSC_TIMER_EXP_N
AU20 SMB_LAN_STBY_LVC3_SDA_R2 GPP_F20_LAN_SMBDATA @BASEBOARD_FAB2_LIB.BASEBOARD_FAB2(SCH_1):SMB_LAN_STBY_LVC3_SDA_R2
AR17 IRQ_PCH_NIC_ALERT_N GPP_F21_LAN_SMBALRT_N @BASEBOARD_FAB2_LIB.BASEBOARD_FAB2(SCH_1):IRQ_PCH_NIC_ALERT_N
AP18 SGPIO_PCH_SSATA_CLOCK GPP_F22_SSATA_SCLOCK @BASEBOARD_FAB2_LIB.BASEBOARD_FAB2(SCH_1):SGPIO_PCH_SSATA_CLOCK
AU17 SGPIO_PCH_SSATA_LOAD GPP_F23_SSATA_SLOAD @BASEBOARD_FAB2_LIB.BASEBOARD_FAB2(SCH_1):SGPIO_PCH_SSATA_LOAD
AK20 FM_MP_PS_FAIL_N GPP_F2_SATAXPCIE5_SATAGP5 @BASEBOARD_FAB2_LIB.BASEBOARD_FAB2(SCH_1):FM_MP_PS_FAIL_N
AK13 FM_MP_PS_REDUNDANT_LOST_N GPP_F3_SATAXPCIE6_SATAGP6 @BASEBOARD_FAB2_LIB.BASEBOARD_FAB2(SCH_1):FM_MP_PS_REDUNDANT_LOST_N
AH13 FM_BMC_READY_N GPP_F4_SATAXPCIE7_SATAGP7 @BASEBOARD_FAB2_LIB.BASEBOARD_FAB2(SCH_1):FM_BMC_READY_N
AH17 FM_BIOS_USB_RECOVERY GPP_F5_SATA_DEVSLP3 @BASEBOARD_FAB2_LIB.BASEBOARD_FAB2(SCH_1):FM_BIOS_USB_RECOVERY
AL18 JTAG_PCH_PLD_TCK GPP_F6_SATA_DEVSLP4 @BASEBOARD_FAB2_LIB.BASEBOARD_FAB2(SCH_1):JTAG_PCH_PLD_TCK
AK17 JTAG_PCH_PLD_TDI GPP_F7_SATA_DEVSLP5 @BASEBOARD_FAB2_LIB.BASEBOARD_FAB2(SCH_1):JTAG_PCH_PLD_TDI
 AH9 JTAG_PCH_PLD_TMS GPP_F8_SATA_DEVSLP6 @BASEBOARD_FAB2_LIB.BASEBOARD_FAB2(SCH_1):JTAG_PCH_PLD_TMS
AR20 JTAG_PCH_PLD_TDO GPP_F9_SATA_DEVSLP7 @BASEBOARD_FAB2_LIB.BASEBOARD_FAB2(SCH_1):JTAG_PCH_PLD_TDO
AY11 FAN_TACH0 GPP_G0_FANTACH0_FANTACH0IE @BASEBOARD_FAB2_LIB.BASEBOARD_FAB2(SCH_1):FAN_TACH0
BE11 FM_CPU0_FIVR_FAULT_LVT3_N GPP_G10_FANPWM2_FANPWM2IE @BASEBOARD_FAB2_LIB.BASEBOARD_FAB2(SCH_1):FM_CPU0_FIVR_FAULT_LVT3_N
BA20 FM_CPU1_FIVR_FAULT_LVT3_N GPP_G11_FANPWM3_FANPMW3IE @BASEBOARD_FAB2_LIB.BASEBOARD_FAB2(SCH_1):FM_CPU1_FIVR_FAULT_LVT3_N
BD13 FM_BOARD_SKU_ID0 GPP_G12 @BASEBOARD_FAB2_LIB.BASEBOARD_FAB2(SCH_1):FM_BOARD_SKU_ID0
AY18 FM_BOARD_SKU_ID1 GPP_G13 @BASEBOARD_FAB2_LIB.BASEBOARD_FAB2(SCH_1):FM_BOARD_SKU_ID1
 AV7 FM_BOARD_SKU_ID2 GPP_G14 @BASEBOARD_FAB2_LIB.BASEBOARD_FAB2(SCH_1):FM_BOARD_SKU_ID2
BE18 FM_BOARD_SKU_ID3 GPP_G15 @BASEBOARD_FAB2_LIB.BASEBOARD_FAB2(SCH_1):FM_BOARD_SKU_ID3
BD17 FM_BOARD_SKU_ID4 GPP_G16 @BASEBOARD_FAB2_LIB.BASEBOARD_FAB2(SCH_1):FM_BOARD_SKU_ID4
 BD9 FM_ADR_COMPLETE_R1 GPP_G17_ADR_COMPLETE @BASEBOARD_FAB2_LIB.BASEBOARD_FAB2(SCH_1):FM_ADR_COMPLETE_R1
 BE7 FM_NMI_EVENT_N GPP_G18_NMI_N @BASEBOARD_FAB2_LIB.BASEBOARD_FAB2(SCH_1):FM_NMI_EVENT_N
BE15 FM_BIOS_SMI_ACTIVE_N GPP_G19_SMI_N @BASEBOARD_FAB2_LIB.BASEBOARD_FAB2(SCH_1):FM_BIOS_SMI_ACTIVE_N
AV15 FAN_TACH1 GPP_G1_FANTACH1_FANTACH1IE @BASEBOARD_FAB2_LIB.BASEBOARD_FAB2(SCH_1):FAN_TACH1
BA17 IRQ_FORCE_NM_THROTTLE_N GPP_G20_SSATA_DEVSLP0 @BASEBOARD_FAB2_LIB.BASEBOARD_FAB2(SCH_1):IRQ_FORCE_NM_THROTTLE_N
 BG7 FM_SOL_UART_CH_SEL GPP_G21_SSATA_DEVSLP1 @BASEBOARD_FAB2_LIB.BASEBOARD_FAB2(SCH_1):FM_SOL_UART_CH_SEL
BD20 FM_CPU0_RC_EN GPP_G22_SSATA_DEVSLP2 @BASEBOARD_FAB2_LIB.BASEBOARD_FAB2(SCH_1):FM_CPU0_RC_EN
BA13 FM_UARTSW_MSB_N GPP_G23_SSATAXPCIE0_SSATAGP0 @BASEBOARD_FAB2_LIB.BASEBOARD_FAB2(SCH_1):FM_UARTSW_MSB_N
BE22 FAN_TACH2 GPP_G2_FANTACH2_FANTACH2IE @BASEBOARD_FAB2_LIB.BASEBOARD_FAB2(SCH_1):FAN_TACH2
 AY7 FAN_TACH3 GPP_G3_FANTACH3_FANTACH3IE @BASEBOARD_FAB2_LIB.BASEBOARD_FAB2(SCH_1):FAN_TACH3
 BA9 IRQ_PVCCIN_CPU0_VRHOT_LVC3_N GPP_G4_FANTACH4_FANTACH4IE @BASEBOARD_FAB2_LIB.BASEBOARD_FAB2(SCH_1):IRQ_PVCCIN_CPU0_VRHOT_LVC3_N
AW20 IRQ_PVCCIN_CPU1_VRHOT_LVC3_N GPP_G5_FANTACH5_FANTACH5IE @BASEBOARD_FAB2_LIB.BASEBOARD_FAB2(SCH_1):IRQ_PVCCIN_CPU1_VRHOT_LVC3_N
AV18 FM_CPU1_THERMTRIP_LATCH_LVT3_N GPP_G6_FANTACH6_FANTACH6IE @BASEBOARD_FAB2_LIB.BASEBOARD_FAB2(SCH_1):FM_CPU1_THERMTRIP_LATCH_LVT3_N
AY15 FM_THROTTLE_N GPP_G7_FANTACH7_FANTACH7IE @BASEBOARD_FAB2_LIB.BASEBOARD_FAB2(SCH_1):FM_THROTTLE_N
BG11 FAN_PWM_OUT_SYS0 GPP_G8_FANPWM0_FANPWM0IE @BASEBOARD_FAB2_LIB.BASEBOARD_FAB2(SCH_1):FAN_PWM_OUT_SYS0
AV11 FAN_PWM_OUT_SYS1 GPP_G9_FANPWM1_FAMPWM1IE @BASEBOARD_FAB2_LIB.BASEBOARD_FAB2(SCH_1):FAN_PWM_OUT_SYS1
 AT4 FM_UARTSW_LSB_N GPP_H0_SRCCLKREQ6_N @BASEBOARD_FAB2_LIB.BASEBOARD_FAB2(SCH_1):FM_UARTSW_LSB_N
 BA4 SMB_VR_STBY_LVC3_SCL_R1 GPP_H10_SML2CLK_IE @BASEBOARD_FAB2_LIB.BASEBOARD_FAB2(SCH_1):SMB_VR_STBY_LVC3_SCL_R1
 BD1 SMB_VR_STBY_LVC3_SDA_R1 GPP_H11_SML2DATA_IE @BASEBOARD_FAB2_LIB.BASEBOARD_FAB2(SCH_1):SMB_VR_STBY_LVC3_SDA_R1
 BB1 FM_FLASH_ATTACH_CFG_STRAP GPP_H12_SML2ALERT_N_IE_N @BASEBOARD_FAB2_LIB.BASEBOARD_FAB2(SCH_1):FM_FLASH_ATTACH_CFG_STRAP
 AY1 SMB_SENSOR_STBY_LVC3_SCL_R1 GPP_H13_SML3CLK_IE @BASEBOARD_FAB2_LIB.BASEBOARD_FAB2(SCH_1):SMB_SENSOR_STBY_LVC3_SCL_R1
 BC2 SMB_SENSOR_STBY_LVC3_SDA_R1 GPP_H14_SML3DATA_IE @BASEBOARD_FAB2_LIB.BASEBOARD_FAB2(SCH_1):SMB_SENSOR_STBY_LVC3_SDA_R1
 BB3 PU_ADR_TIMER_HOLD_OFF_N GPP_H15_SML3ALERT_N_IE_N @BASEBOARD_FAB2_LIB.BASEBOARD_FAB2(SCH_1):PU_ADR_TIMER_HOLD_OFF_N
 BF1 SMB_LAN_STBY_LVC3_SCL_R1 GPP_H16_SML4CLK_IE @BASEBOARD_FAB2_LIB.BASEBOARD_FAB2(SCH_1):SMB_LAN_STBY_LVC3_SCL_R1
 BE4 SMB_LAN_STBY_LVC3_SDA_R1 GPP_H17_SML4DATA_IE @BASEBOARD_FAB2_LIB.BASEBOARD_FAB2(SCH_1):SMB_LAN_STBY_LVC3_SDA_R1
 BC4 FM_OC_DETECT_EN_N GPP_H18_SML4ALERT_N_IE_N @BASEBOARD_FAB2_LIB.BASEBOARD_FAB2(SCH_1):FM_OC_DETECT_EN_N
 BD3 FP_PWR_ID_LED_N GPP_H19_SSATAXPCIE1_SSATAGP1 @BASEBOARD_FAB2_LIB.BASEBOARD_FAB2(SCH_1):FP_PWR_ID_LED_N
 AW4 FM_BACKUP_BIOS_SEL_N GPP_H1_SRCCLKREQ7_N @BASEBOARD_FAB2_LIB.BASEBOARD_FAB2(SCH_1):FM_BACKUP_BIOS_SEL_N
 BF3 FM_BMC_NMI_N GPP_H20_SSATAXPCIE2_SSATAGP2 @BASEBOARD_FAB2_LIB.BASEBOARD_FAB2(SCH_1):FM_BMC_NMI_N
 BA2 FM_BIOS_SMI_ACTIVE_N GPP_H21_SSATAXPCIE3_SSATAGP3 @BASEBOARD_FAB2_LIB.BASEBOARD_FAB2(SCH_1):FM_BIOS_SMI_ACTIVE_N
 BH2 FM_PCH_BMC_THERMTRIP_N GPP_H22_SSATAXPCIE4_SSATAGP4 @BASEBOARD_FAB2_LIB.BASEBOARD_FAB2(SCH_1):FM_PCH_BMC_THERMTRIP_N
 BH4 FM_SSATA_PCIE_M2_SEL GPP_H23_SSATAXPCIE5_SSATAGP5 @BASEBOARD_FAB2_LIB.BASEBOARD_FAB2(SCH_1):FM_SSATA_PCIE_M2_SEL
 AV3 LED_POSTCODE_0 GPP_H2_SRCCLKREQ8_N @BASEBOARD_FAB2_LIB.BASEBOARD_FAB2(SCH_1):LED_POSTCODE_0
 AR1 LED_POSTCODE_1 GPP_H3_SRCCLKREQ9_N @BASEBOARD_FAB2_LIB.BASEBOARD_FAB2(SCH_1):LED_POSTCODE_1
 AT2 LED_POSTCODE_2 GPP_H4_SRCCLKREQ10_N @BASEBOARD_FAB2_LIB.BASEBOARD_FAB2(SCH_1):LED_POSTCODE_2
 AY3 LED_POSTCODE_3 GPP_H5_SRCCLKREQ11_N @BASEBOARD_FAB2_LIB.BASEBOARD_FAB2(SCH_1):LED_POSTCODE_3
 AW2 LED_POSTCODE_4 GPP_H6_SRCCLKREQ12_N @BASEBOARD_FAB2_LIB.BASEBOARD_FAB2(SCH_1):LED_POSTCODE_4
 AV1 LED_POSTCODE_5 GPP_H7_SRCCLKREQ13_N @BASEBOARD_FAB2_LIB.BASEBOARD_FAB2(SCH_1):LED_POSTCODE_5
 AR3 LED_POSTCODE_6 GPP_H8_SRCCLKREQ14_N @BASEBOARD_FAB2_LIB.BASEBOARD_FAB2(SCH_1):LED_POSTCODE_6
 BE2 LED_POSTCODE_7 GPP_H9_SRCCLKREQ15_N @BASEBOARD_FAB2_LIB.BASEBOARD_FAB2(SCH_1):LED_POSTCODE_7
CA20 JTAG_PCH_GBE_TDO GPP_I0_LAN_TDO @BASEBOARD_FAB2_LIB.BASEBOARD_FAB2(SCH_1):JTAG_PCH_GBE_TDO
BV25 FM_BIOS_MRC_DEBUG_MSG_DIS_N GPP_I10 @BASEBOARD_FAB2_LIB.BASEBOARD_FAB2(SCH_1):FM_BIOS_MRC_DEBUG_MSG_DIS_N
BV21 JTAG_PCH_GBE_CLK GPP_I1_LAN_TCK @BASEBOARD_FAB2_LIB.BASEBOARD_FAB2(SCH_1):JTAG_PCH_GBE_CLK
CA22 JTAG_PCH_GBE_TMS GPP_I2_LAN_TMS @BASEBOARD_FAB2_LIB.BASEBOARD_FAB2(SCH_1):JTAG_PCH_GBE_TMS
BY23 JTAG_PCH_GBE_TDI GPP_I3_LAN_TDI @BASEBOARD_FAB2_LIB.BASEBOARD_FAB2(SCH_1):JTAG_PCH_GBE_TDI
BW20 IRQ_DIMM_SAVE_LVT3_N GPP_I4_DO_RESET_IN_N @BASEBOARD_FAB2_LIB.BASEBOARD_FAB2(SCH_1):IRQ_DIMM_SAVE_LVT3_N
BW24 IRQ_BOARD_BMC_ALERT_N GPP_I5_DO_RESET_OUT_N @BASEBOARD_FAB2_LIB.BASEBOARD_FAB2(SCH_1):IRQ_BOARD_BMC_ALERT_N
BV23 FM_CPU1_RC_ERROR_N GPP_I6_RESET_DONE @BASEBOARD_FAB2_LIB.BASEBOARD_FAB2(SCH_1):FM_CPU1_RC_ERROR_N
CA24 JTAG_PCH_GBE_TRST_N GPP_I7_LAN_TRST_N @BASEBOARD_FAB2_LIB.BASEBOARD_FAB2(SCH_1):JTAG_PCH_GBE_TRST_N
BW22 PU_10GBE_LOM_PCI_DISABLE_N GPP_I8_PCI_DIS_N @BASEBOARD_FAB2_LIB.BASEBOARD_FAB2(SCH_1):PU_10GBE_LOM_PCI_DISABLE_N
BY21 FM_10GBE_LOM_DISABLE_N GPP_I9_LAN_DIS_N @BASEBOARD_FAB2_LIB.BASEBOARD_FAB2(SCH_1):FM_10GBE_LOM_DISABLE_N
 BL1 LED_GBE_P0_0 GPP_J0_LAN_LED_P0_0 @BASEBOARD_FAB2_LIB.BASEBOARD_FAB2(SCH_1):LED_GBE_P0_0
 BW5 SMB_PCH_MEZZ_LOM1_SCL GPP_J10_LAN_I2C_SCL_MDC_P1 @BASEBOARD_FAB2_LIB.BASEBOARD_FAB2(SCH_1):SMB_PCH_MEZZ_LOM1_SCL
 BV8 SMB_PCH_MEZZ_LOM1_SDA GPP_J11_LAN_I2C_SDA_MDIO_P1 @BASEBOARD_FAB2_LIB.BASEBOARD_FAB2(SCH_1):SMB_PCH_MEZZ_LOM1_SDA
 BT5 SMB_PCH_MEZZ_LOM2_SCL GPP_J12_LAN_I2C_SCL_MDC_P2 @BASEBOARD_FAB2_LIB.BASEBOARD_FAB2(SCH_1):SMB_PCH_MEZZ_LOM2_SCL
BW11 SMB_PCH_MEZZ_LOM2_SDA GPP_J13_LAN_I2C_SDA_MDIO_P2 @BASEBOARD_FAB2_LIB.BASEBOARD_FAB2(SCH_1):SMB_PCH_MEZZ_LOM2_SDA
 BW6 SMB_PCH_MEZZ_LOM3_SCL GPP_J14_LAN_I2C_SCL_MDC_P3 @BASEBOARD_FAB2_LIB.BASEBOARD_FAB2(SCH_1):SMB_PCH_MEZZ_LOM3_SCL
 BW9 SMB_PCH_MEZZ_LOM3_SDA GPP_J15_LAN_I2C_SDA_MDIO_P3 @BASEBOARD_FAB2_LIB.BASEBOARD_FAB2(SCH_1):SMB_PCH_MEZZ_LOM3_SDA
BV10 FM_GBE0_LVC3_MOD_ABS GPP_J16_LAN_SDP_P0_0 @BASEBOARD_FAB2_LIB.BASEBOARD_FAB2(SCH_1):FM_GBE0_LVC3_MOD_ABS
CA11 TP_PCH_GPP_J17 GPP_J17_LAN_SDP_P0_1 @BASEBOARD_FAB2_LIB.BASEBOARD_FAB2(SCH_1):TP_PCH_GPP_J17
BY10 FM_GBE1_LVC3_MOD_ABS GPP_J18_LAN_SDP_P1_0 @BASEBOARD_FAB2_LIB.BASEBOARD_FAB2(SCH_1):FM_GBE1_LVC3_MOD_ABS
BY14 TP_PCH_GPP_J19 GPP_J19_LAN_SDP_P1_1 @BASEBOARD_FAB2_LIB.BASEBOARD_FAB2(SCH_1):TP_PCH_GPP_J19
 BK4 LED_GBE_P0_1 GPP_J1_LAN_LED_P0_1 @BASEBOARD_FAB2_LIB.BASEBOARD_FAB2(SCH_1):LED_GBE_P0_1
BW13 FM_GBE2_LVC3_MOD_ABS GPP_J20_LAN_SDP_P2_0 @BASEBOARD_FAB2_LIB.BASEBOARD_FAB2(SCH_1):FM_GBE2_LVC3_MOD_ABS
BV12 TP_PCH_GPP_J21 GPP_J21_LAN_SDP_P2_1 @BASEBOARD_FAB2_LIB.BASEBOARD_FAB2(SCH_1):TP_PCH_GPP_J21
BY12 FM_GBE3_LVC3_MOD_ABS GPP_J22_LAN_SDP_P3_0 @BASEBOARD_FAB2_LIB.BASEBOARD_FAB2(SCH_1):FM_GBE3_LVC3_MOD_ABS
BV14 TP_PCH_GPP_J23 GPP_J23_LAN_SDP_P3_1 @BASEBOARD_FAB2_LIB.BASEBOARD_FAB2(SCH_1):TP_PCH_GPP_J23
 BP4 LED_GBE_P1_0 GPP_J2_LAN_LED_P1_0 @BASEBOARD_FAB2_LIB.BASEBOARD_FAB2(SCH_1):LED_GBE_P1_0
 BK2 LED_GBE_P1_1 GPP_J3_LAN_LED_P1_1 @BASEBOARD_FAB2_LIB.BASEBOARD_FAB2(SCH_1):LED_GBE_P1_1
 BL3 LED_GBE_P2_0 GPP_J4_LAN_LED_P2_0 @BASEBOARD_FAB2_LIB.BASEBOARD_FAB2(SCH_1):LED_GBE_P2_0
 BU6 LED_GBE_P2_1 GPP_J5_LAN_LED_P2_1 @BASEBOARD_FAB2_LIB.BASEBOARD_FAB2(SCH_1):LED_GBE_P2_1
CA13 LED_GBE_P3_0 GPP_J6_LAN_LED_P3_0 @BASEBOARD_FAB2_LIB.BASEBOARD_FAB2(SCH_1):LED_GBE_P3_0
 BM2 LED_GBE_P3_1 GPP_J7_LAN_LED_P3_1 @BASEBOARD_FAB2_LIB.BASEBOARD_FAB2(SCH_1):LED_GBE_P3_1
 BM4 SMB_PCH_MEZZ_LOM0_SCL GPP_J8_LAN_I2C_SCL_MDC_P0 @BASEBOARD_FAB2_LIB.BASEBOARD_FAB2(SCH_1):SMB_PCH_MEZZ_LOM0_SCL
 BN3 SMB_PCH_MEZZ_LOM0_SDA GPP_J9_LAN_I2C_SDA_MDIO_P0 @BASEBOARD_FAB2_LIB.BASEBOARD_FAB2(SCH_1):SMB_PCH_MEZZ_LOM0_SDA

RES_0402-100.0,1%,1/16W,CHIP,GA  I148  R8C21
   1 A_RCOMP_3P3      A @BASEBOARD_FAB2_LIB.BASEBOARD_FAB2(SCH_1):A_RCOMP_3P3
   2    GND      B @BASEBOARD_FAB2_LIB.BASEBOARD_FAB2(SCH_1):GND

RES_0402-33.2,1%,1/16W,CHIP,G2A  I218  R2M1
   1 FM_CPLD_ADR_TRIGGER_N      A @BASEBOARD_FAB2_LIB.BASEBOARD_FAB2(SCH_1):FM_CPLD_ADR_TRIGGER_N
   2 FM_CPLD_ADR_TRIGGER_R_N      B @BASEBOARD_FAB2_LIB.BASEBOARD_FAB2(SCH_1):FM_CPLD_ADR_TRIGGER_R_N

RES_0402-33.2,1%,1/16W,CHIP,G2A  I219  R2N26
   1 FM_ADR_COMPLETE      A @BASEBOARD_FAB2_LIB.BASEBOARD_FAB2(SCH_1):FM_ADR_COMPLETE
   2 FM_ADR_COMPLETE_R1      B @BASEBOARD_FAB2_LIB.BASEBOARD_FAB2(SCH_1):FM_ADR_COMPLETE_R1


DRAWING: @BASEBOARD_FAB2_LIB.BASEBOARD_FAB2(SCH_1):PAGE121 

RES_0402-0.0,5%,1/16W,CHIP,G21A  I31  R7C15
   1 SPI_PCH_MOSI_R      A @BASEBOARD_FAB2_LIB.BASEBOARD_FAB2(SCH_1):SPI_PCH_MOSI_R
   2 SPI_PCH_MOSI      B @BASEBOARD_FAB2_LIB.BASEBOARD_FAB2(SCH_1):SPI_PCH_MOSI

RES_0402-33.2,1%,1/16W,CHIP,G2A  I33  R7C16
   1 SPI_PCH_CS0_R_N      A @BASEBOARD_FAB2_LIB.BASEBOARD_FAB2(SCH_1):SPI_PCH_CS0_R_N
   2 SPI_PCH_CS0_N      B @BASEBOARD_FAB2_LIB.BASEBOARD_FAB2(SCH_1):SPI_PCH_CS0_N

LBG_CORE_QAT_EXT_D_BGA1-IC,H91A  I34  U7C1
 C70 FM_PCH_PRSNT_N CGC_DUT_DETECT_N @BASEBOARD_FAB2_LIB.BASEBOARD_FAB2(SCH_1):FM_PCH_PRSNT_N
 AM4 A_1P8_3P3_RCOMP GPIO_RCOMP_1P8_3P3 @BASEBOARD_FAB2_LIB.BASEBOARD_FAB2(SCH_1):A_1P8_3P3_RCOMP
 AJ1 CLK_50M_CKMNG_PCH_10GBE GPP_K0_LAN_NCSI_CLK_IN @BASEBOARD_FAB2_LIB.BASEBOARD_FAB2(SCH_1):CLK_50M_CKMNG_PCH_10GBE
 AH4 RST_PCIE_PCH_PERST_N GPP_K10_PE_RST_N @BASEBOARD_FAB2_LIB.BASEBOARD_FAB2(SCH_1):RST_PCIE_PCH_PERST_N
 AM2 RMII_BMC_PCH_SPRNGVLLE_TXD0 GPP_K1_LAN_NCSI_TXD0 @BASEBOARD_FAB2_LIB.BASEBOARD_FAB2(SCH_1):RMII_BMC_PCH_SPRNGVLLE_TXD0
 AK2 RMII_BMC_PCH_SPRNGVLLE_TXD1 GPP_K2_LAN_NCSI_TXD1 @BASEBOARD_FAB2_LIB.BASEBOARD_FAB2(SCH_1):RMII_BMC_PCH_SPRNGVLLE_TXD1
 AL3 RMII_BMC_PCH_SPRNGVLLE_TXEN GPP_K3_LAN_NCSI_TX_EN @BASEBOARD_FAB2_LIB.BASEBOARD_FAB2(SCH_1):RMII_BMC_PCH_SPRNGVLLE_TXEN
 AN3 RMII_BMC_PCH_SPRNGVLLE_CRSDV_R1 GPP_K4_LAN_NCSI_CRS_DV @BASEBOARD_FAB2_LIB.BASEBOARD_FAB2(SCH_1):RMII_BMC_PCH_SPRNGVLLE_CRSDV_R1
 AL1 RMII_SPRNGVLLE_BMC_PCH_RXD0_R1 GPP_K5_LAN_NCSI_RXD0 @BASEBOARD_FAB2_LIB.BASEBOARD_FAB2(SCH_1):RMII_SPRNGVLLE_BMC_PCH_RXD0_R1
 AN1 RMII_SPRNGVLLE_BMC_PCH_RXD1_R1 GPP_K6_LAN_NCSI_RXD1 @BASEBOARD_FAB2_LIB.BASEBOARD_FAB2(SCH_1):RMII_SPRNGVLLE_BMC_PCH_RXD1_R1
 AH2 RMII_BMC_PCH_SPRNGVLLE_RXER_R GPP_K7 @BASEBOARD_FAB2_LIB.BASEBOARD_FAB2(SCH_1):RMII_BMC_PCH_SPRNGVLLE_RXER_R
 AJ3 RMII_PCH_SPRNGVLLE_ARB_IN GPP_K8_LAN_NCSI_ARB_IN @BASEBOARD_FAB2_LIB.BASEBOARD_FAB2(SCH_1):RMII_PCH_SPRNGVLLE_ARB_IN
 AK4 RMII_PCH_SPRNGVLLE_ARB_OUT_R GPP_K9_LAN_NCSI_ARB_OUT @BASEBOARD_FAB2_LIB.BASEBOARD_FAB2(SCH_1):RMII_PCH_SPRNGVLLE_ARB_OUT_R
AF20 TP_PCH_GPP_L10 GPP_L10_TESTCH0_CLK @BASEBOARD_FAB2_LIB.BASEBOARD_FAB2(SCH_1):TP_PCH_GPP_L10
AD20 TP_PCH_GPP_L11 GPP_L11_TESTCH1_D0 @BASEBOARD_FAB2_LIB.BASEBOARD_FAB2(SCH_1):TP_PCH_GPP_L11
 Y15 H_CPU0_MEMABC_MEMHOT_PCH_N GPP_L12_TESTCH1_D1 @BASEBOARD_FAB2_LIB.BASEBOARD_FAB2(SCH_1):H_CPU0_MEMABC_MEMHOT_PCH_N
AD13 H_CPU0_MEMDEF_MEMHOT_PCH_N GPP_L13_TESTCH1_D2 @BASEBOARD_FAB2_LIB.BASEBOARD_FAB2(SCH_1):H_CPU0_MEMDEF_MEMHOT_PCH_N
AA13 H_CPU1_MEMGHJ_MEMHOT_PCH_N GPP_L14_TESTCH1_D3 @BASEBOARD_FAB2_LIB.BASEBOARD_FAB2(SCH_1):H_CPU1_MEMGHJ_MEMHOT_PCH_N
 Y11 H_CPU1_MEMKLM_MEMHOT_PCH_N GPP_L15_TESTCH1_D4 @BASEBOARD_FAB2_LIB.BASEBOARD_FAB2(SCH_1):H_CPU1_MEMKLM_MEMHOT_PCH_N
  Y7 FM_CPU0_PROCHOT_PCH_N GPP_L16_TESTCH1_D5 @BASEBOARD_FAB2_LIB.BASEBOARD_FAB2(SCH_1):FM_CPU0_PROCHOT_PCH_N
 AA9 FM_CPU1_PROCHOT_PCH_N GPP_L17_TESTCH1_D6 @BASEBOARD_FAB2_LIB.BASEBOARD_FAB2(SCH_1):FM_CPU1_PROCHOT_PCH_N
 AE7 FM_CPU_ERR0_PCH_N GPP_L18_TESTCH1_D7 @BASEBOARD_FAB2_LIB.BASEBOARD_FAB2(SCH_1):FM_CPU_ERR0_PCH_N
AG11 FM_CPU_ERR1_PCH_N GPP_L19_TESTCH1_CLK @BASEBOARD_FAB2_LIB.BASEBOARD_FAB2(SCH_1):FM_CPU_ERR1_PCH_N
AE18 FM_PRSNT_2_1_N GPP_L2_TESTCH0_D0 @BASEBOARD_FAB2_LIB.BASEBOARD_FAB2(SCH_1):FM_PRSNT_2_1_N
AE15 FM_PRSNT_2_2_N GPP_L3_TESTCH0_D1 @BASEBOARD_FAB2_LIB.BASEBOARD_FAB2(SCH_1):FM_PRSNT_2_2_N
AE11 FM_PRSNT_2_3_N GPP_L4_TESTCH0_D2 @BASEBOARD_FAB2_LIB.BASEBOARD_FAB2(SCH_1):FM_PRSNT_2_3_N
 Y18 FM_PRSNT_2_4_N GPP_L5_TESTCH0_D3 @BASEBOARD_FAB2_LIB.BASEBOARD_FAB2(SCH_1):FM_PRSNT_2_4_N
AA20 FM_PRSNT_2_5_N GPP_L6_TESTCH0_D4 @BASEBOARD_FAB2_LIB.BASEBOARD_FAB2(SCH_1):FM_PRSNT_2_5_N
AA17 FM_PRSNT_2_6_N GPP_L7_TESTCH0_D5 @BASEBOARD_FAB2_LIB.BASEBOARD_FAB2(SCH_1):FM_PRSNT_2_6_N
 AD9 FM_OCP_MEZZB_PRES_N GPP_L8_TESTCH0_D6 @BASEBOARD_FAB2_LIB.BASEBOARD_FAB2(SCH_1):FM_OCP_MEZZB_PRES_N
AD17 FM_OCP_MEZZC_PRES_N GPP_L9_TESTCH0_D7 @BASEBOARD_FAB2_LIB.BASEBOARD_FAB2(SCH_1):FM_OCP_MEZZC_PRES_N
 P18 TP_PCH_HDA_BCLK HDA_BCLK @BASEBOARD_FAB2_LIB.BASEBOARD_FAB2(SCH_1):TP_PCH_HDA_BCLK
 M18 TP_PCH_HSA_RST_N HDA_RST_N @BASEBOARD_FAB2_LIB.BASEBOARD_FAB2(SCH_1):TP_PCH_HSA_RST_N
 K20 TP_PCH_HDA_SDI_0 HDA_SDI_0 @BASEBOARD_FAB2_LIB.BASEBOARD_FAB2(SCH_1):TP_PCH_HDA_SDI_0
 V18 TP_PCH_HDA_SDI_1 HDA_SDI_1 @BASEBOARD_FAB2_LIB.BASEBOARD_FAB2(SCH_1):TP_PCH_HDA_SDI_1
 U24 FM_FLASH_DESC_OVERRIDE HDA_SDO @BASEBOARD_FAB2_LIB.BASEBOARD_FAB2(SCH_1):FM_FLASH_DESC_OVERRIDE
 H20 TP_PCH_HDA_SYNC HDA_SYNC @BASEBOARD_FAB2_LIB.BASEBOARD_FAB2(SCH_1):TP_PCH_HDA_SYNC
AG18 FM_INTRUDER_HDR_PCH_N INTRUDER_N @BASEBOARD_FAB2_LIB.BASEBOARD_FAB2(SCH_1):FM_INTRUDER_HDR_PCH_N
 V22 TP_PCH_DISPA_SDO RSVD<68> @BASEBOARD_FAB2_LIB.BASEBOARD_FAB2(SCH_1):TP_PCH_DISPA_SDO
 R20 TP_PCH_DISPA_SDI RSVD<67> @BASEBOARD_FAB2_LIB.BASEBOARD_FAB2(SCH_1):TP_PCH_DISPA_SDI
 U20 TP_PCH_DISPA_BCLK RSVD<66> @BASEBOARD_FAB2_LIB.BASEBOARD_FAB2(SCH_1):TP_PCH_DISPA_BCLK
 BW3 TP_PCH_RSVD46 RSVD<46> @BASEBOARD_FAB2_LIB.BASEBOARD_FAB2(SCH_1):TP_PCH_RSVD46
BG26 TP_PCH_RSVD27 RSVD<27> @BASEBOARD_FAB2_LIB.BASEBOARD_FAB2(SCH_1):TP_PCH_RSVD27
BH24 TP_PCH_RSVD26 RSVD<26> @BASEBOARD_FAB2_LIB.BASEBOARD_FAB2(SCH_1):TP_PCH_RSVD26
 P48 TP_PCH_RSVD25 RSVD<25> @BASEBOARD_FAB2_LIB.BASEBOARD_FAB2(SCH_1):TP_PCH_RSVD25
 P44 TP_PCH_RSVD24 RSVD<24> @BASEBOARD_FAB2_LIB.BASEBOARD_FAB2(SCH_1):TP_PCH_RSVD24
 P40 TP_PCH_RSVD23 RSVD<23> @BASEBOARD_FAB2_LIB.BASEBOARD_FAB2(SCH_1):TP_PCH_RSVD23
AT71 TP_PCH_RSVD22 RSVD<22> @BASEBOARD_FAB2_LIB.BASEBOARD_FAB2(SCH_1):TP_PCH_RSVD22
 A11 TP_PCH_RSVD21 RSVD<21> @BASEBOARD_FAB2_LIB.BASEBOARD_FAB2(SCH_1):TP_PCH_RSVD21
 D10 TP_PCH_RSVD20 RSVD<20> @BASEBOARD_FAB2_LIB.BASEBOARD_FAB2(SCH_1):TP_PCH_RSVD20
  C9 TP_PCH_RSVD19 RSVD<19> @BASEBOARD_FAB2_LIB.BASEBOARD_FAB2(SCH_1):TP_PCH_RSVD19
 C11 TP_PCH_RSVD18 RSVD<18> @BASEBOARD_FAB2_LIB.BASEBOARD_FAB2(SCH_1):TP_PCH_RSVD18
 B10 TP_PCH_RSVD17 RSVD<17> @BASEBOARD_FAB2_LIB.BASEBOARD_FAB2(SCH_1):TP_PCH_RSVD17
  C5 TP_PCH_RSVD16 RSVD<16> @BASEBOARD_FAB2_LIB.BASEBOARD_FAB2(SCH_1):TP_PCH_RSVD16
  C6 TP_PCH_RSVD15 RSVD<15> @BASEBOARD_FAB2_LIB.BASEBOARD_FAB2(SCH_1):TP_PCH_RSVD15
 E18 TP_PCH_RSVD14 RSVD<14> @BASEBOARD_FAB2_LIB.BASEBOARD_FAB2(SCH_1):TP_PCH_RSVD14
 C67 TP_PCH_RSVD13 RSVD<13> @BASEBOARD_FAB2_LIB.BASEBOARD_FAB2(SCH_1):TP_PCH_RSVD13
 C68 TP_PCH_RSVD12 RSVD<12> @BASEBOARD_FAB2_LIB.BASEBOARD_FAB2(SCH_1):TP_PCH_RSVD12
 C18 FM_SINT_PRSNT_N RSVD<11> @BASEBOARD_FAB2_LIB.BASEBOARD_FAB2(SCH_1):FM_SINT_PRSNT_N
  D8 FM_WBG_PRSNT_N RSVD<10> @BASEBOARD_FAB2_LIB.BASEBOARD_FAB2(SCH_1):FM_WBG_PRSNT_N
 F66 TP_PCH_RSVD9 RSVD<9> @BASEBOARD_FAB2_LIB.BASEBOARD_FAB2(SCH_1):TP_PCH_RSVD9
 F69 TP_PCH_RSVD8 RSVD<8> @BASEBOARD_FAB2_LIB.BASEBOARD_FAB2(SCH_1):TP_PCH_RSVD8
  F8 TP_PCH_RSVD7 RSVD<7> @BASEBOARD_FAB2_LIB.BASEBOARD_FAB2(SCH_1):TP_PCH_RSVD7
AT69 TP_PCH_RSVD6 RSVD<6> @BASEBOARD_FAB2_LIB.BASEBOARD_FAB2(SCH_1):TP_PCH_RSVD6
AG15 TP_PCH_RSVD5 RSVD<5> @BASEBOARD_FAB2_LIB.BASEBOARD_FAB2(SCH_1):TP_PCH_RSVD5
 P37 TP_PCH_RSVD4 RSVD<4> @BASEBOARD_FAB2_LIB.BASEBOARD_FAB2(SCH_1):TP_PCH_RSVD4
 V11 TP_PCH_RSVD3 RSVD<3> @BASEBOARD_FAB2_LIB.BASEBOARD_FAB2(SCH_1):TP_PCH_RSVD3
AA58 TP_PCH_RSVD2 RSVD<2> @BASEBOARD_FAB2_LIB.BASEBOARD_FAB2(SCH_1):TP_PCH_RSVD2
AC56 TP_PCH_RSVD1 RSVD<1> @BASEBOARD_FAB2_LIB.BASEBOARD_FAB2(SCH_1):TP_PCH_RSVD1
AF61 TP_PCH_RSVD0 RSVD<0> @BASEBOARD_FAB2_LIB.BASEBOARD_FAB2(SCH_1):TP_PCH_RSVD0
 P11 RST_RTCRST_N RTCRST_N @BASEBOARD_FAB2_LIB.BASEBOARD_FAB2(SCH_1):RST_RTCRST_N
  K2 SPI_PCH_CLK SPI0_CLK @BASEBOARD_FAB2_LIB.BASEBOARD_FAB2(SCH_1):SPI_PCH_CLK
  J3 SPI_PCH_CS0_R_N SPI0_FLASH_CS0_N @BASEBOARD_FAB2_LIB.BASEBOARD_FAB2(SCH_1):SPI_PCH_CS0_R_N
  G7 TP_SPI_PCH_CS1_R1_N SPI0_FLASH_CS1_N @BASEBOARD_FAB2_LIB.BASEBOARD_FAB2(SCH_1):TP_SPI_PCH_CS1_R1_N
  F5 SPI_PCH_IO2 SPI0_IO2 @BASEBOARD_FAB2_LIB.BASEBOARD_FAB2(SCH_1):SPI_PCH_IO2
  L1 SPI_PCH_IO3 SPI0_IO3 @BASEBOARD_FAB2_LIB.BASEBOARD_FAB2(SCH_1):SPI_PCH_IO3
  L3 SPI_PCH_MISO SPI0_MISO_IO1 @BASEBOARD_FAB2_LIB.BASEBOARD_FAB2(SCH_1):SPI_PCH_MISO
  H4 SPI_PCH_MOSI_R SPI0_MOSI_IO0 @BASEBOARD_FAB2_LIB.BASEBOARD_FAB2(SCH_1):SPI_PCH_MOSI_R
  K4 SPI_PCH_TPM_CS_N SPI0_TPM_CS_N @BASEBOARD_FAB2_LIB.BASEBOARD_FAB2(SCH_1):SPI_PCH_TPM_CS_N
 G18 RST_SRTCRST_N SRTCRST_N @BASEBOARD_FAB2_LIB.BASEBOARD_FAB2(SCH_1):RST_SRTCRST_N

RES_0402-100.0,1%,1/16W,CHIP,GA  I35  R8C26
   1 A_1P8_3P3_RCOMP      A @BASEBOARD_FAB2_LIB.BASEBOARD_FAB2(SCH_1):A_1P8_3P3_RCOMP
   2    GND      B @BASEBOARD_FAB2_LIB.BASEBOARD_FAB2(SCH_1):GND

RES_0402-10.0K,1%,1/16W,CHIP,GA  I37  R3N10
   1 P3V3_STBY      A @BASEBOARD_FAB2_LIB.BASEBOARD_FAB2(SCH_1):P3V3_STBY
   2 FM_INTRUDER_HDR_PCH_N      B @BASEBOARD_FAB2_LIB.BASEBOARD_FAB2(SCH_1):FM_INTRUDER_HDR_PCH_N

RES_0402-10.0K,1%,1/16W,CHIP,GA  I73  R7C20
   1 CLK_50M_CKMNG_PCH_10GBE      A @BASEBOARD_FAB2_LIB.BASEBOARD_FAB2(SCH_1):CLK_50M_CKMNG_PCH_10GBE
   2    GND      B @BASEBOARD_FAB2_LIB.BASEBOARD_FAB2(SCH_1):GND

RES_0402-0.0,5%,1/16W,CHIP,G21A  I89  R3P3
   1 RMII_SPRNGVLLE_BMC_PCH_RXD0      A @BASEBOARD_FAB2_LIB.BASEBOARD_FAB2(SCH_1):RMII_SPRNGVLLE_BMC_PCH_RXD0
   2 RMII_SPRNGVLLE_BMC_PCH_RXD0_R1      B @BASEBOARD_FAB2_LIB.BASEBOARD_FAB2(SCH_1):RMII_SPRNGVLLE_BMC_PCH_RXD0_R1

RES_0402-0.0,5%,1/16W,CHIP,G21A  I90  R3P2
   1 RMII_BMC_PCH_SPRNGVLLE_CRSDV      A @BASEBOARD_FAB2_LIB.BASEBOARD_FAB2(SCH_1):RMII_BMC_PCH_SPRNGVLLE_CRSDV
   2 RMII_BMC_PCH_SPRNGVLLE_CRSDV_R1      B @BASEBOARD_FAB2_LIB.BASEBOARD_FAB2(SCH_1):RMII_BMC_PCH_SPRNGVLLE_CRSDV_R1

RES_0402-0.0,5%,1/16W,CHIP,G21A  I91  R2P1
   1 RMII_SPRNGVLLE_BMC_PCH_RXD1      A @BASEBOARD_FAB2_LIB.BASEBOARD_FAB2(SCH_1):RMII_SPRNGVLLE_BMC_PCH_RXD1
   2 RMII_SPRNGVLLE_BMC_PCH_RXD1_R1      B @BASEBOARD_FAB2_LIB.BASEBOARD_FAB2(SCH_1):RMII_SPRNGVLLE_BMC_PCH_RXD1_R1

RES_0402-33.2,1%,1/16W,CHIP,G2A  I98  R7C14
   1 RMII_BMC_PCH_SPRNGVLLE_RXER      A @BASEBOARD_FAB2_LIB.BASEBOARD_FAB2(SCH_1):RMII_BMC_PCH_SPRNGVLLE_RXER
   2 RMII_BMC_PCH_SPRNGVLLE_RXER_R      B @BASEBOARD_FAB2_LIB.BASEBOARD_FAB2(SCH_1):RMII_BMC_PCH_SPRNGVLLE_RXER_R

RES_0402-33.2,1%,1/16W,CHIP,G2A  I101  R8D11
   1 RMII_PCH_SPRNGVLLE_ARB_OUT      A @BASEBOARD_FAB2_LIB.BASEBOARD_FAB2(SCH_1):RMII_PCH_SPRNGVLLE_ARB_OUT
   2 RMII_PCH_SPRNGVLLE_ARB_OUT_R      B @BASEBOARD_FAB2_LIB.BASEBOARD_FAB2(SCH_1):RMII_PCH_SPRNGVLLE_ARB_OUT_R


DRAWING: @BASEBOARD_FAB2_LIB.BASEBOARD_FAB2(SCH_1):PAGE122 

LBG_CORE_QAT_EXT_D_BGA1-IC,H91A  I63  U7C1
AT27 TP_PCH_RSVD59 RSVD<59> @BASEBOARD_FAB2_LIB.BASEBOARD_FAB2(SCH_1):TP_PCH_RSVD59
AP27 TP_PCH_RSVD58 RSVD<58> @BASEBOARD_FAB2_LIB.BASEBOARD_FAB2(SCH_1):TP_PCH_RSVD58
 P29 TP_PCH_RSVD31 RSVD<31> @BASEBOARD_FAB2_LIB.BASEBOARD_FAB2(SCH_1):TP_PCH_RSVD31
 R31 TP_PCH_RSVD30 RSVD<30> @BASEBOARD_FAB2_LIB.BASEBOARD_FAB2(SCH_1):TP_PCH_RSVD30
 P33 TP_PCH_RSVD29 RSVD<29> @BASEBOARD_FAB2_LIB.BASEBOARD_FAB2(SCH_1):TP_PCH_RSVD29
 R35 TP_PCH_RSVD28 RSVD<28> @BASEBOARD_FAB2_LIB.BASEBOARD_FAB2(SCH_1):TP_PCH_RSVD28
AE46 P1V05_PCH_STBY_ISCLK_PLL VCCA_CLKFILT_1P05<4> @BASEBOARD_FAB2_LIB.BASEBOARD_FAB2(SCH_1):P1V05_PCH_STBY_ISCLK_PLL
AJ48 P1V05_PCH_STBY_ISCLK_PLL VCCA_CLKFILT_1P05<3> @BASEBOARD_FAB2_LIB.BASEBOARD_FAB2(SCH_1):P1V05_PCH_STBY_ISCLK_PLL
AJ46 P1V05_PCH_STBY_ISCLK_PLL VCCA_CLKFILT_1P05<2> @BASEBOARD_FAB2_LIB.BASEBOARD_FAB2(SCH_1):P1V05_PCH_STBY_ISCLK_PLL
AG45 P1V05_PCH_STBY_ISCLK_PLL VCCA_CLKFILT_1P05<1> @BASEBOARD_FAB2_LIB.BASEBOARD_FAB2(SCH_1):P1V05_PCH_STBY_ISCLK_PLL
 W50 P1V05_PCH_STBY_ISCLK_PLL VCCA_CLKFILT_1P05<0> @BASEBOARD_FAB2_LIB.BASEBOARD_FAB2(SCH_1):P1V05_PCH_STBY_ISCLK_PLL
 U50 P1V05_PCH_STBY VCCA_CLKUNF_1P05<1> @BASEBOARD_FAB2_LIB.BASEBOARD_FAB2(SCH_1):P1V05_PCH_STBY
AH50 P1V05_PCH_STBY VCCA_CLKUNF_1P05<0> @BASEBOARD_FAB2_LIB.BASEBOARD_FAB2(SCH_1):P1V05_PCH_STBY
AD50 P1V05_PCH_STBY_VCCA_XTAL VCCA_CLKXTAL_1P05 @BASEBOARD_FAB2_LIB.BASEBOARD_FAB2(SCH_1):P1V05_PCH_STBY_VCCA_XTAL
AG48 P1V05_PCH_STBY_VCCA_PLL0 VCCA_PLL0_1P05 @BASEBOARD_FAB2_LIB.BASEBOARD_FAB2(SCH_1):P1V05_PCH_STBY_VCCA_PLL0
AE45 P1V05_PCH_STBY_VCCA_PLL1 VCCA_PLL1_1P05 @BASEBOARD_FAB2_LIB.BASEBOARD_FAB2(SCH_1):P1V05_PCH_STBY_VCCA_PLL1
AK43 P1V05_PCH_STBY VCCMPHY_1P05<12> @BASEBOARD_FAB2_LIB.BASEBOARD_FAB2(SCH_1):P1V05_PCH_STBY
AK45 P1V05_PCH_STBY VCCMPHY_1P05<11> @BASEBOARD_FAB2_LIB.BASEBOARD_FAB2(SCH_1):P1V05_PCH_STBY
AM43 P1V05_PCH_STBY VCCMPHY_1P05<10> @BASEBOARD_FAB2_LIB.BASEBOARD_FAB2(SCH_1):P1V05_PCH_STBY
AM45 P1V05_PCH_STBY VCCMPHY_1P05<9> @BASEBOARD_FAB2_LIB.BASEBOARD_FAB2(SCH_1):P1V05_PCH_STBY
AP43 P1V05_PCH_STBY VCCMPHY_1P05<8> @BASEBOARD_FAB2_LIB.BASEBOARD_FAB2(SCH_1):P1V05_PCH_STBY
AP45 P1V05_PCH_STBY VCCMPHY_1P05<7> @BASEBOARD_FAB2_LIB.BASEBOARD_FAB2(SCH_1):P1V05_PCH_STBY
AT43 P1V05_PCH_STBY VCCMPHY_1P05<6> @BASEBOARD_FAB2_LIB.BASEBOARD_FAB2(SCH_1):P1V05_PCH_STBY
AT45 P1V05_PCH_STBY VCCMPHY_1P05<5> @BASEBOARD_FAB2_LIB.BASEBOARD_FAB2(SCH_1):P1V05_PCH_STBY
AU43 P1V05_PCH_STBY VCCMPHY_1P05<4> @BASEBOARD_FAB2_LIB.BASEBOARD_FAB2(SCH_1):P1V05_PCH_STBY
AU45 P1V05_PCH_STBY VCCMPHY_1P05<3> @BASEBOARD_FAB2_LIB.BASEBOARD_FAB2(SCH_1):P1V05_PCH_STBY
AJ43 P1V05_PCH_STBY VCCMPHY_1P05<2> @BASEBOARD_FAB2_LIB.BASEBOARD_FAB2(SCH_1):P1V05_PCH_STBY
AW43 P1V05_PCH_STBY VCCMPHY_1P05<1> @BASEBOARD_FAB2_LIB.BASEBOARD_FAB2(SCH_1):P1V05_PCH_STBY
AW45 P1V05_PCH_STBY VCCMPHY_1P05<0> @BASEBOARD_FAB2_LIB.BASEBOARD_FAB2(SCH_1):P1V05_PCH_STBY
BA39 P1V05_PCH_STBY_KR_PLL VCCP10GBEPLL_1P05<3> @BASEBOARD_FAB2_LIB.BASEBOARD_FAB2(SCH_1):P1V05_PCH_STBY_KR_PLL
BA41 P1V05_PCH_STBY_KR_PLL VCCP10GBEPLL_1P05<2> @BASEBOARD_FAB2_LIB.BASEBOARD_FAB2(SCH_1):P1V05_PCH_STBY_KR_PLL
BB40 P1V05_PCH_STBY_KR_PLL VCCP10GBEPLL_1P05<1> @BASEBOARD_FAB2_LIB.BASEBOARD_FAB2(SCH_1):P1V05_PCH_STBY_KR_PLL
BD38 P1V05_PCH_STBY_KR_PLL VCCP10GBEPLL_1P05<0> @BASEBOARD_FAB2_LIB.BASEBOARD_FAB2(SCH_1):P1V05_PCH_STBY_KR_PLL
BA27 P1V8_PCH_STBY VCCP10GBE_HV_1P8<1> @BASEBOARD_FAB2_LIB.BASEBOARD_FAB2(SCH_1):P1V8_PCH_STBY
BA29 P1V8_PCH_STBY VCCP10GBE_HV_1P8<0> @BASEBOARD_FAB2_LIB.BASEBOARD_FAB2(SCH_1):P1V8_PCH_STBY
BA30 P1V05_PCH_STBY VCCP10GBE_LV_1P05<6> @BASEBOARD_FAB2_LIB.BASEBOARD_FAB2(SCH_1):P1V05_PCH_STBY
BA32 P1V05_PCH_STBY VCCP10GBE_LV_1P05<5> @BASEBOARD_FAB2_LIB.BASEBOARD_FAB2(SCH_1):P1V05_PCH_STBY
BA34 P1V05_PCH_STBY VCCP10GBE_LV_1P05<4> @BASEBOARD_FAB2_LIB.BASEBOARD_FAB2(SCH_1):P1V05_PCH_STBY
BA36 P1V05_PCH_STBY VCCP10GBE_LV_1P05<3> @BASEBOARD_FAB2_LIB.BASEBOARD_FAB2(SCH_1):P1V05_PCH_STBY
BA37 P1V05_PCH_STBY VCCP10GBE_LV_1P05<2> @BASEBOARD_FAB2_LIB.BASEBOARD_FAB2(SCH_1):P1V05_PCH_STBY
BB33 P1V05_PCH_STBY VCCP10GBE_LV_1P05<1> @BASEBOARD_FAB2_LIB.BASEBOARD_FAB2(SCH_1):P1V05_PCH_STBY
BB37 P1V05_PCH_STBY VCCP10GBE_LV_1P05<0> @BASEBOARD_FAB2_LIB.BASEBOARD_FAB2(SCH_1):P1V05_PCH_STBY
AH24 P3V3_STBY VCCPDSW_3P3 @BASEBOARD_FAB2_LIB.BASEBOARD_FAB2(SCH_1):P3V3_STBY
AW24 P3V3_STBY VCCPGPPA @BASEBOARD_FAB2_LIB.BASEBOARD_FAB2(SCH_1):P3V3_STBY
BE26 P3V3_STBY VCCPGPPB @BASEBOARD_FAB2_LIB.BASEBOARD_FAB2(SCH_1):P3V3_STBY
BE40 P3V3_STBY VCCPGPPC @BASEBOARD_FAB2_LIB.BASEBOARD_FAB2(SCH_1):P3V3_STBY
BA43 P3V3_STBY VCCPGPPD @BASEBOARD_FAB2_LIB.BASEBOARD_FAB2(SCH_1):P3V3_STBY
BE44 P3V3_STBY VCCPGPPE @BASEBOARD_FAB2_LIB.BASEBOARD_FAB2(SCH_1):P3V3_STBY
AU27 P3V3_STBY VCCPGPPF @BASEBOARD_FAB2_LIB.BASEBOARD_FAB2(SCH_1):P3V3_STBY
BA26 P3V3_STBY VCCPGPPG @BASEBOARD_FAB2_LIB.BASEBOARD_FAB2(SCH_1):P3V3_STBY
BA24 P3V3_STBY VCCPGPPH @BASEBOARD_FAB2_LIB.BASEBOARD_FAB2(SCH_1):P3V3_STBY
BB26 P3V3_STBY VCCPGPPJ @BASEBOARD_FAB2_LIB.BASEBOARD_FAB2(SCH_1):P3V3_STBY
AU24 P3V3_STBY VCCPGPPK @BASEBOARD_FAB2_LIB.BASEBOARD_FAB2(SCH_1):P3V3_STBY
AK24 P1V8_PCH_STBY VCCPGPP_1P8<6> @BASEBOARD_FAB2_LIB.BASEBOARD_FAB2(SCH_1):P1V8_PCH_STBY
AW27 P1V8_PCH_STBY VCCPGPP_1P8<5> @BASEBOARD_FAB2_LIB.BASEBOARD_FAB2(SCH_1):P1V8_PCH_STBY
AP29 P1V8_PCH_STBY VCCPGPP_1P8<4> @BASEBOARD_FAB2_LIB.BASEBOARD_FAB2(SCH_1):P1V8_PCH_STBY
AM29 P1V8_PCH_STBY VCCPGPP_1P8<3> @BASEBOARD_FAB2_LIB.BASEBOARD_FAB2(SCH_1):P1V8_PCH_STBY
AT29 P1V8_PCH_STBY VCCPGPP_1P8<2> @BASEBOARD_FAB2_LIB.BASEBOARD_FAB2(SCH_1):P1V8_PCH_STBY
AW29 P1V8_PCH_STBY VCCPGPP_1P8<1> @BASEBOARD_FAB2_LIB.BASEBOARD_FAB2(SCH_1):P1V8_PCH_STBY
AU29 P1V8_PCH_STBY VCCPGPP_1P8<0> @BASEBOARD_FAB2_LIB.BASEBOARD_FAB2(SCH_1):P1V8_PCH_STBY
AG27 P1V8_PCH_STBY VCCPHDA_1P8 @BASEBOARD_FAB2_LIB.BASEBOARD_FAB2(SCH_1):P1V8_PCH_STBY
 Y26 P1V05_PCH_STBY VCCPRIM_1P05<19> @BASEBOARD_FAB2_LIB.BASEBOARD_FAB2(SCH_1):P1V05_PCH_STBY
AA24 P1V05_PCH_STBY VCCPRIM_1P05<18> @BASEBOARD_FAB2_LIB.BASEBOARD_FAB2(SCH_1):P1V05_PCH_STBY
AK27 P1V05_PCH_STBY VCCPRIM_1P05<17> @BASEBOARD_FAB2_LIB.BASEBOARD_FAB2(SCH_1):P1V05_PCH_STBY
 R42 P1V05_PCH_STBY VCCPRIM_1P05<16> @BASEBOARD_FAB2_LIB.BASEBOARD_FAB2(SCH_1):P1V05_PCH_STBY
 R46 P1V05_PCH_STBY VCCPRIM_1P05<15> @BASEBOARD_FAB2_LIB.BASEBOARD_FAB2(SCH_1):P1V05_PCH_STBY
 T44 P1V05_PCH_STBY VCCPRIM_1P05<14> @BASEBOARD_FAB2_LIB.BASEBOARD_FAB2(SCH_1):P1V05_PCH_STBY
 U46 P1V05_PCH_STBY VCCPRIM_1P05<13> @BASEBOARD_FAB2_LIB.BASEBOARD_FAB2(SCH_1):P1V05_PCH_STBY
 V44 P1V05_PCH_STBY VCCPRIM_1P05<12> @BASEBOARD_FAB2_LIB.BASEBOARD_FAB2(SCH_1):P1V05_PCH_STBY
 Y45 P1V05_PCH_STBY VCCPRIM_1P05<11> @BASEBOARD_FAB2_LIB.BASEBOARD_FAB2(SCH_1):P1V05_PCH_STBY
 Y46 P1V05_PCH_STBY VCCPRIM_1P05<10> @BASEBOARD_FAB2_LIB.BASEBOARD_FAB2(SCH_1):P1V05_PCH_STBY
AA45 P1V05_PCH_STBY VCCPRIM_1P05<9> @BASEBOARD_FAB2_LIB.BASEBOARD_FAB2(SCH_1):P1V05_PCH_STBY
AA46 P1V05_PCH_STBY VCCPRIM_1P05<8> @BASEBOARD_FAB2_LIB.BASEBOARD_FAB2(SCH_1):P1V05_PCH_STBY
AC26 P1V05_PCH_STBY VCCPRIM_1P05<7> @BASEBOARD_FAB2_LIB.BASEBOARD_FAB2(SCH_1):P1V05_PCH_STBY
AJ29 P1V05_PCH_STBY VCCPRIM_1P05<6> @BASEBOARD_FAB2_LIB.BASEBOARD_FAB2(SCH_1):P1V05_PCH_STBY
AM27 P1V05_PCH_STBY VCCPRIM_1P05<5> @BASEBOARD_FAB2_LIB.BASEBOARD_FAB2(SCH_1):P1V05_PCH_STBY
AT39 P1V05_PCH_STBY VCCPRIM_1P05<4> @BASEBOARD_FAB2_LIB.BASEBOARD_FAB2(SCH_1):P1V05_PCH_STBY
AU37 P1V05_PCH_STBY VCCPRIM_1P05<3> @BASEBOARD_FAB2_LIB.BASEBOARD_FAB2(SCH_1):P1V05_PCH_STBY
AU39 P1V05_PCH_STBY VCCPRIM_1P05<2> @BASEBOARD_FAB2_LIB.BASEBOARD_FAB2(SCH_1):P1V05_PCH_STBY
BE48 P1V05_PCH_STBY VCCPRIM_1P05<1> @BASEBOARD_FAB2_LIB.BASEBOARD_FAB2(SCH_1):P1V05_PCH_STBY
BF46 P1V05_PCH_STBY VCCPRIM_1P05<0> @BASEBOARD_FAB2_LIB.BASEBOARD_FAB2(SCH_1):P1V05_PCH_STBY
AJ27 P3V3_RTC_STBY VCCPRTC @BASEBOARD_FAB2_LIB.BASEBOARD_FAB2(SCH_1):P3V3_RTC_STBY
AG29 P3V3_STBY VCCPRTCPRIM_3P3 @BASEBOARD_FAB2_LIB.BASEBOARD_FAB2(SCH_1):P3V3_STBY
AR24 P3V3_STBY VCCPSPI @BASEBOARD_FAB2_LIB.BASEBOARD_FAB2(SCH_1):P3V3_STBY
AK29 P1V8_PCH_STBY VCCPSPI_1P8 @BASEBOARD_FAB2_LIB.BASEBOARD_FAB2(SCH_1):P1V8_PCH_STBY
BA48 P3V3_STBY VCCPUSBDSW_3P3 @BASEBOARD_FAB2_LIB.BASEBOARD_FAB2(SCH_1):P3V3_STBY
AE26 P1V8_PCH_STBY VCCP_1P8<1> @BASEBOARD_FAB2_LIB.BASEBOARD_FAB2(SCH_1):P1V8_PCH_STBY
BD46 P1V8_PCH_STBY VCCP_1P8<0> @BASEBOARD_FAB2_LIB.BASEBOARD_FAB2(SCH_1):P1V8_PCH_STBY
AN24 P3V3_STBY VCCP_3P3<5> @BASEBOARD_FAB2_LIB.BASEBOARD_FAB2(SCH_1):P3V3_STBY
AD24 P3V3_STBY VCCP_3P3<2> @BASEBOARD_FAB2_LIB.BASEBOARD_FAB2(SCH_1):P3V3_STBY
BA45 P3V3_STBY VCCP_3P3<1> @BASEBOARD_FAB2_LIB.BASEBOARD_FAB2(SCH_1):P3V3_STBY
BA46 P3V3_STBY VCCP_3P3<0> @BASEBOARD_FAB2_LIB.BASEBOARD_FAB2(SCH_1):P3V3_STBY
AT48 P1V05_PCH_STBY VCCP_HSIOPLLUNF_1P05 @BASEBOARD_FAB2_LIB.BASEBOARD_FAB2(SCH_1):P1V05_PCH_STBY
AP48 P1V05_PCH_STBY_WM26_PLL VCCP_HSIOPLL_1P05<3> @BASEBOARD_FAB2_LIB.BASEBOARD_FAB2(SCH_1):P1V05_PCH_STBY_WM26_PLL
AU48 P1V05_PCH_STBY_WM26_PLL VCCP_HSIOPLL_1P05<2> @BASEBOARD_FAB2_LIB.BASEBOARD_FAB2(SCH_1):P1V05_PCH_STBY_WM26_PLL
AW48 P1V05_PCH_STBY_WM26_PLL VCCP_HSIOPLL_1P05<0> @BASEBOARD_FAB2_LIB.BASEBOARD_FAB2(SCH_1):P1V05_PCH_STBY_WM26_PLL
AM48 P1V05_PCH_STBY VCCP_UPPLLUNF_1P05 @BASEBOARD_FAB2_LIB.BASEBOARD_FAB2(SCH_1):P1V05_PCH_STBY
AK50 P1V05_PCH_STBY_WM20_PLL VCCP_UPPLL_1P05<2> @BASEBOARD_FAB2_LIB.BASEBOARD_FAB2(SCH_1):P1V05_PCH_STBY_WM20_PLL
AN50 P1V05_PCH_STBY_WM20_PLL VCCP_UPPLL_1P05<0> @BASEBOARD_FAB2_LIB.BASEBOARD_FAB2(SCH_1):P1V05_PCH_STBY_WM20_PLL
AG22 A_PVCCRTC_EXT_CAP VCCRTCEXT @BASEBOARD_FAB2_LIB.BASEBOARD_FAB2(SCH_1):A_PVCCRTC_EXT_CAP


DRAWING: @BASEBOARD_FAB2_LIB.BASEBOARD_FAB2(SCH_1):PAGE123 

LBG_CORE_QAT_EXT_D_BGA1-IC,H91A  I13  U7C1
BP69    GND VSS<494> @BASEBOARD_FAB2_LIB.BASEBOARD_FAB2(SCH_1):GND
BT69    GND VSS<493> @BASEBOARD_FAB2_LIB.BASEBOARD_FAB2(SCH_1):GND
BU70    GND VSS<492> @BASEBOARD_FAB2_LIB.BASEBOARD_FAB2(SCH_1):GND
BR70    GND VSS<491> @BASEBOARD_FAB2_LIB.BASEBOARD_FAB2(SCH_1):GND
 F70    GND VSS<490> @BASEBOARD_FAB2_LIB.BASEBOARD_FAB2(SCH_1):GND
 E70    GND VSS<489> @BASEBOARD_FAB2_LIB.BASEBOARD_FAB2(SCH_1):GND
 BU3    GND VSS<488> @BASEBOARD_FAB2_LIB.BASEBOARD_FAB2(SCH_1):GND
 BR3    GND VSS<487> @BASEBOARD_FAB2_LIB.BASEBOARD_FAB2(SCH_1):GND
  F3    GND VSS<486> @BASEBOARD_FAB2_LIB.BASEBOARD_FAB2(SCH_1):GND
  E3    GND VSS<485> @BASEBOARD_FAB2_LIB.BASEBOARD_FAB2(SCH_1):GND
  A5    GND VSS<484> @BASEBOARD_FAB2_LIB.BASEBOARD_FAB2(SCH_1):GND
  A7    GND VSS<483> @BASEBOARD_FAB2_LIB.BASEBOARD_FAB2(SCH_1):GND
  A9    GND VSS<482> @BASEBOARD_FAB2_LIB.BASEBOARD_FAB2(SCH_1):GND
 A65    GND VSS<481> @BASEBOARD_FAB2_LIB.BASEBOARD_FAB2(SCH_1):GND
 A66    GND VSS<480> @BASEBOARD_FAB2_LIB.BASEBOARD_FAB2(SCH_1):GND
 A68    GND VSS<479> @BASEBOARD_FAB2_LIB.BASEBOARD_FAB2(SCH_1):GND
  J1    GND VSS<478> @BASEBOARD_FAB2_LIB.BASEBOARD_FAB2(SCH_1):GND
 J72    GND VSS<477> @BASEBOARD_FAB2_LIB.BASEBOARD_FAB2(SCH_1):GND
 BN1    GND VSS<476> @BASEBOARD_FAB2_LIB.BASEBOARD_FAB2(SCH_1):GND
BN72    GND VSS<475> @BASEBOARD_FAB2_LIB.BASEBOARD_FAB2(SCH_1):GND
CA68    GND VSS<474> @BASEBOARD_FAB2_LIB.BASEBOARD_FAB2(SCH_1):GND
CA66    GND VSS<473> @BASEBOARD_FAB2_LIB.BASEBOARD_FAB2(SCH_1):GND
CA65    GND VSS<472> @BASEBOARD_FAB2_LIB.BASEBOARD_FAB2(SCH_1):GND
 CA9    GND VSS<471> @BASEBOARD_FAB2_LIB.BASEBOARD_FAB2(SCH_1):GND
 CA7    GND VSS<470> @BASEBOARD_FAB2_LIB.BASEBOARD_FAB2(SCH_1):GND
 CA5    GND VSS<469> @BASEBOARD_FAB2_LIB.BASEBOARD_FAB2(SCH_1):GND
 A70    GND VSS<468> @BASEBOARD_FAB2_LIB.BASEBOARD_FAB2(SCH_1):GND
 CA3    GND VSS<467> @BASEBOARD_FAB2_LIB.BASEBOARD_FAB2(SCH_1):GND
 BW1    GND VSS<466> @BASEBOARD_FAB2_LIB.BASEBOARD_FAB2(SCH_1):GND
 BU1    GND VSS<465> @BASEBOARD_FAB2_LIB.BASEBOARD_FAB2(SCH_1):GND
 BR1    GND VSS<464> @BASEBOARD_FAB2_LIB.BASEBOARD_FAB2(SCH_1):GND
  C3    GND VSS<463> @BASEBOARD_FAB2_LIB.BASEBOARD_FAB2(SCH_1):GND
 C72    GND VSS<462> @BASEBOARD_FAB2_LIB.BASEBOARD_FAB2(SCH_1):GND
  E1    GND VSS<461> @BASEBOARD_FAB2_LIB.BASEBOARD_FAB2(SCH_1):GND
 E72    GND VSS<460> @BASEBOARD_FAB2_LIB.BASEBOARD_FAB2(SCH_1):GND
  G1    GND VSS<459> @BASEBOARD_FAB2_LIB.BASEBOARD_FAB2(SCH_1):GND
 G72    GND VSS<458> @BASEBOARD_FAB2_LIB.BASEBOARD_FAB2(SCH_1):GND
BR72    GND VSS<457> @BASEBOARD_FAB2_LIB.BASEBOARD_FAB2(SCH_1):GND
BU72    GND VSS<456> @BASEBOARD_FAB2_LIB.BASEBOARD_FAB2(SCH_1):GND
BW70    GND VSS<455> @BASEBOARD_FAB2_LIB.BASEBOARD_FAB2(SCH_1):GND
BW72    GND VSS<454> @BASEBOARD_FAB2_LIB.BASEBOARD_FAB2(SCH_1):GND
CA70    GND VSS<453> @BASEBOARD_FAB2_LIB.BASEBOARD_FAB2(SCH_1):GND
BB48    GND VSS<452> @BASEBOARD_FAB2_LIB.BASEBOARD_FAB2(SCH_1):GND
AT37    GND VSS<451> @BASEBOARD_FAB2_LIB.BASEBOARD_FAB2(SCH_1):GND
 Y72    GND VSS<450> @BASEBOARD_FAB2_LIB.BASEBOARD_FAB2(SCH_1):GND
 Y70    GND VSS<449> @BASEBOARD_FAB2_LIB.BASEBOARD_FAB2(SCH_1):GND
 A18    GND VSS<448> @BASEBOARD_FAB2_LIB.BASEBOARD_FAB2(SCH_1):GND
 A22    GND VSS<447> @BASEBOARD_FAB2_LIB.BASEBOARD_FAB2(SCH_1):GND
 A30    GND VSS<446> @BASEBOARD_FAB2_LIB.BASEBOARD_FAB2(SCH_1):GND
 A34    GND VSS<445> @BASEBOARD_FAB2_LIB.BASEBOARD_FAB2(SCH_1):GND
 A37    GND VSS<444> @BASEBOARD_FAB2_LIB.BASEBOARD_FAB2(SCH_1):GND
 A41    GND VSS<443> @BASEBOARD_FAB2_LIB.BASEBOARD_FAB2(SCH_1):GND
 B12    GND VSS<442> @BASEBOARD_FAB2_LIB.BASEBOARD_FAB2(SCH_1):GND
 B19    GND VSS<441> @BASEBOARD_FAB2_LIB.BASEBOARD_FAB2(SCH_1):GND
 B25    GND VSS<440> @BASEBOARD_FAB2_LIB.BASEBOARD_FAB2(SCH_1):GND
 B27    GND VSS<439> @BASEBOARD_FAB2_LIB.BASEBOARD_FAB2(SCH_1):GND
 B47    GND VSS<438> @BASEBOARD_FAB2_LIB.BASEBOARD_FAB2(SCH_1):GND
 C22    GND VSS<437> @BASEBOARD_FAB2_LIB.BASEBOARD_FAB2(SCH_1):GND
 C30    GND VSS<436> @BASEBOARD_FAB2_LIB.BASEBOARD_FAB2(SCH_1):GND
 C34    GND VSS<435> @BASEBOARD_FAB2_LIB.BASEBOARD_FAB2(SCH_1):GND
 C37    GND VSS<434> @BASEBOARD_FAB2_LIB.BASEBOARD_FAB2(SCH_1):GND
 C41    GND VSS<433> @BASEBOARD_FAB2_LIB.BASEBOARD_FAB2(SCH_1):GND
 C65    GND VSS<432> @BASEBOARD_FAB2_LIB.BASEBOARD_FAB2(SCH_1):GND
 D12    GND VSS<431> @BASEBOARD_FAB2_LIB.BASEBOARD_FAB2(SCH_1):GND
 D16    GND VSS<430> @BASEBOARD_FAB2_LIB.BASEBOARD_FAB2(SCH_1):GND
 D19    GND VSS<429> @BASEBOARD_FAB2_LIB.BASEBOARD_FAB2(SCH_1):GND
 D25    GND VSS<428> @BASEBOARD_FAB2_LIB.BASEBOARD_FAB2(SCH_1):GND
 D27    GND VSS<427> @BASEBOARD_FAB2_LIB.BASEBOARD_FAB2(SCH_1):GND
 E59    GND VSS<426> @BASEBOARD_FAB2_LIB.BASEBOARD_FAB2(SCH_1):GND
 E65    GND VSS<425> @BASEBOARD_FAB2_LIB.BASEBOARD_FAB2(SCH_1):GND
 D47    GND VSS<424> @BASEBOARD_FAB2_LIB.BASEBOARD_FAB2(SCH_1):GND
 E11    GND VSS<423> @BASEBOARD_FAB2_LIB.BASEBOARD_FAB2(SCH_1):GND
 E13    GND VSS<422> @BASEBOARD_FAB2_LIB.BASEBOARD_FAB2(SCH_1):GND
 E15    GND VSS<421> @BASEBOARD_FAB2_LIB.BASEBOARD_FAB2(SCH_1):GND
 E20    GND VSS<420> @BASEBOARD_FAB2_LIB.BASEBOARD_FAB2(SCH_1):GND
 E22    GND VSS<419> @BASEBOARD_FAB2_LIB.BASEBOARD_FAB2(SCH_1):GND
 E24    GND VSS<418> @BASEBOARD_FAB2_LIB.BASEBOARD_FAB2(SCH_1):GND
 E26    GND VSS<417> @BASEBOARD_FAB2_LIB.BASEBOARD_FAB2(SCH_1):GND
 E28    GND VSS<416> @BASEBOARD_FAB2_LIB.BASEBOARD_FAB2(SCH_1):GND
 E30    GND VSS<415> @BASEBOARD_FAB2_LIB.BASEBOARD_FAB2(SCH_1):GND
 E32    GND VSS<414> @BASEBOARD_FAB2_LIB.BASEBOARD_FAB2(SCH_1):GND
 E34    GND VSS<413> @BASEBOARD_FAB2_LIB.BASEBOARD_FAB2(SCH_1):GND
 E37    GND VSS<412> @BASEBOARD_FAB2_LIB.BASEBOARD_FAB2(SCH_1):GND
 E39    GND VSS<411> @BASEBOARD_FAB2_LIB.BASEBOARD_FAB2(SCH_1):GND
 E41    GND VSS<410> @BASEBOARD_FAB2_LIB.BASEBOARD_FAB2(SCH_1):GND
 E43    GND VSS<409> @BASEBOARD_FAB2_LIB.BASEBOARD_FAB2(SCH_1):GND
 E45    GND VSS<408> @BASEBOARD_FAB2_LIB.BASEBOARD_FAB2(SCH_1):GND
 E48    GND VSS<407> @BASEBOARD_FAB2_LIB.BASEBOARD_FAB2(SCH_1):GND
 E50    GND VSS<406> @BASEBOARD_FAB2_LIB.BASEBOARD_FAB2(SCH_1):GND
 E52    GND VSS<405> @BASEBOARD_FAB2_LIB.BASEBOARD_FAB2(SCH_1):GND
 E54    GND VSS<404> @BASEBOARD_FAB2_LIB.BASEBOARD_FAB2(SCH_1):GND
 E57    GND VSS<403> @BASEBOARD_FAB2_LIB.BASEBOARD_FAB2(SCH_1):GND
  E6    GND VSS<402> @BASEBOARD_FAB2_LIB.BASEBOARD_FAB2(SCH_1):GND
 E61    GND VSS<401> @BASEBOARD_FAB2_LIB.BASEBOARD_FAB2(SCH_1):GND
 E63    GND VSS<400> @BASEBOARD_FAB2_LIB.BASEBOARD_FAB2(SCH_1):GND
 G59    GND VSS<399> @BASEBOARD_FAB2_LIB.BASEBOARD_FAB2(SCH_1):GND
  E9    GND VSS<398> @BASEBOARD_FAB2_LIB.BASEBOARD_FAB2(SCH_1):GND
 G22    GND VSS<397> @BASEBOARD_FAB2_LIB.BASEBOARD_FAB2(SCH_1):GND
 G29    GND VSS<396> @BASEBOARD_FAB2_LIB.BASEBOARD_FAB2(SCH_1):GND
 G37    GND VSS<395> @BASEBOARD_FAB2_LIB.BASEBOARD_FAB2(SCH_1):GND
 G48    GND VSS<394> @BASEBOARD_FAB2_LIB.BASEBOARD_FAB2(SCH_1):GND
  G6    GND VSS<393> @BASEBOARD_FAB2_LIB.BASEBOARD_FAB2(SCH_1):GND
 G63    GND VSS<392> @BASEBOARD_FAB2_LIB.BASEBOARD_FAB2(SCH_1):GND
 G66    GND VSS<391> @BASEBOARD_FAB2_LIB.BASEBOARD_FAB2(SCH_1):GND
 H58    GND VSS<390> @BASEBOARD_FAB2_LIB.BASEBOARD_FAB2(SCH_1):GND
 J29    GND VSS<389> @BASEBOARD_FAB2_LIB.BASEBOARD_FAB2(SCH_1):GND
  J5    GND VSS<388> @BASEBOARD_FAB2_LIB.BASEBOARD_FAB2(SCH_1):GND
  J7    GND VSS<387> @BASEBOARD_FAB2_LIB.BASEBOARD_FAB2(SCH_1):GND
 H65    GND VSS<386> @BASEBOARD_FAB2_LIB.BASEBOARD_FAB2(SCH_1):GND
 J11    GND VSS<385> @BASEBOARD_FAB2_LIB.BASEBOARD_FAB2(SCH_1):GND
 J15    GND VSS<384> @BASEBOARD_FAB2_LIB.BASEBOARD_FAB2(SCH_1):GND
 J22    GND VSS<383> @BASEBOARD_FAB2_LIB.BASEBOARD_FAB2(SCH_1):GND
 J37    GND VSS<382> @BASEBOARD_FAB2_LIB.BASEBOARD_FAB2(SCH_1):GND
 J44    GND VSS<381> @BASEBOARD_FAB2_LIB.BASEBOARD_FAB2(SCH_1):GND
 J59    GND VSS<380> @BASEBOARD_FAB2_LIB.BASEBOARD_FAB2(SCH_1):GND
 J68    GND VSS<379> @BASEBOARD_FAB2_LIB.BASEBOARD_FAB2(SCH_1):GND
 J70    GND VSS<378> @BASEBOARD_FAB2_LIB.BASEBOARD_FAB2(SCH_1):GND
 K54    GND VSS<377> @BASEBOARD_FAB2_LIB.BASEBOARD_FAB2(SCH_1):GND
 K69    GND VSS<376> @BASEBOARD_FAB2_LIB.BASEBOARD_FAB2(SCH_1):GND
 K71    GND VSS<375> @BASEBOARD_FAB2_LIB.BASEBOARD_FAB2(SCH_1):GND
  L5    GND VSS<374> @BASEBOARD_FAB2_LIB.BASEBOARD_FAB2(SCH_1):GND
 L68    GND VSS<373> @BASEBOARD_FAB2_LIB.BASEBOARD_FAB2(SCH_1):GND
  M2    GND VSS<372> @BASEBOARD_FAB2_LIB.BASEBOARD_FAB2(SCH_1):GND
 M22    GND VSS<371> @BASEBOARD_FAB2_LIB.BASEBOARD_FAB2(SCH_1):GND
 M26    GND VSS<370> @BASEBOARD_FAB2_LIB.BASEBOARD_FAB2(SCH_1):GND
 M29    GND VSS<369> @BASEBOARD_FAB2_LIB.BASEBOARD_FAB2(SCH_1):GND
 M33    GND VSS<368> @BASEBOARD_FAB2_LIB.BASEBOARD_FAB2(SCH_1):GND
 M37    GND VSS<367> @BASEBOARD_FAB2_LIB.BASEBOARD_FAB2(SCH_1):GND
  M4    GND VSS<366> @BASEBOARD_FAB2_LIB.BASEBOARD_FAB2(SCH_1):GND
 M40    GND VSS<365> @BASEBOARD_FAB2_LIB.BASEBOARD_FAB2(SCH_1):GND
 N42    GND VSS<364> @BASEBOARD_FAB2_LIB.BASEBOARD_FAB2(SCH_1):GND
 N50    GND VSS<363> @BASEBOARD_FAB2_LIB.BASEBOARD_FAB2(SCH_1):GND
 M44    GND VSS<362> @BASEBOARD_FAB2_LIB.BASEBOARD_FAB2(SCH_1):GND
 M48    GND VSS<361> @BASEBOARD_FAB2_LIB.BASEBOARD_FAB2(SCH_1):GND
 N13    GND VSS<360> @BASEBOARD_FAB2_LIB.BASEBOARD_FAB2(SCH_1):GND
 N17    GND VSS<359> @BASEBOARD_FAB2_LIB.BASEBOARD_FAB2(SCH_1):GND
 N20    GND VSS<358> @BASEBOARD_FAB2_LIB.BASEBOARD_FAB2(SCH_1):GND
 N24    GND VSS<357> @BASEBOARD_FAB2_LIB.BASEBOARD_FAB2(SCH_1):GND
 N27    GND VSS<356> @BASEBOARD_FAB2_LIB.BASEBOARD_FAB2(SCH_1):GND
 N31    GND VSS<355> @BASEBOARD_FAB2_LIB.BASEBOARD_FAB2(SCH_1):GND

LBG_CORE_QAT_EXT_D_BGA1-IC,H91A  I21  U7C1
AE27 P1V05_PCH_STBY VCCMPHY_1P05<13> @BASEBOARD_FAB2_LIB.BASEBOARD_FAB2(SCH_1):P1V05_PCH_STBY
AK32 PVNN_PCH_STBY VCCPRIM_AVID<62> @BASEBOARD_FAB2_LIB.BASEBOARD_FAB2(SCH_1):PVNN_PCH_STBY
 U31 PVNN_PCH_STBY VCCPRIM_AVID<61> @BASEBOARD_FAB2_LIB.BASEBOARD_FAB2(SCH_1):PVNN_PCH_STBY
 U35 PVNN_PCH_STBY VCCPRIM_AVID<60> @BASEBOARD_FAB2_LIB.BASEBOARD_FAB2(SCH_1):PVNN_PCH_STBY
 U38 PVNN_PCH_STBY VCCPRIM_AVID<59> @BASEBOARD_FAB2_LIB.BASEBOARD_FAB2(SCH_1):PVNN_PCH_STBY
 V29 PVNN_PCH_STBY VCCPRIM_AVID<58> @BASEBOARD_FAB2_LIB.BASEBOARD_FAB2(SCH_1):PVNN_PCH_STBY
 V33 PVNN_PCH_STBY VCCPRIM_AVID<57> @BASEBOARD_FAB2_LIB.BASEBOARD_FAB2(SCH_1):PVNN_PCH_STBY
 V40 PVNN_PCH_STBY VCCPRIM_AVID<56> @BASEBOARD_FAB2_LIB.BASEBOARD_FAB2(SCH_1):PVNN_PCH_STBY
 Y29 PVNN_PCH_STBY VCCPRIM_AVID<55> @BASEBOARD_FAB2_LIB.BASEBOARD_FAB2(SCH_1):PVNN_PCH_STBY
 Y30 PVNN_PCH_STBY VCCPRIM_AVID<54> @BASEBOARD_FAB2_LIB.BASEBOARD_FAB2(SCH_1):PVNN_PCH_STBY
 Y32 PVNN_PCH_STBY VCCPRIM_AVID<53> @BASEBOARD_FAB2_LIB.BASEBOARD_FAB2(SCH_1):PVNN_PCH_STBY
 Y34 PVNN_PCH_STBY VCCPRIM_AVID<52> @BASEBOARD_FAB2_LIB.BASEBOARD_FAB2(SCH_1):PVNN_PCH_STBY
 Y36 PVNN_PCH_STBY VCCPRIM_AVID<51> @BASEBOARD_FAB2_LIB.BASEBOARD_FAB2(SCH_1):PVNN_PCH_STBY
 Y37 PVNN_PCH_STBY VCCPRIM_AVID<50> @BASEBOARD_FAB2_LIB.BASEBOARD_FAB2(SCH_1):PVNN_PCH_STBY
 Y39 PVNN_PCH_STBY VCCPRIM_AVID<49> @BASEBOARD_FAB2_LIB.BASEBOARD_FAB2(SCH_1):PVNN_PCH_STBY
 Y41 PVNN_PCH_STBY VCCPRIM_AVID<48> @BASEBOARD_FAB2_LIB.BASEBOARD_FAB2(SCH_1):PVNN_PCH_STBY
AA29 PVNN_PCH_STBY VCCPRIM_AVID<47> @BASEBOARD_FAB2_LIB.BASEBOARD_FAB2(SCH_1):PVNN_PCH_STBY
AA30 PVNN_PCH_STBY VCCPRIM_AVID<46> @BASEBOARD_FAB2_LIB.BASEBOARD_FAB2(SCH_1):PVNN_PCH_STBY
AA32 PVNN_PCH_STBY VCCPRIM_AVID<45> @BASEBOARD_FAB2_LIB.BASEBOARD_FAB2(SCH_1):PVNN_PCH_STBY
AA34 PVNN_PCH_STBY VCCPRIM_AVID<44> @BASEBOARD_FAB2_LIB.BASEBOARD_FAB2(SCH_1):PVNN_PCH_STBY
AA36 PVNN_PCH_STBY VCCPRIM_AVID<43> @BASEBOARD_FAB2_LIB.BASEBOARD_FAB2(SCH_1):PVNN_PCH_STBY
AA37 PVNN_PCH_STBY VCCPRIM_AVID<42> @BASEBOARD_FAB2_LIB.BASEBOARD_FAB2(SCH_1):PVNN_PCH_STBY
AA39 PVNN_PCH_STBY VCCPRIM_AVID<41> @BASEBOARD_FAB2_LIB.BASEBOARD_FAB2(SCH_1):PVNN_PCH_STBY
AA41 PVNN_PCH_STBY VCCPRIM_AVID<40> @BASEBOARD_FAB2_LIB.BASEBOARD_FAB2(SCH_1):PVNN_PCH_STBY
AC29 PVNN_PCH_STBY VCCPRIM_AVID<39> @BASEBOARD_FAB2_LIB.BASEBOARD_FAB2(SCH_1):PVNN_PCH_STBY
AC30 PVNN_PCH_STBY VCCPRIM_AVID<38> @BASEBOARD_FAB2_LIB.BASEBOARD_FAB2(SCH_1):PVNN_PCH_STBY
AC32 PVNN_PCH_STBY VCCPRIM_AVID<37> @BASEBOARD_FAB2_LIB.BASEBOARD_FAB2(SCH_1):PVNN_PCH_STBY
AC34 PVNN_PCH_STBY VCCPRIM_AVID<36> @BASEBOARD_FAB2_LIB.BASEBOARD_FAB2(SCH_1):PVNN_PCH_STBY
AC36 PVNN_PCH_STBY VCCPRIM_AVID<35> @BASEBOARD_FAB2_LIB.BASEBOARD_FAB2(SCH_1):PVNN_PCH_STBY
AC37 PVNN_PCH_STBY VCCPRIM_AVID<34> @BASEBOARD_FAB2_LIB.BASEBOARD_FAB2(SCH_1):PVNN_PCH_STBY
AC39 PVNN_PCH_STBY VCCPRIM_AVID<33> @BASEBOARD_FAB2_LIB.BASEBOARD_FAB2(SCH_1):PVNN_PCH_STBY
AC41 PVNN_PCH_STBY VCCPRIM_AVID<32> @BASEBOARD_FAB2_LIB.BASEBOARD_FAB2(SCH_1):PVNN_PCH_STBY
 U27 PVNN_PCH_STBY VCCPRIM_AVID<31> @BASEBOARD_FAB2_LIB.BASEBOARD_FAB2(SCH_1):PVNN_PCH_STBY
AE30 PVNN_PCH_STBY VCCPRIM_AVID<30> @BASEBOARD_FAB2_LIB.BASEBOARD_FAB2(SCH_1):PVNN_PCH_STBY
AE32 PVNN_PCH_STBY VCCPRIM_AVID<29> @BASEBOARD_FAB2_LIB.BASEBOARD_FAB2(SCH_1):PVNN_PCH_STBY
AE34 PVNN_PCH_STBY VCCPRIM_AVID<28> @BASEBOARD_FAB2_LIB.BASEBOARD_FAB2(SCH_1):PVNN_PCH_STBY
AE36 PVNN_PCH_STBY VCCPRIM_AVID<27> @BASEBOARD_FAB2_LIB.BASEBOARD_FAB2(SCH_1):PVNN_PCH_STBY
AE37 PVNN_PCH_STBY VCCPRIM_AVID<26> @BASEBOARD_FAB2_LIB.BASEBOARD_FAB2(SCH_1):PVNN_PCH_STBY
AE39 PVNN_PCH_STBY VCCPRIM_AVID<25> @BASEBOARD_FAB2_LIB.BASEBOARD_FAB2(SCH_1):PVNN_PCH_STBY
AE41 PVNN_PCH_STBY VCCPRIM_AVID<24> @BASEBOARD_FAB2_LIB.BASEBOARD_FAB2(SCH_1):PVNN_PCH_STBY
AG32 PVNN_PCH_STBY VCCPRIM_AVID<23> @BASEBOARD_FAB2_LIB.BASEBOARD_FAB2(SCH_1):PVNN_PCH_STBY
AG34 PVNN_PCH_STBY VCCPRIM_AVID<22> @BASEBOARD_FAB2_LIB.BASEBOARD_FAB2(SCH_1):PVNN_PCH_STBY
AG36 PVNN_PCH_STBY VCCPRIM_AVID<21> @BASEBOARD_FAB2_LIB.BASEBOARD_FAB2(SCH_1):PVNN_PCH_STBY
AG37 PVNN_PCH_STBY VCCPRIM_AVID<20> @BASEBOARD_FAB2_LIB.BASEBOARD_FAB2(SCH_1):PVNN_PCH_STBY
AG39 PVNN_PCH_STBY VCCPRIM_AVID<19> @BASEBOARD_FAB2_LIB.BASEBOARD_FAB2(SCH_1):PVNN_PCH_STBY
AK34 PVNN_PCH_STBY VCCPRIM_AVID<18> @BASEBOARD_FAB2_LIB.BASEBOARD_FAB2(SCH_1):PVNN_PCH_STBY
AK37 PVNN_PCH_STBY VCCPRIM_AVID<17> @BASEBOARD_FAB2_LIB.BASEBOARD_FAB2(SCH_1):PVNN_PCH_STBY
AK39 PVNN_PCH_STBY VCCPRIM_AVID<16> @BASEBOARD_FAB2_LIB.BASEBOARD_FAB2(SCH_1):PVNN_PCH_STBY
AM32 PVNN_PCH_STBY VCCPRIM_AVID<15> @BASEBOARD_FAB2_LIB.BASEBOARD_FAB2(SCH_1):PVNN_PCH_STBY
AM34 PVNN_PCH_STBY VCCPRIM_AVID<14> @BASEBOARD_FAB2_LIB.BASEBOARD_FAB2(SCH_1):PVNN_PCH_STBY
AM36 PVNN_PCH_STBY VCCPRIM_AVID<13> @BASEBOARD_FAB2_LIB.BASEBOARD_FAB2(SCH_1):PVNN_PCH_STBY
AM37 PVNN_PCH_STBY VCCPRIM_AVID<12> @BASEBOARD_FAB2_LIB.BASEBOARD_FAB2(SCH_1):PVNN_PCH_STBY
AM39 PVNN_PCH_STBY VCCPRIM_AVID<11> @BASEBOARD_FAB2_LIB.BASEBOARD_FAB2(SCH_1):PVNN_PCH_STBY
AP32 PVNN_PCH_STBY VCCPRIM_AVID<10> @BASEBOARD_FAB2_LIB.BASEBOARD_FAB2(SCH_1):PVNN_PCH_STBY
AP34 PVNN_PCH_STBY VCCPRIM_AVID<9> @BASEBOARD_FAB2_LIB.BASEBOARD_FAB2(SCH_1):PVNN_PCH_STBY
AP36 PVNN_PCH_STBY VCCPRIM_AVID<8> @BASEBOARD_FAB2_LIB.BASEBOARD_FAB2(SCH_1):PVNN_PCH_STBY
AP37 PVNN_PCH_STBY VCCPRIM_AVID<7> @BASEBOARD_FAB2_LIB.BASEBOARD_FAB2(SCH_1):PVNN_PCH_STBY
AP39 PVNN_PCH_STBY VCCPRIM_AVID<6> @BASEBOARD_FAB2_LIB.BASEBOARD_FAB2(SCH_1):PVNN_PCH_STBY
AT32 PVNN_PCH_STBY VCCPRIM_AVID<5> @BASEBOARD_FAB2_LIB.BASEBOARD_FAB2(SCH_1):PVNN_PCH_STBY
AT34 PVNN_PCH_STBY VCCPRIM_AVID<4> @BASEBOARD_FAB2_LIB.BASEBOARD_FAB2(SCH_1):PVNN_PCH_STBY
AT36 PVNN_PCH_STBY VCCPRIM_AVID<3> @BASEBOARD_FAB2_LIB.BASEBOARD_FAB2(SCH_1):PVNN_PCH_STBY
AU32 PVNN_PCH_STBY VCCPRIM_AVID<2> @BASEBOARD_FAB2_LIB.BASEBOARD_FAB2(SCH_1):PVNN_PCH_STBY
AU34 PVNN_PCH_STBY VCCPRIM_AVID<1> @BASEBOARD_FAB2_LIB.BASEBOARD_FAB2(SCH_1):PVNN_PCH_STBY
AU36 PVNN_PCH_STBY VCCPRIM_AVID<0> @BASEBOARD_FAB2_LIB.BASEBOARD_FAB2(SCH_1):PVNN_PCH_STBY
 V37 VSENSE_PVNN_PCH_STBY_QAT VCCPRIM_AVID_QAT_SENSE @BASEBOARD_FAB2_LIB.BASEBOARD_FAB2(SCH_1):VSENSE_PVNN_PCH_STBY_QAT
AK36 VSENSE_PVNN_PCH_STBY_FPK VCCPRIM_AVID_SENSE @BASEBOARD_FAB2_LIB.BASEBOARD_FAB2(SCH_1):VSENSE_PVNN_PCH_STBY_FPK


DRAWING: @BASEBOARD_FAB2_LIB.BASEBOARD_FAB2(SCH_1):PAGE124 

LBG_CORE_QAT_EXT_D_BGA1-IC,H91A  I15  U7C1
BK24    GND VSS<74> @BASEBOARD_FAB2_LIB.BASEBOARD_FAB2(SCH_1):GND
BK27    GND VSS<73> @BASEBOARD_FAB2_LIB.BASEBOARD_FAB2(SCH_1):GND
BK31    GND VSS<72> @BASEBOARD_FAB2_LIB.BASEBOARD_FAB2(SCH_1):GND
BK35    GND VSS<71> @BASEBOARD_FAB2_LIB.BASEBOARD_FAB2(SCH_1):GND
BK38    GND VSS<70> @BASEBOARD_FAB2_LIB.BASEBOARD_FAB2(SCH_1):GND
BK42    GND VSS<69> @BASEBOARD_FAB2_LIB.BASEBOARD_FAB2(SCH_1):GND
BK50    GND VSS<68> @BASEBOARD_FAB2_LIB.BASEBOARD_FAB2(SCH_1):GND
BL22    GND VSS<67> @BASEBOARD_FAB2_LIB.BASEBOARD_FAB2(SCH_1):GND
BL40    GND VSS<66> @BASEBOARD_FAB2_LIB.BASEBOARD_FAB2(SCH_1):GND
BL68    GND VSS<65> @BASEBOARD_FAB2_LIB.BASEBOARD_FAB2(SCH_1):GND
BL37    GND VSS<64> @BASEBOARD_FAB2_LIB.BASEBOARD_FAB2(SCH_1):GND
 BL5    GND VSS<63> @BASEBOARD_FAB2_LIB.BASEBOARD_FAB2(SCH_1):GND
BL63    GND VSS<62> @BASEBOARD_FAB2_LIB.BASEBOARD_FAB2(SCH_1):GND
BL70    GND VSS<61> @BASEBOARD_FAB2_LIB.BASEBOARD_FAB2(SCH_1):GND
BL72    GND VSS<60> @BASEBOARD_FAB2_LIB.BASEBOARD_FAB2(SCH_1):GND
BM13    GND VSS<59> @BASEBOARD_FAB2_LIB.BASEBOARD_FAB2(SCH_1):GND
BM17    GND VSS<58> @BASEBOARD_FAB2_LIB.BASEBOARD_FAB2(SCH_1):GND
BN37    GND VSS<57> @BASEBOARD_FAB2_LIB.BASEBOARD_FAB2(SCH_1):GND
BM46    GND VSS<56> @BASEBOARD_FAB2_LIB.BASEBOARD_FAB2(SCH_1):GND
BM50    GND VSS<55> @BASEBOARD_FAB2_LIB.BASEBOARD_FAB2(SCH_1):GND
BM58    GND VSS<54> @BASEBOARD_FAB2_LIB.BASEBOARD_FAB2(SCH_1):GND
BM69    GND VSS<53> @BASEBOARD_FAB2_LIB.BASEBOARD_FAB2(SCH_1):GND
BM71    GND VSS<52> @BASEBOARD_FAB2_LIB.BASEBOARD_FAB2(SCH_1):GND
 BM9    GND VSS<51> @BASEBOARD_FAB2_LIB.BASEBOARD_FAB2(SCH_1):GND
BN22    GND VSS<50> @BASEBOARD_FAB2_LIB.BASEBOARD_FAB2(SCH_1):GND
BN59    GND VSS<49> @BASEBOARD_FAB2_LIB.BASEBOARD_FAB2(SCH_1):GND
 BN5    GND VSS<48> @BASEBOARD_FAB2_LIB.BASEBOARD_FAB2(SCH_1):GND
BN52    GND VSS<47> @BASEBOARD_FAB2_LIB.BASEBOARD_FAB2(SCH_1):GND
BN66    GND VSS<46> @BASEBOARD_FAB2_LIB.BASEBOARD_FAB2(SCH_1):GND
BR20    GND VSS<45> @BASEBOARD_FAB2_LIB.BASEBOARD_FAB2(SCH_1):GND
BR50    GND VSS<44> @BASEBOARD_FAB2_LIB.BASEBOARD_FAB2(SCH_1):GND
 BT8    GND VSS<43> @BASEBOARD_FAB2_LIB.BASEBOARD_FAB2(SCH_1):GND
BR54    GND VSS<42> @BASEBOARD_FAB2_LIB.BASEBOARD_FAB2(SCH_1):GND
BR58    GND VSS<41> @BASEBOARD_FAB2_LIB.BASEBOARD_FAB2(SCH_1):GND
 BR6    GND VSS<40> @BASEBOARD_FAB2_LIB.BASEBOARD_FAB2(SCH_1):GND
BT66    GND VSS<39> @BASEBOARD_FAB2_LIB.BASEBOARD_FAB2(SCH_1):GND
BU13    GND VSS<38> @BASEBOARD_FAB2_LIB.BASEBOARD_FAB2(SCH_1):GND
BU11    GND VSS<37> @BASEBOARD_FAB2_LIB.BASEBOARD_FAB2(SCH_1):GND
BV49    GND VSS<36> @BASEBOARD_FAB2_LIB.BASEBOARD_FAB2(SCH_1):GND
BU15    GND VSS<35> @BASEBOARD_FAB2_LIB.BASEBOARD_FAB2(SCH_1):GND
BU18    GND VSS<34> @BASEBOARD_FAB2_LIB.BASEBOARD_FAB2(SCH_1):GND
BU20    GND VSS<33> @BASEBOARD_FAB2_LIB.BASEBOARD_FAB2(SCH_1):GND
BU22    GND VSS<32> @BASEBOARD_FAB2_LIB.BASEBOARD_FAB2(SCH_1):GND
BU24    GND VSS<31> @BASEBOARD_FAB2_LIB.BASEBOARD_FAB2(SCH_1):GND
BU26    GND VSS<30> @BASEBOARD_FAB2_LIB.BASEBOARD_FAB2(SCH_1):GND
BU28    GND VSS<29> @BASEBOARD_FAB2_LIB.BASEBOARD_FAB2(SCH_1):GND
BU30    GND VSS<28> @BASEBOARD_FAB2_LIB.BASEBOARD_FAB2(SCH_1):GND
BU32    GND VSS<27> @BASEBOARD_FAB2_LIB.BASEBOARD_FAB2(SCH_1):GND
BU34    GND VSS<26> @BASEBOARD_FAB2_LIB.BASEBOARD_FAB2(SCH_1):GND
BU37    GND VSS<25> @BASEBOARD_FAB2_LIB.BASEBOARD_FAB2(SCH_1):GND
BU39    GND VSS<24> @BASEBOARD_FAB2_LIB.BASEBOARD_FAB2(SCH_1):GND
BU41    GND VSS<23> @BASEBOARD_FAB2_LIB.BASEBOARD_FAB2(SCH_1):GND
BU43    GND VSS<22> @BASEBOARD_FAB2_LIB.BASEBOARD_FAB2(SCH_1):GND
BU45    GND VSS<21> @BASEBOARD_FAB2_LIB.BASEBOARD_FAB2(SCH_1):GND
BU48    GND VSS<20> @BASEBOARD_FAB2_LIB.BASEBOARD_FAB2(SCH_1):GND
BU50    GND VSS<19> @BASEBOARD_FAB2_LIB.BASEBOARD_FAB2(SCH_1):GND
BU52    GND VSS<18> @BASEBOARD_FAB2_LIB.BASEBOARD_FAB2(SCH_1):GND
BU54    GND VSS<17> @BASEBOARD_FAB2_LIB.BASEBOARD_FAB2(SCH_1):GND
BU57    GND VSS<16> @BASEBOARD_FAB2_LIB.BASEBOARD_FAB2(SCH_1):GND
BU59    GND VSS<15> @BASEBOARD_FAB2_LIB.BASEBOARD_FAB2(SCH_1):GND
BU61    GND VSS<14> @BASEBOARD_FAB2_LIB.BASEBOARD_FAB2(SCH_1):GND
BU63    GND VSS<13> @BASEBOARD_FAB2_LIB.BASEBOARD_FAB2(SCH_1):GND
 BU9    GND VSS<12> @BASEBOARD_FAB2_LIB.BASEBOARD_FAB2(SCH_1):GND
BV40    GND VSS<11> @BASEBOARD_FAB2_LIB.BASEBOARD_FAB2(SCH_1):GND
BW15    GND VSS<10> @BASEBOARD_FAB2_LIB.BASEBOARD_FAB2(SCH_1):GND
BW18    GND VSS<9> @BASEBOARD_FAB2_LIB.BASEBOARD_FAB2(SCH_1):GND
BW26    GND VSS<8> @BASEBOARD_FAB2_LIB.BASEBOARD_FAB2(SCH_1):GND
BW52    GND VSS<7> @BASEBOARD_FAB2_LIB.BASEBOARD_FAB2(SCH_1):GND
BY40    GND VSS<6> @BASEBOARD_FAB2_LIB.BASEBOARD_FAB2(SCH_1):GND
BY49    GND VSS<5> @BASEBOARD_FAB2_LIB.BASEBOARD_FAB2(SCH_1):GND
CA15    GND VSS<4> @BASEBOARD_FAB2_LIB.BASEBOARD_FAB2(SCH_1):GND
CA18    GND VSS<3> @BASEBOARD_FAB2_LIB.BASEBOARD_FAB2(SCH_1):GND
CA26    GND VSS<2> @BASEBOARD_FAB2_LIB.BASEBOARD_FAB2(SCH_1):GND
CA50    GND VSS<1> @BASEBOARD_FAB2_LIB.BASEBOARD_FAB2(SCH_1):GND
CA52    GND VSS<0> @BASEBOARD_FAB2_LIB.BASEBOARD_FAB2(SCH_1):GND

LBG_CORE_QAT_EXT_D_BGA1-IC,H91A  I16  U7C1
AL68    GND VSS<214> @BASEBOARD_FAB2_LIB.BASEBOARD_FAB2(SCH_1):GND
AL70    GND VSS<213> @BASEBOARD_FAB2_LIB.BASEBOARD_FAB2(SCH_1):GND
AL72    GND VSS<212> @BASEBOARD_FAB2_LIB.BASEBOARD_FAB2(SCH_1):GND
AM26    GND VSS<211> @BASEBOARD_FAB2_LIB.BASEBOARD_FAB2(SCH_1):GND
AM30    GND VSS<210> @BASEBOARD_FAB2_LIB.BASEBOARD_FAB2(SCH_1):GND
AM41    GND VSS<209> @BASEBOARD_FAB2_LIB.BASEBOARD_FAB2(SCH_1):GND
AM46    GND VSS<208> @BASEBOARD_FAB2_LIB.BASEBOARD_FAB2(SCH_1):GND
AN13    GND VSS<207> @BASEBOARD_FAB2_LIB.BASEBOARD_FAB2(SCH_1):GND
AN17    GND VSS<206> @BASEBOARD_FAB2_LIB.BASEBOARD_FAB2(SCH_1):GND
AN68    GND VSS<205> @BASEBOARD_FAB2_LIB.BASEBOARD_FAB2(SCH_1):GND
AP22    GND VSS<204> @BASEBOARD_FAB2_LIB.BASEBOARD_FAB2(SCH_1):GND
AN20    GND VSS<203> @BASEBOARD_FAB2_LIB.BASEBOARD_FAB2(SCH_1):GND
 AN5    GND VSS<202> @BASEBOARD_FAB2_LIB.BASEBOARD_FAB2(SCH_1):GND
AN58    GND VSS<201> @BASEBOARD_FAB2_LIB.BASEBOARD_FAB2(SCH_1):GND
 AN9    GND VSS<200> @BASEBOARD_FAB2_LIB.BASEBOARD_FAB2(SCH_1):GND
 AP2    GND VSS<199> @BASEBOARD_FAB2_LIB.BASEBOARD_FAB2(SCH_1):GND
AP26    GND VSS<198> @BASEBOARD_FAB2_LIB.BASEBOARD_FAB2(SCH_1):GND
AP30    GND VSS<197> @BASEBOARD_FAB2_LIB.BASEBOARD_FAB2(SCH_1):GND
 AP4    GND VSS<196> @BASEBOARD_FAB2_LIB.BASEBOARD_FAB2(SCH_1):GND
AP41    GND VSS<195> @BASEBOARD_FAB2_LIB.BASEBOARD_FAB2(SCH_1):GND
AP46    GND VSS<194> @BASEBOARD_FAB2_LIB.BASEBOARD_FAB2(SCH_1):GND
AP52    GND VSS<193> @BASEBOARD_FAB2_LIB.BASEBOARD_FAB2(SCH_1):GND
AP66    GND VSS<192> @BASEBOARD_FAB2_LIB.BASEBOARD_FAB2(SCH_1):GND
 AR5    GND VSS<191> @BASEBOARD_FAB2_LIB.BASEBOARD_FAB2(SCH_1):GND
AR50    GND VSS<190> @BASEBOARD_FAB2_LIB.BASEBOARD_FAB2(SCH_1):GND
AR58    GND VSS<189> @BASEBOARD_FAB2_LIB.BASEBOARD_FAB2(SCH_1):GND
AR65    GND VSS<188> @BASEBOARD_FAB2_LIB.BASEBOARD_FAB2(SCH_1):GND
AR68    GND VSS<187> @BASEBOARD_FAB2_LIB.BASEBOARD_FAB2(SCH_1):GND
AR70    GND VSS<186> @BASEBOARD_FAB2_LIB.BASEBOARD_FAB2(SCH_1):GND
AR72    GND VSS<185> @BASEBOARD_FAB2_LIB.BASEBOARD_FAB2(SCH_1):GND
 AT7    GND VSS<184> @BASEBOARD_FAB2_LIB.BASEBOARD_FAB2(SCH_1):GND
AT11    GND VSS<183> @BASEBOARD_FAB2_LIB.BASEBOARD_FAB2(SCH_1):GND
AT15    GND VSS<182> @BASEBOARD_FAB2_LIB.BASEBOARD_FAB2(SCH_1):GND
AT18    GND VSS<181> @BASEBOARD_FAB2_LIB.BASEBOARD_FAB2(SCH_1):GND
AT22    GND VSS<180> @BASEBOARD_FAB2_LIB.BASEBOARD_FAB2(SCH_1):GND
AT26    GND VSS<179> @BASEBOARD_FAB2_LIB.BASEBOARD_FAB2(SCH_1):GND
AT30    GND VSS<178> @BASEBOARD_FAB2_LIB.BASEBOARD_FAB2(SCH_1):GND
AT41    GND VSS<177> @BASEBOARD_FAB2_LIB.BASEBOARD_FAB2(SCH_1):GND
AT46    GND VSS<176> @BASEBOARD_FAB2_LIB.BASEBOARD_FAB2(SCH_1):GND
AT59    GND VSS<175> @BASEBOARD_FAB2_LIB.BASEBOARD_FAB2(SCH_1):GND
AU26    GND VSS<174> @BASEBOARD_FAB2_LIB.BASEBOARD_FAB2(SCH_1):GND
AU30    GND VSS<173> @BASEBOARD_FAB2_LIB.BASEBOARD_FAB2(SCH_1):GND
AE22    GND VSS<172> @BASEBOARD_FAB2_LIB.BASEBOARD_FAB2(SCH_1):GND
AU41    GND VSS<171> @BASEBOARD_FAB2_LIB.BASEBOARD_FAB2(SCH_1):GND
AU46    GND VSS<170> @BASEBOARD_FAB2_LIB.BASEBOARD_FAB2(SCH_1):GND
AU50    GND VSS<169> @BASEBOARD_FAB2_LIB.BASEBOARD_FAB2(SCH_1):GND
AU54    GND VSS<168> @BASEBOARD_FAB2_LIB.BASEBOARD_FAB2(SCH_1):GND
AU61    GND VSS<167> @BASEBOARD_FAB2_LIB.BASEBOARD_FAB2(SCH_1):GND
 AV5    GND VSS<166> @BASEBOARD_FAB2_LIB.BASEBOARD_FAB2(SCH_1):GND
AV22    GND VSS<165> @BASEBOARD_FAB2_LIB.BASEBOARD_FAB2(SCH_1):GND
AV59    GND VSS<164> @BASEBOARD_FAB2_LIB.BASEBOARD_FAB2(SCH_1):GND
AV68    GND VSS<163> @BASEBOARD_FAB2_LIB.BASEBOARD_FAB2(SCH_1):GND
 AW9    GND VSS<162> @BASEBOARD_FAB2_LIB.BASEBOARD_FAB2(SCH_1):GND
AW13    GND VSS<161> @BASEBOARD_FAB2_LIB.BASEBOARD_FAB2(SCH_1):GND
AW17    GND VSS<160> @BASEBOARD_FAB2_LIB.BASEBOARD_FAB2(SCH_1):GND
AW26    GND VSS<159> @BASEBOARD_FAB2_LIB.BASEBOARD_FAB2(SCH_1):GND
AW30    GND VSS<158> @BASEBOARD_FAB2_LIB.BASEBOARD_FAB2(SCH_1):GND
AW32    GND VSS<157> @BASEBOARD_FAB2_LIB.BASEBOARD_FAB2(SCH_1):GND
AW34    GND VSS<156> @BASEBOARD_FAB2_LIB.BASEBOARD_FAB2(SCH_1):GND
AW36    GND VSS<155> @BASEBOARD_FAB2_LIB.BASEBOARD_FAB2(SCH_1):GND
AW37    GND VSS<154> @BASEBOARD_FAB2_LIB.BASEBOARD_FAB2(SCH_1):GND
AW39    GND VSS<153> @BASEBOARD_FAB2_LIB.BASEBOARD_FAB2(SCH_1):GND
AW41    GND VSS<152> @BASEBOARD_FAB2_LIB.BASEBOARD_FAB2(SCH_1):GND
AW46    GND VSS<151> @BASEBOARD_FAB2_LIB.BASEBOARD_FAB2(SCH_1):GND
AW50    GND VSS<150> @BASEBOARD_FAB2_LIB.BASEBOARD_FAB2(SCH_1):GND
AW58    GND VSS<149> @BASEBOARD_FAB2_LIB.BASEBOARD_FAB2(SCH_1):GND
AW61    GND VSS<148> @BASEBOARD_FAB2_LIB.BASEBOARD_FAB2(SCH_1):GND
 AY5    GND VSS<147> @BASEBOARD_FAB2_LIB.BASEBOARD_FAB2(SCH_1):GND
AY22    GND VSS<146> @BASEBOARD_FAB2_LIB.BASEBOARD_FAB2(SCH_1):GND
AY56    GND VSS<145> @BASEBOARD_FAB2_LIB.BASEBOARD_FAB2(SCH_1):GND
AY63    GND VSS<144> @BASEBOARD_FAB2_LIB.BASEBOARD_FAB2(SCH_1):GND
AY68    GND VSS<143> @BASEBOARD_FAB2_LIB.BASEBOARD_FAB2(SCH_1):GND
BA50    GND VSS<142> @BASEBOARD_FAB2_LIB.BASEBOARD_FAB2(SCH_1):GND
BA54    GND VSS<141> @BASEBOARD_FAB2_LIB.BASEBOARD_FAB2(SCH_1):GND
BA58    GND VSS<140> @BASEBOARD_FAB2_LIB.BASEBOARD_FAB2(SCH_1):GND
 BB5    GND VSS<139> @BASEBOARD_FAB2_LIB.BASEBOARD_FAB2(SCH_1):GND
 BB7    GND VSS<138> @BASEBOARD_FAB2_LIB.BASEBOARD_FAB2(SCH_1):GND
BB11    GND VSS<137> @BASEBOARD_FAB2_LIB.BASEBOARD_FAB2(SCH_1):GND
BB15    GND VSS<136> @BASEBOARD_FAB2_LIB.BASEBOARD_FAB2(SCH_1):GND
BB18    GND VSS<135> @BASEBOARD_FAB2_LIB.BASEBOARD_FAB2(SCH_1):GND
BB22    GND VSS<134> @BASEBOARD_FAB2_LIB.BASEBOARD_FAB2(SCH_1):GND
BB44    GND VSS<133> @BASEBOARD_FAB2_LIB.BASEBOARD_FAB2(SCH_1):GND
BB59    GND VSS<132> @BASEBOARD_FAB2_LIB.BASEBOARD_FAB2(SCH_1):GND
BB66    GND VSS<131> @BASEBOARD_FAB2_LIB.BASEBOARD_FAB2(SCH_1):GND
BB68    GND VSS<130> @BASEBOARD_FAB2_LIB.BASEBOARD_FAB2(SCH_1):GND
BB70    GND VSS<129> @BASEBOARD_FAB2_LIB.BASEBOARD_FAB2(SCH_1):GND
BB72    GND VSS<128> @BASEBOARD_FAB2_LIB.BASEBOARD_FAB2(SCH_1):GND
BC69    GND VSS<127> @BASEBOARD_FAB2_LIB.BASEBOARD_FAB2(SCH_1):GND
BC71    GND VSS<126> @BASEBOARD_FAB2_LIB.BASEBOARD_FAB2(SCH_1):GND
BD24    GND VSS<125> @BASEBOARD_FAB2_LIB.BASEBOARD_FAB2(SCH_1):GND
BD27    GND VSS<124> @BASEBOARD_FAB2_LIB.BASEBOARD_FAB2(SCH_1):GND
BD31    GND VSS<123> @BASEBOARD_FAB2_LIB.BASEBOARD_FAB2(SCH_1):GND
BD35    GND VSS<122> @BASEBOARD_FAB2_LIB.BASEBOARD_FAB2(SCH_1):GND
 BD5    GND VSS<121> @BASEBOARD_FAB2_LIB.BASEBOARD_FAB2(SCH_1):GND
BD50    GND VSS<120> @BASEBOARD_FAB2_LIB.BASEBOARD_FAB2(SCH_1):GND
BD54    GND VSS<119> @BASEBOARD_FAB2_LIB.BASEBOARD_FAB2(SCH_1):GND
BD68    GND VSS<118> @BASEBOARD_FAB2_LIB.BASEBOARD_FAB2(SCH_1):GND
BE29    GND VSS<117> @BASEBOARD_FAB2_LIB.BASEBOARD_FAB2(SCH_1):GND
BE33    GND VSS<116> @BASEBOARD_FAB2_LIB.BASEBOARD_FAB2(SCH_1):GND
BE37    GND VSS<115> @BASEBOARD_FAB2_LIB.BASEBOARD_FAB2(SCH_1):GND
BE56    GND VSS<114> @BASEBOARD_FAB2_LIB.BASEBOARD_FAB2(SCH_1):GND
BE59    GND VSS<113> @BASEBOARD_FAB2_LIB.BASEBOARD_FAB2(SCH_1):GND
BE63    GND VSS<112> @BASEBOARD_FAB2_LIB.BASEBOARD_FAB2(SCH_1):GND
BE66    GND VSS<111> @BASEBOARD_FAB2_LIB.BASEBOARD_FAB2(SCH_1):GND
BF13    GND VSS<110> @BASEBOARD_FAB2_LIB.BASEBOARD_FAB2(SCH_1):GND
BF17    GND VSS<109> @BASEBOARD_FAB2_LIB.BASEBOARD_FAB2(SCH_1):GND
BF54    GND VSS<108> @BASEBOARD_FAB2_LIB.BASEBOARD_FAB2(SCH_1):GND
BG44    GND VSS<107> @BASEBOARD_FAB2_LIB.BASEBOARD_FAB2(SCH_1):GND
BF20    GND VSS<106> @BASEBOARD_FAB2_LIB.BASEBOARD_FAB2(SCH_1):GND
BF24    GND VSS<105> @BASEBOARD_FAB2_LIB.BASEBOARD_FAB2(SCH_1):GND
BF27    GND VSS<104> @BASEBOARD_FAB2_LIB.BASEBOARD_FAB2(SCH_1):GND
BF38    GND VSS<103> @BASEBOARD_FAB2_LIB.BASEBOARD_FAB2(SCH_1):GND
BF42    GND VSS<102> @BASEBOARD_FAB2_LIB.BASEBOARD_FAB2(SCH_1):GND
 BF5    GND VSS<101> @BASEBOARD_FAB2_LIB.BASEBOARD_FAB2(SCH_1):GND
BF50    GND VSS<100> @BASEBOARD_FAB2_LIB.BASEBOARD_FAB2(SCH_1):GND
BF58    GND VSS<99> @BASEBOARD_FAB2_LIB.BASEBOARD_FAB2(SCH_1):GND
BF61    GND VSS<98> @BASEBOARD_FAB2_LIB.BASEBOARD_FAB2(SCH_1):GND
BF65    GND VSS<97> @BASEBOARD_FAB2_LIB.BASEBOARD_FAB2(SCH_1):GND
BF68    GND VSS<96> @BASEBOARD_FAB2_LIB.BASEBOARD_FAB2(SCH_1):GND
 BF9    GND VSS<95> @BASEBOARD_FAB2_LIB.BASEBOARD_FAB2(SCH_1):GND
BG33    GND VSS<94> @BASEBOARD_FAB2_LIB.BASEBOARD_FAB2(SCH_1):GND
BG48    GND VSS<93> @BASEBOARD_FAB2_LIB.BASEBOARD_FAB2(SCH_1):GND
BG59    GND VSS<92> @BASEBOARD_FAB2_LIB.BASEBOARD_FAB2(SCH_1):GND
BG63    GND VSS<91> @BASEBOARD_FAB2_LIB.BASEBOARD_FAB2(SCH_1):GND
BH27    GND VSS<90> @BASEBOARD_FAB2_LIB.BASEBOARD_FAB2(SCH_1):GND
BH38    GND VSS<89> @BASEBOARD_FAB2_LIB.BASEBOARD_FAB2(SCH_1):GND
BH42    GND VSS<88> @BASEBOARD_FAB2_LIB.BASEBOARD_FAB2(SCH_1):GND
BH46    GND VSS<87> @BASEBOARD_FAB2_LIB.BASEBOARD_FAB2(SCH_1):GND
BH54    GND VSS<86> @BASEBOARD_FAB2_LIB.BASEBOARD_FAB2(SCH_1):GND
 BJ1    GND VSS<85> @BASEBOARD_FAB2_LIB.BASEBOARD_FAB2(SCH_1):GND
BJ11    GND VSS<84> @BASEBOARD_FAB2_LIB.BASEBOARD_FAB2(SCH_1):GND
 BJ5    GND VSS<83> @BASEBOARD_FAB2_LIB.BASEBOARD_FAB2(SCH_1):GND
 BJ7    GND VSS<82> @BASEBOARD_FAB2_LIB.BASEBOARD_FAB2(SCH_1):GND
BJ15    GND VSS<81> @BASEBOARD_FAB2_LIB.BASEBOARD_FAB2(SCH_1):GND
BJ18    GND VSS<80> @BASEBOARD_FAB2_LIB.BASEBOARD_FAB2(SCH_1):GND
BJ26    GND VSS<79> @BASEBOARD_FAB2_LIB.BASEBOARD_FAB2(SCH_1):GND
 BJ3    GND VSS<78> @BASEBOARD_FAB2_LIB.BASEBOARD_FAB2(SCH_1):GND
BJ33    GND VSS<77> @BASEBOARD_FAB2_LIB.BASEBOARD_FAB2(SCH_1):GND
BJ52    GND VSS<76> @BASEBOARD_FAB2_LIB.BASEBOARD_FAB2(SCH_1):GND
BJ68    GND VSS<75> @BASEBOARD_FAB2_LIB.BASEBOARD_FAB2(SCH_1):GND

LBG_CORE_QAT_EXT_D_BGA1-IC,H91A  I17  U7C1
 N35    GND VSS<354> @BASEBOARD_FAB2_LIB.BASEBOARD_FAB2(SCH_1):GND
 N38    GND VSS<353> @BASEBOARD_FAB2_LIB.BASEBOARD_FAB2(SCH_1):GND
 N46    GND VSS<352> @BASEBOARD_FAB2_LIB.BASEBOARD_FAB2(SCH_1):GND
  N5    GND VSS<351> @BASEBOARD_FAB2_LIB.BASEBOARD_FAB2(SCH_1):GND
 R38    GND VSS<350> @BASEBOARD_FAB2_LIB.BASEBOARD_FAB2(SCH_1):GND
 N68    GND VSS<349> @BASEBOARD_FAB2_LIB.BASEBOARD_FAB2(SCH_1):GND
  N9    GND VSS<348> @BASEBOARD_FAB2_LIB.BASEBOARD_FAB2(SCH_1):GND
AE43    GND VSS<347> @BASEBOARD_FAB2_LIB.BASEBOARD_FAB2(SCH_1):GND
 P63    GND VSS<346> @BASEBOARD_FAB2_LIB.BASEBOARD_FAB2(SCH_1):GND
 R27    GND VSS<345> @BASEBOARD_FAB2_LIB.BASEBOARD_FAB2(SCH_1):GND
 U42    GND VSS<344> @BASEBOARD_FAB2_LIB.BASEBOARD_FAB2(SCH_1):GND
  R5    GND VSS<343> @BASEBOARD_FAB2_LIB.BASEBOARD_FAB2(SCH_1):GND
 R50    GND VSS<342> @BASEBOARD_FAB2_LIB.BASEBOARD_FAB2(SCH_1):GND
 R54    GND VSS<341> @BASEBOARD_FAB2_LIB.BASEBOARD_FAB2(SCH_1):GND
 T56    GND VSS<340> @BASEBOARD_FAB2_LIB.BASEBOARD_FAB2(SCH_1):GND
 R58    GND VSS<339> @BASEBOARD_FAB2_LIB.BASEBOARD_FAB2(SCH_1):GND
 R68    GND VSS<338> @BASEBOARD_FAB2_LIB.BASEBOARD_FAB2(SCH_1):GND
 T11    GND VSS<337> @BASEBOARD_FAB2_LIB.BASEBOARD_FAB2(SCH_1):GND
 T15    GND VSS<336> @BASEBOARD_FAB2_LIB.BASEBOARD_FAB2(SCH_1):GND
 T18    GND VSS<335> @BASEBOARD_FAB2_LIB.BASEBOARD_FAB2(SCH_1):GND
 T22    GND VSS<334> @BASEBOARD_FAB2_LIB.BASEBOARD_FAB2(SCH_1):GND
 T26    GND VSS<333> @BASEBOARD_FAB2_LIB.BASEBOARD_FAB2(SCH_1):GND
 T29    GND VSS<332> @BASEBOARD_FAB2_LIB.BASEBOARD_FAB2(SCH_1):GND
 T33    GND VSS<331> @BASEBOARD_FAB2_LIB.BASEBOARD_FAB2(SCH_1):GND
 T37    GND VSS<330> @BASEBOARD_FAB2_LIB.BASEBOARD_FAB2(SCH_1):GND
 T40    GND VSS<329> @BASEBOARD_FAB2_LIB.BASEBOARD_FAB2(SCH_1):GND
AJ45    GND VSS<328> @BASEBOARD_FAB2_LIB.BASEBOARD_FAB2(SCH_1):GND
 T48    GND VSS<327> @BASEBOARD_FAB2_LIB.BASEBOARD_FAB2(SCH_1):GND
 T52    GND VSS<326> @BASEBOARD_FAB2_LIB.BASEBOARD_FAB2(SCH_1):GND
 T66    GND VSS<325> @BASEBOARD_FAB2_LIB.BASEBOARD_FAB2(SCH_1):GND
  T7    GND VSS<324> @BASEBOARD_FAB2_LIB.BASEBOARD_FAB2(SCH_1):GND
AF50    GND VSS<323> @BASEBOARD_FAB2_LIB.BASEBOARD_FAB2(SCH_1):GND
AG46    GND VSS<322> @BASEBOARD_FAB2_LIB.BASEBOARD_FAB2(SCH_1):GND
 U58    GND VSS<321> @BASEBOARD_FAB2_LIB.BASEBOARD_FAB2(SCH_1):GND
 V26    GND VSS<320> @BASEBOARD_FAB2_LIB.BASEBOARD_FAB2(SCH_1):GND
 V48    GND VSS<319> @BASEBOARD_FAB2_LIB.BASEBOARD_FAB2(SCH_1):GND
  V5    GND VSS<318> @BASEBOARD_FAB2_LIB.BASEBOARD_FAB2(SCH_1):GND
 V52    GND VSS<317> @BASEBOARD_FAB2_LIB.BASEBOARD_FAB2(SCH_1):GND
 W58    GND VSS<316> @BASEBOARD_FAB2_LIB.BASEBOARD_FAB2(SCH_1):GND
 V66    GND VSS<315> @BASEBOARD_FAB2_LIB.BASEBOARD_FAB2(SCH_1):GND
 V68    GND VSS<314> @BASEBOARD_FAB2_LIB.BASEBOARD_FAB2(SCH_1):GND
 W13    GND VSS<313> @BASEBOARD_FAB2_LIB.BASEBOARD_FAB2(SCH_1):GND
 W17    GND VSS<312> @BASEBOARD_FAB2_LIB.BASEBOARD_FAB2(SCH_1):GND
 W20    GND VSS<311> @BASEBOARD_FAB2_LIB.BASEBOARD_FAB2(SCH_1):GND
 W24    GND VSS<310> @BASEBOARD_FAB2_LIB.BASEBOARD_FAB2(SCH_1):GND
AA50    GND VSS<309> @BASEBOARD_FAB2_LIB.BASEBOARD_FAB2(SCH_1):GND
 Y43    GND VSS<308> @BASEBOARD_FAB2_LIB.BASEBOARD_FAB2(SCH_1):GND
 W61    GND VSS<307> @BASEBOARD_FAB2_LIB.BASEBOARD_FAB2(SCH_1):GND
  W9    GND VSS<306> @BASEBOARD_FAB2_LIB.BASEBOARD_FAB2(SCH_1):GND
 Y22    GND VSS<305> @BASEBOARD_FAB2_LIB.BASEBOARD_FAB2(SCH_1):GND
 Y27    GND VSS<304> @BASEBOARD_FAB2_LIB.BASEBOARD_FAB2(SCH_1):GND
 Y48    GND VSS<303> @BASEBOARD_FAB2_LIB.BASEBOARD_FAB2(SCH_1):GND
  Y5    GND VSS<302> @BASEBOARD_FAB2_LIB.BASEBOARD_FAB2(SCH_1):GND
 Y52    GND VSS<301> @BASEBOARD_FAB2_LIB.BASEBOARD_FAB2(SCH_1):GND
 Y59    GND VSS<300> @BASEBOARD_FAB2_LIB.BASEBOARD_FAB2(SCH_1):GND
 Y63    GND VSS<299> @BASEBOARD_FAB2_LIB.BASEBOARD_FAB2(SCH_1):GND
 Y68    GND VSS<298> @BASEBOARD_FAB2_LIB.BASEBOARD_FAB2(SCH_1):GND
AA26    GND VSS<297> @BASEBOARD_FAB2_LIB.BASEBOARD_FAB2(SCH_1):GND
AA27    GND VSS<296> @BASEBOARD_FAB2_LIB.BASEBOARD_FAB2(SCH_1):GND
AA43    GND VSS<295> @BASEBOARD_FAB2_LIB.BASEBOARD_FAB2(SCH_1):GND
AA48    GND VSS<294> @BASEBOARD_FAB2_LIB.BASEBOARD_FAB2(SCH_1):GND
 AB5    GND VSS<293> @BASEBOARD_FAB2_LIB.BASEBOARD_FAB2(SCH_1):GND
AB68    GND VSS<292> @BASEBOARD_FAB2_LIB.BASEBOARD_FAB2(SCH_1):GND
AB70    GND VSS<291> @BASEBOARD_FAB2_LIB.BASEBOARD_FAB2(SCH_1):GND
AB72    GND VSS<290> @BASEBOARD_FAB2_LIB.BASEBOARD_FAB2(SCH_1):GND
AC11    GND VSS<289> @BASEBOARD_FAB2_LIB.BASEBOARD_FAB2(SCH_1):GND
AC15    GND VSS<288> @BASEBOARD_FAB2_LIB.BASEBOARD_FAB2(SCH_1):GND
AC18    GND VSS<287> @BASEBOARD_FAB2_LIB.BASEBOARD_FAB2(SCH_1):GND
AC22    GND VSS<286> @BASEBOARD_FAB2_LIB.BASEBOARD_FAB2(SCH_1):GND
AC45    GND VSS<285> @BASEBOARD_FAB2_LIB.BASEBOARD_FAB2(SCH_1):GND
AD58    GND VSS<284> @BASEBOARD_FAB2_LIB.BASEBOARD_FAB2(SCH_1):GND
AC27    GND VSS<283> @BASEBOARD_FAB2_LIB.BASEBOARD_FAB2(SCH_1):GND
AC43    GND VSS<282> @BASEBOARD_FAB2_LIB.BASEBOARD_FAB2(SCH_1):GND
AC46    GND VSS<281> @BASEBOARD_FAB2_LIB.BASEBOARD_FAB2(SCH_1):GND
AC48    GND VSS<280> @BASEBOARD_FAB2_LIB.BASEBOARD_FAB2(SCH_1):GND
AC52    GND VSS<279> @BASEBOARD_FAB2_LIB.BASEBOARD_FAB2(SCH_1):GND
AC59    GND VSS<278> @BASEBOARD_FAB2_LIB.BASEBOARD_FAB2(SCH_1):GND
AC63    GND VSS<277> @BASEBOARD_FAB2_LIB.BASEBOARD_FAB2(SCH_1):GND
AC66    GND VSS<276> @BASEBOARD_FAB2_LIB.BASEBOARD_FAB2(SCH_1):GND
 AC7    GND VSS<275> @BASEBOARD_FAB2_LIB.BASEBOARD_FAB2(SCH_1):GND
 AD5    GND VSS<274> @BASEBOARD_FAB2_LIB.BASEBOARD_FAB2(SCH_1):GND
AD65    GND VSS<273> @BASEBOARD_FAB2_LIB.BASEBOARD_FAB2(SCH_1):GND
AD68    GND VSS<272> @BASEBOARD_FAB2_LIB.BASEBOARD_FAB2(SCH_1):GND
AE29    GND VSS<271> @BASEBOARD_FAB2_LIB.BASEBOARD_FAB2(SCH_1):GND
 J18    GND VSS<270> @BASEBOARD_FAB2_LIB.BASEBOARD_FAB2(SCH_1):GND
AE48    GND VSS<269> @BASEBOARD_FAB2_LIB.BASEBOARD_FAB2(SCH_1):GND
AE52    GND VSS<268> @BASEBOARD_FAB2_LIB.BASEBOARD_FAB2(SCH_1):GND
AE56    GND VSS<267> @BASEBOARD_FAB2_LIB.BASEBOARD_FAB2(SCH_1):GND
AE59    GND VSS<266> @BASEBOARD_FAB2_LIB.BASEBOARD_FAB2(SCH_1):GND
AE63    GND VSS<265> @BASEBOARD_FAB2_LIB.BASEBOARD_FAB2(SCH_1):GND
AE66    GND VSS<264> @BASEBOARD_FAB2_LIB.BASEBOARD_FAB2(SCH_1):GND
 AF1    GND VSS<263> @BASEBOARD_FAB2_LIB.BASEBOARD_FAB2(SCH_1):GND
AF13    GND VSS<262> @BASEBOARD_FAB2_LIB.BASEBOARD_FAB2(SCH_1):GND
 AF5    GND VSS<261> @BASEBOARD_FAB2_LIB.BASEBOARD_FAB2(SCH_1):GND
 AF9    GND VSS<260> @BASEBOARD_FAB2_LIB.BASEBOARD_FAB2(SCH_1):GND
AF17    GND VSS<259> @BASEBOARD_FAB2_LIB.BASEBOARD_FAB2(SCH_1):GND
AF24    GND VSS<258> @BASEBOARD_FAB2_LIB.BASEBOARD_FAB2(SCH_1):GND
 AF3    GND VSS<257> @BASEBOARD_FAB2_LIB.BASEBOARD_FAB2(SCH_1):GND
AF68    GND VSS<256> @BASEBOARD_FAB2_LIB.BASEBOARD_FAB2(SCH_1):GND
AG26    GND VSS<255> @BASEBOARD_FAB2_LIB.BASEBOARD_FAB2(SCH_1):GND
AG30    GND VSS<254> @BASEBOARD_FAB2_LIB.BASEBOARD_FAB2(SCH_1):GND
AG41    GND VSS<253> @BASEBOARD_FAB2_LIB.BASEBOARD_FAB2(SCH_1):GND
AG43    GND VSS<252> @BASEBOARD_FAB2_LIB.BASEBOARD_FAB2(SCH_1):GND
AG52    GND VSS<251> @BASEBOARD_FAB2_LIB.BASEBOARD_FAB2(SCH_1):GND
AG56    GND VSS<250> @BASEBOARD_FAB2_LIB.BASEBOARD_FAB2(SCH_1):GND
AG59    GND VSS<249> @BASEBOARD_FAB2_LIB.BASEBOARD_FAB2(SCH_1):GND
AG66    GND VSS<248> @BASEBOARD_FAB2_LIB.BASEBOARD_FAB2(SCH_1):GND
AH20    GND VSS<247> @BASEBOARD_FAB2_LIB.BASEBOARD_FAB2(SCH_1):GND
AJ11    GND VSS<246> @BASEBOARD_FAB2_LIB.BASEBOARD_FAB2(SCH_1):GND
AJ32    GND VSS<245> @BASEBOARD_FAB2_LIB.BASEBOARD_FAB2(SCH_1):GND
AJ56    GND VSS<244> @BASEBOARD_FAB2_LIB.BASEBOARD_FAB2(SCH_1):GND
AK30    GND VSS<243> @BASEBOARD_FAB2_LIB.BASEBOARD_FAB2(SCH_1):GND
AJ15    GND VSS<242> @BASEBOARD_FAB2_LIB.BASEBOARD_FAB2(SCH_1):GND
AJ18    GND VSS<241> @BASEBOARD_FAB2_LIB.BASEBOARD_FAB2(SCH_1):GND
AJ22    GND VSS<240> @BASEBOARD_FAB2_LIB.BASEBOARD_FAB2(SCH_1):GND
AJ26    GND VSS<239> @BASEBOARD_FAB2_LIB.BASEBOARD_FAB2(SCH_1):GND
AJ30    GND VSS<238> @BASEBOARD_FAB2_LIB.BASEBOARD_FAB2(SCH_1):GND
AJ34    GND VSS<237> @BASEBOARD_FAB2_LIB.BASEBOARD_FAB2(SCH_1):GND
AJ36    GND VSS<236> @BASEBOARD_FAB2_LIB.BASEBOARD_FAB2(SCH_1):GND
AJ37    GND VSS<235> @BASEBOARD_FAB2_LIB.BASEBOARD_FAB2(SCH_1):GND
AJ39    GND VSS<234> @BASEBOARD_FAB2_LIB.BASEBOARD_FAB2(SCH_1):GND
AJ41    GND VSS<233> @BASEBOARD_FAB2_LIB.BASEBOARD_FAB2(SCH_1):GND
 AJ5    GND VSS<232> @BASEBOARD_FAB2_LIB.BASEBOARD_FAB2(SCH_1):GND
AJ52    GND VSS<231> @BASEBOARD_FAB2_LIB.BASEBOARD_FAB2(SCH_1):GND
AJ59    GND VSS<230> @BASEBOARD_FAB2_LIB.BASEBOARD_FAB2(SCH_1):GND
AJ66    GND VSS<229> @BASEBOARD_FAB2_LIB.BASEBOARD_FAB2(SCH_1):GND
AJ68    GND VSS<228> @BASEBOARD_FAB2_LIB.BASEBOARD_FAB2(SCH_1):GND
 AJ7    GND VSS<227> @BASEBOARD_FAB2_LIB.BASEBOARD_FAB2(SCH_1):GND
AK26    GND VSS<226> @BASEBOARD_FAB2_LIB.BASEBOARD_FAB2(SCH_1):GND
AK41    GND VSS<225> @BASEBOARD_FAB2_LIB.BASEBOARD_FAB2(SCH_1):GND
AK46    GND VSS<224> @BASEBOARD_FAB2_LIB.BASEBOARD_FAB2(SCH_1):GND
AK48    GND VSS<223> @BASEBOARD_FAB2_LIB.BASEBOARD_FAB2(SCH_1):GND
AK58    GND VSS<222> @BASEBOARD_FAB2_LIB.BASEBOARD_FAB2(SCH_1):GND
AK61    GND VSS<221> @BASEBOARD_FAB2_LIB.BASEBOARD_FAB2(SCH_1):GND
AK69    GND VSS<220> @BASEBOARD_FAB2_LIB.BASEBOARD_FAB2(SCH_1):GND
AK71    GND VSS<219> @BASEBOARD_FAB2_LIB.BASEBOARD_FAB2(SCH_1):GND
AL22    GND VSS<218> @BASEBOARD_FAB2_LIB.BASEBOARD_FAB2(SCH_1):GND
 AL5    GND VSS<217> @BASEBOARD_FAB2_LIB.BASEBOARD_FAB2(SCH_1):GND
AL52    GND VSS<216> @BASEBOARD_FAB2_LIB.BASEBOARD_FAB2(SCH_1):GND
AL59    GND VSS<215> @BASEBOARD_FAB2_LIB.BASEBOARD_FAB2(SCH_1):GND


DRAWING: @BASEBOARD_FAB2_LIB.BASEBOARD_FAB2(SCH_1):PAGE125 

RES_0402-1.00K,1%,1/16W,EMPTY,A  I11  R2R11
   1 SPI_PCH_IO2      A @BASEBOARD_FAB2_LIB.BASEBOARD_FAB2(SCH_1):SPI_PCH_IO2
   2    GND      B @BASEBOARD_FAB2_LIB.BASEBOARD_FAB2(SCH_1):GND

RES_0402-1.00K,1%,1/16W,CHIP,GA  I15  R2T1
   1 SPI_PCH_IO3      A @BASEBOARD_FAB2_LIB.BASEBOARD_FAB2(SCH_1):SPI_PCH_IO3
   2    GND      B @BASEBOARD_FAB2_LIB.BASEBOARD_FAB2(SCH_1):GND

RES_0402-1.00K,1%,1/16W,EMPTY,A  I21  R8E6
   1 P3V3_STBY      A @BASEBOARD_FAB2_LIB.BASEBOARD_FAB2(SCH_1):P3V3_STBY
   2 SPI_PCH_MOSI      B @BASEBOARD_FAB2_LIB.BASEBOARD_FAB2(SCH_1):SPI_PCH_MOSI

RES_0402-1.00K,1%,1/16W,EMPTY,A  I24  R8E4
   1 SPI_PCH_MOSI      A @BASEBOARD_FAB2_LIB.BASEBOARD_FAB2(SCH_1):SPI_PCH_MOSI
   2    GND      B @BASEBOARD_FAB2_LIB.BASEBOARD_FAB2(SCH_1):GND

RES_0402-1.00K,1%,1/16W,CHIP,GA  I40  R8C18
   1 P3V3_STBY      A @BASEBOARD_FAB2_LIB.BASEBOARD_FAB2(SCH_1):P3V3_STBY
   2 PU_PCH_TLS_ENABLE_STRAP      B @BASEBOARD_FAB2_LIB.BASEBOARD_FAB2(SCH_1):PU_PCH_TLS_ENABLE_STRAP

RES_0402-1.00K,1%,1/16W,EMPTY,A  I41  R8C17
   1 PU_PCH_TLS_ENABLE_STRAP      A @BASEBOARD_FAB2_LIB.BASEBOARD_FAB2(SCH_1):PU_PCH_TLS_ENABLE_STRAP
   2    GND      B @BASEBOARD_FAB2_LIB.BASEBOARD_FAB2(SCH_1):GND

RES_0402-1.00K,1%,1/16W,EMPTY,A  I50  R8D5
   1 PU_ADR_TIMER_HOLD_OFF_N      A @BASEBOARD_FAB2_LIB.BASEBOARD_FAB2(SCH_1):PU_ADR_TIMER_HOLD_OFF_N
   2    GND      B @BASEBOARD_FAB2_LIB.BASEBOARD_FAB2(SCH_1):GND

RES_0402-10.0K,1%,1/16W,CHIP,GA  I52  R8D13
   1 P3V3_STBY      A @BASEBOARD_FAB2_LIB.BASEBOARD_FAB2(SCH_1):P3V3_STBY
   2 PU_ADR_TIMER_HOLD_OFF_N      B @BASEBOARD_FAB2_LIB.BASEBOARD_FAB2(SCH_1):PU_ADR_TIMER_HOLD_OFF_N

RES_0402-8.2K,1%,1/16W,EMPTY,GA  I60  R7D13
   1 P3V3_STBY      A @BASEBOARD_FAB2_LIB.BASEBOARD_FAB2(SCH_1):P3V3_STBY
   2 RMII_BMC_PCH_SPRNGVLLE_RXER      B @BASEBOARD_FAB2_LIB.BASEBOARD_FAB2(SCH_1):RMII_BMC_PCH_SPRNGVLLE_RXER

RES_0402-1.00K,1%,1/16W,CHIP,GA  I70  R7D1
   1 RMII_PCH_SPRNGVLLE_ARB_OUT      A @BASEBOARD_FAB2_LIB.BASEBOARD_FAB2(SCH_1):RMII_PCH_SPRNGVLLE_ARB_OUT
   2    GND      B @BASEBOARD_FAB2_LIB.BASEBOARD_FAB2(SCH_1):GND

RES_0402-10.0K,1%,1/16W,EMPTY,A  I71  R8D16
   1 P3V3_STBY      A @BASEBOARD_FAB2_LIB.BASEBOARD_FAB2(SCH_1):P3V3_STBY
   2 RMII_PCH_SPRNGVLLE_ARB_OUT      B @BASEBOARD_FAB2_LIB.BASEBOARD_FAB2(SCH_1):RMII_PCH_SPRNGVLLE_ARB_OUT

RES_0402-4.75K,1%,1/16W,EMPTY,A  I72  R3N2
   1 P3V3_STBY      A @BASEBOARD_FAB2_LIB.BASEBOARD_FAB2(SCH_1):P3V3_STBY
   2 FM_FLASH_DESC_OVERRIDE      B @BASEBOARD_FAB2_LIB.BASEBOARD_FAB2(SCH_1):FM_FLASH_DESC_OVERRIDE

RES_0402-4.75K,1%,1/16W,CHIP,GA  I76  R2U30
   1 P3V3_STBY      A @BASEBOARD_FAB2_LIB.BASEBOARD_FAB2(SCH_1):P3V3_STBY
   2 FM_UV_ADR_TRIGGER_EN      B @BASEBOARD_FAB2_LIB.BASEBOARD_FAB2(SCH_1):FM_UV_ADR_TRIGGER_EN

RES_0402-1.00K,1%,1/16W,EMPTY,A  I78  R3N17
   1 P3V3_STBY      A @BASEBOARD_FAB2_LIB.BASEBOARD_FAB2(SCH_1):P3V3_STBY
   2 SPI_PCH_IO3      B @BASEBOARD_FAB2_LIB.BASEBOARD_FAB2(SCH_1):SPI_PCH_IO3

RES_0402-1.00K,1%,1/16W,EMPTY,A  I83  R2N14
   1 P3V3_STBY      A @BASEBOARD_FAB2_LIB.BASEBOARD_FAB2(SCH_1):P3V3_STBY
   2 FM_USB_P0_EN_BOOT_BIOS_STRAP_N      B @BASEBOARD_FAB2_LIB.BASEBOARD_FAB2(SCH_1):FM_USB_P0_EN_BOOT_BIOS_STRAP_N


DRAWING: @BASEBOARD_FAB2_LIB.BASEBOARD_FAB2(SCH_1):PAGE126 

RES_0402-1.00K,1%,1/16W,EMPTY,A  I6  R7D19
   1 FM_OC_DETECT_EN_N      A @BASEBOARD_FAB2_LIB.BASEBOARD_FAB2(SCH_1):FM_OC_DETECT_EN_N
   2    GND      B @BASEBOARD_FAB2_LIB.BASEBOARD_FAB2(SCH_1):GND

RES_0402-4.75K,1%,1/16W,CHIP,GA  I10  R2N10
   1 P3V3_STBY      A @BASEBOARD_FAB2_LIB.BASEBOARD_FAB2(SCH_1):P3V3_STBY
   2 FM_PCH_BMC_THERMTRIP_EXI_STRAP_      B @BASEBOARD_FAB2_LIB.BASEBOARD_FAB2(SCH_1):FM_PCH_BMC_THERMTRIP_EXI_STRAP_N

RES_0402-4.75K,1%,1/16W,CHIP,GA  I12  R1D35
   1 P3V3_STBY      A @BASEBOARD_FAB2_LIB.BASEBOARD_FAB2(SCH_1):P3V3_STBY
   2 FM_OC_DETECT_EN_N      B @BASEBOARD_FAB2_LIB.BASEBOARD_FAB2(SCH_1):FM_OC_DETECT_EN_N

FET_N_SOT23LF-2N7002,FET,C7925A  I13  Q8E2
   1 RST_RSMRST_DLY   GATE @BASEBOARD_FAB2_LIB.BASEBOARD_FAB2(SCH_1):RST_RSMRST_DLY
   2    GND    SRC @BASEBOARD_FAB2_LIB.BASEBOARD_FAB2(SCH_1):GND
   3 IRQ_SML0_ALERT_N    DRN @BASEBOARD_FAB2_LIB.BASEBOARD_FAB2(SCH_1):IRQ_SML0_ALERT_N

RES_0402-4.75K,1%,1/16W,CHIP,GA  I20  R8C9
   1 P3V3_STBY      A @BASEBOARD_FAB2_LIB.BASEBOARD_FAB2(SCH_1):P3V3_STBY
   2 IRQ_SML0_ALERT_N      B @BASEBOARD_FAB2_LIB.BASEBOARD_FAB2(SCH_1):IRQ_SML0_ALERT_N

RES_0402-4.75K,1%,1/16W,EMPTY,A  I22  R3P62
   1 P3V3_STBY      A @BASEBOARD_FAB2_LIB.BASEBOARD_FAB2(SCH_1):P3V3_STBY
   2 FM_FLASH_ATTACH_CFG_STRAP      B @BASEBOARD_FAB2_LIB.BASEBOARD_FAB2(SCH_1):FM_FLASH_ATTACH_CFG_STRAP

RES_0402-1.00K,1%,1/16W,EMPTY,A  I23  R3P64
   1 FM_FLASH_ATTACH_CFG_STRAP      A @BASEBOARD_FAB2_LIB.BASEBOARD_FAB2(SCH_1):FM_FLASH_ATTACH_CFG_STRAP
   2    GND      B @BASEBOARD_FAB2_LIB.BASEBOARD_FAB2(SCH_1):GND


DRAWING: @BASEBOARD_FAB2_LIB.BASEBOARD_FAB2(SCH_1):PAGE127 

FERRITE_SM-120,FB,693286-027  I8  FB3M1
   1 P1V05_PCH_STBY      A @BASEBOARD_FAB2_LIB.BASEBOARD_FAB2(SCH_1):P1V05_PCH_STBY
   2 P1V05_PCH_STBY_VCCA_PLL1      B @BASEBOARD_FAB2_LIB.BASEBOARD_FAB2(SCH_1):P1V05_PCH_STBY_VCCA_PLL1

CAP_A_0402V-1.0UF,6.3V,10%,X6SA  I9  C3M21
   1 P1V05_PCH_STBY      A @BASEBOARD_FAB2_LIB.BASEBOARD_FAB2(SCH_1):P1V05_PCH_STBY
   2    GND      B @BASEBOARD_FAB2_LIB.BASEBOARD_FAB2(SCH_1):GND

FERRITE_SM-120,FB,693286-027  I17  FB3M2
   1 P1V05_PCH_STBY      A @BASEBOARD_FAB2_LIB.BASEBOARD_FAB2(SCH_1):P1V05_PCH_STBY
   2 P1V05_PCH_STBY_VCCA_PLL0      B @BASEBOARD_FAB2_LIB.BASEBOARD_FAB2(SCH_1):P1V05_PCH_STBY_VCCA_PLL0

CAP_A_0402V-1.0UF,6.3V,10%,X6SA  I18  C3M22
   1 P1V05_PCH_STBY      A @BASEBOARD_FAB2_LIB.BASEBOARD_FAB2(SCH_1):P1V05_PCH_STBY
   2    GND      B @BASEBOARD_FAB2_LIB.BASEBOARD_FAB2(SCH_1):GND

FERRITE_SM-120,FB,693286-027  I26  FB3M3
   1 P1V05_PCH_STBY      A @BASEBOARD_FAB2_LIB.BASEBOARD_FAB2(SCH_1):P1V05_PCH_STBY
   2 P1V05_PCH_STBY_VCCA_XTAL      B @BASEBOARD_FAB2_LIB.BASEBOARD_FAB2(SCH_1):P1V05_PCH_STBY_VCCA_XTAL

CAP_A_0402V-1.0UF,6.3V,10%,X6SA  I27  C3M30
   1 P1V05_PCH_STBY      A @BASEBOARD_FAB2_LIB.BASEBOARD_FAB2(SCH_1):P1V05_PCH_STBY
   2    GND      B @BASEBOARD_FAB2_LIB.BASEBOARD_FAB2(SCH_1):GND

CAP_0603LF-10UF,4V,20%,X6S,E15A  I43  C2M5
   1 P1V05_PCH_STBY_WM20_PLL      A @BASEBOARD_FAB2_LIB.BASEBOARD_FAB2(SCH_1):P1V05_PCH_STBY_WM20_PLL
   2    GND      B @BASEBOARD_FAB2_LIB.BASEBOARD_FAB2(SCH_1):GND

CAP_A_0402V-1.0UF,6.3V,10%,X6SA  I44  C2M7
   1 P1V05_PCH_STBY_WM20_PLL      A @BASEBOARD_FAB2_LIB.BASEBOARD_FAB2(SCH_1):P1V05_PCH_STBY_WM20_PLL
   2    GND      B @BASEBOARD_FAB2_LIB.BASEBOARD_FAB2(SCH_1):GND

FERRITE_SM-120,FB,693286-027  I46  FB2M1
   1 P1V05_PCH_STBY      A @BASEBOARD_FAB2_LIB.BASEBOARD_FAB2(SCH_1):P1V05_PCH_STBY
   2 P1V05_PCH_STBY_WM20_PLL      B @BASEBOARD_FAB2_LIB.BASEBOARD_FAB2(SCH_1):P1V05_PCH_STBY_WM20_PLL

CAP_0603LF-10UF,4V,20%,X6S,E15A  I49  C2M10
   1 P1V05_PCH_STBY_WM26_PLL      A @BASEBOARD_FAB2_LIB.BASEBOARD_FAB2(SCH_1):P1V05_PCH_STBY_WM26_PLL
   2    GND      B @BASEBOARD_FAB2_LIB.BASEBOARD_FAB2(SCH_1):GND

CAP_A_0402V-1.0UF,6.3V,10%,X6SA  I50  C2M9
   1 P1V05_PCH_STBY_WM26_PLL      A @BASEBOARD_FAB2_LIB.BASEBOARD_FAB2(SCH_1):P1V05_PCH_STBY_WM26_PLL
   2    GND      B @BASEBOARD_FAB2_LIB.BASEBOARD_FAB2(SCH_1):GND

FERRITE_SM-120,FB,693286-027  I56  FB3M4
   1 P1V05_PCH_STBY      A @BASEBOARD_FAB2_LIB.BASEBOARD_FAB2(SCH_1):P1V05_PCH_STBY
   2 P1V05_PCH_STBY_ISCLK_PLL      B @BASEBOARD_FAB2_LIB.BASEBOARD_FAB2(SCH_1):P1V05_PCH_STBY_ISCLK_PLL

CAP_A_0402V-1.0UF,6.3V,10%,X6SA  I57  C3M31
   1 P1V05_PCH_STBY      A @BASEBOARD_FAB2_LIB.BASEBOARD_FAB2(SCH_1):P1V05_PCH_STBY
   2    GND      B @BASEBOARD_FAB2_LIB.BASEBOARD_FAB2(SCH_1):GND

CAP_0603LF-10UF,4V,20%,X6S,E15A  I64  C2N6
   1 P1V05_PCH_STBY_KR_PLL      A @BASEBOARD_FAB2_LIB.BASEBOARD_FAB2(SCH_1):P1V05_PCH_STBY_KR_PLL
   2    GND      B @BASEBOARD_FAB2_LIB.BASEBOARD_FAB2(SCH_1):GND

CAP_A_0402V-1.0UF,6.3V,10%,X6SA  I65  C2N5
   1 P1V05_PCH_STBY_KR_PLL      A @BASEBOARD_FAB2_LIB.BASEBOARD_FAB2(SCH_1):P1V05_PCH_STBY_KR_PLL
   2    GND      B @BASEBOARD_FAB2_LIB.BASEBOARD_FAB2(SCH_1):GND

FERRITE_SM-120,FB,693286-027  I69  FB2M2
   1 P1V05_PCH_STBY      A @BASEBOARD_FAB2_LIB.BASEBOARD_FAB2(SCH_1):P1V05_PCH_STBY
   2 P1V05_PCH_STBY_WM26_PLL      B @BASEBOARD_FAB2_LIB.BASEBOARD_FAB2(SCH_1):P1V05_PCH_STBY_WM26_PLL

INDUCTOR_SMT-0.022UH,IND,72189A  I71  L2M1
   1 P1V05_PCH_STBY    INA @BASEBOARD_FAB2_LIB.BASEBOARD_FAB2(SCH_1):P1V05_PCH_STBY
   2 P1V05_PCH_STBY_KR_PLL    INB @BASEBOARD_FAB2_LIB.BASEBOARD_FAB2(SCH_1):P1V05_PCH_STBY_KR_PLL

CAP_A_0402V-1.0UF,6.3V,10%,X6SA  I74  C2M8
   1 P1V05_PCH_STBY      A @BASEBOARD_FAB2_LIB.BASEBOARD_FAB2(SCH_1):P1V05_PCH_STBY
   2    GND      B @BASEBOARD_FAB2_LIB.BASEBOARD_FAB2(SCH_1):GND

CAP_A_0402V-1.0UF,6.3V,10%,X6SA  I76  C2M6
   1 P1V05_PCH_STBY      A @BASEBOARD_FAB2_LIB.BASEBOARD_FAB2(SCH_1):P1V05_PCH_STBY
   2    GND      B @BASEBOARD_FAB2_LIB.BASEBOARD_FAB2(SCH_1):GND

CAP_A_0402V-1.0UF,6.3V,10%,X6SA  I78  C2M25
   1 P1V05_PCH_STBY      A @BASEBOARD_FAB2_LIB.BASEBOARD_FAB2(SCH_1):P1V05_PCH_STBY
   2    GND      B @BASEBOARD_FAB2_LIB.BASEBOARD_FAB2(SCH_1):GND

CAP_A_0402V-1.0UF,6.3V,10%,X6SA  I80  C3M29
   1 P1V05_PCH_STBY_ISCLK_PLL      A @BASEBOARD_FAB2_LIB.BASEBOARD_FAB2(SCH_1):P1V05_PCH_STBY_ISCLK_PLL
   2    GND      B @BASEBOARD_FAB2_LIB.BASEBOARD_FAB2(SCH_1):GND

CAP_0603LF-10UF,4V,20%,X6S,E15A  I81  C3M24
   1 P1V05_PCH_STBY_ISCLK_PLL      A @BASEBOARD_FAB2_LIB.BASEBOARD_FAB2(SCH_1):P1V05_PCH_STBY_ISCLK_PLL
   2    GND      B @BASEBOARD_FAB2_LIB.BASEBOARD_FAB2(SCH_1):GND

CAP_0603LF-10UF,4V,20%,X6S,E15A  I82  C3M23
   1 P1V05_PCH_STBY_VCCA_XTAL      A @BASEBOARD_FAB2_LIB.BASEBOARD_FAB2(SCH_1):P1V05_PCH_STBY_VCCA_XTAL
   2    GND      B @BASEBOARD_FAB2_LIB.BASEBOARD_FAB2(SCH_1):GND

CAP_A_0402V-1.0UF,6.3V,10%,X6SA  I83  C3M27
   1 P1V05_PCH_STBY_VCCA_XTAL      A @BASEBOARD_FAB2_LIB.BASEBOARD_FAB2(SCH_1):P1V05_PCH_STBY_VCCA_XTAL
   2    GND      B @BASEBOARD_FAB2_LIB.BASEBOARD_FAB2(SCH_1):GND

CAP_A_0402V-1.0UF,6.3V,10%,X6SA  I84  C3M20
   1 P1V05_PCH_STBY_VCCA_PLL0      A @BASEBOARD_FAB2_LIB.BASEBOARD_FAB2(SCH_1):P1V05_PCH_STBY_VCCA_PLL0
   2    GND      B @BASEBOARD_FAB2_LIB.BASEBOARD_FAB2(SCH_1):GND

CAP_0603LF-10UF,4V,20%,X6S,E15A  I85  C3M18
   1 P1V05_PCH_STBY_VCCA_PLL0      A @BASEBOARD_FAB2_LIB.BASEBOARD_FAB2(SCH_1):P1V05_PCH_STBY_VCCA_PLL0
   2    GND      B @BASEBOARD_FAB2_LIB.BASEBOARD_FAB2(SCH_1):GND

CAP_0603LF-10UF,4V,20%,X6S,E15A  I86  C3M17
   1 P1V05_PCH_STBY_VCCA_PLL1      A @BASEBOARD_FAB2_LIB.BASEBOARD_FAB2(SCH_1):P1V05_PCH_STBY_VCCA_PLL1
   2    GND      B @BASEBOARD_FAB2_LIB.BASEBOARD_FAB2(SCH_1):GND

CAP_A_0402V-1.0UF,6.3V,10%,X6SA  I87  C3M19
   1 P1V05_PCH_STBY_VCCA_PLL1      A @BASEBOARD_FAB2_LIB.BASEBOARD_FAB2(SCH_1):P1V05_PCH_STBY_VCCA_PLL1
   2    GND      B @BASEBOARD_FAB2_LIB.BASEBOARD_FAB2(SCH_1):GND


DRAWING: @BASEBOARD_FAB2_LIB.BASEBOARD_FAB2(SCH_1):PAGE129 

CAP_0402-0.22UF,16V,10%,X7R,A3A  I35  C7B25
   1 DMI_CPU0_PCH_TX_DP<3>      A @BASEBOARD_FAB2_LIB.BASEBOARD_FAB2(SCH_1):DMI_CPU0_PCH_TX_DP(3)
   2 DMI_CPU0_PCH_TX_C_DP<3>      B @BASEBOARD_FAB2_LIB.BASEBOARD_FAB2(SCH_1):DMI_CPU0_PCH_TX_C_DP(3)

CAP_0402-0.22UF,16V,10%,X7R,A3A  I69  C7B27
   1 DMI_CPU0_PCH_TX_DP<2>      A @BASEBOARD_FAB2_LIB.BASEBOARD_FAB2(SCH_1):DMI_CPU0_PCH_TX_DP(2)
   2 DMI_CPU0_PCH_TX_C_DP<2>      B @BASEBOARD_FAB2_LIB.BASEBOARD_FAB2(SCH_1):DMI_CPU0_PCH_TX_C_DP(2)

CAP_0402-0.22UF,16V,10%,X7R,A3A  I70  C7B28
   1 DMI_CPU0_PCH_TX_DP<1>      A @BASEBOARD_FAB2_LIB.BASEBOARD_FAB2(SCH_1):DMI_CPU0_PCH_TX_DP(1)
   2 DMI_CPU0_PCH_TX_C_DP<1>      B @BASEBOARD_FAB2_LIB.BASEBOARD_FAB2(SCH_1):DMI_CPU0_PCH_TX_C_DP(1)

CAP_0402-0.22UF,16V,10%,X7R,A3A  I71  C7C2
   1 DMI_CPU0_PCH_TX_DP<0>      A @BASEBOARD_FAB2_LIB.BASEBOARD_FAB2(SCH_1):DMI_CPU0_PCH_TX_DP(0)
   2 DMI_CPU0_PCH_TX_C_DP<0>      B @BASEBOARD_FAB2_LIB.BASEBOARD_FAB2(SCH_1):DMI_CPU0_PCH_TX_C_DP(0)

CAP_0402-0.22UF,16V,10%,X7R,A3A  I72  C3M40
   1 DMI_CPU0_PCH_RX_DP<0>      A @BASEBOARD_FAB2_LIB.BASEBOARD_FAB2(SCH_1):DMI_CPU0_PCH_RX_DP(0)
   2 DMI_CPU0_PCH_RX_C_DP<0>      B @BASEBOARD_FAB2_LIB.BASEBOARD_FAB2(SCH_1):DMI_CPU0_PCH_RX_C_DP(0)

CAP_0402-0.22UF,16V,10%,X7R,A3A  I73  C3M37
   1 DMI_CPU0_PCH_RX_DP<1>      A @BASEBOARD_FAB2_LIB.BASEBOARD_FAB2(SCH_1):DMI_CPU0_PCH_RX_DP(1)
   2 DMI_CPU0_PCH_RX_C_DP<1>      B @BASEBOARD_FAB2_LIB.BASEBOARD_FAB2(SCH_1):DMI_CPU0_PCH_RX_C_DP(1)

CAP_0402-0.22UF,16V,10%,X7R,A3A  I74  C3N9
   1 DMI_CPU0_PCH_RX_DP<2>      A @BASEBOARD_FAB2_LIB.BASEBOARD_FAB2(SCH_1):DMI_CPU0_PCH_RX_DP(2)
   2 DMI_CPU0_PCH_RX_C_DP<2>      B @BASEBOARD_FAB2_LIB.BASEBOARD_FAB2(SCH_1):DMI_CPU0_PCH_RX_C_DP(2)

CAP_0402-0.22UF,16V,10%,X7R,A3A  I75  C3N8
   1 DMI_CPU0_PCH_RX_DP<3>      A @BASEBOARD_FAB2_LIB.BASEBOARD_FAB2(SCH_1):DMI_CPU0_PCH_RX_DP(3)
   2 DMI_CPU0_PCH_RX_C_DP<3>      B @BASEBOARD_FAB2_LIB.BASEBOARD_FAB2(SCH_1):DMI_CPU0_PCH_RX_C_DP(3)

CAP_0402-0.22UF,16V,10%,X7R,A3A  I76  C7C3
   1 DMI_CPU0_PCH_TX_DN<0>      A @BASEBOARD_FAB2_LIB.BASEBOARD_FAB2(SCH_1):DMI_CPU0_PCH_TX_DN(0)
   2 DMI_CPU0_PCH_TX_C_DN<0>      B @BASEBOARD_FAB2_LIB.BASEBOARD_FAB2(SCH_1):DMI_CPU0_PCH_TX_C_DN(0)

CAP_0402-0.22UF,16V,10%,X7R,A3A  I77  C7C1
   1 DMI_CPU0_PCH_TX_DN<1>      A @BASEBOARD_FAB2_LIB.BASEBOARD_FAB2(SCH_1):DMI_CPU0_PCH_TX_DN(1)
   2 DMI_CPU0_PCH_TX_C_DN<1>      B @BASEBOARD_FAB2_LIB.BASEBOARD_FAB2(SCH_1):DMI_CPU0_PCH_TX_C_DN(1)

CAP_0402-0.22UF,16V,10%,X7R,A3A  I78  C7B29
   1 DMI_CPU0_PCH_TX_DN<2>      A @BASEBOARD_FAB2_LIB.BASEBOARD_FAB2(SCH_1):DMI_CPU0_PCH_TX_DN(2)
   2 DMI_CPU0_PCH_TX_C_DN<2>      B @BASEBOARD_FAB2_LIB.BASEBOARD_FAB2(SCH_1):DMI_CPU0_PCH_TX_C_DN(2)

CAP_0402-0.22UF,16V,10%,X7R,A3A  I79  C7B26
   1 DMI_CPU0_PCH_TX_DN<3>      A @BASEBOARD_FAB2_LIB.BASEBOARD_FAB2(SCH_1):DMI_CPU0_PCH_TX_DN(3)
   2 DMI_CPU0_PCH_TX_C_DN<3>      B @BASEBOARD_FAB2_LIB.BASEBOARD_FAB2(SCH_1):DMI_CPU0_PCH_TX_C_DN(3)

CAP_0402-0.22UF,16V,10%,X7R,A3A  I80  C3M44
   1 DMI_CPU0_PCH_RX_DN<0>      A @BASEBOARD_FAB2_LIB.BASEBOARD_FAB2(SCH_1):DMI_CPU0_PCH_RX_DN(0)
   2 DMI_CPU0_PCH_RX_C_DN<0>      B @BASEBOARD_FAB2_LIB.BASEBOARD_FAB2(SCH_1):DMI_CPU0_PCH_RX_C_DN(0)

CAP_0402-0.22UF,16V,10%,X7R,A3A  I81  C3M41
   1 DMI_CPU0_PCH_RX_DN<1>      A @BASEBOARD_FAB2_LIB.BASEBOARD_FAB2(SCH_1):DMI_CPU0_PCH_RX_DN(1)
   2 DMI_CPU0_PCH_RX_C_DN<1>      B @BASEBOARD_FAB2_LIB.BASEBOARD_FAB2(SCH_1):DMI_CPU0_PCH_RX_C_DN(1)

CAP_0402-0.22UF,16V,10%,X7R,A3A  I82  C3M45
   1 DMI_CPU0_PCH_RX_DN<2>      A @BASEBOARD_FAB2_LIB.BASEBOARD_FAB2(SCH_1):DMI_CPU0_PCH_RX_DN(2)
   2 DMI_CPU0_PCH_RX_C_DN<2>      B @BASEBOARD_FAB2_LIB.BASEBOARD_FAB2(SCH_1):DMI_CPU0_PCH_RX_C_DN(2)

CAP_0402-0.22UF,16V,10%,X7R,A3A  I83  C3N13
   1 DMI_CPU0_PCH_RX_DN<3>      A @BASEBOARD_FAB2_LIB.BASEBOARD_FAB2(SCH_1):DMI_CPU0_PCH_RX_DN(3)
   2 DMI_CPU0_PCH_RX_C_DN<3>      B @BASEBOARD_FAB2_LIB.BASEBOARD_FAB2(SCH_1):DMI_CPU0_PCH_RX_C_DN(3)


DRAWING: @BASEBOARD_FAB2_LIB.BASEBOARD_FAB2(SCH_1):PAGE130 

CAP_0603-10UF,6.3V,20%,X6S,E15A  I2  C7D2
   1 P3V3_STBY      A @BASEBOARD_FAB2_LIB.BASEBOARD_FAB2(SCH_1):P3V3_STBY
   2    GND      B @BASEBOARD_FAB2_LIB.BASEBOARD_FAB2(SCH_1):GND

CAP_A_0402V-1.0UF,6.3V,10%,X6SA  I4  C2N26
   1 P3V3_STBY      A @BASEBOARD_FAB2_LIB.BASEBOARD_FAB2(SCH_1):P3V3_STBY
   2    GND      B @BASEBOARD_FAB2_LIB.BASEBOARD_FAB2(SCH_1):GND

CAP_A_0402V-1.0UF,6.3V,10%,X6SA  I7  C2N19
   1 P3V3_STBY      A @BASEBOARD_FAB2_LIB.BASEBOARD_FAB2(SCH_1):P3V3_STBY
   2    GND      B @BASEBOARD_FAB2_LIB.BASEBOARD_FAB2(SCH_1):GND

CAP_0603-10UF,6.3V,20%,X6S,E15A  I8  C2N24
   1 P3V3_STBY      A @BASEBOARD_FAB2_LIB.BASEBOARD_FAB2(SCH_1):P3V3_STBY
   2    GND      B @BASEBOARD_FAB2_LIB.BASEBOARD_FAB2(SCH_1):GND

CAP_0603-10UF,6.3V,20%,X6S,E15A  I9  C2N22
   1 P3V3_STBY      A @BASEBOARD_FAB2_LIB.BASEBOARD_FAB2(SCH_1):P3V3_STBY
   2    GND      B @BASEBOARD_FAB2_LIB.BASEBOARD_FAB2(SCH_1):GND

CAP_A_0402V-1.0UF,6.3V,10%,X6SA  I12  C2N20
   1 P3V3_STBY      A @BASEBOARD_FAB2_LIB.BASEBOARD_FAB2(SCH_1):P3V3_STBY
   2    GND      B @BASEBOARD_FAB2_LIB.BASEBOARD_FAB2(SCH_1):GND

CAP_0603-10UF,6.3V,20%,X6S,E15A  I15  C2N21
   1 P3V3_STBY      A @BASEBOARD_FAB2_LIB.BASEBOARD_FAB2(SCH_1):P3V3_STBY
   2    GND      B @BASEBOARD_FAB2_LIB.BASEBOARD_FAB2(SCH_1):GND

CAP_A_0402V-0.1UF,16V,10%,X7R,A  I16  C3N29
   1 A_PVCCRTC_EXT_CAP      A @BASEBOARD_FAB2_LIB.BASEBOARD_FAB2(SCH_1):A_PVCCRTC_EXT_CAP
   2    GND      B @BASEBOARD_FAB2_LIB.BASEBOARD_FAB2(SCH_1):GND

CAP_0603-10UF,6.3V,20%,X6S,E15A  I19  C8C3
   1 P3V3_STBY      A @BASEBOARD_FAB2_LIB.BASEBOARD_FAB2(SCH_1):P3V3_STBY
   2    GND      B @BASEBOARD_FAB2_LIB.BASEBOARD_FAB2(SCH_1):GND

CAP_0603-10UF,6.3V,20%,X6S,E15A  I20  C8C4
   1 P3V3_STBY      A @BASEBOARD_FAB2_LIB.BASEBOARD_FAB2(SCH_1):P3V3_STBY
   2    GND      B @BASEBOARD_FAB2_LIB.BASEBOARD_FAB2(SCH_1):GND

CAP_0603-10UF,6.3V,20%,X6S,E15A  I21  C8C5
   1 P3V3_STBY      A @BASEBOARD_FAB2_LIB.BASEBOARD_FAB2(SCH_1):P3V3_STBY
   2    GND      B @BASEBOARD_FAB2_LIB.BASEBOARD_FAB2(SCH_1):GND

CAP_0603-10UF,6.3V,20%,X6S,E15A  I22  C8C6
   1 P3V3_STBY      A @BASEBOARD_FAB2_LIB.BASEBOARD_FAB2(SCH_1):P3V3_STBY
   2    GND      B @BASEBOARD_FAB2_LIB.BASEBOARD_FAB2(SCH_1):GND

CAP_0603-10UF,6.3V,20%,X6S,E15A  I24  C2N23
   1 P3V3_STBY      A @BASEBOARD_FAB2_LIB.BASEBOARD_FAB2(SCH_1):P3V3_STBY
   2    GND      B @BASEBOARD_FAB2_LIB.BASEBOARD_FAB2(SCH_1):GND

CAP_0603-10UF,6.3V,20%,X6S,E15A  I25  C2N14
   1 P3V3_STBY      A @BASEBOARD_FAB2_LIB.BASEBOARD_FAB2(SCH_1):P3V3_STBY
   2    GND      B @BASEBOARD_FAB2_LIB.BASEBOARD_FAB2(SCH_1):GND

CAP_0603-10UF,6.3V,20%,X6S,E15A  I28  C2N17
   1 P3V3_STBY      A @BASEBOARD_FAB2_LIB.BASEBOARD_FAB2(SCH_1):P3V3_STBY
   2    GND      B @BASEBOARD_FAB2_LIB.BASEBOARD_FAB2(SCH_1):GND

CAP_A_0402V-1.0UF,6.3V,10%,X6SA  I29  C2N18
   1 P3V3_STBY      A @BASEBOARD_FAB2_LIB.BASEBOARD_FAB2(SCH_1):P3V3_STBY
   2    GND      B @BASEBOARD_FAB2_LIB.BASEBOARD_FAB2(SCH_1):GND

CAP_A_0603V-22.0UF,4V,20%,X6S,A  I30  C8B2
   1 P1V8_PCH_STBY      A @BASEBOARD_FAB2_LIB.BASEBOARD_FAB2(SCH_1):P1V8_PCH_STBY
   2    GND      B @BASEBOARD_FAB2_LIB.BASEBOARD_FAB2(SCH_1):GND

CAP_A_0603V-22.0UF,4V,20%,X6S,A  I32  C8B3
   1 P1V8_PCH_STBY      A @BASEBOARD_FAB2_LIB.BASEBOARD_FAB2(SCH_1):P1V8_PCH_STBY
   2    GND      B @BASEBOARD_FAB2_LIB.BASEBOARD_FAB2(SCH_1):GND

CAP_A_0402V-1.0UF,6.3V,10%,X6SA  I34  C2N25
   1 P3V3_STBY      A @BASEBOARD_FAB2_LIB.BASEBOARD_FAB2(SCH_1):P3V3_STBY
   2    GND      B @BASEBOARD_FAB2_LIB.BASEBOARD_FAB2(SCH_1):GND

CAP_A_0402V-1.0UF,6.3V,10%,X6SA  I37  C2M16
   1 P3V3_STBY      A @BASEBOARD_FAB2_LIB.BASEBOARD_FAB2(SCH_1):P3V3_STBY
   2    GND      B @BASEBOARD_FAB2_LIB.BASEBOARD_FAB2(SCH_1):GND

CAP_A_0603V-22.0UF,4V,20%,X6S,A  I38  C7D3
   1 P1V8_PCH_STBY      A @BASEBOARD_FAB2_LIB.BASEBOARD_FAB2(SCH_1):P1V8_PCH_STBY
   2    GND      B @BASEBOARD_FAB2_LIB.BASEBOARD_FAB2(SCH_1):GND

CAP_A_0603V-22.0UF,4V,20%,X6S,A  I39  C8B4
   1 P1V8_PCH_STBY      A @BASEBOARD_FAB2_LIB.BASEBOARD_FAB2(SCH_1):P1V8_PCH_STBY
   2    GND      B @BASEBOARD_FAB2_LIB.BASEBOARD_FAB2(SCH_1):GND

CAP_A_0603V-22.0UF,4V,20%,X6S,A  I41  C8B1
   1 P1V8_PCH_STBY      A @BASEBOARD_FAB2_LIB.BASEBOARD_FAB2(SCH_1):P1V8_PCH_STBY
   2    GND      B @BASEBOARD_FAB2_LIB.BASEBOARD_FAB2(SCH_1):GND

CAP_A_0402V-1.0UF,6.3V,10%,X6SA  I42  C3N23
   1 P3V3_STBY      A @BASEBOARD_FAB2_LIB.BASEBOARD_FAB2(SCH_1):P3V3_STBY
   2    GND      B @BASEBOARD_FAB2_LIB.BASEBOARD_FAB2(SCH_1):GND

CAP_A_0603V-22.0UF,4V,20%,X6S,A  I43  C2M1
   1 P1V8_PCH_STBY      A @BASEBOARD_FAB2_LIB.BASEBOARD_FAB2(SCH_1):P1V8_PCH_STBY
   2    GND      B @BASEBOARD_FAB2_LIB.BASEBOARD_FAB2(SCH_1):GND

CAP_A_0603V-22.0UF,4V,20%,X6S,A  I45  C2M2
   1 P1V8_PCH_STBY      A @BASEBOARD_FAB2_LIB.BASEBOARD_FAB2(SCH_1):P1V8_PCH_STBY
   2    GND      B @BASEBOARD_FAB2_LIB.BASEBOARD_FAB2(SCH_1):GND

CAP_A_0402V-1.0UF,6.3V,10%,X6SA  I47  C2N15
   1 P1V8_PCH_STBY      A @BASEBOARD_FAB2_LIB.BASEBOARD_FAB2(SCH_1):P1V8_PCH_STBY
   2    GND      B @BASEBOARD_FAB2_LIB.BASEBOARD_FAB2(SCH_1):GND

CAP_A_0402V-1.0UF,6.3V,10%,X6SA  I49  C3N21
   1 P1V8_PCH_STBY      A @BASEBOARD_FAB2_LIB.BASEBOARD_FAB2(SCH_1):P1V8_PCH_STBY
   2    GND      B @BASEBOARD_FAB2_LIB.BASEBOARD_FAB2(SCH_1):GND

CAP_A_0402V-1.0UF,6.3V,10%,X6SA  I50  C3N25
   1 P1V8_PCH_STBY      A @BASEBOARD_FAB2_LIB.BASEBOARD_FAB2(SCH_1):P1V8_PCH_STBY
   2    GND      B @BASEBOARD_FAB2_LIB.BASEBOARD_FAB2(SCH_1):GND

CAP_A_0402V-1.0UF,6.3V,10%,X6SA  I52  C2N16
   1 P1V8_PCH_STBY      A @BASEBOARD_FAB2_LIB.BASEBOARD_FAB2(SCH_1):P1V8_PCH_STBY
   2    GND      B @BASEBOARD_FAB2_LIB.BASEBOARD_FAB2(SCH_1):GND

CAP_A_0402V-1.0UF,6.3V,10%,X6SA  I53  C3N22
   1 P1V8_PCH_STBY      A @BASEBOARD_FAB2_LIB.BASEBOARD_FAB2(SCH_1):P1V8_PCH_STBY
   2    GND      B @BASEBOARD_FAB2_LIB.BASEBOARD_FAB2(SCH_1):GND


DRAWING: @BASEBOARD_FAB2_LIB.BASEBOARD_FAB2(SCH_1):PAGE131 

CAP_A_0603V-22.0UF,4V,20%,X6S,A  I1  C7B15
   1 P1V05_PCH_STBY      A @BASEBOARD_FAB2_LIB.BASEBOARD_FAB2(SCH_1):P1V05_PCH_STBY
   2    GND      B @BASEBOARD_FAB2_LIB.BASEBOARD_FAB2(SCH_1):GND

CAP_A_0603V-22.0UF,4V,20%,X6S,A  I2  C7B19
   1 P1V05_PCH_STBY      A @BASEBOARD_FAB2_LIB.BASEBOARD_FAB2(SCH_1):P1V05_PCH_STBY
   2    GND      B @BASEBOARD_FAB2_LIB.BASEBOARD_FAB2(SCH_1):GND

CAP_A_0603V-22.0UF,4V,20%,X6S,A  I3  C7B16
   1 P1V05_PCH_STBY      A @BASEBOARD_FAB2_LIB.BASEBOARD_FAB2(SCH_1):P1V05_PCH_STBY
   2    GND      B @BASEBOARD_FAB2_LIB.BASEBOARD_FAB2(SCH_1):GND

CAP_A_0603V-22.0UF,4V,20%,X6S,A  I4  C7B21
   1 P1V05_PCH_STBY      A @BASEBOARD_FAB2_LIB.BASEBOARD_FAB2(SCH_1):P1V05_PCH_STBY
   2    GND      B @BASEBOARD_FAB2_LIB.BASEBOARD_FAB2(SCH_1):GND

CAP_A_0603V-22.0UF,4V,20%,X6S,A  I6  C7B20
   1 P1V05_PCH_STBY      A @BASEBOARD_FAB2_LIB.BASEBOARD_FAB2(SCH_1):P1V05_PCH_STBY
   2    GND      B @BASEBOARD_FAB2_LIB.BASEBOARD_FAB2(SCH_1):GND

CAP_A_0603V-22.0UF,4V,20%,X6S,A  I7  C7B23
   1 P1V05_PCH_STBY      A @BASEBOARD_FAB2_LIB.BASEBOARD_FAB2(SCH_1):P1V05_PCH_STBY
   2    GND      B @BASEBOARD_FAB2_LIB.BASEBOARD_FAB2(SCH_1):GND

CAP_A_0603V-22.0UF,4V,20%,X6S,A  I8  C8B10
   1 P1V05_PCH_STBY      A @BASEBOARD_FAB2_LIB.BASEBOARD_FAB2(SCH_1):P1V05_PCH_STBY
   2    GND      B @BASEBOARD_FAB2_LIB.BASEBOARD_FAB2(SCH_1):GND

CAP_A_0603V-22.0UF,4V,20%,X6S,A  I10  C7B22
   1 P1V05_PCH_STBY      A @BASEBOARD_FAB2_LIB.BASEBOARD_FAB2(SCH_1):P1V05_PCH_STBY
   2    GND      B @BASEBOARD_FAB2_LIB.BASEBOARD_FAB2(SCH_1):GND

CAP_A_0603V-22.0UF,4V,20%,X6S,A  I11  C7B24
   1 P1V05_PCH_STBY      A @BASEBOARD_FAB2_LIB.BASEBOARD_FAB2(SCH_1):P1V05_PCH_STBY
   2    GND      B @BASEBOARD_FAB2_LIB.BASEBOARD_FAB2(SCH_1):GND

CAP_A_0603V-22.0UF,4V,20%,X6S,A  I12  C7B18
   1 P1V05_PCH_STBY      A @BASEBOARD_FAB2_LIB.BASEBOARD_FAB2(SCH_1):P1V05_PCH_STBY
   2    GND      B @BASEBOARD_FAB2_LIB.BASEBOARD_FAB2(SCH_1):GND

CAP_A_0603V-22.0UF,4V,20%,X6S,A  I14  C8B9
   1 P1V05_PCH_STBY      A @BASEBOARD_FAB2_LIB.BASEBOARD_FAB2(SCH_1):P1V05_PCH_STBY
   2    GND      B @BASEBOARD_FAB2_LIB.BASEBOARD_FAB2(SCH_1):GND

CAP_A_0603V-22.0UF,4V,20%,X6S,A  I15  C8B11
   1 P1V05_PCH_STBY      A @BASEBOARD_FAB2_LIB.BASEBOARD_FAB2(SCH_1):P1V05_PCH_STBY
   2    GND      B @BASEBOARD_FAB2_LIB.BASEBOARD_FAB2(SCH_1):GND

CAP_A_0603V-22.0UF,4V,20%,X6S,A  I16  C8B14
   1 P1V05_PCH_STBY      A @BASEBOARD_FAB2_LIB.BASEBOARD_FAB2(SCH_1):P1V05_PCH_STBY
   2    GND      B @BASEBOARD_FAB2_LIB.BASEBOARD_FAB2(SCH_1):GND

CAP_A_0603V-22.0UF,4V,20%,X6S,A  I18  C7B17
   1 P1V05_PCH_STBY      A @BASEBOARD_FAB2_LIB.BASEBOARD_FAB2(SCH_1):P1V05_PCH_STBY
   2    GND      B @BASEBOARD_FAB2_LIB.BASEBOARD_FAB2(SCH_1):GND

CAP_A_0603V-22.0UF,4V,20%,X6S,A  I20  C8B13
   1 P1V05_PCH_STBY      A @BASEBOARD_FAB2_LIB.BASEBOARD_FAB2(SCH_1):P1V05_PCH_STBY
   2    GND      B @BASEBOARD_FAB2_LIB.BASEBOARD_FAB2(SCH_1):GND

CAP_0805-47UF,4V,20%,X6S,C9533A  I22  C8B16
   1 P1V05_PCH_STBY      A @BASEBOARD_FAB2_LIB.BASEBOARD_FAB2(SCH_1):P1V05_PCH_STBY
   2    GND      B @BASEBOARD_FAB2_LIB.BASEBOARD_FAB2(SCH_1):GND

CAP_0805-47UF,4V,20%,X6S,C9533A  I24  C8B15
   1 P1V05_PCH_STBY      A @BASEBOARD_FAB2_LIB.BASEBOARD_FAB2(SCH_1):P1V05_PCH_STBY
   2    GND      B @BASEBOARD_FAB2_LIB.BASEBOARD_FAB2(SCH_1):GND

CAP_A_0402V-1.0UF,6.3V,10%,X6SA  I27  C2M22
   1 P1V05_PCH_STBY      A @BASEBOARD_FAB2_LIB.BASEBOARD_FAB2(SCH_1):P1V05_PCH_STBY
   2    GND      B @BASEBOARD_FAB2_LIB.BASEBOARD_FAB2(SCH_1):GND

CAP_A_0402V-1.0UF,6.3V,10%,X6SA  I28  C2M21
   1 P1V05_PCH_STBY      A @BASEBOARD_FAB2_LIB.BASEBOARD_FAB2(SCH_1):P1V05_PCH_STBY
   2    GND      B @BASEBOARD_FAB2_LIB.BASEBOARD_FAB2(SCH_1):GND

CAP_A_0402V-1.0UF,6.3V,10%,X6SA  I29  C2M18
   1 P1V05_PCH_STBY      A @BASEBOARD_FAB2_LIB.BASEBOARD_FAB2(SCH_1):P1V05_PCH_STBY
   2    GND      B @BASEBOARD_FAB2_LIB.BASEBOARD_FAB2(SCH_1):GND

CAP_A_0402V-1.0UF,6.3V,10%,X6SA  I31  C2M19
   1 P1V05_PCH_STBY      A @BASEBOARD_FAB2_LIB.BASEBOARD_FAB2(SCH_1):P1V05_PCH_STBY
   2    GND      B @BASEBOARD_FAB2_LIB.BASEBOARD_FAB2(SCH_1):GND

CAP_A_0402V-1.0UF,6.3V,10%,X6SA  I32  C3M38
   1 P1V05_PCH_STBY      A @BASEBOARD_FAB2_LIB.BASEBOARD_FAB2(SCH_1):P1V05_PCH_STBY
   2    GND      B @BASEBOARD_FAB2_LIB.BASEBOARD_FAB2(SCH_1):GND

CAP_0805-47UF,4V,20%,X6S,C9533A  I34  C2M17
   1 P1V05_PCH_STBY      A @BASEBOARD_FAB2_LIB.BASEBOARD_FAB2(SCH_1):P1V05_PCH_STBY
   2    GND      B @BASEBOARD_FAB2_LIB.BASEBOARD_FAB2(SCH_1):GND

CAP_0805-47UF,4V,20%,X6S,C9533A  I35  C2M11
   1 P1V05_PCH_STBY      A @BASEBOARD_FAB2_LIB.BASEBOARD_FAB2(SCH_1):P1V05_PCH_STBY
   2    GND      B @BASEBOARD_FAB2_LIB.BASEBOARD_FAB2(SCH_1):GND

CAP_0805-47UF,4V,20%,X6S,C9533A  I37  C8A13
   1 P1V05_PCH_STBY      A @BASEBOARD_FAB2_LIB.BASEBOARD_FAB2(SCH_1):P1V05_PCH_STBY
   2    GND      B @BASEBOARD_FAB2_LIB.BASEBOARD_FAB2(SCH_1):GND

CAP_A_0402V-1.0UF,6.3V,10%,X6SA  I39  C2M20
   1 P1V05_PCH_STBY      A @BASEBOARD_FAB2_LIB.BASEBOARD_FAB2(SCH_1):P1V05_PCH_STBY
   2    GND      B @BASEBOARD_FAB2_LIB.BASEBOARD_FAB2(SCH_1):GND

CAP_A_0402V-1.0UF,6.3V,10%,X6SA  I40  C2N13
   1 P1V05_PCH_STBY      A @BASEBOARD_FAB2_LIB.BASEBOARD_FAB2(SCH_1):P1V05_PCH_STBY
   2    GND      B @BASEBOARD_FAB2_LIB.BASEBOARD_FAB2(SCH_1):GND

CAP_A_0402V-1.0UF,6.3V,10%,X6SA  I41  C2N2
   1 P1V05_PCH_STBY      A @BASEBOARD_FAB2_LIB.BASEBOARD_FAB2(SCH_1):P1V05_PCH_STBY
   2    GND      B @BASEBOARD_FAB2_LIB.BASEBOARD_FAB2(SCH_1):GND

CAP_A_0402V-1.0UF,6.3V,10%,X6SA  I42  C3M43
   1 P1V05_PCH_STBY      A @BASEBOARD_FAB2_LIB.BASEBOARD_FAB2(SCH_1):P1V05_PCH_STBY
   2    GND      B @BASEBOARD_FAB2_LIB.BASEBOARD_FAB2(SCH_1):GND

CAP_A_0402V-1.0UF,6.3V,10%,X6SA  I43  C2N7
   1 P1V05_PCH_STBY      A @BASEBOARD_FAB2_LIB.BASEBOARD_FAB2(SCH_1):P1V05_PCH_STBY
   2    GND      B @BASEBOARD_FAB2_LIB.BASEBOARD_FAB2(SCH_1):GND

CAP_A_0402V-1.0UF,6.3V,10%,X6SA  I44  C3M39
   1 P1V05_PCH_STBY      A @BASEBOARD_FAB2_LIB.BASEBOARD_FAB2(SCH_1):P1V05_PCH_STBY
   2    GND      B @BASEBOARD_FAB2_LIB.BASEBOARD_FAB2(SCH_1):GND

CAP_A_0402V-1.0UF,6.3V,10%,X6SA  I45  C3M42
   1 P1V05_PCH_STBY      A @BASEBOARD_FAB2_LIB.BASEBOARD_FAB2(SCH_1):P1V05_PCH_STBY
   2    GND      B @BASEBOARD_FAB2_LIB.BASEBOARD_FAB2(SCH_1):GND

CAP_A_0402V-1.0UF,6.3V,10%,X6SA  I47  C2N8
   1 P1V05_PCH_STBY      A @BASEBOARD_FAB2_LIB.BASEBOARD_FAB2(SCH_1):P1V05_PCH_STBY
   2    GND      B @BASEBOARD_FAB2_LIB.BASEBOARD_FAB2(SCH_1):GND

CAP_A_0603V-22.0UF,4V,20%,X6S,A  I48  C2M13
   1 P1V05_PCH_STBY      A @BASEBOARD_FAB2_LIB.BASEBOARD_FAB2(SCH_1):P1V05_PCH_STBY
   2    GND      B @BASEBOARD_FAB2_LIB.BASEBOARD_FAB2(SCH_1):GND

CAP_A_0603V-22.0UF,4V,20%,X6S,A  I50  C2N10
   1 P1V05_PCH_STBY      A @BASEBOARD_FAB2_LIB.BASEBOARD_FAB2(SCH_1):P1V05_PCH_STBY
   2    GND      B @BASEBOARD_FAB2_LIB.BASEBOARD_FAB2(SCH_1):GND

CAP_A_0603V-22.0UF,4V,20%,X6S,A  I52  C2M12
   1 P1V05_PCH_STBY      A @BASEBOARD_FAB2_LIB.BASEBOARD_FAB2(SCH_1):P1V05_PCH_STBY
   2    GND      B @BASEBOARD_FAB2_LIB.BASEBOARD_FAB2(SCH_1):GND


DRAWING: @BASEBOARD_FAB2_LIB.BASEBOARD_FAB2(SCH_1):PAGE132 

CAP_A_0603V-22.0UF,4V,20%,X6S,A  I1  C3L25
   1 PVNN_PCH_STBY      A @BASEBOARD_FAB2_LIB.BASEBOARD_FAB2(SCH_1):PVNN_PCH_STBY
   2    GND      B @BASEBOARD_FAB2_LIB.BASEBOARD_FAB2(SCH_1):GND

CAP_A_0603V-22.0UF,4V,20%,X6S,A  I2  C3M7
   1 PVNN_PCH_STBY      A @BASEBOARD_FAB2_LIB.BASEBOARD_FAB2(SCH_1):PVNN_PCH_STBY
   2    GND      B @BASEBOARD_FAB2_LIB.BASEBOARD_FAB2(SCH_1):GND

CAP_A_0603V-22.0UF,4V,20%,X6S,A  I3  C3L26
   1 PVNN_PCH_STBY      A @BASEBOARD_FAB2_LIB.BASEBOARD_FAB2(SCH_1):PVNN_PCH_STBY
   2    GND      B @BASEBOARD_FAB2_LIB.BASEBOARD_FAB2(SCH_1):GND

CAP_A_0603V-22.0UF,4V,20%,X6S,A  I4  C3L27
   1 PVNN_PCH_STBY      A @BASEBOARD_FAB2_LIB.BASEBOARD_FAB2(SCH_1):PVNN_PCH_STBY
   2    GND      B @BASEBOARD_FAB2_LIB.BASEBOARD_FAB2(SCH_1):GND

CAP_A_0603V-22.0UF,4V,20%,X6S,A  I6  C3M6
   1 PVNN_PCH_STBY      A @BASEBOARD_FAB2_LIB.BASEBOARD_FAB2(SCH_1):PVNN_PCH_STBY
   2    GND      B @BASEBOARD_FAB2_LIB.BASEBOARD_FAB2(SCH_1):GND

CAP_A_0603V-22.0UF,4V,20%,X6S,A  I7  C7C9
   1 PVNN_PCH_STBY      A @BASEBOARD_FAB2_LIB.BASEBOARD_FAB2(SCH_1):PVNN_PCH_STBY
   2    GND      B @BASEBOARD_FAB2_LIB.BASEBOARD_FAB2(SCH_1):GND

CAP_A_0603V-22.0UF,4V,20%,X6S,A  I8  C3N27
   1 PVNN_PCH_STBY      A @BASEBOARD_FAB2_LIB.BASEBOARD_FAB2(SCH_1):PVNN_PCH_STBY
   2    GND      B @BASEBOARD_FAB2_LIB.BASEBOARD_FAB2(SCH_1):GND

CAP_A_0603V-22.0UF,4V,20%,X6S,A  I9  C3N30
   1 PVNN_PCH_STBY      A @BASEBOARD_FAB2_LIB.BASEBOARD_FAB2(SCH_1):PVNN_PCH_STBY
   2    GND      B @BASEBOARD_FAB2_LIB.BASEBOARD_FAB2(SCH_1):GND

CAP_A_0603V-22.0UF,4V,20%,X6S,A  I11  C7A36
   1 PVNN_PCH_STBY      A @BASEBOARD_FAB2_LIB.BASEBOARD_FAB2(SCH_1):PVNN_PCH_STBY
   2    GND      B @BASEBOARD_FAB2_LIB.BASEBOARD_FAB2(SCH_1):GND

CAP_A_0603V-22.0UF,4V,20%,X6S,A  I12  C3N12
   1 PVNN_PCH_STBY      A @BASEBOARD_FAB2_LIB.BASEBOARD_FAB2(SCH_1):PVNN_PCH_STBY
   2    GND      B @BASEBOARD_FAB2_LIB.BASEBOARD_FAB2(SCH_1):GND

CAP_A_0603V-22.0UF,4V,20%,X6S,A  I13  C3N10
   1 PVNN_PCH_STBY      A @BASEBOARD_FAB2_LIB.BASEBOARD_FAB2(SCH_1):PVNN_PCH_STBY
   2    GND      B @BASEBOARD_FAB2_LIB.BASEBOARD_FAB2(SCH_1):GND

CAP_A_0603V-22.0UF,4V,20%,X6S,A  I16  C3N24
   1 PVNN_PCH_STBY      A @BASEBOARD_FAB2_LIB.BASEBOARD_FAB2(SCH_1):PVNN_PCH_STBY
   2    GND      B @BASEBOARD_FAB2_LIB.BASEBOARD_FAB2(SCH_1):GND

CAP_A_0603V-22.0UF,4V,20%,X6S,A  I17  C3N28
   1 PVNN_PCH_STBY      A @BASEBOARD_FAB2_LIB.BASEBOARD_FAB2(SCH_1):PVNN_PCH_STBY
   2    GND      B @BASEBOARD_FAB2_LIB.BASEBOARD_FAB2(SCH_1):GND

CAP_A_0603V-22.0UF,4V,20%,X6S,A  I19  C3N11
   1 PVNN_PCH_STBY      A @BASEBOARD_FAB2_LIB.BASEBOARD_FAB2(SCH_1):PVNN_PCH_STBY
   2    GND      B @BASEBOARD_FAB2_LIB.BASEBOARD_FAB2(SCH_1):GND

CAP_A_0603V-22.0UF,4V,20%,X6S,A  I20  C3N31
   1 PVNN_PCH_STBY      A @BASEBOARD_FAB2_LIB.BASEBOARD_FAB2(SCH_1):PVNN_PCH_STBY
   2    GND      B @BASEBOARD_FAB2_LIB.BASEBOARD_FAB2(SCH_1):GND

CAP_0805-47UF,4V,20%,X6S,C9533A  I23  C7A33
   1 PVNN_PCH_STBY      A @BASEBOARD_FAB2_LIB.BASEBOARD_FAB2(SCH_1):PVNN_PCH_STBY
   2    GND      B @BASEBOARD_FAB2_LIB.BASEBOARD_FAB2(SCH_1):GND

CAP_0805-47UF,4V,20%,X6S,C9533A  I24  C7B4
   1 PVNN_PCH_STBY      A @BASEBOARD_FAB2_LIB.BASEBOARD_FAB2(SCH_1):PVNN_PCH_STBY
   2    GND      B @BASEBOARD_FAB2_LIB.BASEBOARD_FAB2(SCH_1):GND

CAP_A_0402V-1.0UF,6.3V,10%,X6SA  I26  C2N9
   1 PVNN_PCH_STBY      A @BASEBOARD_FAB2_LIB.BASEBOARD_FAB2(SCH_1):PVNN_PCH_STBY
   2    GND      B @BASEBOARD_FAB2_LIB.BASEBOARD_FAB2(SCH_1):GND

CAP_A_0402V-1.0UF,6.3V,10%,X6SA  I27  C2N3
   1 PVNN_PCH_STBY      A @BASEBOARD_FAB2_LIB.BASEBOARD_FAB2(SCH_1):PVNN_PCH_STBY
   2    GND      B @BASEBOARD_FAB2_LIB.BASEBOARD_FAB2(SCH_1):GND

CAP_A_0402V-1.0UF,6.3V,10%,X6SA  I28  C2N4
   1 PVNN_PCH_STBY      A @BASEBOARD_FAB2_LIB.BASEBOARD_FAB2(SCH_1):PVNN_PCH_STBY
   2    GND      B @BASEBOARD_FAB2_LIB.BASEBOARD_FAB2(SCH_1):GND

CAP_A_0402V-1.0UF,6.3V,10%,X6SA  I29  C2N12
   1 PVNN_PCH_STBY      A @BASEBOARD_FAB2_LIB.BASEBOARD_FAB2(SCH_1):PVNN_PCH_STBY
   2    GND      B @BASEBOARD_FAB2_LIB.BASEBOARD_FAB2(SCH_1):GND

CAP_A_0402V-1.0UF,6.3V,10%,X6SA  I30  C2N11
   1 PVNN_PCH_STBY      A @BASEBOARD_FAB2_LIB.BASEBOARD_FAB2(SCH_1):PVNN_PCH_STBY
   2    GND      B @BASEBOARD_FAB2_LIB.BASEBOARD_FAB2(SCH_1):GND

CAP_A_0402V-1.0UF,6.3V,10%,X6SA  I31  C3N19
   1 PVNN_PCH_STBY      A @BASEBOARD_FAB2_LIB.BASEBOARD_FAB2(SCH_1):PVNN_PCH_STBY
   2    GND      B @BASEBOARD_FAB2_LIB.BASEBOARD_FAB2(SCH_1):GND

CAP_A_0402V-1.0UF,6.3V,10%,X6SA  I32  C3N3
   1 PVNN_PCH_STBY      A @BASEBOARD_FAB2_LIB.BASEBOARD_FAB2(SCH_1):PVNN_PCH_STBY
   2    GND      B @BASEBOARD_FAB2_LIB.BASEBOARD_FAB2(SCH_1):GND

CAP_A_0402V-1.0UF,6.3V,10%,X6SA  I34  C3N1
   1 PVNN_PCH_STBY      A @BASEBOARD_FAB2_LIB.BASEBOARD_FAB2(SCH_1):PVNN_PCH_STBY
   2    GND      B @BASEBOARD_FAB2_LIB.BASEBOARD_FAB2(SCH_1):GND

CAP_A_0402V-1.0UF,6.3V,10%,X6SA  I35  C3N7
   1 PVNN_PCH_STBY      A @BASEBOARD_FAB2_LIB.BASEBOARD_FAB2(SCH_1):PVNN_PCH_STBY
   2    GND      B @BASEBOARD_FAB2_LIB.BASEBOARD_FAB2(SCH_1):GND

CAP_A_0402V-1.0UF,6.3V,10%,X6SA  I36  C3N16
   1 PVNN_PCH_STBY      A @BASEBOARD_FAB2_LIB.BASEBOARD_FAB2(SCH_1):PVNN_PCH_STBY
   2    GND      B @BASEBOARD_FAB2_LIB.BASEBOARD_FAB2(SCH_1):GND

CAP_0805-47UF,4V,20%,X6S,C9533A  I38  C7A32
   1 PVNN_PCH_STBY      A @BASEBOARD_FAB2_LIB.BASEBOARD_FAB2(SCH_1):PVNN_PCH_STBY
   2    GND      B @BASEBOARD_FAB2_LIB.BASEBOARD_FAB2(SCH_1):GND

CAP_0805-47UF,4V,20%,X6S,C9533A  I40  C7A31
   1 PVNN_PCH_STBY      A @BASEBOARD_FAB2_LIB.BASEBOARD_FAB2(SCH_1):PVNN_PCH_STBY
   2    GND      B @BASEBOARD_FAB2_LIB.BASEBOARD_FAB2(SCH_1):GND

CAP_A_0402V-1.0UF,6.3V,10%,X6SA  I42  C3N18
   1 PVNN_PCH_STBY      A @BASEBOARD_FAB2_LIB.BASEBOARD_FAB2(SCH_1):PVNN_PCH_STBY
   2    GND      B @BASEBOARD_FAB2_LIB.BASEBOARD_FAB2(SCH_1):GND

CAP_A_0402V-1.0UF,6.3V,10%,X6SA  I43  C3N2
   1 PVNN_PCH_STBY      A @BASEBOARD_FAB2_LIB.BASEBOARD_FAB2(SCH_1):PVNN_PCH_STBY
   2    GND      B @BASEBOARD_FAB2_LIB.BASEBOARD_FAB2(SCH_1):GND

CAP_A_0402V-1.0UF,6.3V,10%,X6SA  I44  C3N6
   1 PVNN_PCH_STBY      A @BASEBOARD_FAB2_LIB.BASEBOARD_FAB2(SCH_1):PVNN_PCH_STBY
   2    GND      B @BASEBOARD_FAB2_LIB.BASEBOARD_FAB2(SCH_1):GND

CAP_A_0402V-1.0UF,6.3V,10%,X6SA  I45  C3N17
   1 PVNN_PCH_STBY      A @BASEBOARD_FAB2_LIB.BASEBOARD_FAB2(SCH_1):PVNN_PCH_STBY
   2    GND      B @BASEBOARD_FAB2_LIB.BASEBOARD_FAB2(SCH_1):GND

CAP_A_0402V-1.0UF,6.3V,10%,X6SA  I46  C3N4
   1 PVNN_PCH_STBY      A @BASEBOARD_FAB2_LIB.BASEBOARD_FAB2(SCH_1):PVNN_PCH_STBY
   2    GND      B @BASEBOARD_FAB2_LIB.BASEBOARD_FAB2(SCH_1):GND

CAP_A_0402V-1.0UF,6.3V,10%,X6SA  I48  C3N5
   1 PVNN_PCH_STBY      A @BASEBOARD_FAB2_LIB.BASEBOARD_FAB2(SCH_1):PVNN_PCH_STBY
   2    GND      B @BASEBOARD_FAB2_LIB.BASEBOARD_FAB2(SCH_1):GND

CAP_A_0402V-1.0UF,6.3V,10%,X6SA  I49  C3N15
   1 PVNN_PCH_STBY      A @BASEBOARD_FAB2_LIB.BASEBOARD_FAB2(SCH_1):PVNN_PCH_STBY
   2    GND      B @BASEBOARD_FAB2_LIB.BASEBOARD_FAB2(SCH_1):GND

CAP_A_0402V-1.0UF,6.3V,10%,X6SA  I51  C3N20
   1 PVNN_PCH_STBY      A @BASEBOARD_FAB2_LIB.BASEBOARD_FAB2(SCH_1):PVNN_PCH_STBY
   2    GND      B @BASEBOARD_FAB2_LIB.BASEBOARD_FAB2(SCH_1):GND

CAP_A_0603V-22.0UF,4V,20%,X6S,A  I52  C3L23
   1 PVNN_PCH_STBY      A @BASEBOARD_FAB2_LIB.BASEBOARD_FAB2(SCH_1):PVNN_PCH_STBY
   2    GND      B @BASEBOARD_FAB2_LIB.BASEBOARD_FAB2(SCH_1):GND

CAP_A_0603V-22.0UF,4V,20%,X6S,A  I54  C3L22
   1 PVNN_PCH_STBY      A @BASEBOARD_FAB2_LIB.BASEBOARD_FAB2(SCH_1):PVNN_PCH_STBY
   2    GND      B @BASEBOARD_FAB2_LIB.BASEBOARD_FAB2(SCH_1):GND

CAP_A_0603V-22.0UF,4V,20%,X6S,A  I56  C3L24
   1 PVNN_PCH_STBY      A @BASEBOARD_FAB2_LIB.BASEBOARD_FAB2(SCH_1):PVNN_PCH_STBY
   2    GND      B @BASEBOARD_FAB2_LIB.BASEBOARD_FAB2(SCH_1):GND


DRAWING: @BASEBOARD_FAB2_LIB.BASEBOARD_FAB2(SCH_1):PAGE133 

RES_0402-2.0K,1%,1/16W,CHIP,G2A  I120  R3N3
   1    GND      A @BASEBOARD_FAB2_LIB.BASEBOARD_FAB2(SCH_1):GND
   2 PWRGD_PCH_PWROK      B @BASEBOARD_FAB2_LIB.BASEBOARD_FAB2(SCH_1):PWRGD_PCH_PWROK

RES_0402-10.0K,1%,1/16W,EMPTY,A  I122  R2N12
   1    GND      A @BASEBOARD_FAB2_LIB.BASEBOARD_FAB2(SCH_1):GND
   2 PWRGD_SYS_PWROK      B @BASEBOARD_FAB2_LIB.BASEBOARD_FAB2(SCH_1):PWRGD_SYS_PWROK

RES_0402-10.0K,1%,1/16W,CHIP,GA  I200  R7D8
   1 P3V3_STBY      A @BASEBOARD_FAB2_LIB.BASEBOARD_FAB2(SCH_1):P3V3_STBY
   2 PU_LPC_CLKRUN_N      B @BASEBOARD_FAB2_LIB.BASEBOARD_FAB2(SCH_1):PU_LPC_CLKRUN_N

RES_0402-10.0K,1%,1/16W,CHIP,GA  I202  R7D10
   1 P3V3_STBY      A @BASEBOARD_FAB2_LIB.BASEBOARD_FAB2(SCH_1):P3V3_STBY
   2 PU_LPC_PME_N      B @BASEBOARD_FAB2_LIB.BASEBOARD_FAB2(SCH_1):PU_LPC_PME_N

RES_0402-10.0K,1%,1/16W,CHIP,GA  I237  R7D12
   1 P3V3_STBY      A @BASEBOARD_FAB2_LIB.BASEBOARD_FAB2(SCH_1):P3V3_STBY
   2 FM_OCP_MEZZA_PRES_N      B @BASEBOARD_FAB2_LIB.BASEBOARD_FAB2(SCH_1):FM_OCP_MEZZA_PRES_N

RES_0402-4.75K,1%,1/16W,CHIP,GA  I243  R7D3
   1 P3V3_STBY      A @BASEBOARD_FAB2_LIB.BASEBOARD_FAB2(SCH_1):P3V3_STBY
   2 IRQ_LPC_SERIRQ_N      B @BASEBOARD_FAB2_LIB.BASEBOARD_FAB2(SCH_1):IRQ_LPC_SERIRQ_N

RES_0402-10.0K,1%,1/16W,CHIP,GA  I245  R7D4
   1 P3V3_STBY      A @BASEBOARD_FAB2_LIB.BASEBOARD_FAB2(SCH_1):P3V3_STBY
   2 PU_IRQ_PCH_SCI_WHEA_N      B @BASEBOARD_FAB2_LIB.BASEBOARD_FAB2(SCH_1):PU_IRQ_PCH_SCI_WHEA_N

RES_0402-10.0K,1%,1/16W,CHIP,GA  I247  R2N16
   1 P3V3_STBY      A @BASEBOARD_FAB2_LIB.BASEBOARD_FAB2(SCH_1):P3V3_STBY
   2 PU_IRQ_VRALERT_N      B @BASEBOARD_FAB2_LIB.BASEBOARD_FAB2(SCH_1):PU_IRQ_VRALERT_N

RES_0402-1.00K,1%,1/16W,CHIP,GA  I258  R2R5
   1 P3V3_STBY      A @BASEBOARD_FAB2_LIB.BASEBOARD_FAB2(SCH_1):P3V3_STBY
   2 FM_PCH_PLD_DATA      B @BASEBOARD_FAB2_LIB.BASEBOARD_FAB2(SCH_1):FM_PCH_PLD_DATA

RES_0402-10.0K,1%,1/16W,CHIP,GA  I267  R2N9
   1 P3V3_STBY      A @BASEBOARD_FAB2_LIB.BASEBOARD_FAB2(SCH_1):P3V3_STBY
   2 PU_10GBE_LOM_PCI_DISABLE_N      B @BASEBOARD_FAB2_LIB.BASEBOARD_FAB2(SCH_1):PU_10GBE_LOM_PCI_DISABLE_N

RES_0402-1.00K,1%,1/16W,CHIP,GA  I280  R8B23
   1 P3V3_STBY      A @BASEBOARD_FAB2_LIB.BASEBOARD_FAB2(SCH_1):P3V3_STBY
   2 FM_XRC_PRESENT_N      B @BASEBOARD_FAB2_LIB.BASEBOARD_FAB2(SCH_1):FM_XRC_PRESENT_N

RES_0402-1.00K,1%,1/16W,CHIP,GA  I282  R8B30
   1 P3V3_STBY      A @BASEBOARD_FAB2_LIB.BASEBOARD_FAB2(SCH_1):P3V3_STBY
   2 FM_XRC_READY_N      B @BASEBOARD_FAB2_LIB.BASEBOARD_FAB2(SCH_1):FM_XRC_READY_N

RES_0402-1.00K,1%,1/16W,CHIP,GA  I284  R2M4
   1 P3V3_STBY      A @BASEBOARD_FAB2_LIB.BASEBOARD_FAB2(SCH_1):P3V3_STBY
   2 IRQ_HSC_FAULT_N      B @BASEBOARD_FAB2_LIB.BASEBOARD_FAB2(SCH_1):IRQ_HSC_FAULT_N

RES_0402-1.00K,1%,1/16W,CHIP,GA  I286  R8C4
   1 P3V3_STBY      A @BASEBOARD_FAB2_LIB.BASEBOARD_FAB2(SCH_1):P3V3_STBY
   2 IRQ_BMC_PCH_SMI_LPC_N      B @BASEBOARD_FAB2_LIB.BASEBOARD_FAB2(SCH_1):IRQ_BMC_PCH_SMI_LPC_N

RES_0402-10.0K,1%,1/16W,CHIP,GA  I295  R7B6
   1 P3V3_STBY      A @BASEBOARD_FAB2_LIB.BASEBOARD_FAB2(SCH_1):P3V3_STBY
   2 FM_PCH_PRSNT_N      B @BASEBOARD_FAB2_LIB.BASEBOARD_FAB2(SCH_1):FM_PCH_PRSNT_N

RES_0402-10.0K,1%,1/16W,CHIP,GA  I296  R7C8
   1 P3V3_STBY      A @BASEBOARD_FAB2_LIB.BASEBOARD_FAB2(SCH_1):P3V3_STBY
   2 FM_WBG_PRSNT_N      B @BASEBOARD_FAB2_LIB.BASEBOARD_FAB2(SCH_1):FM_WBG_PRSNT_N

RES_0402-10.0K,1%,1/16W,CHIP,GA  I297  R7C5
   1 P3V3_STBY      A @BASEBOARD_FAB2_LIB.BASEBOARD_FAB2(SCH_1):P3V3_STBY
   2 FM_SINT_PRSNT_N      B @BASEBOARD_FAB2_LIB.BASEBOARD_FAB2(SCH_1):FM_SINT_PRSNT_N

RES_0402-4.75K,1%,1/16W,CHIP,GA  I301  R8D14
   1 P3V3_STBY      A @BASEBOARD_FAB2_LIB.BASEBOARD_FAB2(SCH_1):P3V3_STBY
   2 FP_PWR_ID_LED_N      B @BASEBOARD_FAB2_LIB.BASEBOARD_FAB2(SCH_1):FP_PWR_ID_LED_N

RES_0402-4.75K,1%,1/16W,CHIP,GA  I303  R8C6
   1 P3V3_STBY      A @BASEBOARD_FAB2_LIB.BASEBOARD_FAB2(SCH_1):P3V3_STBY
   2 FM_BIOS_POST_CMPLT_N      B @BASEBOARD_FAB2_LIB.BASEBOARD_FAB2(SCH_1):FM_BIOS_POST_CMPLT_N

RES_0402-4.75K,1%,1/16W,CHIP,GA  I304  R8C2
   1 P3V3_STBY      A @BASEBOARD_FAB2_LIB.BASEBOARD_FAB2(SCH_1):P3V3_STBY
   2 IRQ_BMC_PCH_SCI_LPC_N      B @BASEBOARD_FAB2_LIB.BASEBOARD_FAB2(SCH_1):IRQ_BMC_PCH_SCI_LPC_N

RES_0402-4.75K,1%,1/16W,CHIP,GA  I306  R7D6
   1 P3V3_STBY      A @BASEBOARD_FAB2_LIB.BASEBOARD_FAB2(SCH_1):P3V3_STBY
   2 FM_BMC_READY_N      B @BASEBOARD_FAB2_LIB.BASEBOARD_FAB2(SCH_1):FM_BMC_READY_N

RES_0402-4.75K,1%,1/16W,CHIP,GA  I307  R8B31
   1 P3V3_STBY      A @BASEBOARD_FAB2_LIB.BASEBOARD_FAB2(SCH_1):P3V3_STBY
   2 FM_THROTTLE_N      B @BASEBOARD_FAB2_LIB.BASEBOARD_FAB2(SCH_1):FM_THROTTLE_N

RES_0402-4.75K,1%,1/16W,CHIP,GA  I309  R2N7
   1 P3V3_STBY      A @BASEBOARD_FAB2_LIB.BASEBOARD_FAB2(SCH_1):P3V3_STBY
   2 IRQ_BOARD_BMC_ALERT_N      B @BASEBOARD_FAB2_LIB.BASEBOARD_FAB2(SCH_1):IRQ_BOARD_BMC_ALERT_N

RES_0402-1.00K,1%,1/16W,CHIP,GA  I315  R3P7
   1 P1V05_PCH_STBY      A @BASEBOARD_FAB2_LIB.BASEBOARD_FAB2(SCH_1):P1V05_PCH_STBY
   2 FM_PRSNT_2_1_N      B @BASEBOARD_FAB2_LIB.BASEBOARD_FAB2(SCH_1):FM_PRSNT_2_1_N

RES_0402-1.00K,1%,1/16W,CHIP,GA  I316  R3P5
   1 P1V05_PCH_STBY      A @BASEBOARD_FAB2_LIB.BASEBOARD_FAB2(SCH_1):P1V05_PCH_STBY
   2 FM_PRSNT_2_2_N      B @BASEBOARD_FAB2_LIB.BASEBOARD_FAB2(SCH_1):FM_PRSNT_2_2_N

RES_0402-1.00K,1%,1/16W,CHIP,GA  I317  R3P6
   1 P1V05_PCH_STBY      A @BASEBOARD_FAB2_LIB.BASEBOARD_FAB2(SCH_1):P1V05_PCH_STBY
   2 FM_PRSNT_2_3_N      B @BASEBOARD_FAB2_LIB.BASEBOARD_FAB2(SCH_1):FM_PRSNT_2_3_N

RES_0402-1.00K,1%,1/16W,CHIP,GA  I318  R3N15
   1 P1V05_PCH_STBY      A @BASEBOARD_FAB2_LIB.BASEBOARD_FAB2(SCH_1):P1V05_PCH_STBY
   2 FM_PRSNT_2_4_N      B @BASEBOARD_FAB2_LIB.BASEBOARD_FAB2(SCH_1):FM_PRSNT_2_4_N

RES_0402-1.00K,1%,1/16W,CHIP,GA  I321  R3N16
   1 P1V05_PCH_STBY      A @BASEBOARD_FAB2_LIB.BASEBOARD_FAB2(SCH_1):P1V05_PCH_STBY
   2 FM_PRSNT_2_5_N      B @BASEBOARD_FAB2_LIB.BASEBOARD_FAB2(SCH_1):FM_PRSNT_2_5_N

RES_0402-1.00K,1%,1/16W,CHIP,GA  I322  R3P8
   1 P1V05_PCH_STBY      A @BASEBOARD_FAB2_LIB.BASEBOARD_FAB2(SCH_1):P1V05_PCH_STBY
   2 FM_PRSNT_2_6_N      B @BASEBOARD_FAB2_LIB.BASEBOARD_FAB2(SCH_1):FM_PRSNT_2_6_N

RES_0402-4.75K,1%,1/16W,CHIP,GA  I326  R8C1
   1 P3V3_STBY      A @BASEBOARD_FAB2_LIB.BASEBOARD_FAB2(SCH_1):P3V3_STBY
   2 FM_SLT_CFG1      B @BASEBOARD_FAB2_LIB.BASEBOARD_FAB2(SCH_1):FM_SLT_CFG1

RES_0402-4.75K,1%,1/16W,CHIP,GA  I327  R8C7
   1 P3V3_STBY      A @BASEBOARD_FAB2_LIB.BASEBOARD_FAB2(SCH_1):P3V3_STBY
   2 FM_SLT_CFG0      B @BASEBOARD_FAB2_LIB.BASEBOARD_FAB2(SCH_1):FM_SLT_CFG0

RES_0402-1.00K,1%,1/16W,CHIP,GA  I331  R7D7
   1 P3V3_STBY      A @BASEBOARD_FAB2_LIB.BASEBOARD_FAB2(SCH_1):P3V3_STBY
   2 IRQ_PIRQA_SPI_TPM_N      B @BASEBOARD_FAB2_LIB.BASEBOARD_FAB2(SCH_1):IRQ_PIRQA_SPI_TPM_N

RES_0402-1.00K,1%,1/16W,CHIP,GA  I332  R7D2
   1 P3V3_STBY      A @BASEBOARD_FAB2_LIB.BASEBOARD_FAB2(SCH_1):P3V3_STBY
   2 PU_FM_RCIN_N      B @BASEBOARD_FAB2_LIB.BASEBOARD_FAB2(SCH_1):PU_FM_RCIN_N

RES_0402-4.75K,1%,1/16W,CHIP,GA  I333  R8C25
   1 P3V3_STBY      A @BASEBOARD_FAB2_LIB.BASEBOARD_FAB2(SCH_1):P3V3_STBY
   2 IRQ_PCH_NIC_ALERT_N      B @BASEBOARD_FAB2_LIB.BASEBOARD_FAB2(SCH_1):IRQ_PCH_NIC_ALERT_N

RES_0402-4.75K,1%,1/16W,CHIP,GA  I341  R2N32
   1 P3V3_STBY      A @BASEBOARD_FAB2_LIB.BASEBOARD_FAB2(SCH_1):P3V3_STBY
   2 FM_BIOS_SMI_ACTIVE_N      B @BASEBOARD_FAB2_LIB.BASEBOARD_FAB2(SCH_1):FM_BIOS_SMI_ACTIVE_N

RES_0402-1.5K,1%,1/16W,CHIP,G2A  I349  R2M8
   1 P3V3_STBY      A @BASEBOARD_FAB2_LIB.BASEBOARD_FAB2(SCH_1):P3V3_STBY
   2 FM_CPU0_RC_ERROR_N      B @BASEBOARD_FAB2_LIB.BASEBOARD_FAB2(SCH_1):FM_CPU0_RC_ERROR_N

RES_0402-1.5K,1%,1/16W,CHIP,G2A  I352  R2N29
   1 P3V3_STBY      A @BASEBOARD_FAB2_LIB.BASEBOARD_FAB2(SCH_1):P3V3_STBY
   2 FM_CPU1_RC_ERROR_N      B @BASEBOARD_FAB2_LIB.BASEBOARD_FAB2(SCH_1):FM_CPU1_RC_ERROR_N

RES_0402-10.0K,1%,1/16W,CHIP,GA  I355  R8E3
   1 P3V3_STBY      A @BASEBOARD_FAB2_LIB.BASEBOARD_FAB2(SCH_1):P3V3_STBY
   2 FM_TPM_PRES_N      B @BASEBOARD_FAB2_LIB.BASEBOARD_FAB2(SCH_1):FM_TPM_PRES_N

RES_0402-4.75K,1%,1/16W,CHIP,GA  I356  R7D44
   1 P1V05_PCH_STBY      A @BASEBOARD_FAB2_LIB.BASEBOARD_FAB2(SCH_1):P1V05_PCH_STBY
   2 FM_OCP_MEZZB_PRES_N      B @BASEBOARD_FAB2_LIB.BASEBOARD_FAB2(SCH_1):FM_OCP_MEZZB_PRES_N

RES_0402-4.75K,1%,1/16W,CHIP,GA  I357  R3P53
   1 P1V05_PCH_STBY      A @BASEBOARD_FAB2_LIB.BASEBOARD_FAB2(SCH_1):P1V05_PCH_STBY
   2 FM_OCP_MEZZC_PRES_N      B @BASEBOARD_FAB2_LIB.BASEBOARD_FAB2(SCH_1):FM_OCP_MEZZC_PRES_N

RES_0402-10.0K,1%,1/16W,CHIP,GA  I360  R2P22
   1 P3V3_STBY      A @BASEBOARD_FAB2_LIB.BASEBOARD_FAB2(SCH_1):P3V3_STBY
   2 FM_CPU1_RC_EN      B @BASEBOARD_FAB2_LIB.BASEBOARD_FAB2(SCH_1):FM_CPU1_RC_EN

RES_0402-10.0K,1%,1/16W,CHIP,GA  I362  R8D44
   1 P3V3_STBY      A @BASEBOARD_FAB2_LIB.BASEBOARD_FAB2(SCH_1):P3V3_STBY
   2 FM_CPU0_RC_EN      B @BASEBOARD_FAB2_LIB.BASEBOARD_FAB2(SCH_1):FM_CPU0_RC_EN


DRAWING: @BASEBOARD_FAB2_LIB.BASEBOARD_FAB2(SCH_1):PAGE134 

RES_0402-4.75K,1%,1/16W,CHIP,GA  I3  R2P17
   1 P3V3_STBY      A @BASEBOARD_FAB2_LIB.BASEBOARD_FAB2(SCH_1):P3V3_STBY
   2 FM_PCH_BMC_THERMTRIP_N      B @BASEBOARD_FAB2_LIB.BASEBOARD_FAB2(SCH_1):FM_PCH_BMC_THERMTRIP_N

FET_N_SOT23-2N7002,FET,C79254-A  I4  Q8D2
   1 RST_PLTRST_BUF_N   GATE @BASEBOARD_FAB2_LIB.BASEBOARD_FAB2(SCH_1):RST_PLTRST_BUF_N
   2 FM_PCH_BMC_THERMTRIP_EXI_STRAP_    SRC @BASEBOARD_FAB2_LIB.BASEBOARD_FAB2(SCH_1):FM_PCH_BMC_THERMTRIP_EXI_STRAP_N
   3 FM_PCH_BMC_THERMTRIP_N    DRN @BASEBOARD_FAB2_LIB.BASEBOARD_FAB2(SCH_1):FM_PCH_BMC_THERMTRIP_N

RES_0402-10.0K,1%,1/16W,CHIP,GA  I9  R7C21
   1 P1V05_PCH_STBY      A @BASEBOARD_FAB2_LIB.BASEBOARD_FAB2(SCH_1):P1V05_PCH_STBY
   2 FM_PCH_LVC1_THERMTRIP_N      B @BASEBOARD_FAB2_LIB.BASEBOARD_FAB2(SCH_1):FM_PCH_LVC1_THERMTRIP_N

FET_N_SOT23-2N7002,FET,C79254-A  I10  Q7D1
   1 FM_THERMTRIP_DLY_R   GATE @BASEBOARD_FAB2_LIB.BASEBOARD_FAB2(SCH_1):FM_THERMTRIP_DLY_R
   2    GND    SRC @BASEBOARD_FAB2_LIB.BASEBOARD_FAB2(SCH_1):GND
   3 FM_PCH_LVC1_THERMTRIP_N    DRN @BASEBOARD_FAB2_LIB.BASEBOARD_FAB2(SCH_1):FM_PCH_LVC1_THERMTRIP_N

RES_0402-1.00K,1%,1/16W,CHIP,GA  I11  R7D18
   1 FM_THERMTRIP_DLY      A @BASEBOARD_FAB2_LIB.BASEBOARD_FAB2(SCH_1):FM_THERMTRIP_DLY
   2 FM_THERMTRIP_DLY_R      B @BASEBOARD_FAB2_LIB.BASEBOARD_FAB2(SCH_1):FM_THERMTRIP_DLY_R


DRAWING: @BASEBOARD_FAB2_LIB.BASEBOARD_FAB2(SCH_1):PAGE135 

RES_0402-10.0K,1%,1/16W,CHIP,GA  I107  R2P19
   1 P3V3_STBY      A @BASEBOARD_FAB2_LIB.BASEBOARD_FAB2(SCH_1):P3V3_STBY
   2 FM_DIS_ADR_DLY      B @BASEBOARD_FAB2_LIB.BASEBOARD_FAB2(SCH_1):FM_DIS_ADR_DLY

RES_0402-10.0K,1%,1/16W,CHIP,GA  I112  R2N23
   1 P3V3_STBY      A @BASEBOARD_FAB2_LIB.BASEBOARD_FAB2(SCH_1):P3V3_STBY
   2 FM_QAT_EN_N      B @BASEBOARD_FAB2_LIB.BASEBOARD_FAB2(SCH_1):FM_QAT_EN_N

RES_0402-1.00K,1%,1/16W,EMPTY,A  I113  R2N24
   1 FM_QAT_EN_N      A @BASEBOARD_FAB2_LIB.BASEBOARD_FAB2(SCH_1):FM_QAT_EN_N
   2    GND      B @BASEBOARD_FAB2_LIB.BASEBOARD_FAB2(SCH_1):GND

RES_0402-2.21K,1%,1/16W,CHIP,GA  I117  R9A12
   1 FM_PCH_SATA_RAID_KEY_R      A @BASEBOARD_FAB2_LIB.BASEBOARD_FAB2(SCH_1):FM_PCH_SATA_RAID_KEY_R
   2 P3V3_STBY      B @BASEBOARD_FAB2_LIB.BASEBOARD_FAB2(SCH_1):P3V3_STBY

RES_0402-33.2,1%,1/16W,CHIP,G2A  I118  R9A13
   1 FM_PCH_SATA_RAID_KEY_R      A @BASEBOARD_FAB2_LIB.BASEBOARD_FAB2(SCH_1):FM_PCH_SATA_RAID_KEY_R
   2 FM_PCH_SATA_RAID_KEY      B @BASEBOARD_FAB2_LIB.BASEBOARD_FAB2(SCH_1):FM_PCH_SATA_RAID_KEY

RES_0402-1.00K,1%,1/16W,CHIP,GA  I120  R8D21
   1 P3V3_STBY      A @BASEBOARD_FAB2_LIB.BASEBOARD_FAB2(SCH_1):P3V3_STBY
   2 FM_IE_DISABLE_N      B @BASEBOARD_FAB2_LIB.BASEBOARD_FAB2(SCH_1):FM_IE_DISABLE_N

RES_0402-4.75K,1%,1/16W,CHIP,GA  I121  R7D30
   1 P3V3_STBY      A @BASEBOARD_FAB2_LIB.BASEBOARD_FAB2(SCH_1):P3V3_STBY
   2 FM_CPLD_UART_CH_LOCK_N      B @BASEBOARD_FAB2_LIB.BASEBOARD_FAB2(SCH_1):FM_CPLD_UART_CH_LOCK_N

CONN12_C73564003_PIP-CONN,C735A  I124  J8G2
   1 TP_JUMPER_BLOCK_1_1    IO1 @BASEBOARD_FAB2_LIB.BASEBOARD_FAB2(SCH_1):TP_JUMPER_BLOCK_1_1
  10 FM_DIS_ADR_DLY   IO10 @BASEBOARD_FAB2_LIB.BASEBOARD_FAB2(SCH_1):FM_DIS_ADR_DLY
  11    GND   IO11 @BASEBOARD_FAB2_LIB.BASEBOARD_FAB2(SCH_1):GND
  12    GND   IO12 @BASEBOARD_FAB2_LIB.BASEBOARD_FAB2(SCH_1):GND
   2 TP_JUMPER_BLOCK_1_2    IO2 @BASEBOARD_FAB2_LIB.BASEBOARD_FAB2(SCH_1):TP_JUMPER_BLOCK_1_2
   3 RST_BMC_SRST_N    IO3 @BASEBOARD_FAB2_LIB.BASEBOARD_FAB2(SCH_1):RST_BMC_SRST_N
   4 FM_IE_DISABLE_N    IO4 @BASEBOARD_FAB2_LIB.BASEBOARD_FAB2(SCH_1):FM_IE_DISABLE_N
   5    GND    IO5 @BASEBOARD_FAB2_LIB.BASEBOARD_FAB2(SCH_1):GND
   6    GND    IO6 @BASEBOARD_FAB2_LIB.BASEBOARD_FAB2(SCH_1):GND
   7 TP_JUMPER_BLOCK_1_7    IO7 @BASEBOARD_FAB2_LIB.BASEBOARD_FAB2(SCH_1):TP_JUMPER_BLOCK_ 1_7
   8 TP_JUMPER_BLOCK_1_8    IO8 @BASEBOARD_FAB2_LIB.BASEBOARD_FAB2(SCH_1):TP_JUMPER_BLOCK_1_8
   9 FM_CPLD_UART_CH_LOCK_N    IO9 @BASEBOARD_FAB2_LIB.BASEBOARD_FAB2(SCH_1):FM_CPLD_UART_CH_LOCK_N

RES_0402-2.21K,1%,1/16W,CHIP,GA  I129  R9A16
   1 PU_KEY_CONN_PIN2_R      A @BASEBOARD_FAB2_LIB.BASEBOARD_FAB2(SCH_1):PU_KEY_CONN_PIN2_R
   2 P3V3_STBY      B @BASEBOARD_FAB2_LIB.BASEBOARD_FAB2(SCH_1):P3V3_STBY

CONN4_D42317002_PIP-CONN,D4231A  I131  J9A1
   1    GND    IO1 @BASEBOARD_FAB2_LIB.BASEBOARD_FAB2(SCH_1):GND
   2 PU_KEY_CONN_PIN2_R    IO2 @BASEBOARD_FAB2_LIB.BASEBOARD_FAB2(SCH_1):PU_KEY_CONN_PIN2_R
   3    GND    IO3 @BASEBOARD_FAB2_LIB.BASEBOARD_FAB2(SCH_1):GND
   4 FM_PCH_SATA_RAID_KEY_R    IO4 @BASEBOARD_FAB2_LIB.BASEBOARD_FAB2(SCH_1):FM_PCH_SATA_RAID_KEY_R


DRAWING: @BASEBOARD_FAB2_LIB.BASEBOARD_FAB2(SCH_1):PAGE136 

RES_0402-10.0K,1%,1/16W,CHIP,GA  I101  R7G26
   1 P3V3_STBY      A @BASEBOARD_FAB2_LIB.BASEBOARD_FAB2(SCH_1):P3V3_STBY
   2 FM_ME_RECOVER_N      B @BASEBOARD_FAB2_LIB.BASEBOARD_FAB2(SCH_1):FM_ME_RECOVER_N

RES_0402-1.00K,1%,1/16W,CHIP,GA  I102  R7G28
   1 PD_ME_RCVR_N      A @BASEBOARD_FAB2_LIB.BASEBOARD_FAB2(SCH_1):PD_ME_RCVR_N
   2    GND      B @BASEBOARD_FAB2_LIB.BASEBOARD_FAB2(SCH_1):GND

RES_0402-33.2,1%,1/16W,CHIP,G2A  I126  R8E20
   1 FM_BIOS_TOP_SWAP_SPKR_R      A @BASEBOARD_FAB2_LIB.BASEBOARD_FAB2(SCH_1):FM_BIOS_TOP_SWAP_SPKR_R
   2 FM_BIOS_TOP_SWAP_SPKR      B @BASEBOARD_FAB2_LIB.BASEBOARD_FAB2(SCH_1):FM_BIOS_TOP_SWAP_SPKR

CAP_A_0402V-0.1UF,16V,10%,X7R,A  I128  C8E8
   1 P3V3_STBY      A @BASEBOARD_FAB2_LIB.BASEBOARD_FAB2(SCH_1):P3V3_STBY
   2    GND      B @BASEBOARD_FAB2_LIB.BASEBOARD_FAB2(SCH_1):GND

TTL1G126_A_SOT-74HC1G126,IC,A7B  I130  U8E3
   1 RST_PLTRST_TOP_SWAP     OE @BASEBOARD_FAB2_LIB.BASEBOARD_FAB2(SCH_1):RST_PLTRST_TOP_SWAP
   2 FM_BIOS_TOP_SWAP      A @BASEBOARD_FAB2_LIB.BASEBOARD_FAB2(SCH_1):FM_BIOS_TOP_SWAP
   4 FM_BIOS_TOP_SWAP_SPKR_R      Y @BASEBOARD_FAB2_LIB.BASEBOARD_FAB2(SCH_1):FM_BIOS_TOP_SWAP_SPKR_R

RES_0402-4.75K,1%,1/16W,CHIP,GA  I133  R8E14
   1 P3V3_STBY      A @BASEBOARD_FAB2_LIB.BASEBOARD_FAB2(SCH_1):P3V3_STBY
   2 RST_PLTRST_TOP_SWAP      B @BASEBOARD_FAB2_LIB.BASEBOARD_FAB2(SCH_1):RST_PLTRST_TOP_SWAP

FET_N_SOT23LF-2N7002,FET,C7925A  I134  Q8E1
   1 RST_PLTRST_N   GATE @BASEBOARD_FAB2_LIB.BASEBOARD_FAB2(SCH_1):RST_PLTRST_N
   2    GND    SRC @BASEBOARD_FAB2_LIB.BASEBOARD_FAB2(SCH_1):GND
   3 RST_PLTRST_TOP_SWAP    DRN @BASEBOARD_FAB2_LIB.BASEBOARD_FAB2(SCH_1):RST_PLTRST_TOP_SWAP

RES_0402-1.00K,1%,1/16W,CHIP,GA  I139  R7G31
   1 P3V3_STBY      A @BASEBOARD_FAB2_LIB.BASEBOARD_FAB2(SCH_1):P3V3_STBY
   2 PU_BIOS_RECOVER_BOOT      B @BASEBOARD_FAB2_LIB.BASEBOARD_FAB2(SCH_1):PU_BIOS_RECOVER_BOOT

RES_0402-20.0K,1%,1/16W,CHIP,GA  I140  R8E16
   1 FM_BIOS_TOP_SWAP      A @BASEBOARD_FAB2_LIB.BASEBOARD_FAB2(SCH_1):FM_BIOS_TOP_SWAP
   2    GND      B @BASEBOARD_FAB2_LIB.BASEBOARD_FAB2(SCH_1):GND

RES_0402-10.0K,1%,1/16W,CHIP,GA  I147  R2N28
   1 P3V3_STBY      A @BASEBOARD_FAB2_LIB.BASEBOARD_FAB2(SCH_1):P3V3_STBY
   2 FM_PASSWORD_CLEAR_N      B @BASEBOARD_FAB2_LIB.BASEBOARD_FAB2(SCH_1):FM_PASSWORD_CLEAR_N

RES_0402-1.00K,1%,1/16W,CHIP,GA  I148  R7G29
   1 PD_PASSWORD_CLEAR      A @BASEBOARD_FAB2_LIB.BASEBOARD_FAB2(SCH_1):PD_PASSWORD_CLEAR
   2    GND      B @BASEBOARD_FAB2_LIB.BASEBOARD_FAB2(SCH_1):GND

RES_0402-1.00K,1%,1/16W,CHIP,GA  I155  R7G27
   1 P3V3_STBY      A @BASEBOARD_FAB2_LIB.BASEBOARD_FAB2(SCH_1):P3V3_STBY
   2 PU_BIOS_USB_RECOVERY      B @BASEBOARD_FAB2_LIB.BASEBOARD_FAB2(SCH_1):PU_BIOS_USB_RECOVERY

RES_0402-10.0K,1%,1/16W,CHIP,GA  I156  R3T14
   1 FM_BIOS_USB_RECOVERY      A @BASEBOARD_FAB2_LIB.BASEBOARD_FAB2(SCH_1):FM_BIOS_USB_RECOVERY
   2    GND      B @BASEBOARD_FAB2_LIB.BASEBOARD_FAB2(SCH_1):GND

CONN12_C73564003_PIP-CONN,C735A  I174  J7G3
   1 TP_ME_RCVR_BOOT    IO1 @BASEBOARD_FAB2_LIB.BASEBOARD_FAB2(SCH_1):TP_ME_RCVR_BOOT
  10 FM_BIOS_TOP_SWAP   IO10 @BASEBOARD_FAB2_LIB.BASEBOARD_FAB2(SCH_1):FM_BIOS_TOP_SWAP
  11 PD_PASSWORD_CLEAR   IO11 @BASEBOARD_FAB2_LIB.BASEBOARD_FAB2(SCH_1):PD_PASSWORD_CLEAR
  12 PU_BIOS_RECOVER_BOOT   IO12 @BASEBOARD_FAB2_LIB.BASEBOARD_FAB2(SCH_1):PU_BIOS_RECOVER_BOOT
   2 TP_BIOS_USB_RECOVERY    IO2 @BASEBOARD_FAB2_LIB.BASEBOARD_FAB2(SCH_1):TP_BIOS_USB_RECOVERY
   3 FM_ME_RECOVER_N    IO3 @BASEBOARD_FAB2_LIB.BASEBOARD_FAB2(SCH_1):FM_ME_RECOVER_N
   4 FM_BIOS_USB_RECOVERY    IO4 @BASEBOARD_FAB2_LIB.BASEBOARD_FAB2(SCH_1):FM_BIOS_USB_RECOVERY
   5 PD_ME_RCVR_N    IO5 @BASEBOARD_FAB2_LIB.BASEBOARD_FAB2(SCH_1):PD_ME_RCVR_N
   6 PU_BIOS_USB_RECOVERY    IO6 @BASEBOARD_FAB2_LIB.BASEBOARD_FAB2(SCH_1):PU_BIOS_USB_RECOVERY
   7 TP_PASSWORD_CLEAR    IO7 @BASEBOARD_FAB2_LIB.BASEBOARD_FAB2(SCH_1):TP_PASSWORD_CLEAR
   8 TP_BIOS_RECOVER_BOOT    IO8 @BASEBOARD_FAB2_LIB.BASEBOARD_FAB2(SCH_1):TP_BIOS_RECOVER_BOOT
   9 FM_PASSWORD_CLEAR_N    IO9 @BASEBOARD_FAB2_LIB.BASEBOARD_FAB2(SCH_1):FM_PASSWORD_CLEAR_N


DRAWING: @BASEBOARD_FAB2_LIB.BASEBOARD_FAB2(SCH_1):PAGE137 

RES_0402-1.0M,1%,1/16W,EMPTY,GA  I11  R7C11
   1    GND      A @BASEBOARD_FAB2_LIB.BASEBOARD_FAB2(SCH_1):GND
   2 RST_RTCRST_N      B @BASEBOARD_FAB2_LIB.BASEBOARD_FAB2(SCH_1):RST_RTCRST_N

RES_0402-20.0K,1%,1/16W,CHIP,GA  I13  R7C10
   1 P3V3_RTC_STBY      A @BASEBOARD_FAB2_LIB.BASEBOARD_FAB2(SCH_1):P3V3_RTC_STBY
   2 RST_RTCRST_N      B @BASEBOARD_FAB2_LIB.BASEBOARD_FAB2(SCH_1):RST_RTCRST_N

CAP_A_0402V-1.0UF,6.3V,10%,X6SA  I14  C7C19
   1 RST_RTCRST_N      A @BASEBOARD_FAB2_LIB.BASEBOARD_FAB2(SCH_1):RST_RTCRST_N
   2    GND      B @BASEBOARD_FAB2_LIB.BASEBOARD_FAB2(SCH_1):GND

RES_0402-1.00K,1%,1/16W,CHIP,GA  I15  R1U63
   1 PD_RST_RTCRST_N      A @BASEBOARD_FAB2_LIB.BASEBOARD_FAB2(SCH_1):PD_RST_RTCRST_N
   2    GND      B @BASEBOARD_FAB2_LIB.BASEBOARD_FAB2(SCH_1):GND

RES_0402-20.0K,1%,1/16W,CHIP,GA  I19  R3N4
   1 P3V3_RTC_STBY      A @BASEBOARD_FAB2_LIB.BASEBOARD_FAB2(SCH_1):P3V3_RTC_STBY
   2 RST_SRTCRST_N      B @BASEBOARD_FAB2_LIB.BASEBOARD_FAB2(SCH_1):RST_SRTCRST_N

CAP_A_0402V-1.0UF,6.3V,10%,X6SA  I20  C3N32
   1 RST_SRTCRST_N      A @BASEBOARD_FAB2_LIB.BASEBOARD_FAB2(SCH_1):RST_SRTCRST_N
   2    GND      B @BASEBOARD_FAB2_LIB.BASEBOARD_FAB2(SCH_1):GND

RES_0402-10.0K,1%,1/16W,CHIP,GA  I67  R7C13
   1 P3V3_STBY      A @BASEBOARD_FAB2_LIB.BASEBOARD_FAB2(SCH_1):P3V3_STBY
   2 FM_UART_PRES_N      B @BASEBOARD_FAB2_LIB.BASEBOARD_FAB2(SCH_1):FM_UART_PRES_N

RES_0402-1.00K,1%,1/16W,CHIP,GA  I69  R1U64
   1 PD_IE_DEBUG_MODE      A @BASEBOARD_FAB2_LIB.BASEBOARD_FAB2(SCH_1):PD_IE_DEBUG_MODE
   2    GND      B @BASEBOARD_FAB2_LIB.BASEBOARD_FAB2(SCH_1):GND

CONN12_C73564003_PIP-CONN,C735A  I128  J9G1
   1 TP_BMC_DISABLE    IO1 @BASEBOARD_FAB2_LIB.BASEBOARD_FAB2(SCH_1):TP_BMC_DISABLE
  10 TP_JUMPER_BLOCK_2_10   IO10 @BASEBOARD_FAB2_LIB.BASEBOARD_FAB2(SCH_1):TP_JUMPER_BLOCK_2_10
  11 PD_IE_DEBUG_MODE   IO11 @BASEBOARD_FAB2_LIB.BASEBOARD_FAB2(SCH_1):PD_IE_DEBUG_MODE
  12 TP_JUMPER_BLOCK_2_12   IO12 @BASEBOARD_FAB2_LIB.BASEBOARD_FAB2(SCH_1):TP_JUMPER_BLOCK_2_12
   2 TP_RST_RTCRST_N    IO2 @BASEBOARD_FAB2_LIB.BASEBOARD_FAB2(SCH_1):TP_RST_RTCRST_N
   3 FM_ROMA<0>    IO3 @BASEBOARD_FAB2_LIB.BASEBOARD_FAB2(SCH_1):FM_ROMA(0)
   4 RST_RTCRST_N    IO4 @BASEBOARD_FAB2_LIB.BASEBOARD_FAB2(SCH_1):RST_RTCRST_N
   5 FM_BMC_DISABLE    IO5 @BASEBOARD_FAB2_LIB.BASEBOARD_FAB2(SCH_1):FM_BMC_DISABLE
   6 PD_RST_RTCRST_N    IO6 @BASEBOARD_FAB2_LIB.BASEBOARD_FAB2(SCH_1):PD_RST_RTCRST_N
   7 TP_IE_DEBUG_MODE    IO7 @BASEBOARD_FAB2_LIB.BASEBOARD_FAB2(SCH_1):TP_IE_DEBUG_MODE
   8 TP_JUMPER_BLOCK_2_8    IO8 @BASEBOARD_FAB2_LIB.BASEBOARD_FAB2(SCH_1):TP_JUMPER_BLOCK_2_8
   9 FM_UART_PRES_N    IO9 @BASEBOARD_FAB2_LIB.BASEBOARD_FAB2(SCH_1):FM_UART_PRES_N


DRAWING: @BASEBOARD_FAB2_LIB.BASEBOARD_FAB2(SCH_1):PAGE138 

RES_0402-665,1.0%,1/16W,CHIP,GA  I83  R2T53
   1 P3V3_STBY      A @BASEBOARD_FAB2_LIB.BASEBOARD_FAB2(SCH_1):P3V3_STBY
   2 SMB_BMC_PMBUS_STBY_LVC3_SDA      B @BASEBOARD_FAB2_LIB.BASEBOARD_FAB2(SCH_1):SMB_BMC_PMBUS_STBY_LVC3_SDA

RES_0402-665,1.0%,1/16W,CHIP,GA  I84  R2T54
   1 P3V3_STBY      A @BASEBOARD_FAB2_LIB.BASEBOARD_FAB2(SCH_1):P3V3_STBY
   2 SMB_BMC_PMBUS_STBY_LVC3_SCL      B @BASEBOARD_FAB2_LIB.BASEBOARD_FAB2(SCH_1):SMB_BMC_PMBUS_STBY_LVC3_SCL

RES_0402-1.37K,1%,1/16W,CHIP,GA  I87  R8D17
   1 P3V3_STBY      A @BASEBOARD_FAB2_LIB.BASEBOARD_FAB2(SCH_1):P3V3_STBY
   2 SMB_VR_STBY_LVC3_SDA      B @BASEBOARD_FAB2_LIB.BASEBOARD_FAB2(SCH_1):SMB_VR_STBY_LVC3_SDA

RES_0402-1.37K,1%,1/16W,CHIP,GA  I88  R8D15
   1 P3V3_STBY      A @BASEBOARD_FAB2_LIB.BASEBOARD_FAB2(SCH_1):P3V3_STBY
   2 SMB_VR_STBY_LVC3_SCL      B @BASEBOARD_FAB2_LIB.BASEBOARD_FAB2(SCH_1):SMB_VR_STBY_LVC3_SCL

RES_0402-665,1.0%,1/16W,CHIP,GA  I89  R2N8
   1 P3V3_STBY      A @BASEBOARD_FAB2_LIB.BASEBOARD_FAB2(SCH_1):P3V3_STBY
   2 SMB_SMLINK0_STBY_LVC3_SDA      B @BASEBOARD_FAB2_LIB.BASEBOARD_FAB2(SCH_1):SMB_SMLINK0_STBY_LVC3_SDA

RES_0402-665,1.0%,1/16W,CHIP,GA  I90  R2N5
   1 P3V3_STBY      A @BASEBOARD_FAB2_LIB.BASEBOARD_FAB2(SCH_1):P3V3_STBY
   2 SMB_SMLINK0_STBY_LVC3_SCL      B @BASEBOARD_FAB2_LIB.BASEBOARD_FAB2(SCH_1):SMB_SMLINK0_STBY_LVC3_SCL

RES_0402-2.0K,1%,1/16W,CHIP,G2A  I91  R8C16
   1 P3V3_STBY      A @BASEBOARD_FAB2_LIB.BASEBOARD_FAB2(SCH_1):P3V3_STBY
   2 SMB_HOST_STBY_LVC3_SDA      B @BASEBOARD_FAB2_LIB.BASEBOARD_FAB2(SCH_1):SMB_HOST_STBY_LVC3_SDA

RES_0402-2.0K,1%,1/16W,CHIP,G2A  I92  R8C15
   1 P3V3_STBY      A @BASEBOARD_FAB2_LIB.BASEBOARD_FAB2(SCH_1):P3V3_STBY
   2 SMB_HOST_STBY_LVC3_SCL      B @BASEBOARD_FAB2_LIB.BASEBOARD_FAB2(SCH_1):SMB_HOST_STBY_LVC3_SCL

RES_0402-3.3K,5%,1/16W,CHIP,G2A  I95  R8B24
   1 P3V3_STBY      A @BASEBOARD_FAB2_LIB.BASEBOARD_FAB2(SCH_1):P3V3_STBY
   2 SMB_SLOTX24_PCH_STBY_LVC3_SDA      B @BASEBOARD_FAB2_LIB.BASEBOARD_FAB2(SCH_1):SMB_SLOTX24_PCH_STBY_LVC3_SDA

RES_0402-3.3K,5%,1/16W,CHIP,G2A  I96  R8B26
   1 P3V3_STBY      A @BASEBOARD_FAB2_LIB.BASEBOARD_FAB2(SCH_1):P3V3_STBY
   2 SMB_SLOTX24_PCH_STBY_LVC3_SCL      B @BASEBOARD_FAB2_LIB.BASEBOARD_FAB2(SCH_1):SMB_SLOTX24_PCH_STBY_LVC3_SCL

RES_0402-665,1.0%,1/16W,CHIP,GA  I97  R2U11
   1 P3V3_STBY      A @BASEBOARD_FAB2_LIB.BASEBOARD_FAB2(SCH_1):P3V3_STBY
   2 SMB_LAN_STBY_LVC3_SDA      B @BASEBOARD_FAB2_LIB.BASEBOARD_FAB2(SCH_1):SMB_LAN_STBY_LVC3_SDA

RES_0402-665,1.0%,1/16W,CHIP,GA  I98  R2U3
   1 P3V3_STBY      A @BASEBOARD_FAB2_LIB.BASEBOARD_FAB2(SCH_1):P3V3_STBY
   2 SMB_LAN_STBY_LVC3_SCL      B @BASEBOARD_FAB2_LIB.BASEBOARD_FAB2(SCH_1):SMB_LAN_STBY_LVC3_SCL

RES_0402-20.0,1%,1/16W,CHIP,G2A  I116  R2T55
   1 SMB_PMBUS_BMC_STBY_LVC3_SDA_R1      A @BASEBOARD_FAB2_LIB.BASEBOARD_FAB2(SCH_1):SMB_PMBUS_BMC_STBY_LVC3_SDA_R1
   2 SMB_BMC_PMBUS_STBY_LVC3_SDA      B @BASEBOARD_FAB2_LIB.BASEBOARD_FAB2(SCH_1):SMB_BMC_PMBUS_STBY_LVC3_SDA

RES_0402-20.0,1%,1/16W,EMPTY,GA  I158  R2U8
   1 SMB_LAN_STBY_LVC3_SCL      A @BASEBOARD_FAB2_LIB.BASEBOARD_FAB2(SCH_1):SMB_LAN_STBY_LVC3_SCL
   2 SMB_OCP_FRU_STBY_LVC3_SCL      B @BASEBOARD_FAB2_LIB.BASEBOARD_FAB2(SCH_1):SMB_OCP_FRU_STBY_LVC3_SCL

RES_0402-20.0,1%,1/16W,EMPTY,GA  I159  R2U12
   1 SMB_LAN_STBY_LVC3_SDA      A @BASEBOARD_FAB2_LIB.BASEBOARD_FAB2(SCH_1):SMB_LAN_STBY_LVC3_SDA
   2 SMB_OCP_FRU_STBY_LVC3_SDA      B @BASEBOARD_FAB2_LIB.BASEBOARD_FAB2(SCH_1):SMB_OCP_FRU_STBY_LVC3_SDA

RES_0402-20.0,1%,1/16W,CHIP,G2A  I160  R2T56
   1 SMB_PMBUS_BMC_STBY_LVC3_SCL_R1      A @BASEBOARD_FAB2_LIB.BASEBOARD_FAB2(SCH_1):SMB_PMBUS_BMC_STBY_LVC3_SCL_R1
   2 SMB_BMC_PMBUS_STBY_LVC3_SCL      B @BASEBOARD_FAB2_LIB.BASEBOARD_FAB2(SCH_1):SMB_BMC_PMBUS_STBY_LVC3_SCL

RES_0402-20.0,1%,1/16W,CHIP,G2A  I161  R8D3
   1 SMB_SENSOR_STBY_LVC3_SCL_R1      A @BASEBOARD_FAB2_LIB.BASEBOARD_FAB2(SCH_1):SMB_SENSOR_STBY_LVC3_SCL_R1
   2 SMB_SENSOR_PCH_STBY_LVC3_SCL      B @BASEBOARD_FAB2_LIB.BASEBOARD_FAB2(SCH_1):SMB_SENSOR_PCH_STBY_LVC3_SCL

RES_0402-20.0,1%,1/16W,CHIP,G2A  I162  R8D6
   1 SMB_SENSOR_STBY_LVC3_SDA_R1      A @BASEBOARD_FAB2_LIB.BASEBOARD_FAB2(SCH_1):SMB_SENSOR_STBY_LVC3_SDA_R1
   2 SMB_SENSOR_PCH_STBY_LVC3_SDA      B @BASEBOARD_FAB2_LIB.BASEBOARD_FAB2(SCH_1):SMB_SENSOR_PCH_STBY_LVC3_SDA

RES_0402-20.0,1%,1/16W,CHIP,G2A  I163  R8D7
   1 SMB_VR_STBY_LVC3_SDA_R1      A @BASEBOARD_FAB2_LIB.BASEBOARD_FAB2(SCH_1):SMB_VR_STBY_LVC3_SDA_R1
   2 SMB_VR_STBY_LVC3_SDA      B @BASEBOARD_FAB2_LIB.BASEBOARD_FAB2(SCH_1):SMB_VR_STBY_LVC3_SDA

RES_0402-20.0,1%,1/16W,CHIP,G2A  I164  R8D4
   1 SMB_VR_STBY_LVC3_SCL_R1      A @BASEBOARD_FAB2_LIB.BASEBOARD_FAB2(SCH_1):SMB_VR_STBY_LVC3_SCL_R1
   2 SMB_VR_STBY_LVC3_SCL      B @BASEBOARD_FAB2_LIB.BASEBOARD_FAB2(SCH_1):SMB_VR_STBY_LVC3_SCL

RES_0402-20.0,1%,1/16W,CHIP,G2A  I165  R2U9
   1 SMB_LAN_STBY_LVC3_SDA_R1      A @BASEBOARD_FAB2_LIB.BASEBOARD_FAB2(SCH_1):SMB_LAN_STBY_LVC3_SDA_R1
   2 SMB_LAN_STBY_LVC3_SDA      B @BASEBOARD_FAB2_LIB.BASEBOARD_FAB2(SCH_1):SMB_LAN_STBY_LVC3_SDA

RES_0402-20.0,1%,1/16W,CHIP,G2A  I166  R2U6
   1 SMB_LAN_STBY_LVC3_SCL_R1      A @BASEBOARD_FAB2_LIB.BASEBOARD_FAB2(SCH_1):SMB_LAN_STBY_LVC3_SCL_R1
   2 SMB_LAN_STBY_LVC3_SCL      B @BASEBOARD_FAB2_LIB.BASEBOARD_FAB2(SCH_1):SMB_LAN_STBY_LVC3_SCL

RES_0402-20.0,1%,1/16W,CHIP,G2A  I167  R8C20
   1 SMB_HOST_STBY_LVC3_SDA_R1      A @BASEBOARD_FAB2_LIB.BASEBOARD_FAB2(SCH_1):SMB_HOST_STBY_LVC3_SDA_R1
   2 SMB_HOST_STBY_LVC3_SDA      B @BASEBOARD_FAB2_LIB.BASEBOARD_FAB2(SCH_1):SMB_HOST_STBY_LVC3_SDA

RES_0402-20.0,1%,1/16W,CHIP,G2A  I168  R8C14
   1 SMB_HOST_STBY_LVC3_SCL_R1      A @BASEBOARD_FAB2_LIB.BASEBOARD_FAB2(SCH_1):SMB_HOST_STBY_LVC3_SCL_R1
   2 SMB_HOST_STBY_LVC3_SCL      B @BASEBOARD_FAB2_LIB.BASEBOARD_FAB2(SCH_1):SMB_HOST_STBY_LVC3_SCL

RES_0402-20.0,1%,1/16W,CHIP,G2A  I169  R8C11
   1 SMB_SMLINK0_STBY_LVC3_SDA_R1      A @BASEBOARD_FAB2_LIB.BASEBOARD_FAB2(SCH_1):SMB_SMLINK0_STBY_LVC3_SDA_R1
   2 SMB_SMLINK0_STBY_LVC3_SDA      B @BASEBOARD_FAB2_LIB.BASEBOARD_FAB2(SCH_1):SMB_SMLINK0_STBY_LVC3_SDA

RES_0402-20.0,1%,1/16W,CHIP,G2A  I170  R8C12
   1 SMB_SMLINK0_STBY_LVC3_SCL_R1      A @BASEBOARD_FAB2_LIB.BASEBOARD_FAB2(SCH_1):SMB_SMLINK0_STBY_LVC3_SCL_R1
   2 SMB_SMLINK0_STBY_LVC3_SCL      B @BASEBOARD_FAB2_LIB.BASEBOARD_FAB2(SCH_1):SMB_SMLINK0_STBY_LVC3_SCL

RES_0402-0.0,5%,1/16W,CHIP,G21A  I171  R2N20
   1 SMB_LAN_STBY_LVC3_SDA_R2      A @BASEBOARD_FAB2_LIB.BASEBOARD_FAB2(SCH_1):SMB_LAN_STBY_LVC3_SDA_R2
   2 SMB_LAN_STBY_LVC3_SDA      B @BASEBOARD_FAB2_LIB.BASEBOARD_FAB2(SCH_1):SMB_LAN_STBY_LVC3_SDA

RES_0402-20.0,1%,1/16W,CHIP,G2A  I173  R8B27
   1 SMB_SLOTX24_STBY_LVC3_SDA_R1      A @BASEBOARD_FAB2_LIB.BASEBOARD_FAB2(SCH_1):SMB_SLOTX24_STBY_LVC3_SDA_R1
   2 SMB_SLOTX24_PCH_STBY_LVC3_SDA      B @BASEBOARD_FAB2_LIB.BASEBOARD_FAB2(SCH_1):SMB_SLOTX24_PCH_STBY_LVC3_SDA

RES_0402-20.0,1%,1/16W,CHIP,G2A  I174  R8B28
   1 SMB_SLOTX24_STBY_LVC3_SCL_R1      A @BASEBOARD_FAB2_LIB.BASEBOARD_FAB2(SCH_1):SMB_SLOTX24_STBY_LVC3_SCL_R1
   2 SMB_SLOTX24_PCH_STBY_LVC3_SCL      B @BASEBOARD_FAB2_LIB.BASEBOARD_FAB2(SCH_1):SMB_SLOTX24_PCH_STBY_LVC3_SCL

RES_0402-0.0,5%,1/16W,CHIP,G21A  I175  R2N21
   1 SMB_LAN_STBY_LVC3_SCL_R2      A @BASEBOARD_FAB2_LIB.BASEBOARD_FAB2(SCH_1):SMB_LAN_STBY_LVC3_SCL_R2
   2 SMB_LAN_STBY_LVC3_SCL      B @BASEBOARD_FAB2_LIB.BASEBOARD_FAB2(SCH_1):SMB_LAN_STBY_LVC3_SCL


DRAWING: @BASEBOARD_FAB2_LIB.BASEBOARD_FAB2(SCH_1):PAGE139 

SPRINGVILLE_SM1-IC,G47144-004  I72  EU9E1
  37 A_CBOT   CBOT @BASEBOARD_FAB2_LIB.BASEBOARD_FAB2(SCH_1):A_CBOT
  40 A_CTOP   CTOP @BASEBOARD_FAB2_LIB.BASEBOARD_FAB2(SCH_1):A_CTOP
  28 FM_1GB_LOM_DISABLE_N DEV_OFF_N @BASEBOARD_FAB2_LIB.BASEBOARD_FAB2(SCH_1):FM_1GB_LOM_DISABLE_N
  65    GND    GND @BASEBOARD_FAB2_LIB.BASEBOARD_FAB2(SCH_1):GND
  19 PU_JTAG_SPRV_TCK JTAG_CLK @BASEBOARD_FAB2_LIB.BASEBOARD_FAB2(SCH_1):PU_JTAG_SPRV_TCK
  29 PU_JTAG_SPRV_TDI JTAG_TDI @BASEBOARD_FAB2_LIB.BASEBOARD_FAB2(SCH_1):PU_JTAG_SPRV_TDI
   4 PU_JTAG_SPRV_TDO JTAG_TDO @BASEBOARD_FAB2_LIB.BASEBOARD_FAB2(SCH_1):PU_JTAG_SPRV_TDO
  18 PU_JTAG_SPRV_TMS JTAG_TMS @BASEBOARD_FAB2_LIB.BASEBOARD_FAB2(SCH_1):PU_JTAG_SPRV_TMS
   1 PU_SPRV_LAN_PWR_GOOD LAN_PWR_GOOD @BASEBOARD_FAB2_LIB.BASEBOARD_FAB2(SCH_1):PU_SPRV_LAN_PWR_GOOD
  31 LED_LAN_0_N   LED0 @BASEBOARD_FAB2_LIB.BASEBOARD_FAB2(SCH_1):LED_LAN_0_N
  30 LED_LAN_1_N   LED1 @BASEBOARD_FAB2_LIB.BASEBOARD_FAB2(SCH_1):LED_LAN_1_N
  33 LED_LAN_2_N   LED2 @BASEBOARD_FAB2_LIB.BASEBOARD_FAB2(SCH_1):LED_LAN_2_N
  57 NIC_MDI_SPRV_RJ45_0_DN MDI_MINUS0_SFP_I2C_DATA @BASEBOARD_FAB2_LIB.BASEBOARD_FAB2(SCH_1):NIC_MDI_SPRV_RJ45_0_DN
  54 NIC_MDI_SPRV_RJ45_1_DN MDI_MINUS1_SRDS_SIG_DET @BASEBOARD_FAB2_LIB.BASEBOARD_FAB2(SCH_1):NIC_MDI_SPRV_RJ45_1_DN
  52 NIC_SET_N_MDI_2_DN MDI_MINUS2_SETN @BASEBOARD_FAB2_LIB.BASEBOARD_FAB2(SCH_1):NIC_SET_N_MDI_2_DN
  49 NIC_SER_N_MDI_3_DN MDI_MINUS3_SERN @BASEBOARD_FAB2_LIB.BASEBOARD_FAB2(SCH_1):NIC_SER_N_MDI_3_DN
  58 NIC_MDI_SPRV_RJ45_0_DP MDI_PLUS0_NC @BASEBOARD_FAB2_LIB.BASEBOARD_FAB2(SCH_1):NIC_MDI_SPRV_RJ45_0_DP
  55 NIC_MDI_SPRV_RJ45_1_DP MDI_PLUS1_SFP_I2C_CLK @BASEBOARD_FAB2_LIB.BASEBOARD_FAB2(SCH_1):NIC_MDI_SPRV_RJ45_1_DP
  53 NIC_SET_P_MDI_2_DP MDI_PLUS2_SETP @BASEBOARD_FAB2_LIB.BASEBOARD_FAB2(SCH_1):NIC_SET_P_MDI_2_DP
  50 NIC_SER_P_MDI_3_DP MDI_PLUS3_SERP @BASEBOARD_FAB2_LIB.BASEBOARD_FAB2(SCH_1):NIC_SER_P_MDI_3_DP
  22 NC_SPRNGVLLE_22     NC @BASEBOARD_FAB2_LIB.BASEBOARD_FAB2(SCH_1):NC_SPRNGVLLE_22
  43 RMII_PCH_SPRNGVLLE_ARB_OUT NC_SI_ARB_IN @BASEBOARD_FAB2_LIB.BASEBOARD_FAB2(SCH_1):RMII_PCH_SPRNGVLLE_ARB_OUT
  44 RMII_PCH_SPRNGVLLE_ARB_IN_R NC_SI_ARB_OUT @BASEBOARD_FAB2_LIB.BASEBOARD_FAB2(SCH_1):RMII_PCH_SPRNGVLLE_ARB_IN_R
   2 CLK_50M_CKMNG_SPRVLLE NC_SI_CLK_IN @BASEBOARD_FAB2_LIB.BASEBOARD_FAB2(SCH_1):CLK_50M_CKMNG_SPRVLLE
   3 RMII_BMC_PCH_SPRNGVLLE_CRSDV_R NC_SI_CRS_DV @BASEBOARD_FAB2_LIB.BASEBOARD_FAB2(SCH_1):RMII_BMC_PCH_SPRNGVLLE_CRSDV_R
   6 RMII_SPRNGVLLE_BMC_PCH_RXD0_R NC_SI_RXD0 @BASEBOARD_FAB2_LIB.BASEBOARD_FAB2(SCH_1):RMII_SPRNGVLLE_BMC_PCH_RXD0_R
   5 RMII_SPRNGVLLE_BMC_PCH_RXD1_R NC_SI_RXD1 @BASEBOARD_FAB2_LIB.BASEBOARD_FAB2(SCH_1):RMII_SPRNGVLLE_BMC_PCH_RXD1_R
   9 RMII_BMC_PCH_SPRNGVLLE_TXD0 NC_SI_TXD0 @BASEBOARD_FAB2_LIB.BASEBOARD_FAB2(SCH_1):RMII_BMC_PCH_SPRNGVLLE_TXD0
   8 RMII_BMC_PCH_SPRNGVLLE_TXD1 NC_SI_TXD1 @BASEBOARD_FAB2_LIB.BASEBOARD_FAB2(SCH_1):RMII_BMC_PCH_SPRNGVLLE_TXD1
   7 RMII_BMC_PCH_SPRNGVLLE_TXEN NC_SI_TX_EN @BASEBOARD_FAB2_LIB.BASEBOARD_FAB2(SCH_1):RMII_BMC_PCH_SPRNGVLLE_TXEN
  15 SPI_NIC_CS_R_N NVM_CS_N @BASEBOARD_FAB2_LIB.BASEBOARD_FAB2(SCH_1):SPI_NIC_CS_R_N
  12 SPI_NIC_MOSI_R NVM_SI @BASEBOARD_FAB2_LIB.BASEBOARD_FAB2(SCH_1):SPI_NIC_MOSI_R
  13 SPI_NIC_SCLK_R NVM_SK @BASEBOARD_FAB2_LIB.BASEBOARD_FAB2(SCH_1):SPI_NIC_SCLK_R
  14 SPI_NIC_MISO NVM_SO @BASEBOARD_FAB2_LIB.BASEBOARD_FAB2(SCH_1):SPI_NIC_MISO
  25 CLK_100M_SPRV_DN PECLKN @BASEBOARD_FAB2_LIB.BASEBOARD_FAB2(SCH_1):CLK_100M_SPRV_DN
  26 CLK_100M_SPRV_DP PECLKP @BASEBOARD_FAB2_LIB.BASEBOARD_FAB2(SCH_1):CLK_100M_SPRV_DP
  23 PE_PCH_SPRV_TX_C_DN  PE_RN @BASEBOARD_FAB2_LIB.BASEBOARD_FAB2(SCH_1):PE_PCH_SPRV_TX_C_DN
  24 PE_PCH_SPRV_TX_C_DP  PE_RP @BASEBOARD_FAB2_LIB.BASEBOARD_FAB2(SCH_1):PE_PCH_SPRV_TX_C_DP
  17 RST_PLTRST_SPRV_R_N PE_RST_N @BASEBOARD_FAB2_LIB.BASEBOARD_FAB2(SCH_1):RST_PLTRST_SPRV_R_N
  20 PE_PCH_SPRV_RX_DN  PE_TN @BASEBOARD_FAB2_LIB.BASEBOARD_FAB2(SCH_1):PE_PCH_SPRV_RX_DN
  21 PE_PCH_SPRV_RX_DP  PE_TP @BASEBOARD_FAB2_LIB.BASEBOARD_FAB2(SCH_1):PE_PCH_SPRV_RX_DP
  16 FM_PE_SPRV_WAKE_N PE_WAKE_N @BASEBOARD_FAB2_LIB.BASEBOARD_FAB2(SCH_1):FM_PE_SPRV_WAKE_N
  48 PD_SPRV_RSET   RSET @BASEBOARD_FAB2_LIB.BASEBOARD_FAB2(SCH_1):PD_SPRV_RSET
  63 TP_SPRV_SDP0   SDP0 @BASEBOARD_FAB2_LIB.BASEBOARD_FAB2(SCH_1):TP_SPRV_SDP0
  61 TP_SPRV_SDP1 SDP1_PCIE_DIS_SDP1 @BASEBOARD_FAB2_LIB.BASEBOARD_FAB2(SCH_1):TP_SPRV_SDP1
  62 TP_SPRV_SDP2   SDP2 @BASEBOARD_FAB2_LIB.BASEBOARD_FAB2(SCH_1):TP_SPRV_SDP2
  60 TP_SPRV_SDP3   SDP3 @BASEBOARD_FAB2_LIB.BASEBOARD_FAB2(SCH_1):TP_SPRV_SDP3
  35 IRQ_LOM_ALERT_N SMB_ALRT_N @BASEBOARD_FAB2_LIB.BASEBOARD_FAB2(SCH_1):IRQ_LOM_ALERT_N
  34 SMB_SPRINGVILLE_STBY_LVC3_SCL SMB_CLK @BASEBOARD_FAB2_LIB.BASEBOARD_FAB2(SCH_1):SMB_SPRINGVILLE_STBY_LVC3_SCL
  36 SMB_SPRINGVILLE_STBY_LVC3_SDA SMB_DATA @BASEBOARD_FAB2_LIB.BASEBOARD_FAB2(SCH_1):SMB_SPRINGVILLE_STBY_LVC3_SDA
  42 P0V9_LAN VDD0P9<3> @BASEBOARD_FAB2_LIB.BASEBOARD_FAB2(SCH_1):P0V9_LAN
  11 P0V9_LAN VDD0P9<2> @BASEBOARD_FAB2_LIB.BASEBOARD_FAB2(SCH_1):P0V9_LAN
  32 P0V9_LAN VDD0P9<1> @BASEBOARD_FAB2_LIB.BASEBOARD_FAB2(SCH_1):P0V9_LAN
  59 P0V9_LAN VDD0P9<0> @BASEBOARD_FAB2_LIB.BASEBOARD_FAB2(SCH_1):P0V9_LAN
  38 P0V9_LAN_I210 VDD0P9_OUT @BASEBOARD_FAB2_LIB.BASEBOARD_FAB2(SCH_1):P0V9_LAN_I210
  47 P1V5_LAN VDD1P5<1> @BASEBOARD_FAB2_LIB.BASEBOARD_FAB2(SCH_1):P1V5_LAN
  56 P1V5_LAN_I210 VDD1P5<0> @BASEBOARD_FAB2_LIB.BASEBOARD_FAB2(SCH_1):P1V5_LAN_I210
  39 P1V5_LAN VDD1P5_OUT @BASEBOARD_FAB2_LIB.BASEBOARD_FAB2(SCH_1):P1V5_LAN
  10 P3V3_STBY VDD3P3<4> @BASEBOARD_FAB2_LIB.BASEBOARD_FAB2(SCH_1):P3V3_STBY
  27 P3V3_STBY VDD3P3<3> @BASEBOARD_FAB2_LIB.BASEBOARD_FAB2(SCH_1):P3V3_STBY
  41 P3V3_STBY VDD3P3<2> @BASEBOARD_FAB2_LIB.BASEBOARD_FAB2(SCH_1):P3V3_STBY
  51 P3V3_STBY_P1V5_LAN_I210 VDD3P3<1> @BASEBOARD_FAB2_LIB.BASEBOARD_FAB2(SCH_1):P3V3_STBY_P1V5_LAN_I210
  64 P3V3_STBY VDD3P3<0> @BASEBOARD_FAB2_LIB.BASEBOARD_FAB2(SCH_1):P3V3_STBY
  46 XTAL_25MHZ_IN_R  XTAL1 @BASEBOARD_FAB2_LIB.BASEBOARD_FAB2(SCH_1):XTAL_25MHZ_IN_R
  45 XTAL_25MHZ_OUT  XTAL2 @BASEBOARD_FAB2_LIB.BASEBOARD_FAB2(SCH_1):XTAL_25MHZ_OUT

CAP_0402LF-0.039UF,25V,10%,X7RA  I76  C9E7
   1 A_CTOP      A @BASEBOARD_FAB2_LIB.BASEBOARD_FAB2(SCH_1):A_CTOP
   2 A_CBOT      B @BASEBOARD_FAB2_LIB.BASEBOARD_FAB2(SCH_1):A_CBOT

CAP_A_0402V-0.1UF,16V,10%,X7R,A  I87  C9E5
   1 PE_PCH_SPRV_RX_DN      A @BASEBOARD_FAB2_LIB.BASEBOARD_FAB2(SCH_1):PE_PCH_SPRV_RX_DN
   2 PE_PCH_SPRV_RX_C_DN      B @BASEBOARD_FAB2_LIB.BASEBOARD_FAB2(SCH_1):PE_PCH_SPRV_RX_C_DN

CAP_A_0402V-0.1UF,16V,10%,X7R,A  I88  C9E4
   1 PE_PCH_SPRV_RX_DP      A @BASEBOARD_FAB2_LIB.BASEBOARD_FAB2(SCH_1):PE_PCH_SPRV_RX_DP
   2 PE_PCH_SPRV_RX_C_DP      B @BASEBOARD_FAB2_LIB.BASEBOARD_FAB2(SCH_1):PE_PCH_SPRV_RX_C_DP

CAP_A_0402V-0.1UF,16V,10%,X7R,A  I89  C2M23
   1 PE_PCH_SPRV_TX_DP      A @BASEBOARD_FAB2_LIB.BASEBOARD_FAB2(SCH_1):PE_PCH_SPRV_TX_DP
   2 PE_PCH_SPRV_TX_C_DP      B @BASEBOARD_FAB2_LIB.BASEBOARD_FAB2(SCH_1):PE_PCH_SPRV_TX_C_DP

CAP_A_0402V-0.1UF,16V,10%,X7R,A  I90  C2M24
   1 PE_PCH_SPRV_TX_DN      A @BASEBOARD_FAB2_LIB.BASEBOARD_FAB2(SCH_1):PE_PCH_SPRV_TX_DN
   2 PE_PCH_SPRV_TX_C_DN      B @BASEBOARD_FAB2_LIB.BASEBOARD_FAB2(SCH_1):PE_PCH_SPRV_TX_C_DN

CRYSTAL_2013-25.000MHZ,IC,D717A  I109  Y9E1
   1 XTAL_25MHZ_IN      A @BASEBOARD_FAB2_LIB.BASEBOARD_FAB2(SCH_1):XTAL_25MHZ_IN
   3 XTAL_25MHZ_OUT_R      B @BASEBOARD_FAB2_LIB.BASEBOARD_FAB2(SCH_1):XTAL_25MHZ_OUT_R

RES_0402-0.0,5%,1/16W,CHIP,G21A  I110  R9E20
   1 XTAL_25MHZ_IN      A @BASEBOARD_FAB2_LIB.BASEBOARD_FAB2(SCH_1):XTAL_25MHZ_IN
   2 XTAL_25MHZ_IN_R      B @BASEBOARD_FAB2_LIB.BASEBOARD_FAB2(SCH_1):XTAL_25MHZ_IN_R

CAP_0402LF-22.0PF,50V,5%,COG,AA  I111  C9E8
   1 XTAL_25MHZ_OUT_R      A @BASEBOARD_FAB2_LIB.BASEBOARD_FAB2(SCH_1):XTAL_25MHZ_OUT_R
   2    GND      B @BASEBOARD_FAB2_LIB.BASEBOARD_FAB2(SCH_1):GND

CAP_0402LF-22.0PF,50V,5%,COG,AA  I112  C9E9
   1 XTAL_25MHZ_IN      A @BASEBOARD_FAB2_LIB.BASEBOARD_FAB2(SCH_1):XTAL_25MHZ_IN
   2    GND      B @BASEBOARD_FAB2_LIB.BASEBOARD_FAB2(SCH_1):GND

RES_0402-33.2,1%,1/16W,CHIP,G2A  I128  R9E9
   1 SPI_NIC_MOSI_R      A @BASEBOARD_FAB2_LIB.BASEBOARD_FAB2(SCH_1):SPI_NIC_MOSI_R
   2 SPI_NIC_MOSI      B @BASEBOARD_FAB2_LIB.BASEBOARD_FAB2(SCH_1):SPI_NIC_MOSI

RES_0402-33.2,1%,1/16W,CHIP,G2A  I129  R9E5
   1 SPI_NIC_CS_R_N      A @BASEBOARD_FAB2_LIB.BASEBOARD_FAB2(SCH_1):SPI_NIC_CS_R_N
   2 SPI_NIC_CS_N      B @BASEBOARD_FAB2_LIB.BASEBOARD_FAB2(SCH_1):SPI_NIC_CS_N

RES_0402-33.2,1%,1/16W,CHIP,G2A  I130  R9E8
   1 SPI_NIC_SCLK_R      A @BASEBOARD_FAB2_LIB.BASEBOARD_FAB2(SCH_1):SPI_NIC_SCLK_R
   2 SPI_NIC_SCLK      B @BASEBOARD_FAB2_LIB.BASEBOARD_FAB2(SCH_1):SPI_NIC_SCLK

CAP_0603-10UF,6.3V,20%,X6S,E15A  I134  C1T4
   1 P0V9_LAN      A @BASEBOARD_FAB2_LIB.BASEBOARD_FAB2(SCH_1):P0V9_LAN
   2    GND      B @BASEBOARD_FAB2_LIB.BASEBOARD_FAB2(SCH_1):GND

CAP_0603-10UF,6.3V,20%,X6S,E15A  I135  C1R30
   1 P1V5_LAN      A @BASEBOARD_FAB2_LIB.BASEBOARD_FAB2(SCH_1):P1V5_LAN
   2    GND      B @BASEBOARD_FAB2_LIB.BASEBOARD_FAB2(SCH_1):GND

CAP_0603-10UF,6.3V,20%,X6S,E15A  I136  C1R22
   1 P3V3_STBY      A @BASEBOARD_FAB2_LIB.BASEBOARD_FAB2(SCH_1):P3V3_STBY
   2    GND      B @BASEBOARD_FAB2_LIB.BASEBOARD_FAB2(SCH_1):GND

CAP_1210-47UF,16V,20%,EMPTY,D3A  I140  C9F2
   1 P3V3_STBY      A @BASEBOARD_FAB2_LIB.BASEBOARD_FAB2(SCH_1):P3V3_STBY
   2    GND      B @BASEBOARD_FAB2_LIB.BASEBOARD_FAB2(SCH_1):GND

CAP_0603-10UF,6.3V,20%,X6S,E15A  I142  C1R13
   1 P3V3_STBY      A @BASEBOARD_FAB2_LIB.BASEBOARD_FAB2(SCH_1):P3V3_STBY
   2    GND      B @BASEBOARD_FAB2_LIB.BASEBOARD_FAB2(SCH_1):GND

CAP_A_0402V-0.1UF,16V,10%,X7R,A  I143  C1R20
   1 P3V3_STBY      A @BASEBOARD_FAB2_LIB.BASEBOARD_FAB2(SCH_1):P3V3_STBY
   2    GND      B @BASEBOARD_FAB2_LIB.BASEBOARD_FAB2(SCH_1):GND

CAP_A_0402V-0.1UF,16V,10%,X7R,A  I144  C1T3
   1 P3V3_STBY      A @BASEBOARD_FAB2_LIB.BASEBOARD_FAB2(SCH_1):P3V3_STBY
   2    GND      B @BASEBOARD_FAB2_LIB.BASEBOARD_FAB2(SCH_1):GND

CAP_A_0402V-0.1UF,16V,10%,X7R,A  I145  C1R14
   1 P3V3_STBY      A @BASEBOARD_FAB2_LIB.BASEBOARD_FAB2(SCH_1):P3V3_STBY
   2    GND      B @BASEBOARD_FAB2_LIB.BASEBOARD_FAB2(SCH_1):GND

CAP_A_0402V-0.1UF,16V,10%,X7R,A  I146  C1R21
   1 P3V3_STBY      A @BASEBOARD_FAB2_LIB.BASEBOARD_FAB2(SCH_1):P3V3_STBY
   2    GND      B @BASEBOARD_FAB2_LIB.BASEBOARD_FAB2(SCH_1):GND

CAP_A_0402V-0.1UF,16V,10%,X7R,A  I149  C1R26
   1 P1V5_LAN      A @BASEBOARD_FAB2_LIB.BASEBOARD_FAB2(SCH_1):P1V5_LAN
   2    GND      B @BASEBOARD_FAB2_LIB.BASEBOARD_FAB2(SCH_1):GND

CAP_A_0402V-0.1UF,16V,10%,X7R,A  I150  C1R29
   1 P1V5_LAN      A @BASEBOARD_FAB2_LIB.BASEBOARD_FAB2(SCH_1):P1V5_LAN
   2    GND      B @BASEBOARD_FAB2_LIB.BASEBOARD_FAB2(SCH_1):GND

CAP_A_0402V-0.1UF,16V,10%,X7R,A  I151  C1R19
   1 P1V5_LAN      A @BASEBOARD_FAB2_LIB.BASEBOARD_FAB2(SCH_1):P1V5_LAN
   2    GND      B @BASEBOARD_FAB2_LIB.BASEBOARD_FAB2(SCH_1):GND

CAP_A_0402V-0.1UF,16V,10%,X7R,A  I152  C1R31
   1 P1V5_LAN      A @BASEBOARD_FAB2_LIB.BASEBOARD_FAB2(SCH_1):P1V5_LAN
   2    GND      B @BASEBOARD_FAB2_LIB.BASEBOARD_FAB2(SCH_1):GND

CAP_0603-10UF,6.3V,20%,X6S,E15A  I153  C1R17
   1 P1V5_LAN      A @BASEBOARD_FAB2_LIB.BASEBOARD_FAB2(SCH_1):P1V5_LAN
   2    GND      B @BASEBOARD_FAB2_LIB.BASEBOARD_FAB2(SCH_1):GND

CAP_1210-47UF,16V,20%,EMPTY,D3A  I155  C9E6
   1 P1V5_LAN      A @BASEBOARD_FAB2_LIB.BASEBOARD_FAB2(SCH_1):P1V5_LAN
   2    GND      B @BASEBOARD_FAB2_LIB.BASEBOARD_FAB2(SCH_1):GND

CAP_A_0402V-0.1UF,16V,10%,X7R,A  I157  C1R18
   1 P0V9_LAN      A @BASEBOARD_FAB2_LIB.BASEBOARD_FAB2(SCH_1):P0V9_LAN
   2    GND      B @BASEBOARD_FAB2_LIB.BASEBOARD_FAB2(SCH_1):GND

CAP_A_0402V-0.1UF,16V,10%,X7R,A  I158  C1T5
   1 P0V9_LAN      A @BASEBOARD_FAB2_LIB.BASEBOARD_FAB2(SCH_1):P0V9_LAN
   2    GND      B @BASEBOARD_FAB2_LIB.BASEBOARD_FAB2(SCH_1):GND

CAP_A_0402V-0.1UF,16V,10%,X7R,A  I159  C1R24
   1 P0V9_LAN      A @BASEBOARD_FAB2_LIB.BASEBOARD_FAB2(SCH_1):P0V9_LAN
   2    GND      B @BASEBOARD_FAB2_LIB.BASEBOARD_FAB2(SCH_1):GND

CAP_A_0402V-0.1UF,16V,10%,X7R,A  I160  C1R15
   1 P0V9_LAN      A @BASEBOARD_FAB2_LIB.BASEBOARD_FAB2(SCH_1):P0V9_LAN
   2    GND      B @BASEBOARD_FAB2_LIB.BASEBOARD_FAB2(SCH_1):GND

CAP_0603-10UF,6.3V,20%,X6S,E15A  I161  C1R16
   1 P0V9_LAN      A @BASEBOARD_FAB2_LIB.BASEBOARD_FAB2(SCH_1):P0V9_LAN
   2    GND      B @BASEBOARD_FAB2_LIB.BASEBOARD_FAB2(SCH_1):GND

CAP_A_0603V-22.0UF,4V,20%,EMPTA  I163  C9E1
   1 P0V9_LAN      A @BASEBOARD_FAB2_LIB.BASEBOARD_FAB2(SCH_1):P0V9_LAN
   2    GND      B @BASEBOARD_FAB2_LIB.BASEBOARD_FAB2(SCH_1):GND

RES_0402-3.32K,1%,1/16W,CHIP,GA  I173  R9F5
   1 P3V3_STBY      A @BASEBOARD_FAB2_LIB.BASEBOARD_FAB2(SCH_1):P3V3_STBY
   2 PU_SPRV_LAN_PWR_GOOD      B @BASEBOARD_FAB2_LIB.BASEBOARD_FAB2(SCH_1):PU_SPRV_LAN_PWR_GOOD

RES_0402-4.99K,1%,1/16W,CHIP,GA  I174  R9E23
   1 PD_SPRV_RSET      A @BASEBOARD_FAB2_LIB.BASEBOARD_FAB2(SCH_1):PD_SPRV_RSET
   2    GND      B @BASEBOARD_FAB2_LIB.BASEBOARD_FAB2(SCH_1):GND

RES_0402-10.0K,1%,1/16W,CHIP,GA  I177  R9E2
   1 P3V3_STBY      A @BASEBOARD_FAB2_LIB.BASEBOARD_FAB2(SCH_1):P3V3_STBY
   2 PU_JTAG_SPRV_TCK      B @BASEBOARD_FAB2_LIB.BASEBOARD_FAB2(SCH_1):PU_JTAG_SPRV_TCK

RES_0402-10.0K,1%,1/16W,CHIP,GA  I178  R9E3
   1 P3V3_STBY      A @BASEBOARD_FAB2_LIB.BASEBOARD_FAB2(SCH_1):P3V3_STBY
   2 PU_JTAG_SPRV_TMS      B @BASEBOARD_FAB2_LIB.BASEBOARD_FAB2(SCH_1):PU_JTAG_SPRV_TMS

RES_0402-10.0K,1%,1/16W,CHIP,GA  I179  R9E1
   1 P3V3_STBY      A @BASEBOARD_FAB2_LIB.BASEBOARD_FAB2(SCH_1):P3V3_STBY
   2 PU_JTAG_SPRV_TDI      B @BASEBOARD_FAB2_LIB.BASEBOARD_FAB2(SCH_1):PU_JTAG_SPRV_TDI

RES_0402-10.0K,1%,1/16W,CHIP,GA  I181  R9E22
   1 PU_JTAG_SPRV_TDO      A @BASEBOARD_FAB2_LIB.BASEBOARD_FAB2(SCH_1):PU_JTAG_SPRV_TDO
   2 P3V3_STBY      B @BASEBOARD_FAB2_LIB.BASEBOARD_FAB2(SCH_1):P3V3_STBY

RES_0402-3.32K,1%,1/16W,CHIP,GA  I193  R9E7
   1 P3V3_STBY      A @BASEBOARD_FAB2_LIB.BASEBOARD_FAB2(SCH_1):P3V3_STBY
   2 IRQ_LOM_ALERT_N      B @BASEBOARD_FAB2_LIB.BASEBOARD_FAB2(SCH_1):IRQ_LOM_ALERT_N

RES_0402-0.0,5%,1/16W,CHIP,G21A  I195  R1R1
   1 RST_PLTRST_N      A @BASEBOARD_FAB2_LIB.BASEBOARD_FAB2(SCH_1):RST_PLTRST_N
   2 RST_PLTRST_SPRV_R_N      B @BASEBOARD_FAB2_LIB.BASEBOARD_FAB2(SCH_1):RST_PLTRST_SPRV_R_N

RES_0402-10.0K,1%,1/16W,CHIP,GA  I200  R9E4
   1 P3V3_STBY      A @BASEBOARD_FAB2_LIB.BASEBOARD_FAB2(SCH_1):P3V3_STBY
   2 RST_PLTRST_SPRV_R_N      B @BASEBOARD_FAB2_LIB.BASEBOARD_FAB2(SCH_1):RST_PLTRST_SPRV_R_N

RES_0402-0.0,5%,1/16W,CHIP,G21A  I201  R9E18
   1 XTAL_25MHZ_OUT_R      A @BASEBOARD_FAB2_LIB.BASEBOARD_FAB2(SCH_1):XTAL_25MHZ_OUT_R
   2 XTAL_25MHZ_OUT      B @BASEBOARD_FAB2_LIB.BASEBOARD_FAB2(SCH_1):XTAL_25MHZ_OUT

RES_0402-10.0K,1%,1/16W,CHIP,GA  I212  R9E13
   1 RMII_BMC_PCH_SPRNGVLLE_TXEN      A @BASEBOARD_FAB2_LIB.BASEBOARD_FAB2(SCH_1):RMII_BMC_PCH_SPRNGVLLE_TXEN
   2    GND      B @BASEBOARD_FAB2_LIB.BASEBOARD_FAB2(SCH_1):GND

RES_0402-10.0K,1%,1/16W,CHIP,GA  I213  R1R12
   1 CLK_50M_CKMNG_SPRVLLE      A @BASEBOARD_FAB2_LIB.BASEBOARD_FAB2(SCH_1):CLK_50M_CKMNG_SPRVLLE
   2    GND      B @BASEBOARD_FAB2_LIB.BASEBOARD_FAB2(SCH_1):GND

RES_0402-10.0K,1%,1/16W,CHIP,GA  I214  R1T1
   1 RMII_BMC_PCH_SPRNGVLLE_CRSDV      A @BASEBOARD_FAB2_LIB.BASEBOARD_FAB2(SCH_1):RMII_BMC_PCH_SPRNGVLLE_CRSDV
   2    GND      B @BASEBOARD_FAB2_LIB.BASEBOARD_FAB2(SCH_1):GND

RES_0402-22.1,1.0%,1/16W,CHIP,A  I225  R9F1
   1 RMII_BMC_PCH_SPRNGVLLE_CRSDV_R      A @BASEBOARD_FAB2_LIB.BASEBOARD_FAB2(SCH_1):RMII_BMC_PCH_SPRNGVLLE_CRSDV_R
   2 RMII_BMC_PCH_SPRNGVLLE_CRSDV      B @BASEBOARD_FAB2_LIB.BASEBOARD_FAB2(SCH_1):RMII_BMC_PCH_SPRNGVLLE_CRSDV

RES_0402-22.1,1.0%,1/16W,CHIP,A  I228  R9E19
   1 RMII_SPRNGVLLE_BMC_PCH_RXD1_R      A @BASEBOARD_FAB2_LIB.BASEBOARD_FAB2(SCH_1):RMII_SPRNGVLLE_BMC_PCH_RXD1_R
   2 RMII_SPRNGVLLE_BMC_PCH_RXD1      B @BASEBOARD_FAB2_LIB.BASEBOARD_FAB2(SCH_1):RMII_SPRNGVLLE_BMC_PCH_RXD1

RES_0402-22.1,1.0%,1/16W,CHIP,A  I229  R9E17
   1 RMII_SPRNGVLLE_BMC_PCH_RXD0_R      A @BASEBOARD_FAB2_LIB.BASEBOARD_FAB2(SCH_1):RMII_SPRNGVLLE_BMC_PCH_RXD0_R
   2 RMII_SPRNGVLLE_BMC_PCH_RXD0      B @BASEBOARD_FAB2_LIB.BASEBOARD_FAB2(SCH_1):RMII_SPRNGVLLE_BMC_PCH_RXD0

RES_0402-33.2,1%,1/16W,CHIP,G2A  I235  R9E16
   1 RMII_PCH_SPRNGVLLE_ARB_IN_R      A @BASEBOARD_FAB2_LIB.BASEBOARD_FAB2(SCH_1):RMII_PCH_SPRNGVLLE_ARB_IN_R
   2 RMII_PCH_SPRNGVLLE_ARB_IN      B @BASEBOARD_FAB2_LIB.BASEBOARD_FAB2(SCH_1):RMII_PCH_SPRNGVLLE_ARB_IN

RES_0603-0,5.0%,1/10W,CHIP,G22A  I237  R1R15
   1 P0V9_LAN      A @BASEBOARD_FAB2_LIB.BASEBOARD_FAB2(SCH_1):P0V9_LAN
   2 P0V9_LAN_I210      B @BASEBOARD_FAB2_LIB.BASEBOARD_FAB2(SCH_1):P0V9_LAN_I210

RES_0603-0,5.0%,1/10W,CHIP,G22A  I238  R1T32
   1 P1V5_LAN      A @BASEBOARD_FAB2_LIB.BASEBOARD_FAB2(SCH_1):P1V5_LAN
   2 P1V5_LAN_I210      B @BASEBOARD_FAB2_LIB.BASEBOARD_FAB2(SCH_1):P1V5_LAN_I210

RES_0603-0,5.0%,1/10W,CHIP,G22A  I239  R1T34
   1 P3V3_STBY      A @BASEBOARD_FAB2_LIB.BASEBOARD_FAB2(SCH_1):P3V3_STBY
   2 P3V3_STBY_P1V5_LAN_I210      B @BASEBOARD_FAB2_LIB.BASEBOARD_FAB2(SCH_1):P3V3_STBY_P1V5_LAN_I210

RES_0603-0,5.0%,1/10W,EMPTY,G2A  I240  R1T33
   1 P1V5_LAN      A @BASEBOARD_FAB2_LIB.BASEBOARD_FAB2(SCH_1):P1V5_LAN
   2 P3V3_STBY_P1V5_LAN_I210      B @BASEBOARD_FAB2_LIB.BASEBOARD_FAB2(SCH_1):P3V3_STBY_P1V5_LAN_I210

CAP_A_0603V-22.0UF,4V,20%,EMPTA  I241  C9E12
   1 P0V9_LAN      A @BASEBOARD_FAB2_LIB.BASEBOARD_FAB2(SCH_1):P0V9_LAN
   2    GND      B @BASEBOARD_FAB2_LIB.BASEBOARD_FAB2(SCH_1):GND


DRAWING: @BASEBOARD_FAB2_LIB.BASEBOARD_FAB2(SCH_1):PAGE140 

M25PE16_SM-IC,H77797-001  I1  U9E1
   1 SPI_NIC_CS_N    S_N @BASEBOARD_FAB2_LIB.BASEBOARD_FAB2(SCH_1):SPI_NIC_CS_N
   7 PU_NV_HOLD_N RESET_N @BASEBOARD_FAB2_LIB.BASEBOARD_FAB2(SCH_1):PU_NV_HOLD_N
   6 SPI_NIC_SCLK      C @BASEBOARD_FAB2_LIB.BASEBOARD_FAB2(SCH_1):SPI_NIC_SCLK
   5 SPI_NIC_MOSI    DQ0 @BASEBOARD_FAB2_LIB.BASEBOARD_FAB2(SCH_1):SPI_NIC_MOSI
   2 SPI_NIC_MISO_R    DQ1 @BASEBOARD_FAB2_LIB.BASEBOARD_FAB2(SCH_1):SPI_NIC_MISO_R
   8 P3V3_STBY    VCC @BASEBOARD_FAB2_LIB.BASEBOARD_FAB2(SCH_1):P3V3_STBY
   4    GND    VSS @BASEBOARD_FAB2_LIB.BASEBOARD_FAB2(SCH_1):GND
   3 PU_NV_WP_N    W_N @BASEBOARD_FAB2_LIB.BASEBOARD_FAB2(SCH_1):PU_NV_WP_N

CAP_A_0402V-0.1UF,16V,10%,X7R,A  I3  C1R25
   1 P3V3_STBY      A @BASEBOARD_FAB2_LIB.BASEBOARD_FAB2(SCH_1):P3V3_STBY
   2    GND      B @BASEBOARD_FAB2_LIB.BASEBOARD_FAB2(SCH_1):GND

RES_0402-3.32K,1%,1/16W,CHIP,GA  I10  R1R9
   1 P3V3_STBY      A @BASEBOARD_FAB2_LIB.BASEBOARD_FAB2(SCH_1):P3V3_STBY
   2 PU_NV_HOLD_N      B @BASEBOARD_FAB2_LIB.BASEBOARD_FAB2(SCH_1):PU_NV_HOLD_N

RES_0402-3.32K,1%,1/16W,CHIP,GA  I11  R1R3
   1 P3V3_STBY      A @BASEBOARD_FAB2_LIB.BASEBOARD_FAB2(SCH_1):P3V3_STBY
   2 PU_NV_WP_N      B @BASEBOARD_FAB2_LIB.BASEBOARD_FAB2(SCH_1):PU_NV_WP_N

RES_0402-20.0K,1%,1/16W,CHIP,GA  I12  R1R7
   1 P3V3_STBY      A @BASEBOARD_FAB2_LIB.BASEBOARD_FAB2(SCH_1):P3V3_STBY
   2 SPI_NIC_MOSI      B @BASEBOARD_FAB2_LIB.BASEBOARD_FAB2(SCH_1):SPI_NIC_MOSI

RES_0402-3.32K,1%,1/16W,EMPTY,A  I14  R1R6
   1 SPI_NIC_MOSI      A @BASEBOARD_FAB2_LIB.BASEBOARD_FAB2(SCH_1):SPI_NIC_MOSI
   2    GND      B @BASEBOARD_FAB2_LIB.BASEBOARD_FAB2(SCH_1):GND

RES_0402-33.2,1%,1/16W,CHIP,G2A  I17  R9E6
   1 SPI_NIC_MISO_R      A @BASEBOARD_FAB2_LIB.BASEBOARD_FAB2(SCH_1):SPI_NIC_MISO_R
   2 SPI_NIC_MISO      B @BASEBOARD_FAB2_LIB.BASEBOARD_FAB2(SCH_1):SPI_NIC_MISO


DRAWING: @BASEBOARD_FAB2_LIB.BASEBOARD_FAB2(SCH_1):PAGE141 

RES_0402-150.0,1%,1/16W,CHIP,GA  I28  R9G3
   1 LED_LAN_0_R_N      A @BASEBOARD_FAB2_LIB.BASEBOARD_FAB2(SCH_1):LED_LAN_0_R_N
   2 LED_LAN_0_N      B @BASEBOARD_FAB2_LIB.BASEBOARD_FAB2(SCH_1):LED_LAN_0_N

RES_0402-150.0,1%,1/16W,CHIP,GA  I30  R9G2
   1 LED_LAN_2_R_N      A @BASEBOARD_FAB2_LIB.BASEBOARD_FAB2(SCH_1):LED_LAN_2_R_N
   2 LED_LAN_2_N      B @BASEBOARD_FAB2_LIB.BASEBOARD_FAB2(SCH_1):LED_LAN_2_N

CAP_A_0402V-0.1UF,16V,10%,X7R,A  I33  C9G7
   1 P3V3_STBY      A @BASEBOARD_FAB2_LIB.BASEBOARD_FAB2(SCH_1):P3V3_STBY
   2    GND      B @BASEBOARD_FAB2_LIB.BASEBOARD_FAB2(SCH_1):GND

CAP_0402LF-470PF,50V,10%,X7R,AA  I36  C9G2
   1 P3V3_STBY      A @BASEBOARD_FAB2_LIB.BASEBOARD_FAB2(SCH_1):P3V3_STBY
   2    GND      B @BASEBOARD_FAB2_LIB.BASEBOARD_FAB2(SCH_1):GND

CAP_A_0402V-0.1UF,16V,10%,X7R,A  I46  C9G4
   1 GND_LAN_TRCT1234_C      A @BASEBOARD_FAB2_LIB.BASEBOARD_FAB2(SCH_1):GND_LAN_TRCT1234_C
   2    GND      B @BASEBOARD_FAB2_LIB.BASEBOARD_FAB2(SCH_1):GND

CAP_A_0402V-0.1UF,16V,10%,X7R,A  I47  C9G6
   1 GND_LAN_TRCT1234_C      A @BASEBOARD_FAB2_LIB.BASEBOARD_FAB2(SCH_1):GND_LAN_TRCT1234_C
   2    GND      B @BASEBOARD_FAB2_LIB.BASEBOARD_FAB2(SCH_1):GND

CAP_0402-1.0UF,16V,10%,X7S,G71A  I48  C9G5
   1 GND_LAN_TRCT1234_C      A @BASEBOARD_FAB2_LIB.BASEBOARD_FAB2(SCH_1):GND_LAN_TRCT1234_C
   2    GND      B @BASEBOARD_FAB2_LIB.BASEBOARD_FAB2(SCH_1):GND

RES_0402-150.0,1%,1/16W,CHIP,GA  I54  R9G1
   1 LED_LAN_1_N      A @BASEBOARD_FAB2_LIB.BASEBOARD_FAB2(SCH_1):LED_LAN_1_N
   2 LED_LAN_1_R_N      B @BASEBOARD_FAB2_LIB.BASEBOARD_FAB2(SCH_1):LED_LAN_1_R_N

RES_0402-0.0,5%,1/16W,CHIP,G21A  I56  R9G4
   1 NIC_LED_ACT_ANODE_R      A @BASEBOARD_FAB2_LIB.BASEBOARD_FAB2(SCH_1):NIC_LED_ACT_ANODE_R
   2 P3V3_STBY      B @BASEBOARD_FAB2_LIB.BASEBOARD_FAB2(SCH_1):P3V3_STBY

CAP_0402LF-470PF,50V,10%,X7R,AA  I58  C9G1
   1 LED_LAN_2_N      A @BASEBOARD_FAB2_LIB.BASEBOARD_FAB2(SCH_1):LED_LAN_2_N
   2    GND      B @BASEBOARD_FAB2_LIB.BASEBOARD_FAB2(SCH_1):GND

CAP_0402LF-470PF,50V,10%,X7R,AA  I59  C9G3
   1 LED_LAN_0_N      A @BASEBOARD_FAB2_LIB.BASEBOARD_FAB2(SCH_1):LED_LAN_0_N
   2    GND      B @BASEBOARD_FAB2_LIB.BASEBOARD_FAB2(SCH_1):GND

CAP_0402LF-470PF,50V,10%,X7R,AA  I60  C9F22
   1 LED_LAN_1_N      A @BASEBOARD_FAB2_LIB.BASEBOARD_FAB2(SCH_1):LED_LAN_1_N
   2    GND      B @BASEBOARD_FAB2_LIB.BASEBOARD_FAB2(SCH_1):GND

RES_0402-0.0,5%,1/16W,CHIP,G21A  I75  R9G9
   1 NIC_SER_P_MDI_3_DP      A @BASEBOARD_FAB2_LIB.BASEBOARD_FAB2(SCH_1):NIC_SER_P_MDI_3_DP
   2 NIC_MDI_SPRV_RJ45_3_R_DP      B @BASEBOARD_FAB2_LIB.BASEBOARD_FAB2(SCH_1):NIC_MDI_SPRV_RJ45_3_R_DP

RES_0402-0.0,5%,1/16W,CHIP,G21A  I76  R9G11
   1 NIC_SER_N_MDI_3_DN      A @BASEBOARD_FAB2_LIB.BASEBOARD_FAB2(SCH_1):NIC_SER_N_MDI_3_DN
   2 NIC_MDI_SPRV_RJ45_3_R_DN      B @BASEBOARD_FAB2_LIB.BASEBOARD_FAB2(SCH_1):NIC_MDI_SPRV_RJ45_3_R_DN

RES_0402-0.0,5%,1/16W,CHIP,G21A  I77  R9G18
   1 NIC_SET_P_MDI_2_DP      A @BASEBOARD_FAB2_LIB.BASEBOARD_FAB2(SCH_1):NIC_SET_P_MDI_2_DP
   2 NIC_MDI_SPRV_RJ45_2_R_DP      B @BASEBOARD_FAB2_LIB.BASEBOARD_FAB2(SCH_1):NIC_MDI_SPRV_RJ45_2_R_DP

RES_0402-0.0,5%,1/16W,CHIP,G21A  I78  R9G17
   1 NIC_SET_N_MDI_2_DN      A @BASEBOARD_FAB2_LIB.BASEBOARD_FAB2(SCH_1):NIC_SET_N_MDI_2_DN
   2 NIC_MDI_SPRV_RJ45_2_R_DN      B @BASEBOARD_FAB2_LIB.BASEBOARD_FAB2(SCH_1):NIC_MDI_SPRV_RJ45_2_R_DN

RES_0402-0.0,5%,1/16W,CHIP,G21A  I79  R9G19
   1 NIC_MDI_SPRV_RJ45_1_DP      A @BASEBOARD_FAB2_LIB.BASEBOARD_FAB2(SCH_1):NIC_MDI_SPRV_RJ45_1_DP
   2 NIC_MDI_SPRV_RJ45_1_R_DP      B @BASEBOARD_FAB2_LIB.BASEBOARD_FAB2(SCH_1):NIC_MDI_SPRV_RJ45_1_R_DP

RES_0402-0.0,5%,1/16W,CHIP,G21A  I80  R9G20
   1 NIC_MDI_SPRV_RJ45_1_DN      A @BASEBOARD_FAB2_LIB.BASEBOARD_FAB2(SCH_1):NIC_MDI_SPRV_RJ45_1_DN
   2 NIC_MDI_SPRV_RJ45_1_R_DN      B @BASEBOARD_FAB2_LIB.BASEBOARD_FAB2(SCH_1):NIC_MDI_SPRV_RJ45_1_R_DN

RES_0402-0.0,5%,1/16W,CHIP,G21A  I81  R9G24
   1 NIC_MDI_SPRV_RJ45_0_DP      A @BASEBOARD_FAB2_LIB.BASEBOARD_FAB2(SCH_1):NIC_MDI_SPRV_RJ45_0_DP
   2 NIC_MDI_SPRV_RJ45_0_R_DP      B @BASEBOARD_FAB2_LIB.BASEBOARD_FAB2(SCH_1):NIC_MDI_SPRV_RJ45_0_R_DP

RES_0402-0.0,5%,1/16W,CHIP,G21A  I82  R9G22
   1 NIC_MDI_SPRV_RJ45_0_DN      A @BASEBOARD_FAB2_LIB.BASEBOARD_FAB2(SCH_1):NIC_MDI_SPRV_RJ45_0_DN
   2 NIC_MDI_SPRV_RJ45_0_R_DN      B @BASEBOARD_FAB2_LIB.BASEBOARD_FAB2(SCH_1):NIC_MDI_SPRV_RJ45_0_R_DN

CAP_0402LF-4700PF,50V,10%,EMPTA  I99  C9G9
   1 NIC_SER_P_MDI_3_DP      A @BASEBOARD_FAB2_LIB.BASEBOARD_FAB2(SCH_1):NIC_SER_P_MDI_3_DP
   2 NIC_MDI_MNG_RX_DP      B @BASEBOARD_FAB2_LIB.BASEBOARD_FAB2(SCH_1):NIC_MDI_MNG_RX_DP

CAP_0402LF-4700PF,50V,10%,EMPTA  I100  C9G12
   1 NIC_SER_N_MDI_3_DN      A @BASEBOARD_FAB2_LIB.BASEBOARD_FAB2(SCH_1):NIC_SER_N_MDI_3_DN
   2 NIC_MDI_MNG_RX_DN      B @BASEBOARD_FAB2_LIB.BASEBOARD_FAB2(SCH_1):NIC_MDI_MNG_RX_DN

CAP_0402LF-4700PF,50V,10%,EMPTA  I101  C9G16
   1 NIC_SET_P_MDI_2_DP      A @BASEBOARD_FAB2_LIB.BASEBOARD_FAB2(SCH_1):NIC_SET_P_MDI_2_DP
   2 NIC_MDI_MNG_TX_DP      B @BASEBOARD_FAB2_LIB.BASEBOARD_FAB2(SCH_1):NIC_MDI_MNG_TX_DP

CAP_0402LF-4700PF,50V,10%,EMPTA  I102  C9G13
   1 NIC_SET_N_MDI_2_DN      A @BASEBOARD_FAB2_LIB.BASEBOARD_FAB2(SCH_1):NIC_SET_N_MDI_2_DN
   2 NIC_MDI_MNG_TX_DN      B @BASEBOARD_FAB2_LIB.BASEBOARD_FAB2(SCH_1):NIC_MDI_MNG_TX_DN

CONN17_H71061002_PIP1-CONN,H71A  I109  JA9G1
 MH2 GND_NIC    MH2 @BASEBOARD_FAB2_LIB.BASEBOARD_FAB2(SCH_1):GND_NIC
 MH1 GND_NIC    MH1 @BASEBOARD_FAB2_LIB.BASEBOARD_FAB2(SCH_1):GND_NIC
  R1 GND_LAN_TRCT1234_C  TRCT3 @BASEBOARD_FAB2_LIB.BASEBOARD_FAB2(SCH_1):GND_LAN_TRCT1234_C
  R2 NIC_MDI_SPRV_RJ45_2_R_DN  TRD3N @BASEBOARD_FAB2_LIB.BASEBOARD_FAB2(SCH_1):NIC_MDI_SPRV_RJ45_2_R_DN
  R3 NIC_MDI_SPRV_RJ45_2_R_DP  TRD3P @BASEBOARD_FAB2_LIB.BASEBOARD_FAB2(SCH_1):NIC_MDI_SPRV_RJ45_2_R_DP
  R4 NIC_MDI_SPRV_RJ45_1_R_DP  TRD2P @BASEBOARD_FAB2_LIB.BASEBOARD_FAB2(SCH_1):NIC_MDI_SPRV_RJ45_1_R_DP
  R5 NIC_MDI_SPRV_RJ45_1_R_DN  TRD2N @BASEBOARD_FAB2_LIB.BASEBOARD_FAB2(SCH_1):NIC_MDI_SPRV_RJ45_1_R_DN
  R6 GND_LAN_TRCT1234_C  TRCT2 @BASEBOARD_FAB2_LIB.BASEBOARD_FAB2(SCH_1):GND_LAN_TRCT1234_C
  R7 GND_LAN_TRCT1234_C  TRCT4 @BASEBOARD_FAB2_LIB.BASEBOARD_FAB2(SCH_1):GND_LAN_TRCT1234_C
  R8 NIC_MDI_SPRV_RJ45_3_R_DP  TRD4P @BASEBOARD_FAB2_LIB.BASEBOARD_FAB2(SCH_1):NIC_MDI_SPRV_RJ45_3_R_DP
  R9 NIC_MDI_SPRV_RJ45_3_R_DN  TRD4N @BASEBOARD_FAB2_LIB.BASEBOARD_FAB2(SCH_1):NIC_MDI_SPRV_RJ45_3_R_DN
 R10 NIC_MDI_SPRV_RJ45_0_R_DN  TRD1N @BASEBOARD_FAB2_LIB.BASEBOARD_FAB2(SCH_1):NIC_MDI_SPRV_RJ45_0_R_DN
 R11 NIC_MDI_SPRV_RJ45_0_R_DP  TRD1P @BASEBOARD_FAB2_LIB.BASEBOARD_FAB2(SCH_1):NIC_MDI_SPRV_RJ45_0_R_DP
 R12 GND_LAN_TRCT1234_C  TRCT1 @BASEBOARD_FAB2_LIB.BASEBOARD_FAB2(SCH_1):GND_LAN_TRCT1234_C
  L3 LED_LAN_2_R_N     L3 @BASEBOARD_FAB2_LIB.BASEBOARD_FAB2(SCH_1):LED_LAN_2_R_N
  L2 P3V3_STBY     L2 @BASEBOARD_FAB2_LIB.BASEBOARD_FAB2(SCH_1):P3V3_STBY
  L1 LED_LAN_0_R_N     L1 @BASEBOARD_FAB2_LIB.BASEBOARD_FAB2(SCH_1):LED_LAN_0_R_N
  L5 LED_LAN_1_R_N     L5 @BASEBOARD_FAB2_LIB.BASEBOARD_FAB2(SCH_1):LED_LAN_1_R_N
  L4 NIC_LED_ACT_ANODE_R     L4 @BASEBOARD_FAB2_LIB.BASEBOARD_FAB2(SCH_1):NIC_LED_ACT_ANODE_R

RES_0402-0.0,5%,1/16W,CHIP,G21A  I112  R1U51
   1    GND      A @BASEBOARD_FAB2_LIB.BASEBOARD_FAB2(SCH_1):GND
   2 GND_NIC      B @BASEBOARD_FAB2_LIB.BASEBOARD_FAB2(SCH_1):GND_NIC

RES_0402-0.0,5%,1/16W,CHIP,G21A  I114  R1U3
   1    GND      A @BASEBOARD_FAB2_LIB.BASEBOARD_FAB2(SCH_1):GND
   2 GND_NIC      B @BASEBOARD_FAB2_LIB.BASEBOARD_FAB2(SCH_1):GND_NIC


DRAWING: @BASEBOARD_FAB2_LIB.BASEBOARD_FAB2(SCH_1):PAGE142 

TTL1G126_A_SOT-74HC1G126,IC,A7B  I1  U8E4
   1 PU_TRI_STATE_EN     OE @BASEBOARD_FAB2_LIB.BASEBOARD_FAB2(SCH_1):PU_TRI_STATE_EN
   2 FM_ALL_WAKE_N      A @BASEBOARD_FAB2_LIB.BASEBOARD_FAB2(SCH_1):FM_ALL_WAKE_N
   4 IRQ_LVC3_WAKE_R_N      Y @BASEBOARD_FAB2_LIB.BASEBOARD_FAB2(SCH_1):IRQ_LVC3_WAKE_R_N

RES_0402-33.2,1%,1/16W,CHIP,G2A  I2  R8E17
   1 IRQ_LVC3_WAKE_R_N      A @BASEBOARD_FAB2_LIB.BASEBOARD_FAB2(SCH_1):IRQ_LVC3_WAKE_R_N
   2 IRQ_LVC3_WAKE_N      B @BASEBOARD_FAB2_LIB.BASEBOARD_FAB2(SCH_1):IRQ_LVC3_WAKE_N

RES_0402-4.75K,1%,1/16W,CHIP,GA  I3  R8E23
   1 PU_TRI_STATE_EN      A @BASEBOARD_FAB2_LIB.BASEBOARD_FAB2(SCH_1):PU_TRI_STATE_EN
   2 P3V3_STBY      B @BASEBOARD_FAB2_LIB.BASEBOARD_FAB2(SCH_1):P3V3_STBY

RES_0402-0.0,5%,1/16W,EMPTY,G2A  I18  R8E29
   1 FM_PE_BMC_WAKE_N      A @BASEBOARD_FAB2_LIB.BASEBOARD_FAB2(SCH_1):FM_PE_BMC_WAKE_N
   2 FM_ALL_WAKE_N      B @BASEBOARD_FAB2_LIB.BASEBOARD_FAB2(SCH_1):FM_ALL_WAKE_N

CAP_A_0402V-0.1UF,16V,10%,X7R,A  I20  C8E5
   1 P3V3_STBY      A @BASEBOARD_FAB2_LIB.BASEBOARD_FAB2(SCH_1):P3V3_STBY
   2    GND      B @BASEBOARD_FAB2_LIB.BASEBOARD_FAB2(SCH_1):GND

RES_0402-10.0K,1%,1/16W,CHIP,GA  I23  R8E30
   1 P3V3_STBY      A @BASEBOARD_FAB2_LIB.BASEBOARD_FAB2(SCH_1):P3V3_STBY
   2 FM_ALL_WAKE_N      B @BASEBOARD_FAB2_LIB.BASEBOARD_FAB2(SCH_1):FM_ALL_WAKE_N

RES_0402-10.0K,1%,1/16W,CHIP,GA  I28  R8E36
   1 P3V3_STBY      A @BASEBOARD_FAB2_LIB.BASEBOARD_FAB2(SCH_1):P3V3_STBY
   2 FM_PE_SLOTX24_WAKE_N      B @BASEBOARD_FAB2_LIB.BASEBOARD_FAB2(SCH_1):FM_PE_SLOTX24_WAKE_N

RES_0402-0.0,5%,1/16W,CHIP,G21A  I30  R8E26
   1 FM_PE_OCP_WAKE_N      A @BASEBOARD_FAB2_LIB.BASEBOARD_FAB2(SCH_1):FM_PE_OCP_WAKE_N
   2 FM_ALL_WAKE_N      B @BASEBOARD_FAB2_LIB.BASEBOARD_FAB2(SCH_1):FM_ALL_WAKE_N

RES_0402-0.0,5%,1/16W,CHIP,G21A  I31  R8E28
   1 FM_PE_SLOTX24_WAKE_N      A @BASEBOARD_FAB2_LIB.BASEBOARD_FAB2(SCH_1):FM_PE_SLOTX24_WAKE_N
   2 FM_ALL_WAKE_N      B @BASEBOARD_FAB2_LIB.BASEBOARD_FAB2(SCH_1):FM_ALL_WAKE_N

RES_0402-0.0,5%,1/16W,CHIP,G21A  I32  R8E27
   1 FM_PE_M2_WAKE_N      A @BASEBOARD_FAB2_LIB.BASEBOARD_FAB2(SCH_1):FM_PE_M2_WAKE_N
   2 FM_ALL_WAKE_N      B @BASEBOARD_FAB2_LIB.BASEBOARD_FAB2(SCH_1):FM_ALL_WAKE_N

RES_0402-0.0,5%,1/16W,CHIP,G21A  I33  R8E21
   1 FM_PE_SPRV_WAKE_N      A @BASEBOARD_FAB2_LIB.BASEBOARD_FAB2(SCH_1):FM_PE_SPRV_WAKE_N
   2 FM_ALL_WAKE_N      B @BASEBOARD_FAB2_LIB.BASEBOARD_FAB2(SCH_1):FM_ALL_WAKE_N


DRAWING: @BASEBOARD_FAB2_LIB.BASEBOARD_FAB2(SCH_1):PAGE152 

GTL2014_SM-IC,D66151-001  I1  U9G1
  13 H_CPU1_KLM_MEMHOT_LVT3_R_N     A0 @BASEBOARD_FAB2_LIB.BASEBOARD_FAB2(SCH_1):H_CPU1_KLM_MEMHOT_LVT3_R_N
  12 H_CPU1_GHJ_MEMHOT_LVT3_R_N     A1 @BASEBOARD_FAB2_LIB.BASEBOARD_FAB2(SCH_1):H_CPU1_GHJ_MEMHOT_LVT3_R_N
  10 H_CPU0_DEF_MEMHOT_LVT3_R_N     A2 @BASEBOARD_FAB2_LIB.BASEBOARD_FAB2(SCH_1):H_CPU0_DEF_MEMHOT_LVT3_R_N
   9 H_CPU0_ABC_MEMHOT_LVT3_R_N     A3 @BASEBOARD_FAB2_LIB.BASEBOARD_FAB2(SCH_1):H_CPU0_ABC_MEMHOT_LVT3_R_N
   2 H_CPU1_MEMKLM_MEMHOT_G_R_N     B0 @BASEBOARD_FAB2_LIB.BASEBOARD_FAB2(SCH_1):H_CPU1_MEMKLM_MEMHOT_G_R_N
   3 H_CPU1_MEMGHJ_MEMHOT_G_R_N     B1 @BASEBOARD_FAB2_LIB.BASEBOARD_FAB2(SCH_1):H_CPU1_MEMGHJ_MEMHOT_G_R_N
   5 H_CPU0_MEMDEF_MEMHOT_G_R_N     B2 @BASEBOARD_FAB2_LIB.BASEBOARD_FAB2(SCH_1):H_CPU0_MEMDEF_MEMHOT_G_R_N
   6 H_CPU0_MEMABC_MEMHOT_G_R_N     B3 @BASEBOARD_FAB2_LIB.BASEBOARD_FAB2(SCH_1):H_CPU0_MEMABC_MEMHOT_G_R_N
   1 PD_DIR_2    DIR @BASEBOARD_FAB2_LIB.BASEBOARD_FAB2(SCH_1):PD_DIR_2
  11    GND GND<2> @BASEBOARD_FAB2_LIB.BASEBOARD_FAB2(SCH_1):GND
   8    GND GND<1> @BASEBOARD_FAB2_LIB.BASEBOARD_FAB2(SCH_1):GND
   7    GND GND<0> @BASEBOARD_FAB2_LIB.BASEBOARD_FAB2(SCH_1):GND
  14   P3V3    VCC @BASEBOARD_FAB2_LIB.BASEBOARD_FAB2(SCH_1):P3V3
   4 P0V7_GTL2014_2   VREF @BASEBOARD_FAB2_LIB.BASEBOARD_FAB2(SCH_1):P0V7_GTL2014_2

RES_0402-1.00K,1%,1/16W,CHIP,GA  I2  R1U30
   1 PD_DIR_2      A @BASEBOARD_FAB2_LIB.BASEBOARD_FAB2(SCH_1):PD_DIR_2
   2    GND      B @BASEBOARD_FAB2_LIB.BASEBOARD_FAB2(SCH_1):GND

RES_0402-33.2,1%,1/16W,CHIP,G2A  I6  R1U46
   1 H_CPU0_MEMABC_MEMHOT_LVT3_K_N      A @BASEBOARD_FAB2_LIB.BASEBOARD_FAB2(SCH_1):H_CPU0_MEMABC_MEMHOT_LVT3_K_N
   2 H_CPU0_MEMABC_MEMHOT_LVT3_N      B @BASEBOARD_FAB2_LIB.BASEBOARD_FAB2(SCH_1):H_CPU0_MEMABC_MEMHOT_LVT3_N

RES_0402-33.2,1%,1/16W,CHIP,G2A  I14  R9G31
   1 H_CPU0_MEMDEF_MEMHOT_LVT3_K_N      A @BASEBOARD_FAB2_LIB.BASEBOARD_FAB2(SCH_1):H_CPU0_MEMDEF_MEMHOT_LVT3_K_N
   2 H_CPU0_MEMDEF_MEMHOT_LVT3_N      B @BASEBOARD_FAB2_LIB.BASEBOARD_FAB2(SCH_1):H_CPU0_MEMDEF_MEMHOT_LVT3_N

RES_0402-33.2,1%,1/16W,CHIP,G2A  I15  R1U36
   1 H_CPU1_MEMGHJ_MEMHOT_LVT3_K_N      A @BASEBOARD_FAB2_LIB.BASEBOARD_FAB2(SCH_1):H_CPU1_MEMGHJ_MEMHOT_LVT3_K_N
   2 H_CPU1_MEMGHJ_MEMHOT_LVT3_N      B @BASEBOARD_FAB2_LIB.BASEBOARD_FAB2(SCH_1):H_CPU1_MEMGHJ_MEMHOT_LVT3_N

RES_0402-33.2,1%,1/16W,CHIP,G2A  I16  R1U34
   1 H_CPU1_MEMKLM_MEMHOT_LVT3_K_N      A @BASEBOARD_FAB2_LIB.BASEBOARD_FAB2(SCH_1):H_CPU1_MEMKLM_MEMHOT_LVT3_K_N
   2 H_CPU1_MEMKLM_MEMHOT_LVT3_N      B @BASEBOARD_FAB2_LIB.BASEBOARD_FAB2(SCH_1):H_CPU1_MEMKLM_MEMHOT_LVT3_N

CAP_0402-1.0UF,16V,10%,X6S,D97A  I18  C1U19
   1   P3V3      A @BASEBOARD_FAB2_LIB.BASEBOARD_FAB2(SCH_1):P3V3
   2    GND      B @BASEBOARD_FAB2_LIB.BASEBOARD_FAB2(SCH_1):GND

RES_0402-49.9,1%,1/16W,CHIP,G2A  I25  R1U43
   1 PVCCIO_CPU0      A @BASEBOARD_FAB2_LIB.BASEBOARD_FAB2(SCH_1):PVCCIO_CPU0
   2 P0V7_GTL2014_2      B @BASEBOARD_FAB2_LIB.BASEBOARD_FAB2(SCH_1):P0V7_GTL2014_2

RES_0402-100.0,1%,1/16W,CHIP,GA  I26  R1U37
   1 P0V7_GTL2014_2      A @BASEBOARD_FAB2_LIB.BASEBOARD_FAB2(SCH_1):P0V7_GTL2014_2
   2    GND      B @BASEBOARD_FAB2_LIB.BASEBOARD_FAB2(SCH_1):GND

CAP_A_0402V-0.1UF,16V,10%,X7R,A  I27  C1U22
   1 P0V7_GTL2014_2      A @BASEBOARD_FAB2_LIB.BASEBOARD_FAB2(SCH_1):P0V7_GTL2014_2
   2    GND      B @BASEBOARD_FAB2_LIB.BASEBOARD_FAB2(SCH_1):GND

RES_0402-0.0,5%,1/16W,CHIP,G21A  I45  R9G34
   1 H_CPU0_MEMABC_MEMHOT_G_N      A @BASEBOARD_FAB2_LIB.BASEBOARD_FAB2(SCH_1):H_CPU0_MEMABC_MEMHOT_G_N
   2 H_CPU0_MEMABC_MEMHOT_G_R_N      B @BASEBOARD_FAB2_LIB.BASEBOARD_FAB2(SCH_1):H_CPU0_MEMABC_MEMHOT_G_R_N

RES_0402-0.0,5%,1/16W,EMPTY,G2A  I47  R9G27
   1 H_CPU0_MEMDEF_MEMHOT_G_PCH_N      A @BASEBOARD_FAB2_LIB.BASEBOARD_FAB2(SCH_1):H_CPU0_MEMDEF_MEMHOT_G_PCH_N
   2 H_CPU0_MEMDEF_MEMHOT_LVT3_K_N      B @BASEBOARD_FAB2_LIB.BASEBOARD_FAB2(SCH_1):H_CPU0_MEMDEF_MEMHOT_LVT3_K_N

RES_0402-0.0,5%,1/16W,CHIP,G21A  I49  R1U58
   1 H_CPU0_MEMDEF_MEMHOT_G_N      A @BASEBOARD_FAB2_LIB.BASEBOARD_FAB2(SCH_1):H_CPU0_MEMDEF_MEMHOT_G_N
   2 H_CPU0_MEMDEF_MEMHOT_G_R_N      B @BASEBOARD_FAB2_LIB.BASEBOARD_FAB2(SCH_1):H_CPU0_MEMDEF_MEMHOT_G_R_N

RES_0402-0.0,5%,1/16W,EMPTY,G2A  I50  R1U56
   1 H_CPU0_MEMDEF_MEMHOT_G_PCH_N      A @BASEBOARD_FAB2_LIB.BASEBOARD_FAB2(SCH_1):H_CPU0_MEMDEF_MEMHOT_G_PCH_N
   2 H_CPU0_MEMDEF_MEMHOT_G_N      B @BASEBOARD_FAB2_LIB.BASEBOARD_FAB2(SCH_1):H_CPU0_MEMDEF_MEMHOT_G_N

RES_0402-0.0,5%,1/16W,EMPTY,G2A  I51  R2U51
   1 H_CPU0_MEMABC_MEMHOT_G_PCH_N      A @BASEBOARD_FAB2_LIB.BASEBOARD_FAB2(SCH_1):H_CPU0_MEMABC_MEMHOT_G_PCH_N
   2 H_CPU0_MEMABC_MEMHOT_G_N      B @BASEBOARD_FAB2_LIB.BASEBOARD_FAB2(SCH_1):H_CPU0_MEMABC_MEMHOT_G_N

RES_0402-150.0,1%,1/16W,CHIP,GA  I53  R2U40
   1 PVCCIO_CPU0      A @BASEBOARD_FAB2_LIB.BASEBOARD_FAB2(SCH_1):PVCCIO_CPU0
   2 H_CPU0_MEMABC_MEMHOT_G_N      B @BASEBOARD_FAB2_LIB.BASEBOARD_FAB2(SCH_1):H_CPU0_MEMABC_MEMHOT_G_N

RES_0402-150.0,1%,1/16W,CHIP,GA  I54  R2U41
   1 PVCCIO_CPU0      A @BASEBOARD_FAB2_LIB.BASEBOARD_FAB2(SCH_1):PVCCIO_CPU0
   2 H_CPU0_MEMDEF_MEMHOT_G_N      B @BASEBOARD_FAB2_LIB.BASEBOARD_FAB2(SCH_1):H_CPU0_MEMDEF_MEMHOT_G_N

RES_0402-150.0,1%,1/16W,CHIP,GA  I56  R1U41
   1 PVCCIO_CPU1      A @BASEBOARD_FAB2_LIB.BASEBOARD_FAB2(SCH_1):PVCCIO_CPU1
   2 H_CPU1_MEMGHJ_MEMHOT_G_N      B @BASEBOARD_FAB2_LIB.BASEBOARD_FAB2(SCH_1):H_CPU1_MEMGHJ_MEMHOT_G_N

RES_0402-150.0,1%,1/16W,CHIP,GA  I57  R1U35
   1 PVCCIO_CPU1      A @BASEBOARD_FAB2_LIB.BASEBOARD_FAB2(SCH_1):PVCCIO_CPU1
   2 H_CPU1_MEMKLM_MEMHOT_G_N      B @BASEBOARD_FAB2_LIB.BASEBOARD_FAB2(SCH_1):H_CPU1_MEMKLM_MEMHOT_G_N

RES_0402-150.0,1%,1/16W,CHIP,GA  I58  R4P17
   1 H_CPU0_MEMABC_MEMHOT_G_N      A @BASEBOARD_FAB2_LIB.BASEBOARD_FAB2(SCH_1):H_CPU0_MEMABC_MEMHOT_G_N
   2 PVCCIO_CPU0      B @BASEBOARD_FAB2_LIB.BASEBOARD_FAB2(SCH_1):PVCCIO_CPU0

RES_0402-150.0,1%,1/16W,CHIP,GA  I59  R4P20
   1 H_CPU0_MEMDEF_MEMHOT_G_N      A @BASEBOARD_FAB2_LIB.BASEBOARD_FAB2(SCH_1):H_CPU0_MEMDEF_MEMHOT_G_N
   2 PVCCIO_CPU0      B @BASEBOARD_FAB2_LIB.BASEBOARD_FAB2(SCH_1):PVCCIO_CPU0

RES_0402-150.0,1%,1/16W,CHIP,GA  I61  R7P5
   1 H_CPU1_MEMGHJ_MEMHOT_G_N      A @BASEBOARD_FAB2_LIB.BASEBOARD_FAB2(SCH_1):H_CPU1_MEMGHJ_MEMHOT_G_N
   2 PVCCIO_CPU1      B @BASEBOARD_FAB2_LIB.BASEBOARD_FAB2(SCH_1):PVCCIO_CPU1

RES_0402-150.0,1%,1/16W,CHIP,GA  I62  R7P21
   1 H_CPU1_MEMKLM_MEMHOT_G_N      A @BASEBOARD_FAB2_LIB.BASEBOARD_FAB2(SCH_1):H_CPU1_MEMKLM_MEMHOT_G_N
   2 PVCCIO_CPU1      B @BASEBOARD_FAB2_LIB.BASEBOARD_FAB2(SCH_1):PVCCIO_CPU1

RES_0402-0.0,5%,1/16W,CHIP,G21A  I64  R1U53
   1 H_CPU1_MEMGHJ_MEMHOT_G_N      A @BASEBOARD_FAB2_LIB.BASEBOARD_FAB2(SCH_1):H_CPU1_MEMGHJ_MEMHOT_G_N
   2 H_CPU1_MEMGHJ_MEMHOT_G_R_N      B @BASEBOARD_FAB2_LIB.BASEBOARD_FAB2(SCH_1):H_CPU1_MEMGHJ_MEMHOT_G_R_N

RES_0402-0.0,5%,1/16W,CHIP,G21A  I65  R1U60
   1 H_CPU1_MEMKLM_MEMHOT_G_N      A @BASEBOARD_FAB2_LIB.BASEBOARD_FAB2(SCH_1):H_CPU1_MEMKLM_MEMHOT_G_N
   2 H_CPU1_MEMKLM_MEMHOT_G_R_N      B @BASEBOARD_FAB2_LIB.BASEBOARD_FAB2(SCH_1):H_CPU1_MEMKLM_MEMHOT_G_R_N

RES_0402-0.0,5%,1/16W,EMPTY,G2A  I66  R2U49
   1 H_CPU0_MEMABC_MEMHOT_G_PCH_N      A @BASEBOARD_FAB2_LIB.BASEBOARD_FAB2(SCH_1):H_CPU0_MEMABC_MEMHOT_G_PCH_N
   2 H_CPU0_MEMABC_MEMHOT_LVT3_K_N      B @BASEBOARD_FAB2_LIB.BASEBOARD_FAB2(SCH_1):H_CPU0_MEMABC_MEMHOT_LVT3_K_N

RES_0402-0.0,5%,1/16W,EMPTY,G2A  I67  R1U55
   1 H_CPU1_MEMGHJ_MEMHOT_G_N      A @BASEBOARD_FAB2_LIB.BASEBOARD_FAB2(SCH_1):H_CPU1_MEMGHJ_MEMHOT_G_N
   2 H_CPU1_MEMGHJ_MEMHOT_G_PCH_N      B @BASEBOARD_FAB2_LIB.BASEBOARD_FAB2(SCH_1):H_CPU1_MEMGHJ_MEMHOT_G_PCH_N

RES_0402-0.0,5%,1/16W,EMPTY,G2A  I68  R1U62
   1 H_CPU1_MEMKLM_MEMHOT_G_N      A @BASEBOARD_FAB2_LIB.BASEBOARD_FAB2(SCH_1):H_CPU1_MEMKLM_MEMHOT_G_N
   2 H_CPU1_MEMKLM_MEMHOT_G_PCH_N      B @BASEBOARD_FAB2_LIB.BASEBOARD_FAB2(SCH_1):H_CPU1_MEMKLM_MEMHOT_G_PCH_N

RES_0402-0.0,5%,1/16W,EMPTY,G2A  I69  R1U57
   1 H_CPU1_MEMGHJ_MEMHOT_LVT3_K_N      A @BASEBOARD_FAB2_LIB.BASEBOARD_FAB2(SCH_1):H_CPU1_MEMGHJ_MEMHOT_LVT3_K_N
   2 H_CPU1_MEMGHJ_MEMHOT_G_PCH_N      B @BASEBOARD_FAB2_LIB.BASEBOARD_FAB2(SCH_1):H_CPU1_MEMGHJ_MEMHOT_G_PCH_N

RES_0402-0.0,5%,1/16W,EMPTY,G2A  I70  R1U61
   1 H_CPU1_MEMKLM_MEMHOT_LVT3_K_N      A @BASEBOARD_FAB2_LIB.BASEBOARD_FAB2(SCH_1):H_CPU1_MEMKLM_MEMHOT_LVT3_K_N
   2 H_CPU1_MEMKLM_MEMHOT_G_PCH_N      B @BASEBOARD_FAB2_LIB.BASEBOARD_FAB2(SCH_1):H_CPU1_MEMKLM_MEMHOT_G_PCH_N

RES_0402-0.0,5%,1/16W,CHIP,G21A  I71  R9G28
   1 H_CPU1_KLM_MEMHOT_LVT3_R_N      A @BASEBOARD_FAB2_LIB.BASEBOARD_FAB2(SCH_1):H_CPU1_KLM_MEMHOT_LVT3_R_N
   2 H_CPU1_MEMKLM_MEMHOT_LVT3_K_N      B @BASEBOARD_FAB2_LIB.BASEBOARD_FAB2(SCH_1):H_CPU1_MEMKLM_MEMHOT_LVT3_K_N

RES_0402-0.0,5%,1/16W,CHIP,G21A  I72  R9G32
   1 H_CPU1_GHJ_MEMHOT_LVT3_R_N      A @BASEBOARD_FAB2_LIB.BASEBOARD_FAB2(SCH_1):H_CPU1_GHJ_MEMHOT_LVT3_R_N
   2 H_CPU1_MEMGHJ_MEMHOT_LVT3_K_N      B @BASEBOARD_FAB2_LIB.BASEBOARD_FAB2(SCH_1):H_CPU1_MEMGHJ_MEMHOT_LVT3_K_N

RES_0402-0.0,5%,1/16W,CHIP,G21A  I73  R9G33
   1 H_CPU0_DEF_MEMHOT_LVT3_R_N      A @BASEBOARD_FAB2_LIB.BASEBOARD_FAB2(SCH_1):H_CPU0_DEF_MEMHOT_LVT3_R_N
   2 H_CPU0_MEMDEF_MEMHOT_LVT3_K_N      B @BASEBOARD_FAB2_LIB.BASEBOARD_FAB2(SCH_1):H_CPU0_MEMDEF_MEMHOT_LVT3_K_N

RES_0402-0.0,5%,1/16W,CHIP,G21A  I74  R1U59
   1 H_CPU0_ABC_MEMHOT_LVT3_R_N      A @BASEBOARD_FAB2_LIB.BASEBOARD_FAB2(SCH_1):H_CPU0_ABC_MEMHOT_LVT3_R_N
   2 H_CPU0_MEMABC_MEMHOT_LVT3_K_N      B @BASEBOARD_FAB2_LIB.BASEBOARD_FAB2(SCH_1):H_CPU0_MEMABC_MEMHOT_LVT3_K_N

RES_0402-0.0,5%,1/16W,CHIP,G21A  I79  R2U47
   1 H_CPU0_MEMABC_MEMHOT_LVT3_N      A @BASEBOARD_FAB2_LIB.BASEBOARD_FAB2(SCH_1):H_CPU0_MEMABC_MEMHOT_LVT3_N
   2 H_CPU0_MEMABC_MEMHOT_LVT3_BMC_N      B @BASEBOARD_FAB2_LIB.BASEBOARD_FAB2(SCH_1):H_CPU0_MEMABC_MEMHOT_LVT3_BMC_N

RES_0402-0.0,5%,1/16W,CHIP,G21A  I92  R9G29
   1 H_CPU0_MEMDEF_MEMHOT_LVT3_N      A @BASEBOARD_FAB2_LIB.BASEBOARD_FAB2(SCH_1):H_CPU0_MEMDEF_MEMHOT_LVT3_N
   2 H_CPU0_MEMDEF_MEMHOT_LVT3_BMC_N      B @BASEBOARD_FAB2_LIB.BASEBOARD_FAB2(SCH_1):H_CPU0_MEMDEF_MEMHOT_LVT3_BMC_N

RES_0402-0.0,5%,1/16W,CHIP,G21A  I93  R1U54
   1 H_CPU1_MEMGHJ_MEMHOT_LVT3_N      A @BASEBOARD_FAB2_LIB.BASEBOARD_FAB2(SCH_1):H_CPU1_MEMGHJ_MEMHOT_LVT3_N
   2 H_CPU1_MEMGHJ_MEMHOT_LVT3_BMC_N      B @BASEBOARD_FAB2_LIB.BASEBOARD_FAB2(SCH_1):H_CPU1_MEMGHJ_MEMHOT_LVT3_BMC_N

RES_0402-0.0,5%,1/16W,CHIP,G21A  I94  R2U46
   1 H_CPU1_MEMKLM_MEMHOT_LVT3_N      A @BASEBOARD_FAB2_LIB.BASEBOARD_FAB2(SCH_1):H_CPU1_MEMKLM_MEMHOT_LVT3_N
   2 H_CPU1_MEMKLM_MEMHOT_LVT3_BMC_N      B @BASEBOARD_FAB2_LIB.BASEBOARD_FAB2(SCH_1):H_CPU1_MEMKLM_MEMHOT_LVT3_BMC_N

RES_0402-0.0,5%,1/16W,EMPTY,G2A  I95  R3N30
   1 H_CPU0_MEMABC_MEMHOT_LVT3_N      A @BASEBOARD_FAB2_LIB.BASEBOARD_FAB2(SCH_1):H_CPU0_MEMABC_MEMHOT_LVT3_N
   2 H_CPU0_MEMABC_MEMHOT_PCH_N      B @BASEBOARD_FAB2_LIB.BASEBOARD_FAB2(SCH_1):H_CPU0_MEMABC_MEMHOT_PCH_N

RES_0402-0.0,5%,1/16W,EMPTY,G2A  I98  R9G30
   1 H_CPU0_MEMDEF_MEMHOT_LVT3_N      A @BASEBOARD_FAB2_LIB.BASEBOARD_FAB2(SCH_1):H_CPU0_MEMDEF_MEMHOT_LVT3_N
   2 H_CPU0_MEMDEF_MEMHOT_PCH_N      B @BASEBOARD_FAB2_LIB.BASEBOARD_FAB2(SCH_1):H_CPU0_MEMDEF_MEMHOT_PCH_N

RES_0402-0.0,5%,1/16W,EMPTY,G2A  I100  R3P63
   1 H_CPU1_MEMGHJ_MEMHOT_LVT3_N      A @BASEBOARD_FAB2_LIB.BASEBOARD_FAB2(SCH_1):H_CPU1_MEMGHJ_MEMHOT_LVT3_N
   2 H_CPU1_MEMGHJ_MEMHOT_PCH_N      B @BASEBOARD_FAB2_LIB.BASEBOARD_FAB2(SCH_1):H_CPU1_MEMGHJ_MEMHOT_PCH_N

RES_0402-0.0,5%,1/16W,EMPTY,G2A  I102  R2U45
   1 H_CPU1_MEMKLM_MEMHOT_LVT3_N      A @BASEBOARD_FAB2_LIB.BASEBOARD_FAB2(SCH_1):H_CPU1_MEMKLM_MEMHOT_LVT3_N
   2 H_CPU1_MEMKLM_MEMHOT_PCH_N      B @BASEBOARD_FAB2_LIB.BASEBOARD_FAB2(SCH_1):H_CPU1_MEMKLM_MEMHOT_PCH_N


DRAWING: @BASEBOARD_FAB2_LIB.BASEBOARD_FAB2(SCH_1):PAGE153 

RES_0402-4.75K,1%,1/16W,EMPTY,A  I90  R7F6
   1 P3V3_STBY      A @BASEBOARD_FAB2_LIB.BASEBOARD_FAB2(SCH_1):P3V3_STBY
   2 PU_SPI0_RST      B @BASEBOARD_FAB2_LIB.BASEBOARD_FAB2(SCH_1):PU_SPI0_RST

RES_0402-4.75K,1%,1/16W,CHIP,GA  I94  R7F5
   1 P3V3_STBY      A @BASEBOARD_FAB2_LIB.BASEBOARD_FAB2(SCH_1):P3V3_STBY
   2 SPI_CS0_PRIMARY_R_N      B @BASEBOARD_FAB2_LIB.BASEBOARD_FAB2(SCH_1):SPI_CS0_PRIMARY_R_N

RES_0402-33.2,1%,1/16W,CHIP,G2A  I98  R7F4
   1 SPI_SWITCH_MISO      A @BASEBOARD_FAB2_LIB.BASEBOARD_FAB2(SCH_1):SPI_SWITCH_MISO
   2 SPI_MISO_R0      B @BASEBOARD_FAB2_LIB.BASEBOARD_FAB2(SCH_1):SPI_MISO_R0

RES_0402-33.2,1%,1/16W,CHIP,G2A  I108  R7F37
   1 SPI_BIOS_SOCKET_IO2      A @BASEBOARD_FAB2_LIB.BASEBOARD_FAB2(SCH_1):SPI_BIOS_SOCKET_IO2
   2 PU_BIOS_SPI_WP0_N      B @BASEBOARD_FAB2_LIB.BASEBOARD_FAB2(SCH_1):PU_BIOS_SPI_WP0_N

RES_0402-33.2,1%,1/16W,CHIP,G2A  I109  R7F3
   1 SPI_BIOS_SOCKET_IO3      A @BASEBOARD_FAB2_LIB.BASEBOARD_FAB2(SCH_1):SPI_BIOS_SOCKET_IO3
   2 PU_BIOS_SPI_HOLD0_N      B @BASEBOARD_FAB2_LIB.BASEBOARD_FAB2(SCH_1):PU_BIOS_SPI_HOLD0_N

CAP_A_0402V-1.0UF,6.3V,10%,X6SA  I130  C7F2
   1 P3V3_STBY      A @BASEBOARD_FAB2_LIB.BASEBOARD_FAB2(SCH_1):P3V3_STBY
   2    GND      B @BASEBOARD_FAB2_LIB.BASEBOARD_FAB2(SCH_1):GND

CAP_A_0402V-0.01UF,25V,10%,X7RA  I131  C7F1
   1 P3V3_STBY      A @BASEBOARD_FAB2_LIB.BASEBOARD_FAB2(SCH_1):P3V3_STBY
   2    GND      B @BASEBOARD_FAB2_LIB.BASEBOARD_FAB2(SCH_1):GND

CAP_A_0402V-0.01UF,25V,10%,X7RA  I136  C3T5
   1 P3V3_STBY      A @BASEBOARD_FAB2_LIB.BASEBOARD_FAB2(SCH_1):P3V3_STBY
   2    GND      B @BASEBOARD_FAB2_LIB.BASEBOARD_FAB2(SCH_1):GND

CAP_A_0402V-1.0UF,6.3V,10%,X6SA  I138  C3T4
   1 P3V3_STBY      A @BASEBOARD_FAB2_LIB.BASEBOARD_FAB2(SCH_1):P3V3_STBY
   2    GND      B @BASEBOARD_FAB2_LIB.BASEBOARD_FAB2(SCH_1):GND

RES_0402-10.0K,1%,1/16W,CHIP,GA  I140  R7F32
   1 P3V3_STBY      A @BASEBOARD_FAB2_LIB.BASEBOARD_FAB2(SCH_1):P3V3_STBY
   2 PU_BIOS_SPI_HOLD0_N      B @BASEBOARD_FAB2_LIB.BASEBOARD_FAB2(SCH_1):PU_BIOS_SPI_HOLD0_N

W25Q256_XSOI-IC,H25002-001  I146  U7F1
   9 PU_BIOS_SPI_WP0_N WP_N_IO<2> @BASEBOARD_FAB2_LIB.BASEBOARD_FAB2(SCH_1):PU_BIOS_SPI_WP0_N
  14 TP_SPI_0_0  NC<0> @BASEBOARD_FAB2_LIB.BASEBOARD_FAB2(SCH_1):TP_SPI_0_0
  13 TP_SPI_0_1  NC<1> @BASEBOARD_FAB2_LIB.BASEBOARD_FAB2(SCH_1):TP_SPI_0_1
  12 TP_SPI_0_2  NC<2> @BASEBOARD_FAB2_LIB.BASEBOARD_FAB2(SCH_1):TP_SPI_0_2
  11 TP_SPI_0_3  NC<3> @BASEBOARD_FAB2_LIB.BASEBOARD_FAB2(SCH_1):TP_SPI_0_3
   6 TP_SPI_0_4  NC<4> @BASEBOARD_FAB2_LIB.BASEBOARD_FAB2(SCH_1):TP_SPI_0_4
   5 TP_SPI_0_5  NC<5> @BASEBOARD_FAB2_LIB.BASEBOARD_FAB2(SCH_1):TP_SPI_0_5
   4 TP_SPI_0_6  NC<6> @BASEBOARD_FAB2_LIB.BASEBOARD_FAB2(SCH_1):TP_SPI_0_6
  10    GND    GND @BASEBOARD_FAB2_LIB.BASEBOARD_FAB2(SCH_1):GND
   8 SPI_MISO_R0 DO_IO<1> @BASEBOARD_FAB2_LIB.BASEBOARD_FAB2(SCH_1):SPI_MISO_R0
  16 SPI_CLK_R0    CLK @BASEBOARD_FAB2_LIB.BASEBOARD_FAB2(SCH_1):SPI_CLK_R0
   2 P3V3_STBY    VCC @BASEBOARD_FAB2_LIB.BASEBOARD_FAB2(SCH_1):P3V3_STBY
   7 SPI_CS0_PRIMARY_R_N   CS_N @BASEBOARD_FAB2_LIB.BASEBOARD_FAB2(SCH_1):SPI_CS0_PRIMARY_R_N
  15 SPI_SWITCH_MOSI_R0 DI_IO<0> @BASEBOARD_FAB2_LIB.BASEBOARD_FAB2(SCH_1):SPI_SWITCH_MOSI_R0
   3 PU_SPI0_RST RESET_N @BASEBOARD_FAB2_LIB.BASEBOARD_FAB2(SCH_1):PU_SPI0_RST
   1 PU_BIOS_SPI_HOLD0_N HOLD_N_IO<3> @BASEBOARD_FAB2_LIB.BASEBOARD_FAB2(SCH_1):PU_BIOS_SPI_HOLD0_N

RES_0402-4.75K,1%,1/16W,EMPTY,A  I150  R3T3
   1 P3V3_STBY      A @BASEBOARD_FAB2_LIB.BASEBOARD_FAB2(SCH_1):P3V3_STBY
   2 PU_SPI1_RST      B @BASEBOARD_FAB2_LIB.BASEBOARD_FAB2(SCH_1):PU_SPI1_RST

RES_0402-4.75K,1%,1/16W,CHIP,GA  I152  R3T5
   1 P3V3_STBY      A @BASEBOARD_FAB2_LIB.BASEBOARD_FAB2(SCH_1):P3V3_STBY
   2 SPI_CS0_SECONDARY_R_N      B @BASEBOARD_FAB2_LIB.BASEBOARD_FAB2(SCH_1):SPI_CS0_SECONDARY_R_N

RES_0402-33.2,1%,1/16W,CHIP,G2A  I155  R3T2
   1 SPI_SWITCH_MISO      A @BASEBOARD_FAB2_LIB.BASEBOARD_FAB2(SCH_1):SPI_SWITCH_MISO
   2 SPI_MISO_R1      B @BASEBOARD_FAB2_LIB.BASEBOARD_FAB2(SCH_1):SPI_MISO_R1

RES_0402-33.2,1%,1/16W,CHIP,G2A  I156  R3U1
   1 SPI_BIOS_SOCKET_IO2      A @BASEBOARD_FAB2_LIB.BASEBOARD_FAB2(SCH_1):SPI_BIOS_SOCKET_IO2
   2 PU_BIOS_SPI_WP1_N      B @BASEBOARD_FAB2_LIB.BASEBOARD_FAB2(SCH_1):PU_BIOS_SPI_WP1_N

RES_0402-33.2,1%,1/16W,CHIP,G2A  I157  R3T1
   1 SPI_BIOS_SOCKET_IO3      A @BASEBOARD_FAB2_LIB.BASEBOARD_FAB2(SCH_1):SPI_BIOS_SOCKET_IO3
   2 PU_BIOS_SPI_HOLD1_N      B @BASEBOARD_FAB2_LIB.BASEBOARD_FAB2(SCH_1):PU_BIOS_SPI_HOLD1_N

W25Q256_XSOI-IC,H25002-001  I165  U3T1
   9 PU_BIOS_SPI_WP1_N WP_N_IO<2> @BASEBOARD_FAB2_LIB.BASEBOARD_FAB2(SCH_1):PU_BIOS_SPI_WP1_N
  14 TP_SPI_1_0  NC<0> @BASEBOARD_FAB2_LIB.BASEBOARD_FAB2(SCH_1):TP_SPI_1_0
  13 TP_SPI_1_1  NC<1> @BASEBOARD_FAB2_LIB.BASEBOARD_FAB2(SCH_1):TP_SPI_1_1
  12 TP_SPI_1_2  NC<2> @BASEBOARD_FAB2_LIB.BASEBOARD_FAB2(SCH_1):TP_SPI_1_2
  11 TP_SPI_1_3  NC<3> @BASEBOARD_FAB2_LIB.BASEBOARD_FAB2(SCH_1):TP_SPI_1_3
   6 TP_SPI_1_4  NC<4> @BASEBOARD_FAB2_LIB.BASEBOARD_FAB2(SCH_1):TP_SPI_1_4
   5 TP_SPI_1_5  NC<5> @BASEBOARD_FAB2_LIB.BASEBOARD_FAB2(SCH_1):TP_SPI_1_5
   4 TP_SPI_1_6  NC<6> @BASEBOARD_FAB2_LIB.BASEBOARD_FAB2(SCH_1):TP_SPI_1_6
  10    GND    GND @BASEBOARD_FAB2_LIB.BASEBOARD_FAB2(SCH_1):GND
   8 SPI_MISO_R1 DO_IO<1> @BASEBOARD_FAB2_LIB.BASEBOARD_FAB2(SCH_1):SPI_MISO_R1
  16 SPI_CLK_R1    CLK @BASEBOARD_FAB2_LIB.BASEBOARD_FAB2(SCH_1):SPI_CLK_R1
   2 P3V3_STBY    VCC @BASEBOARD_FAB2_LIB.BASEBOARD_FAB2(SCH_1):P3V3_STBY
   7 SPI_CS0_SECONDARY_R_N   CS_N @BASEBOARD_FAB2_LIB.BASEBOARD_FAB2(SCH_1):SPI_CS0_SECONDARY_R_N
  15 SPI_SWITCH_MOSI_R1 DI_IO<0> @BASEBOARD_FAB2_LIB.BASEBOARD_FAB2(SCH_1):SPI_SWITCH_MOSI_R1
   3 PU_SPI1_RST RESET_N @BASEBOARD_FAB2_LIB.BASEBOARD_FAB2(SCH_1):PU_SPI1_RST
   1 PU_BIOS_SPI_HOLD1_N HOLD_N_IO<3> @BASEBOARD_FAB2_LIB.BASEBOARD_FAB2(SCH_1):PU_BIOS_SPI_HOLD1_N

RES_0402-33.2,1%,1/16W,CHIP,G2A  I166  R8F8
   1 SPI_SWITCH_CLK      A @BASEBOARD_FAB2_LIB.BASEBOARD_FAB2(SCH_1):SPI_SWITCH_CLK
   2 SPI_CLK_R0      B @BASEBOARD_FAB2_LIB.BASEBOARD_FAB2(SCH_1):SPI_CLK_R0

RES_0402-33.2,1%,1/16W,CHIP,G2A  I167  R8F7
   1 SPI_SWITCH_CLK      A @BASEBOARD_FAB2_LIB.BASEBOARD_FAB2(SCH_1):SPI_SWITCH_CLK
   2 SPI_CLK_R1      B @BASEBOARD_FAB2_LIB.BASEBOARD_FAB2(SCH_1):SPI_CLK_R1

RES_0402-10.0K,1%,1/16W,CHIP,GA  I168  R7F28
   1 P3V3_STBY      A @BASEBOARD_FAB2_LIB.BASEBOARD_FAB2(SCH_1):P3V3_STBY
   2 PU_BIOS_SPI_WP0_N      B @BASEBOARD_FAB2_LIB.BASEBOARD_FAB2(SCH_1):PU_BIOS_SPI_WP0_N

RES_0402-10.0K,1%,1/16W,EMPTY,A  I170  R7F30
   1 PU_BIOS_SPI_WP0_N      A @BASEBOARD_FAB2_LIB.BASEBOARD_FAB2(SCH_1):PU_BIOS_SPI_WP0_N
   2    GND      B @BASEBOARD_FAB2_LIB.BASEBOARD_FAB2(SCH_1):GND

RES_0402-10.0K,1%,1/16W,CHIP,GA  I174  R3T4
   1 P3V3_STBY      A @BASEBOARD_FAB2_LIB.BASEBOARD_FAB2(SCH_1):P3V3_STBY
   2 PU_BIOS_SPI_HOLD1_N      B @BASEBOARD_FAB2_LIB.BASEBOARD_FAB2(SCH_1):PU_BIOS_SPI_HOLD1_N

RES_0402-10.0K,1%,1/16W,CHIP,GA  I178  R3T12
   1 P3V3_STBY      A @BASEBOARD_FAB2_LIB.BASEBOARD_FAB2(SCH_1):P3V3_STBY
   2 PU_BIOS_SPI_WP1_N      B @BASEBOARD_FAB2_LIB.BASEBOARD_FAB2(SCH_1):PU_BIOS_SPI_WP1_N

RES_0402-10.0K,1%,1/16W,EMPTY,A  I179  R3T9
   1 PU_BIOS_SPI_WP1_N      A @BASEBOARD_FAB2_LIB.BASEBOARD_FAB2(SCH_1):PU_BIOS_SPI_WP1_N
   2    GND      B @BASEBOARD_FAB2_LIB.BASEBOARD_FAB2(SCH_1):GND

RES_0402-33.2,1%,1/16W,CHIP,G2A  I181  R7F29
   1 SPI_SWITCH_MOSI      A @BASEBOARD_FAB2_LIB.BASEBOARD_FAB2(SCH_1):SPI_SWITCH_MOSI
   2 SPI_SWITCH_MOSI_R0      B @BASEBOARD_FAB2_LIB.BASEBOARD_FAB2(SCH_1):SPI_SWITCH_MOSI_R0

RES_0402-33.2,1%,1/16W,CHIP,G2A  I184  R3T10
   1 SPI_SWITCH_MOSI      A @BASEBOARD_FAB2_LIB.BASEBOARD_FAB2(SCH_1):SPI_SWITCH_MOSI
   2 SPI_SWITCH_MOSI_R1      B @BASEBOARD_FAB2_LIB.BASEBOARD_FAB2(SCH_1):SPI_SWITCH_MOSI_R1


DRAWING: @BASEBOARD_FAB2_LIB.BASEBOARD_FAB2(SCH_1):PAGE154 

CAP_A_0402V-0.1UF,16V,10%,X7R,A  I14  C8E18
   1 P3V3_STBY      A @BASEBOARD_FAB2_LIB.BASEBOARD_FAB2(SCH_1):P3V3_STBY
   2    GND      B @BASEBOARD_FAB2_LIB.BASEBOARD_FAB2(SCH_1):GND

RES_0402-75,1.0%,1/16W,CHIP,G2A  I62  R2T9
   1 SPI_CS0_SECONDARY_N      A @BASEBOARD_FAB2_LIB.BASEBOARD_FAB2(SCH_1):SPI_CS0_SECONDARY_N
   2 SPI_CS0_SECONDARY_R_N      B @BASEBOARD_FAB2_LIB.BASEBOARD_FAB2(SCH_1):SPI_CS0_SECONDARY_R_N

PI3B3257A_TSSOPLF-IC,E16801-001  I74  U8F1
  16 P3V3_STBY    VCC @BASEBOARD_FAB2_LIB.BASEBOARD_FAB2(SCH_1):P3V3_STBY
   8    GND    GND @BASEBOARD_FAB2_LIB.BASEBOARD_FAB2(SCH_1):GND
  15    GND     EN @BASEBOARD_FAB2_LIB.BASEBOARD_FAB2(SCH_1):GND
   1 FM_BIOS_SPI_BMC_CTRL      S @BASEBOARD_FAB2_LIB.BASEBOARD_FAB2(SCH_1):FM_BIOS_SPI_BMC_CTRL
   4 SPI_SWITCH_CLK     YA @BASEBOARD_FAB2_LIB.BASEBOARD_FAB2(SCH_1):SPI_SWITCH_CLK
   7 SPI_SWITCH_MOSI     YB @BASEBOARD_FAB2_LIB.BASEBOARD_FAB2(SCH_1):SPI_SWITCH_MOSI
   9 SPI_SWITCH_CS0_N     YC @BASEBOARD_FAB2_LIB.BASEBOARD_FAB2(SCH_1):SPI_SWITCH_CS0_N
  12 SPI_SWITCH_MISO     YD @BASEBOARD_FAB2_LIB.BASEBOARD_FAB2(SCH_1):SPI_SWITCH_MISO
   2 SPI_PCH_CLK    IA0 @BASEBOARD_FAB2_LIB.BASEBOARD_FAB2(SCH_1):SPI_PCH_CLK
   3 SPI_BMC_CLK    IA1 @BASEBOARD_FAB2_LIB.BASEBOARD_FAB2(SCH_1):SPI_BMC_CLK
   5 SPI_PCH_MOSI    IB0 @BASEBOARD_FAB2_LIB.BASEBOARD_FAB2(SCH_1):SPI_PCH_MOSI
   6 SPI_BMC_DO    IB1 @BASEBOARD_FAB2_LIB.BASEBOARD_FAB2(SCH_1):SPI_BMC_DO
  11 SPI_PCH_CS0_N    IC0 @BASEBOARD_FAB2_LIB.BASEBOARD_FAB2(SCH_1):SPI_PCH_CS0_N
  10 SPI_BMC_CS0_N    IC1 @BASEBOARD_FAB2_LIB.BASEBOARD_FAB2(SCH_1):SPI_BMC_CS0_N
  14 SPI_PCH_MISO_R    ID0 @BASEBOARD_FAB2_LIB.BASEBOARD_FAB2(SCH_1):SPI_PCH_MISO_R
  13 SPI_BMC_DI    ID1 @BASEBOARD_FAB2_LIB.BASEBOARD_FAB2(SCH_1):SPI_BMC_DI

PI3B3257A_TSSOPLF-IC,E16801-001  I75  U2T1
  16 P3V3_STBY    VCC @BASEBOARD_FAB2_LIB.BASEBOARD_FAB2(SCH_1):P3V3_STBY
   8    GND    GND @BASEBOARD_FAB2_LIB.BASEBOARD_FAB2(SCH_1):GND
  15    GND     EN @BASEBOARD_FAB2_LIB.BASEBOARD_FAB2(SCH_1):GND
   1 FM_BIOS_SPI_BMC_CTRL      S @BASEBOARD_FAB2_LIB.BASEBOARD_FAB2(SCH_1):FM_BIOS_SPI_BMC_CTRL
   4 SPI_BIOS_SOCKET_IO2     YA @BASEBOARD_FAB2_LIB.BASEBOARD_FAB2(SCH_1):SPI_BIOS_SOCKET_IO2
   7 SPI_BIOS_SOCKET_IO3     YB @BASEBOARD_FAB2_LIB.BASEBOARD_FAB2(SCH_1):SPI_BIOS_SOCKET_IO3
   9 TP_SPI_SWITCH1_9     YC @BASEBOARD_FAB2_LIB.BASEBOARD_FAB2(SCH_1):TP_SPI_SWITCH1_9
  12 TP_SPI_SWITCH1_12     YD @BASEBOARD_FAB2_LIB.BASEBOARD_FAB2(SCH_1):TP_SPI_SWITCH1_12
   2 SPI_PCH_IO2_R1    IA0 @BASEBOARD_FAB2_LIB.BASEBOARD_FAB2(SCH_1):SPI_PCH_IO2_R1
   3 TP_SPI_SWITCH1_3    IA1 @BASEBOARD_FAB2_LIB.BASEBOARD_FAB2(SCH_1):TP_SPI_SWITCH1_3
   5 SPI_PCH_IO3_R1    IB0 @BASEBOARD_FAB2_LIB.BASEBOARD_FAB2(SCH_1):SPI_PCH_IO3_R1
   6 TP_SPI_SWITCH1_6    IB1 @BASEBOARD_FAB2_LIB.BASEBOARD_FAB2(SCH_1):TP_SPI_SWITCH1_6
  11 TP_SPI_SWITCH1_11    IC0 @BASEBOARD_FAB2_LIB.BASEBOARD_FAB2(SCH_1):TP_SPI_SWITCH1_11
  10 TP_SPI_SWITCH1_10    IC1 @BASEBOARD_FAB2_LIB.BASEBOARD_FAB2(SCH_1):TP_SPI_SWITCH1_10
  14 TP_SPI_SWITCH1_14    ID0 @BASEBOARD_FAB2_LIB.BASEBOARD_FAB2(SCH_1):TP_SPI_SWITCH1_14
  13 TP_SPI_SWITCH1_13    ID1 @BASEBOARD_FAB2_LIB.BASEBOARD_FAB2(SCH_1):TP_SPI_SWITCH1_13

RES_0402-0.0,5%,1/16W,CHIP,G21A  I92  R2T2
   1 SPI_PCH_IO3      A @BASEBOARD_FAB2_LIB.BASEBOARD_FAB2(SCH_1):SPI_PCH_IO3
   2 SPI_PCH_IO3_R1      B @BASEBOARD_FAB2_LIB.BASEBOARD_FAB2(SCH_1):SPI_PCH_IO3_R1

RES_0402-0.0,5%,1/16W,CHIP,G21A  I93  R2R12
   1 SPI_PCH_IO2      A @BASEBOARD_FAB2_LIB.BASEBOARD_FAB2(SCH_1):SPI_PCH_IO2
   2 SPI_PCH_IO2_R1      B @BASEBOARD_FAB2_LIB.BASEBOARD_FAB2(SCH_1):SPI_PCH_IO2_R1

CAP_A_0402V-0.1UF,16V,10%,X7R,A  I94  C2T1
   1 P3V3_STBY      A @BASEBOARD_FAB2_LIB.BASEBOARD_FAB2(SCH_1):P3V3_STBY
   2    GND      B @BASEBOARD_FAB2_LIB.BASEBOARD_FAB2(SCH_1):GND

TTL1G32_A_SOT-74LVC1G32,IC,E60B  I99  U2T3
   1 FM_DUAL_BIOS_SEL_N      A @BASEBOARD_FAB2_LIB.BASEBOARD_FAB2(SCH_1):FM_DUAL_BIOS_SEL_N
   2 SPI_SWITCH_CS0_N      B @BASEBOARD_FAB2_LIB.BASEBOARD_FAB2(SCH_1):SPI_SWITCH_CS0_N
   4 SPI_CS0_PRIMARY_N      Y @BASEBOARD_FAB2_LIB.BASEBOARD_FAB2(SCH_1):SPI_CS0_PRIMARY_N

TTL1G32_A_SOT-74LVC1G32,IC,E60B  I100  U2T2
   1 FM_BACKUP_BIOS_SEL_N      A @BASEBOARD_FAB2_LIB.BASEBOARD_FAB2(SCH_1):FM_BACKUP_BIOS_SEL_N
   2 SPI_SWITCH_CS0_N      B @BASEBOARD_FAB2_LIB.BASEBOARD_FAB2(SCH_1):SPI_SWITCH_CS0_N
   4 SPI_CS0_SECONDARY_N      Y @BASEBOARD_FAB2_LIB.BASEBOARD_FAB2(SCH_1):SPI_CS0_SECONDARY_N

RES_0402-200.0,1%,1/16W,CHIP,GA  I101  R2T13
   1 SPI_CS0_PRIMARY_N      A @BASEBOARD_FAB2_LIB.BASEBOARD_FAB2(SCH_1):SPI_CS0_PRIMARY_N
   2 SPI_CS0_PRIMARY_R_N      B @BASEBOARD_FAB2_LIB.BASEBOARD_FAB2(SCH_1):SPI_CS0_PRIMARY_R_N

RES_0402-4.75K,1%,1/16W,CHIP,GA  I105  R2T11
   1 P3V3_STBY      A @BASEBOARD_FAB2_LIB.BASEBOARD_FAB2(SCH_1):P3V3_STBY
   2 FM_DUAL_BIOS_SEL_N      B @BASEBOARD_FAB2_LIB.BASEBOARD_FAB2(SCH_1):FM_DUAL_BIOS_SEL_N

RES_0402-10.0K,1%,1/16W,CHIP,GA  I106  R2T8
   1 P3V3_STBY      A @BASEBOARD_FAB2_LIB.BASEBOARD_FAB2(SCH_1):P3V3_STBY
   2 SPI_SWITCH_CS0_N      B @BASEBOARD_FAB2_LIB.BASEBOARD_FAB2(SCH_1):SPI_SWITCH_CS0_N

RES_0402-0.0,5%,1/16W,CHIP,G21A  I119  R8F6
   1 SPI_PCH_MISO      A @BASEBOARD_FAB2_LIB.BASEBOARD_FAB2(SCH_1):SPI_PCH_MISO
   2 SPI_PCH_MISO_R      B @BASEBOARD_FAB2_LIB.BASEBOARD_FAB2(SCH_1):SPI_PCH_MISO_R

FET_N_SOT23LF-2N7002,FET,C7925A  I126  Q8F1
   1 FM_BACKUP_BIOS_SEL_N   GATE @BASEBOARD_FAB2_LIB.BASEBOARD_FAB2(SCH_1):FM_BACKUP_BIOS_SEL_N
   2    GND    SRC @BASEBOARD_FAB2_LIB.BASEBOARD_FAB2(SCH_1):GND
   3 FM_DUAL_BIOS_SEL_N    DRN @BASEBOARD_FAB2_LIB.BASEBOARD_FAB2(SCH_1):FM_DUAL_BIOS_SEL_N

RES_0402-4.75K,1%,1/16W,CHIP,GA  I127  R2T6
   1 P3V3_STBY      A @BASEBOARD_FAB2_LIB.BASEBOARD_FAB2(SCH_1):P3V3_STBY
   2 FM_BACKUP_BIOS_SEL_N      B @BASEBOARD_FAB2_LIB.BASEBOARD_FAB2(SCH_1):FM_BACKUP_BIOS_SEL_N

RES_0402-10.0K,1%,1/16W,CHIP,GA  I128  R1U6
   1 FM_BIOS_SPI_BMC_CTRL      A @BASEBOARD_FAB2_LIB.BASEBOARD_FAB2(SCH_1):FM_BIOS_SPI_BMC_CTRL
   2    GND      B @BASEBOARD_FAB2_LIB.BASEBOARD_FAB2(SCH_1):GND

CAP_A_0402V-0.1UF,16V,10%,X7R,A  I132  C2T12
   1 P3V3_STBY      A @BASEBOARD_FAB2_LIB.BASEBOARD_FAB2(SCH_1):P3V3_STBY
   2    GND      B @BASEBOARD_FAB2_LIB.BASEBOARD_FAB2(SCH_1):GND

CAP_A_0402V-0.1UF,16V,10%,X7R,A  I135  C2T8
   1 P3V3_STBY      A @BASEBOARD_FAB2_LIB.BASEBOARD_FAB2(SCH_1):P3V3_STBY
   2    GND      B @BASEBOARD_FAB2_LIB.BASEBOARD_FAB2(SCH_1):GND


DRAWING: @BASEBOARD_FAB2_LIB.BASEBOARD_FAB2(SCH_1):PAGE155 

RES_0402-0.0,5%,1/16W,CHIP,G21A  I53  R9A8
   1 SPA_SIN_SW_R      A @BASEBOARD_FAB2_LIB.BASEBOARD_FAB2(SCH_1):SPA_SIN_SW_R
   2 SPA_MID_DBG1__RX      B @BASEBOARD_FAB2_LIB.BASEBOARD_FAB2(SCH_1):SPA_MID_DBG1__RX

RES_0402-10.0,1%,1/16W,CHIP,G2A  I65  R1L32
   1 LED_POSTCODE_0      A @BASEBOARD_FAB2_LIB.BASEBOARD_FAB2(SCH_1):LED_POSTCODE_0
   2 LED_POSTCODE_0_R      B @BASEBOARD_FAB2_LIB.BASEBOARD_FAB2(SCH_1):LED_POSTCODE_0_R

RES_0402-10.0,1%,1/16W,CHIP,G2A  I66  R1L30
   1 LED_POSTCODE_1      A @BASEBOARD_FAB2_LIB.BASEBOARD_FAB2(SCH_1):LED_POSTCODE_1
   2 LED_POSTCODE_1_R      B @BASEBOARD_FAB2_LIB.BASEBOARD_FAB2(SCH_1):LED_POSTCODE_1_R

RES_0402-10.0,1%,1/16W,CHIP,G2A  I67  R1L25
   1 LED_POSTCODE_2      A @BASEBOARD_FAB2_LIB.BASEBOARD_FAB2(SCH_1):LED_POSTCODE_2
   2 LED_POSTCODE_2_R      B @BASEBOARD_FAB2_LIB.BASEBOARD_FAB2(SCH_1):LED_POSTCODE_2_R

RES_0402-10.0,1%,1/16W,CHIP,G2A  I68  R1L24
   1 LED_POSTCODE_3      A @BASEBOARD_FAB2_LIB.BASEBOARD_FAB2(SCH_1):LED_POSTCODE_3
   2 LED_POSTCODE_3_R      B @BASEBOARD_FAB2_LIB.BASEBOARD_FAB2(SCH_1):LED_POSTCODE_3_R

RES_0402-10.0,1%,1/16W,CHIP,G2A  I73  R1L20
   1 LED_POSTCODE_4      A @BASEBOARD_FAB2_LIB.BASEBOARD_FAB2(SCH_1):LED_POSTCODE_4
   2 LED_POSTCODE_4_R      B @BASEBOARD_FAB2_LIB.BASEBOARD_FAB2(SCH_1):LED_POSTCODE_4_R

RES_0402-10.0,1%,1/16W,CHIP,G2A  I74  R1L18
   1 LED_POSTCODE_5      A @BASEBOARD_FAB2_LIB.BASEBOARD_FAB2(SCH_1):LED_POSTCODE_5
   2 LED_POSTCODE_5_R      B @BASEBOARD_FAB2_LIB.BASEBOARD_FAB2(SCH_1):LED_POSTCODE_5_R

RES_0402-10.0,1%,1/16W,CHIP,G2A  I75  R1L14
   1 LED_POSTCODE_6      A @BASEBOARD_FAB2_LIB.BASEBOARD_FAB2(SCH_1):LED_POSTCODE_6
   2 LED_POSTCODE_6_R      B @BASEBOARD_FAB2_LIB.BASEBOARD_FAB2(SCH_1):LED_POSTCODE_6_R

RES_0402-10.0,1%,1/16W,CHIP,G2A  I76  R1L11
   1 LED_POSTCODE_7      A @BASEBOARD_FAB2_LIB.BASEBOARD_FAB2(SCH_1):LED_POSTCODE_7
   2 LED_POSTCODE_7_R      B @BASEBOARD_FAB2_LIB.BASEBOARD_FAB2(SCH_1):LED_POSTCODE_7_R

RES_0402-2.21K,1%,1/16W,CHIP,GA  I80  R9A7
   1 P3V3_STBY      A @BASEBOARD_FAB2_LIB.BASEBOARD_FAB2(SCH_1):P3V3_STBY
   2 SPA_SIN_SW_R      B @BASEBOARD_FAB2_LIB.BASEBOARD_FAB2(SCH_1):SPA_SIN_SW_R

CAP_A_0402V-0.1UF,16V,10%,X7R,A  I127  C9A1
   1 P5V_STBY_DGB_FS      A @BASEBOARD_FAB2_LIB.BASEBOARD_FAB2(SCH_1):P5V_STBY_DGB_FS
   2    GND      B @BASEBOARD_FAB2_LIB.BASEBOARD_FAB2(SCH_1):GND

FUSE_SMT-IC,H45581-001  I129  F1L1
   1 P5V_STBY_DBG   A<0> @BASEBOARD_FAB2_LIB.BASEBOARD_FAB2(SCH_1):P5V_STBY_DBG
   2 P5V_STBY_DGB_FS   B<0> @BASEBOARD_FAB2_LIB.BASEBOARD_FAB2(SCH_1):P5V_STBY_DGB_FS

RES_0402-100.0K,1%,1/16W,CHIP,A  I130  R1L9
   1 P12V_STBY      A @BASEBOARD_FAB2_LIB.BASEBOARD_FAB2(SCH_1):P12V_STBY
   2 FM_CPLD_DBG_PWR_EN      B @BASEBOARD_FAB2_LIB.BASEBOARD_FAB2(SCH_1):FM_CPLD_DBG_PWR_EN

CONN14_H54902001_PIP-CONN,H549A  I171  J9A2
   1 LED_POSTCODE_0_R    IO1 @BASEBOARD_FAB2_LIB.BASEBOARD_FAB2(SCH_1):LED_POSTCODE_0_R
  10 SPA_5V_SIN_SW   IO10 @BASEBOARD_FAB2_LIB.BASEBOARD_FAB2(SCH_1):SPA_5V_SIN_SW
  11 FM_DEBUG_RST_BTN_N   IO11 @BASEBOARD_FAB2_LIB.BASEBOARD_FAB2(SCH_1):FM_DEBUG_RST_BTN_N
  12 FM_UART_SWITCH_N   IO12 @BASEBOARD_FAB2_LIB.BASEBOARD_FAB2(SCH_1):FM_UART_SWITCH_N
  13    GND   IO13 @BASEBOARD_FAB2_LIB.BASEBOARD_FAB2(SCH_1):GND
  14 P5V_STBY_DGB_FS   IO14 @BASEBOARD_FAB2_LIB.BASEBOARD_FAB2(SCH_1):P5V_STBY_DGB_FS
   2 LED_POSTCODE_1_R    IO2 @BASEBOARD_FAB2_LIB.BASEBOARD_FAB2(SCH_1):LED_POSTCODE_1_R
   3 LED_POSTCODE_2_R    IO3 @BASEBOARD_FAB2_LIB.BASEBOARD_FAB2(SCH_1):LED_POSTCODE_2_R
   4 LED_POSTCODE_3_R    IO4 @BASEBOARD_FAB2_LIB.BASEBOARD_FAB2(SCH_1):LED_POSTCODE_3_R
   5 LED_POSTCODE_4_R    IO5 @BASEBOARD_FAB2_LIB.BASEBOARD_FAB2(SCH_1):LED_POSTCODE_4_R
   6 LED_POSTCODE_5_R    IO6 @BASEBOARD_FAB2_LIB.BASEBOARD_FAB2(SCH_1):LED_POSTCODE_5_R
   7 LED_POSTCODE_6_R    IO7 @BASEBOARD_FAB2_LIB.BASEBOARD_FAB2(SCH_1):LED_POSTCODE_6_R
   8 LED_POSTCODE_7_R    IO8 @BASEBOARD_FAB2_LIB.BASEBOARD_FAB2(SCH_1):LED_POSTCODE_7_R
   9 SPA_MID_DBG_TX    IO9 @BASEBOARD_FAB2_LIB.BASEBOARD_FAB2(SCH_1):SPA_MID_DBG_TX

TTL1G07_A_SOP-74LVC1G07,IC,C88B  I178  U9A1
   2 SPA_5V_SIN_SW      A @BASEBOARD_FAB2_LIB.BASEBOARD_FAB2(SCH_1):SPA_5V_SIN_SW
   4 SPA_SIN_SW_R      Y @BASEBOARD_FAB2_LIB.BASEBOARD_FAB2(SCH_1):SPA_SIN_SW_R

CAP_A_0402V-0.1UF,16V,10%,X7R,A  I184  C1T56
   1 P3V3_STBY      A @BASEBOARD_FAB2_LIB.BASEBOARD_FAB2(SCH_1):P3V3_STBY
   2    GND      B @BASEBOARD_FAB2_LIB.BASEBOARD_FAB2(SCH_1):GND

RES_0402-10.0,1%,1/16W,CHIP,G2A  I186  R1L2
   1 FM_CPLD_DBG_PWR_EN_N      A @BASEBOARD_FAB2_LIB.BASEBOARD_FAB2(SCH_1):FM_CPLD_DBG_PWR_EN_N
   2 FM_CPLD_DBG_PWR_EN_R_N      B @BASEBOARD_FAB2_LIB.BASEBOARD_FAB2(SCH_1):FM_CPLD_DBG_PWR_EN_R_N

FET_N_DUAL_SMLF-NTJD4001N,FET,A  I187  Q1L2
   5 FM_CPLD_DBG_PWR_EN_R_N GATE<0> @BASEBOARD_FAB2_LIB.BASEBOARD_FAB2(SCH_1):FM_CPLD_DBG_PWR_EN_R_N
   4    GND SOURCE<0> @BASEBOARD_FAB2_LIB.BASEBOARD_FAB2(SCH_1):GND
   3 FM_CPLD_DBG_PWR_EN DRAIN<0> @BASEBOARD_FAB2_LIB.BASEBOARD_FAB2(SCH_1):FM_CPLD_DBG_PWR_EN

FET_N_DUAL_SMLF-NTJD4001N,FET,A  I188  Q1L2
   2 FM_CPLD_DBG_PWR_EN GATE<0> @BASEBOARD_FAB2_LIB.BASEBOARD_FAB2(SCH_1):FM_CPLD_DBG_PWR_EN
   1 P5V_STBY_DBG SOURCE<0> @BASEBOARD_FAB2_LIB.BASEBOARD_FAB2(SCH_1):P5V_STBY_DBG
   6 P5V_STBY DRAIN<0> @BASEBOARD_FAB2_LIB.BASEBOARD_FAB2(SCH_1):P5V_STBY

RES_0402-20.0K,1%,1/16W,EMPTY,A  I191  R9A6
   1 P5V_STBY      A @BASEBOARD_FAB2_LIB.BASEBOARD_FAB2(SCH_1):P5V_STBY
   2 SPA_5V_SIN_SW      B @BASEBOARD_FAB2_LIB.BASEBOARD_FAB2(SCH_1):SPA_5V_SIN_SW

RES_0402-15.0K,1%,1/16W,CHIP,GA  I195  R9A5
   1 P5V_STBY      A @BASEBOARD_FAB2_LIB.BASEBOARD_FAB2(SCH_1):P5V_STBY
   2 FM_UART_SWITCH_N      B @BASEBOARD_FAB2_LIB.BASEBOARD_FAB2(SCH_1):FM_UART_SWITCH_N

RES_0402-0.0,5%,1/16W,CHIP,G21A  I196  R6W19
   1 SPA_5V_SIN_SW      A @BASEBOARD_FAB2_LIB.BASEBOARD_FAB2(SCH_1):SPA_5V_SIN_SW
   2 SPA_SIN_SW_R      B @BASEBOARD_FAB2_LIB.BASEBOARD_FAB2(SCH_1):SPA_SIN_SW_R


DRAWING: @BASEBOARD_FAB2_LIB.BASEBOARD_FAB2(SCH_1):PAGE156 

TTL2G07_SOT23LF-74LVC2G07,IC,DB  I201  U8F3
   1 RST_BMC_SYSRST_BTN_OUT_N     1A @BASEBOARD_FAB2_LIB.BASEBOARD_FAB2(SCH_1):RST_BMC_SYSRST_BTN_OUT_N
   3 FM_BMC_PWRBTN_OUT_N     2A @BASEBOARD_FAB2_LIB.BASEBOARD_FAB2(SCH_1):FM_BMC_PWRBTN_OUT_N
   4 FM_PCH_PWRBTN_R_N     2Y @BASEBOARD_FAB2_LIB.BASEBOARD_FAB2(SCH_1):FM_PCH_PWRBTN_R_N
   6 RST_BMC_SYSRST_BTN_OUT_B_R_N     1Y @BASEBOARD_FAB2_LIB.BASEBOARD_FAB2(SCH_1):RST_BMC_SYSRST_BTN_OUT_B_R_N

RES_0402-4.75K,1%,1/16W,CHIP,GA  I206  R2T34
   1 P3V3_STBY      A @BASEBOARD_FAB2_LIB.BASEBOARD_FAB2(SCH_1):P3V3_STBY
   2 FM_BMC_PWRBTN_OUT_N      B @BASEBOARD_FAB2_LIB.BASEBOARD_FAB2(SCH_1):FM_BMC_PWRBTN_OUT_N

RES_0402-4.75K,1%,1/16W,CHIP,GA  I207  R2T35
   1 P3V3_STBY      A @BASEBOARD_FAB2_LIB.BASEBOARD_FAB2(SCH_1):P3V3_STBY
   2 RST_BMC_SYSRST_BTN_OUT_N      B @BASEBOARD_FAB2_LIB.BASEBOARD_FAB2(SCH_1):RST_BMC_SYSRST_BTN_OUT_N

RES_0402-10.0K,1%,1/16W,CHIP,GA  I210  R2T22
   1 P3V3_STBY      A @BASEBOARD_FAB2_LIB.BASEBOARD_FAB2(SCH_1):P3V3_STBY
   2 RST_BMC_SYSRST_BTN_OUT_B_R_N      B @BASEBOARD_FAB2_LIB.BASEBOARD_FAB2(SCH_1):RST_BMC_SYSRST_BTN_OUT_B_R_N

RES_0402-10.0K,1%,1/16W,CHIP,GA  I211  R8F26
   1 P3V3_STBY      A @BASEBOARD_FAB2_LIB.BASEBOARD_FAB2(SCH_1):P3V3_STBY
   2 FM_PCH_PWRBTN_R_N      B @BASEBOARD_FAB2_LIB.BASEBOARD_FAB2(SCH_1):FM_PCH_PWRBTN_R_N

RES_0402-33.2,1%,1/16W,CHIP,G2A  I214  R8E24
   1 IRQ_BMC_PCH_NMI_STBY_N      A @BASEBOARD_FAB2_LIB.BASEBOARD_FAB2(SCH_1):IRQ_BMC_PCH_NMI_STBY_N
   2 IRQ_BMC_PCH_NMI_STBY_R_N      B @BASEBOARD_FAB2_LIB.BASEBOARD_FAB2(SCH_1):IRQ_BMC_PCH_NMI_STBY_R_N

RES_0402-4.75K,1%,1/16W,CHIP,GA  I215  R8E22
   1 P3V3_STBY      A @BASEBOARD_FAB2_LIB.BASEBOARD_FAB2(SCH_1):P3V3_STBY
   2 IRQ_BMC_PCH_NMI_STBY_N      B @BASEBOARD_FAB2_LIB.BASEBOARD_FAB2(SCH_1):IRQ_BMC_PCH_NMI_STBY_N

RES_0402-4.75K,1%,1/16W,CHIP,GA  I265  R2U2
   1 P3V3_STBY      A @BASEBOARD_FAB2_LIB.BASEBOARD_FAB2(SCH_1):P3V3_STBY
   2 RST_PCH_SYSRST_BTN_OUT_N      B @BASEBOARD_FAB2_LIB.BASEBOARD_FAB2(SCH_1):RST_PCH_SYSRST_BTN_OUT_N

RES_0402-4.75K,1%,1/16W,CHIP,GA  I267  R8G2
   1 P3V3_STBY      A @BASEBOARD_FAB2_LIB.BASEBOARD_FAB2(SCH_1):P3V3_STBY
   2 FM_PCH_PWRBTN_OUT_N      B @BASEBOARD_FAB2_LIB.BASEBOARD_FAB2(SCH_1):FM_PCH_PWRBTN_OUT_N

TTL2G07_SOT23LF-74LVC2G07,IC,DB  I269  U8G1
   1 RST_PCH_SYSRST_BTN_OUT_N     1A @BASEBOARD_FAB2_LIB.BASEBOARD_FAB2(SCH_1):RST_PCH_SYSRST_BTN_OUT_N
   3 FM_PCH_PWRBTN_OUT_N     2A @BASEBOARD_FAB2_LIB.BASEBOARD_FAB2(SCH_1):FM_PCH_PWRBTN_OUT_N
   4 FM_PCH_PWRBTN_R_N     2Y @BASEBOARD_FAB2_LIB.BASEBOARD_FAB2(SCH_1):FM_PCH_PWRBTN_R_N
   6 RST_BMC_SYSRST_BTN_OUT_B_R_N     1Y @BASEBOARD_FAB2_LIB.BASEBOARD_FAB2(SCH_1):RST_BMC_SYSRST_BTN_OUT_B_R_N

CAP_A_0402V-0.1UF,16V,10%,X7R,A  I273  C2T35
   1 P3V3_STBY      A @BASEBOARD_FAB2_LIB.BASEBOARD_FAB2(SCH_1):P3V3_STBY
   2    GND      B @BASEBOARD_FAB2_LIB.BASEBOARD_FAB2(SCH_1):GND

CAP_A_0402V-0.1UF,16V,10%,X7R,A  I275  C8F16
   1 P3V3_STBY      A @BASEBOARD_FAB2_LIB.BASEBOARD_FAB2(SCH_1):P3V3_STBY
   2    GND      B @BASEBOARD_FAB2_LIB.BASEBOARD_FAB2(SCH_1):GND

RES_0402-0.0,5%,1/16W,EMPTY,G2A  I279  R8E11
   1 FM_MEM_THERM_EVENT_LVT3_N      A @BASEBOARD_FAB2_LIB.BASEBOARD_FAB2(SCH_1):FM_MEM_THERM_EVENT_LVT3_N
   2 FM_ADR_SMI_GPIO_N      B @BASEBOARD_FAB2_LIB.BASEBOARD_FAB2(SCH_1):FM_ADR_SMI_GPIO_N

CONN3_C95678002_PIP-CONN,C9567A  I281  J9B2
   1 SMB_SMLINK0_STBY_LVC3_SDA    IO1 @BASEBOARD_FAB2_LIB.BASEBOARD_FAB2(SCH_1):SMB_SMLINK0_STBY_LVC3_SDA
   2    GND    IO2 @BASEBOARD_FAB2_LIB.BASEBOARD_FAB2(SCH_1):GND
   3 SMB_SMLINK0_STBY_LVC3_SCL    IO3 @BASEBOARD_FAB2_LIB.BASEBOARD_FAB2(SCH_1):SMB_SMLINK0_STBY_LVC3_SCL

CONN3_C95678002_PIP-CONN,C9567A  I285  J8C1
   1 SMB_HOST_STBY_LVC3_SDA    IO1 @BASEBOARD_FAB2_LIB.BASEBOARD_FAB2(SCH_1):SMB_HOST_STBY_LVC3_SDA
   2    GND    IO2 @BASEBOARD_FAB2_LIB.BASEBOARD_FAB2(SCH_1):GND
   3 SMB_HOST_STBY_LVC3_SCL    IO3 @BASEBOARD_FAB2_LIB.BASEBOARD_FAB2(SCH_1):SMB_HOST_STBY_LVC3_SCL

RES_0402-49.9,1%,1/16W,CHIP,G2A  I288  R2T18
   1 RST_BMC_SYSRST_BTN_OUT_B_R_N      A @BASEBOARD_FAB2_LIB.BASEBOARD_FAB2(SCH_1):RST_BMC_SYSRST_BTN_OUT_B_R_N
   2 RST_BMC_SYSRST_BTN_OUT_B_N      B @BASEBOARD_FAB2_LIB.BASEBOARD_FAB2(SCH_1):RST_BMC_SYSRST_BTN_OUT_B_N

RES_0402-33.2,1%,1/16W,CHIP,G2A  I289  R2T28
   1 FM_PCH_PWRBTN_R_N      A @BASEBOARD_FAB2_LIB.BASEBOARD_FAB2(SCH_1):FM_PCH_PWRBTN_R_N
   2 FM_PCH_PWRBTN_N      B @BASEBOARD_FAB2_LIB.BASEBOARD_FAB2(SCH_1):FM_PCH_PWRBTN_N

RES_0402-0.0,5%,1/16W,EMPTY,G2A  I299  R6D16
   1 FM_CPU_BMC_INIT      A @BASEBOARD_FAB2_LIB.BASEBOARD_FAB2(SCH_1):FM_CPU_BMC_INIT
   2 H_CPU0_BMCINIT      B @BASEBOARD_FAB2_LIB.BASEBOARD_FAB2(SCH_1):H_CPU0_BMCINIT

RES_0402-0.0,5%,1/16W,EMPTY,G2A  I300  R3D31
   1 FM_CPU_BMC_INIT      A @BASEBOARD_FAB2_LIB.BASEBOARD_FAB2(SCH_1):FM_CPU_BMC_INIT
   2 H_CPU1_BMCINIT      B @BASEBOARD_FAB2_LIB.BASEBOARD_FAB2(SCH_1):H_CPU1_BMCINIT

RES_0402-1.00K,1%,1/16W,CHIP,GA  I302  R6N14
   1    GND      A @BASEBOARD_FAB2_LIB.BASEBOARD_FAB2(SCH_1):GND
   2 PD_PIROM_CPU0_ADDR0      B @BASEBOARD_FAB2_LIB.BASEBOARD_FAB2(SCH_1):PD_PIROM_CPU0_ADDR0

RES_0402-1.00K,1%,1/16W,CHIP,GA  I303  R6N13
   1    GND      A @BASEBOARD_FAB2_LIB.BASEBOARD_FAB2(SCH_1):GND
   2 PD_PIROM_CPU0_ADDR1      B @BASEBOARD_FAB2_LIB.BASEBOARD_FAB2(SCH_1):PD_PIROM_CPU0_ADDR1

RES_0402-1.00K,1%,1/16W,CHIP,GA  I304  R6N15
   1    GND      A @BASEBOARD_FAB2_LIB.BASEBOARD_FAB2(SCH_1):GND
   2 PD_PIROM_CPU0_ADDR2      B @BASEBOARD_FAB2_LIB.BASEBOARD_FAB2(SCH_1):PD_PIROM_CPU0_ADDR2

RES_0402-1.00K,1%,1/16W,CHIP,GA  I312  R1C32
   1    GND      A @BASEBOARD_FAB2_LIB.BASEBOARD_FAB2(SCH_1):GND
   2 PD_PIROM_CPU1_ADDR2      B @BASEBOARD_FAB2_LIB.BASEBOARD_FAB2(SCH_1):PD_PIROM_CPU1_ADDR2

RES_0402-1.00K,1%,1/16W,CHIP,GA  I313  R1C33
   1    GND      A @BASEBOARD_FAB2_LIB.BASEBOARD_FAB2(SCH_1):GND
   2 PD_PIROM_CPU1_ADDR1      B @BASEBOARD_FAB2_LIB.BASEBOARD_FAB2(SCH_1):PD_PIROM_CPU1_ADDR1

RES_0402-10.0K,1%,1/16W,CHIP,GA  I320  R1C34
   1 P3V3_STBY      A @BASEBOARD_FAB2_LIB.BASEBOARD_FAB2(SCH_1):P3V3_STBY
   2 PU_PIROM_CPU1_ADDR0      B @BASEBOARD_FAB2_LIB.BASEBOARD_FAB2(SCH_1):PU_PIROM_CPU1_ADDR0

RES_0402-0.0,5%,1/16W,CHIP,G21A  I321  R9M21
   1 SMB_LAN_STBY_LVC3_SDA      A @BASEBOARD_FAB2_LIB.BASEBOARD_FAB2(SCH_1):SMB_LAN_STBY_LVC3_SDA
   2 SMB_PIROM_CPU1_SDA      B @BASEBOARD_FAB2_LIB.BASEBOARD_FAB2(SCH_1):SMB_PIROM_CPU1_SDA

RES_0402-0.0,5%,1/16W,CHIP,G21A  I322  R4A8
   1 SMB_LAN_STBY_LVC3_SDA      A @BASEBOARD_FAB2_LIB.BASEBOARD_FAB2(SCH_1):SMB_LAN_STBY_LVC3_SDA
   2 SMB_PIROM_CPU0_SDA      B @BASEBOARD_FAB2_LIB.BASEBOARD_FAB2(SCH_1):SMB_PIROM_CPU0_SDA

RES_0402-0.0,5%,1/16W,CHIP,G21A  I323  R9M20
   1 SMB_LAN_STBY_LVC3_SCL      A @BASEBOARD_FAB2_LIB.BASEBOARD_FAB2(SCH_1):SMB_LAN_STBY_LVC3_SCL
   2 SMB_PIROM_CPU1_SCL      B @BASEBOARD_FAB2_LIB.BASEBOARD_FAB2(SCH_1):SMB_PIROM_CPU1_SCL

RES_0402-0.0,5%,1/16W,CHIP,G21A  I324  R4A9
   1 SMB_LAN_STBY_LVC3_SCL      A @BASEBOARD_FAB2_LIB.BASEBOARD_FAB2(SCH_1):SMB_LAN_STBY_LVC3_SCL
   2 SMB_PIROM_CPU0_SCL      B @BASEBOARD_FAB2_LIB.BASEBOARD_FAB2(SCH_1):SMB_PIROM_CPU0_SCL

RES_0402-3.32K,1%,1/16W,EMPTY,A  I331  R3P54
   1 P3V3_STBY      A @BASEBOARD_FAB2_LIB.BASEBOARD_FAB2(SCH_1):P3V3_STBY
   2 FM_CPU0_SM_WP      B @BASEBOARD_FAB2_LIB.BASEBOARD_FAB2(SCH_1):FM_CPU0_SM_WP

RES_0402-1.00K,1%,1/16W,CHIP,GA  I333  R3P56
   1 FM_CPU0_SM_WP      A @BASEBOARD_FAB2_LIB.BASEBOARD_FAB2(SCH_1):FM_CPU0_SM_WP
   2    GND      B @BASEBOARD_FAB2_LIB.BASEBOARD_FAB2(SCH_1):GND

RES_0402-3.32K,1%,1/16W,EMPTY,A  I336  R1C35
   1 P3V3_STBY      A @BASEBOARD_FAB2_LIB.BASEBOARD_FAB2(SCH_1):P3V3_STBY
   2 FM_CPU1_SM_WP      B @BASEBOARD_FAB2_LIB.BASEBOARD_FAB2(SCH_1):FM_CPU1_SM_WP

RES_0402-1.00K,1%,1/16W,CHIP,GA  I337  R1C36
   1 FM_CPU1_SM_WP      A @BASEBOARD_FAB2_LIB.BASEBOARD_FAB2(SCH_1):FM_CPU1_SM_WP
   2    GND      B @BASEBOARD_FAB2_LIB.BASEBOARD_FAB2(SCH_1):GND


DRAWING: @BASEBOARD_FAB2_LIB.BASEBOARD_FAB2(SCH_1):PAGE157 

RES_0402-4.75K,1%,1/16W,CHIP,GA  I97  R2N27
   1   P3V3      A @BASEBOARD_FAB2_LIB.BASEBOARD_FAB2(SCH_1):P3V3
   2 FM_BMC_NMI_N      B @BASEBOARD_FAB2_LIB.BASEBOARD_FAB2(SCH_1):FM_BMC_NMI_N

RES_0402-2.21K,1%,1/16W,CHIP,GA  I296  R8F23
   1 P3V3_STBY      A @BASEBOARD_FAB2_LIB.BASEBOARD_FAB2(SCH_1):P3V3_STBY
   2 IRQ_MEZZ_LAN_ALERT_N      B @BASEBOARD_FAB2_LIB.BASEBOARD_FAB2(SCH_1):IRQ_MEZZ_LAN_ALERT_N

RES_0402-2.21K,1%,1/16W,CHIP,GA  I298  R2T29
   1 P3V3_STBY      A @BASEBOARD_FAB2_LIB.BASEBOARD_FAB2(SCH_1):P3V3_STBY
   2 IRQ_OOB_MGMT_RISER_ALERT_N      B @BASEBOARD_FAB2_LIB.BASEBOARD_FAB2(SCH_1):IRQ_OOB_MGMT_RISER_ALERT_N

RES_0402-51.1,1.0%,1/16W,CHIP,A  I302  R2N25
   1 FM_NMI_EVENT_N      A @BASEBOARD_FAB2_LIB.BASEBOARD_FAB2(SCH_1):FM_NMI_EVENT_N
   2 FM_BMC_NMI_N      B @BASEBOARD_FAB2_LIB.BASEBOARD_FAB2(SCH_1):FM_BMC_NMI_N

RES_0402-4.75K,1%,1/16W,CHIP,GA  I316  R8F24
   1 P3V3_STBY      A @BASEBOARD_FAB2_LIB.BASEBOARD_FAB2(SCH_1):P3V3_STBY
   2 FP_NMI_BTN_N      B @BASEBOARD_FAB2_LIB.BASEBOARD_FAB2(SCH_1):FP_NMI_BTN_N

RES_0402-1.00K,1%,1/16W,CHIP,GA  I326  R2T5
   1 P3V3_STBY      A @BASEBOARD_FAB2_LIB.BASEBOARD_FAB2(SCH_1):P3V3_STBY
   2 H_CPU0_FAST_WAKE      B @BASEBOARD_FAB2_LIB.BASEBOARD_FAB2(SCH_1):H_CPU0_FAST_WAKE

RES_0402-1.00K,1%,1/16W,CHIP,GA  I327  R2T7
   1 P3V3_STBY      A @BASEBOARD_FAB2_LIB.BASEBOARD_FAB2(SCH_1):P3V3_STBY
   2 H_CPU0_FAST_WAKE_LVT3_N      B @BASEBOARD_FAB2_LIB.BASEBOARD_FAB2(SCH_1):H_CPU0_FAST_WAKE_LVT3_N

NPN_SM-MMBT3904,IC,C52245-001  I330  Q2T1
   1 H_CPU0_FAST_WAKE_B_N      B @BASEBOARD_FAB2_LIB.BASEBOARD_FAB2(SCH_1):H_CPU0_FAST_WAKE_B_N
   3 H_CPU0_FAST_WAKE      C @BASEBOARD_FAB2_LIB.BASEBOARD_FAB2(SCH_1):H_CPU0_FAST_WAKE
   2    GND      E @BASEBOARD_FAB2_LIB.BASEBOARD_FAB2(SCH_1):GND

RES_0402-4.75K,1%,1/16W,CHIP,GA  I335  R8D25
   1 P3V3_STBY      A @BASEBOARD_FAB2_LIB.BASEBOARD_FAB2(SCH_1):P3V3_STBY
   2 RST_BMC_SRST_R2_N      B @BASEBOARD_FAB2_LIB.BASEBOARD_FAB2(SCH_1):RST_BMC_SRST_R2_N

FET_N_SOT23LF-2N7002,FET,C7925A  I340  Q2T2
   1 H_CPU0_FAST_WAKE   GATE @BASEBOARD_FAB2_LIB.BASEBOARD_FAB2(SCH_1):H_CPU0_FAST_WAKE
   2    GND    SRC @BASEBOARD_FAB2_LIB.BASEBOARD_FAB2(SCH_1):GND
   3 H_CPU0_FAST_WAKE_LVT3_N    DRN @BASEBOARD_FAB2_LIB.BASEBOARD_FAB2(SCH_1):H_CPU0_FAST_WAKE_LVT3_N

RES_0402-4.75K,1%,1/16W,CHIP,GA  I342  R3N12
   1 P3V3_STBY      A @BASEBOARD_FAB2_LIB.BASEBOARD_FAB2(SCH_1):P3V3_STBY
   2 FM_MP_PS_FAIL_N      B @BASEBOARD_FAB2_LIB.BASEBOARD_FAB2(SCH_1):FM_MP_PS_FAIL_N

RES_0402-4.75K,1%,1/16W,CHIP,GA  I344  R3N11
   1 P3V3_STBY      A @BASEBOARD_FAB2_LIB.BASEBOARD_FAB2(SCH_1):P3V3_STBY
   2 FM_MP_PS_REDUNDANT_LOST_N      B @BASEBOARD_FAB2_LIB.BASEBOARD_FAB2(SCH_1):FM_MP_PS_REDUNDANT_LOST_N

RES_0402-4.75K,1%,1/16W,CHIP,GA  I346  R2M2
   1 P3V3_STBY      A @BASEBOARD_FAB2_LIB.BASEBOARD_FAB2(SCH_1):P3V3_STBY
   2 FM_ADR_SMI_GPIO_N      B @BASEBOARD_FAB2_LIB.BASEBOARD_FAB2(SCH_1):FM_ADR_SMI_GPIO_N

RES_0402-4.75K,1%,1/16W,CHIP,GA  I348  R2M5
   1 P3V3_STBY      A @BASEBOARD_FAB2_LIB.BASEBOARD_FAB2(SCH_1):P3V3_STBY
   2 FM_BMC_CPLD_GPO      B @BASEBOARD_FAB2_LIB.BASEBOARD_FAB2(SCH_1):FM_BMC_CPLD_GPO

SWITCH_D90553001_SMLF-IC,D9055A  I351  S8E1
   1    GND      A @BASEBOARD_FAB2_LIB.BASEBOARD_FAB2(SCH_1):GND
   2 FP_NMI_BTN_OUT_R_N      B @BASEBOARD_FAB2_LIB.BASEBOARD_FAB2(SCH_1):FP_NMI_BTN_OUT_R_N

RES_0402-200.0,1%,1/16W,CHIP,GA  I352  R2R9
   1 FP_NMI_BTN_OUT_R_N      A @BASEBOARD_FAB2_LIB.BASEBOARD_FAB2(SCH_1):FP_NMI_BTN_OUT_R_N
   2 FP_NMI_BTN_OUT_N      B @BASEBOARD_FAB2_LIB.BASEBOARD_FAB2(SCH_1):FP_NMI_BTN_OUT_N

CAP_A_0402V-1.0UF,6.3V,10%,X6SA  I353  C2R12
   1 FP_NMI_BTN_OUT_N      A @BASEBOARD_FAB2_LIB.BASEBOARD_FAB2(SCH_1):FP_NMI_BTN_OUT_N
   2    GND      B @BASEBOARD_FAB2_LIB.BASEBOARD_FAB2(SCH_1):GND

TTL2G14_SMLF-74LVC2G14,IC,D184B  I356  U2R1
   3 FP_NMI_BTN_OUT_N   A<0> @BASEBOARD_FAB2_LIB.BASEBOARD_FAB2(SCH_1):FP_NMI_BTN_OUT_N
   4 FP_NMI_BTN   Y<0> @BASEBOARD_FAB2_LIB.BASEBOARD_FAB2(SCH_1):FP_NMI_BTN

TTL2G14_SMLF-74LVC2G14,IC,D184B  I357  U2R1
   1 FP_NMI_BTN   A<0> @BASEBOARD_FAB2_LIB.BASEBOARD_FAB2(SCH_1):FP_NMI_BTN
   6 FP_NMI_BTN_R_N   Y<0> @BASEBOARD_FAB2_LIB.BASEBOARD_FAB2(SCH_1):FP_NMI_BTN_R_N

RES_0402-33.2,1%,1/16W,CHIP,G2A  I358  R2R10
   1 FP_NMI_BTN_R_N      A @BASEBOARD_FAB2_LIB.BASEBOARD_FAB2(SCH_1):FP_NMI_BTN_R_N
   2 FP_NMI_BTN_N      B @BASEBOARD_FAB2_LIB.BASEBOARD_FAB2(SCH_1):FP_NMI_BTN_N

RES_0402-4.75K,1%,1/16W,EMPTY,A  I361  R8E19
   1 P3V3_STBY      A @BASEBOARD_FAB2_LIB.BASEBOARD_FAB2(SCH_1):P3V3_STBY
   2 FM_BIOS_TOP_SWAP      B @BASEBOARD_FAB2_LIB.BASEBOARD_FAB2(SCH_1):FM_BIOS_TOP_SWAP

RES_0402-4.75K,1%,1/16W,CHIP,GA  I367  R2U4
   1 P3V3_STBY      A @BASEBOARD_FAB2_LIB.BASEBOARD_FAB2(SCH_1):P3V3_STBY
   2 FM_CPLD_BMC_PWRDN_N      B @BASEBOARD_FAB2_LIB.BASEBOARD_FAB2(SCH_1):FM_CPLD_BMC_PWRDN_N

RES_0402-1.00K,1%,1/16W,CHIP,GA  I368  R4R1
   1 H_CPU0_FAST_WAKE_N      A @BASEBOARD_FAB2_LIB.BASEBOARD_FAB2(SCH_1):H_CPU0_FAST_WAKE_N
   2 H_CPU0_FAST_WAKE_B_N      B @BASEBOARD_FAB2_LIB.BASEBOARD_FAB2(SCH_1):H_CPU0_FAST_WAKE_B_N

CAP_A_0402V-0.1UF,16V,10%,X7R,A  I370  C2T3
   1 P3V3_STBY      A @BASEBOARD_FAB2_LIB.BASEBOARD_FAB2(SCH_1):P3V3_STBY
   2    GND      B @BASEBOARD_FAB2_LIB.BASEBOARD_FAB2(SCH_1):GND

TTL1G07_A_SOP-74LVC1G07,IC,C88B  I374  U8D2
   2 PWRGD_DSW_PWROK      A @BASEBOARD_FAB2_LIB.BASEBOARD_FAB2(SCH_1):PWRGD_DSW_PWROK
   4 RST_BMC_SRST_R2_N      Y @BASEBOARD_FAB2_LIB.BASEBOARD_FAB2(SCH_1):RST_BMC_SRST_R2_N

CAP_A_0402V-0.1UF,16V,10%,X7R,A  I376  C8D1
   1 P3V3_STBY      A @BASEBOARD_FAB2_LIB.BASEBOARD_FAB2(SCH_1):P3V3_STBY
   2    GND      B @BASEBOARD_FAB2_LIB.BASEBOARD_FAB2(SCH_1):GND

RES_0402-0.0,5%,1/16W,CHIP,G21A  I379  R9E14
   1 FM_TPM_PRES_RST_N      A @BASEBOARD_FAB2_LIB.BASEBOARD_FAB2(SCH_1):FM_TPM_PRES_RST_N
   2 FM_BMC_ENABLE_N      B @BASEBOARD_FAB2_LIB.BASEBOARD_FAB2(SCH_1):FM_BMC_ENABLE_N

RES_0402-4.75K,1%,1/16W,CHIP,GA  I382  R1L7
   1 P3V3_STBY      A @BASEBOARD_FAB2_LIB.BASEBOARD_FAB2(SCH_1):P3V3_STBY
   2 FM_BMC_CPLD_MP_RST_N      B @BASEBOARD_FAB2_LIB.BASEBOARD_FAB2(SCH_1):FM_BMC_CPLD_MP_RST_N

RES_0402-4.75K,1%,1/16W,CHIP,GA  I385  R8E32
   1 P3V3_STBY      A @BASEBOARD_FAB2_LIB.BASEBOARD_FAB2(SCH_1):P3V3_STBY
   2 FP_NMI_BTN_OUT_R_N      B @BASEBOARD_FAB2_LIB.BASEBOARD_FAB2(SCH_1):FP_NMI_BTN_OUT_R_N

RES_0402-33.2,1%,1/16W,CHIP,G2A  I386  R8D22
   1 RST_BMC_SRST_R2_N      A @BASEBOARD_FAB2_LIB.BASEBOARD_FAB2(SCH_1):RST_BMC_SRST_R2_N
   2 FM_TPM_PRES_RST_N      B @BASEBOARD_FAB2_LIB.BASEBOARD_FAB2(SCH_1):FM_TPM_PRES_RST_N

RES_0402-33.2,1%,1/16W,CHIP,G2A  I388  R8D36
   1 RST_BMC_SRST_R2_N      A @BASEBOARD_FAB2_LIB.BASEBOARD_FAB2(SCH_1):RST_BMC_SRST_R2_N
   2 RST_BMC_DDR3_BUF_IN_N      B @BASEBOARD_FAB2_LIB.BASEBOARD_FAB2(SCH_1):RST_BMC_DDR3_BUF_IN_N


DRAWING: @BASEBOARD_FAB2_LIB.BASEBOARD_FAB2(SCH_1):PAGE158 

CAP_A_0402V-0.1UF,16V,10%,X7R,A  I70  C1T10
   1 P3V3_STBY      A @BASEBOARD_FAB2_LIB.BASEBOARD_FAB2(SCH_1):P3V3_STBY
   2    GND      B @BASEBOARD_FAB2_LIB.BASEBOARD_FAB2(SCH_1):GND

FSA3357_SM-IC,C63273-001  I74  U9F2
   7 UART_MUX_OUT_R      A @BASEBOARD_FAB2_LIB.BASEBOARD_FAB2(SCH_1):UART_MUX_OUT_R
   1 SP2_BMC_CM_UART_TX_R     B0 @BASEBOARD_FAB2_LIB.BASEBOARD_FAB2(SCH_1):SP2_BMC_CM_UART_TX_R
   2 UART_BMC_TXD5     B1 @BASEBOARD_FAB2_LIB.BASEBOARD_FAB2(SCH_1):UART_BMC_TXD5
   3 SP1_BMC_HOST_UART_TX     B2 @BASEBOARD_FAB2_LIB.BASEBOARD_FAB2(SCH_1):SP1_BMC_HOST_UART_TX
   4    GND    GND @BASEBOARD_FAB2_LIB.BASEBOARD_FAB2(SCH_1):GND
   6 FM_UARTSW_LSB_N     S1 @BASEBOARD_FAB2_LIB.BASEBOARD_FAB2(SCH_1):FM_UARTSW_LSB_N
   5 FM_UARTSW_MSB_N     S2 @BASEBOARD_FAB2_LIB.BASEBOARD_FAB2(SCH_1):FM_UARTSW_MSB_N
   8 P3V3_STBY    VCC @BASEBOARD_FAB2_LIB.BASEBOARD_FAB2(SCH_1):P3V3_STBY

FSA3357_SM-IC,C63273-001  I75  U9F1
   7 UART_MUX_IN_R      A @BASEBOARD_FAB2_LIB.BASEBOARD_FAB2(SCH_1):UART_MUX_IN_R
   1 SP2_BMC_CM_UART_RX_R     B0 @BASEBOARD_FAB2_LIB.BASEBOARD_FAB2(SCH_1):SP2_BMC_CM_UART_RX_R
   2 UART_BMC_RXD5     B1 @BASEBOARD_FAB2_LIB.BASEBOARD_FAB2(SCH_1):UART_BMC_RXD5
   3 SP1_BMC_HOST_UART_RX     B2 @BASEBOARD_FAB2_LIB.BASEBOARD_FAB2(SCH_1):SP1_BMC_HOST_UART_RX
   4    GND    GND @BASEBOARD_FAB2_LIB.BASEBOARD_FAB2(SCH_1):GND
   6 FM_UARTSW_LSB_N     S1 @BASEBOARD_FAB2_LIB.BASEBOARD_FAB2(SCH_1):FM_UARTSW_LSB_N
   5 FM_UARTSW_MSB_N     S2 @BASEBOARD_FAB2_LIB.BASEBOARD_FAB2(SCH_1):FM_UARTSW_MSB_N
   8 P3V3_STBY    VCC @BASEBOARD_FAB2_LIB.BASEBOARD_FAB2(SCH_1):P3V3_STBY

RES_0402-100.0,1%,1/16W,CHIP,GA  I86  R9F25
   1 SPA_MID_DBG_RX      A @BASEBOARD_FAB2_LIB.BASEBOARD_FAB2(SCH_1):SPA_MID_DBG_RX
   2 UART_MUX_IN_R      B @BASEBOARD_FAB2_LIB.BASEBOARD_FAB2(SCH_1):UART_MUX_IN_R

RES_0402-0.0,5%,1/16W,CHIP,G21A  I91  R9F27
   1 UART_MUX_OUT_R      A @BASEBOARD_FAB2_LIB.BASEBOARD_FAB2(SCH_1):UART_MUX_OUT_R
   2 SPA_MID_DBG_TX      B @BASEBOARD_FAB2_LIB.BASEBOARD_FAB2(SCH_1):SPA_MID_DBG_TX

CAP_A_0402V-0.1UF,16V,10%,X7R,A  I97  C1T11
   1 P3V3_STBY      A @BASEBOARD_FAB2_LIB.BASEBOARD_FAB2(SCH_1):P3V3_STBY
   2    GND      B @BASEBOARD_FAB2_LIB.BASEBOARD_FAB2(SCH_1):GND

RES_0402-0.0,5%,1/16W,EMPTY,G2A  I99  R9F26
   1 SP2_BMC_CM_UART_TX      A @BASEBOARD_FAB2_LIB.BASEBOARD_FAB2(SCH_1):SP2_BMC_CM_UART_TX
   2 SPA_MID_DBG_TX      B @BASEBOARD_FAB2_LIB.BASEBOARD_FAB2(SCH_1):SPA_MID_DBG_TX

RES_0402-0.0,5%,1/16W,EMPTY,G2A  I100  R9F24
   1 SPA_MID_DBG_RX      A @BASEBOARD_FAB2_LIB.BASEBOARD_FAB2(SCH_1):SPA_MID_DBG_RX
   2 SP2_BMC_CM_UART_RX      B @BASEBOARD_FAB2_LIB.BASEBOARD_FAB2(SCH_1):SP2_BMC_CM_UART_RX

LED_A1LF-GREEN,IC,D14725-022  I130  DS9A4
   2 FM_UARTSW_LSB_N      C @BASEBOARD_FAB2_LIB.BASEBOARD_FAB2(SCH_1):FM_UARTSW_LSB_N
   1 FM_UARTSW_LSB_R_N      A @BASEBOARD_FAB2_LIB.BASEBOARD_FAB2(SCH_1):FM_UARTSW_LSB_R_N

RES_0402-330,5%,1/16W,CHIP,G21A  I131  R1L43
   1 FM_UARTSW_LSB_R_N      A @BASEBOARD_FAB2_LIB.BASEBOARD_FAB2(SCH_1):FM_UARTSW_LSB_R_N
   2 P3V3_STBY      B @BASEBOARD_FAB2_LIB.BASEBOARD_FAB2(SCH_1):P3V3_STBY

LED_A1LF-GREEN,IC,D14725-022  I134  DS9A7
   2 FM_UARTSW_MSB_N      C @BASEBOARD_FAB2_LIB.BASEBOARD_FAB2(SCH_1):FM_UARTSW_MSB_N
   1 FM_UARTSW_MSB_R_N      A @BASEBOARD_FAB2_LIB.BASEBOARD_FAB2(SCH_1):FM_UARTSW_MSB_R_N

RES_0402-330,5%,1/16W,CHIP,G21A  I136  R1L44
   1 FM_UARTSW_MSB_R_N      A @BASEBOARD_FAB2_LIB.BASEBOARD_FAB2(SCH_1):FM_UARTSW_MSB_R_N
   2 P3V3_STBY      B @BASEBOARD_FAB2_LIB.BASEBOARD_FAB2(SCH_1):P3V3_STBY

RES_0402-0.0,5%,1/16W,CHIP,G21A  I148  R9F65
   1 SP2_BMC_CM_UART_TX_R1      A @BASEBOARD_FAB2_LIB.BASEBOARD_FAB2(SCH_1):SP2_BMC_CM_UART_TX_R1
   2 SP2_BMC_CM_UART_TX_R      B @BASEBOARD_FAB2_LIB.BASEBOARD_FAB2(SCH_1):SP2_BMC_CM_UART_TX_R

RES_0402-0.0,5%,1/16W,EMPTY,G2A  I149  R9F68
   1 SP2_BMC_CM_UART_RX_R      A @BASEBOARD_FAB2_LIB.BASEBOARD_FAB2(SCH_1):SP2_BMC_CM_UART_RX_R
   2 SP2_BMC_CM_UART_RX      B @BASEBOARD_FAB2_LIB.BASEBOARD_FAB2(SCH_1):SP2_BMC_CM_UART_RX

RES_0402-0.0,5%,1/16W,CHIP,G21A  I150  R9F69
   1 SP2_BMC_CM_UART_RX_R      A @BASEBOARD_FAB2_LIB.BASEBOARD_FAB2(SCH_1):SP2_BMC_CM_UART_RX_R
   2 SP2_BMC_CM_UART_RX_R1      B @BASEBOARD_FAB2_LIB.BASEBOARD_FAB2(SCH_1):SP2_BMC_CM_UART_RX_R1

RES_0402-0.0,5%,1/16W,EMPTY,G2A  I152  R9F66
   1 SP2_BMC_CM_UART_TX      A @BASEBOARD_FAB2_LIB.BASEBOARD_FAB2(SCH_1):SP2_BMC_CM_UART_TX
   2 SP2_BMC_CM_UART_TX_R      B @BASEBOARD_FAB2_LIB.BASEBOARD_FAB2(SCH_1):SP2_BMC_CM_UART_TX_R


DRAWING: @BASEBOARD_FAB2_LIB.BASEBOARD_FAB2(SCH_1):PAGE159 

RES_0402-2.26K,1.0%,1/16W,EMPTA  I210  R8G3
   1 P3V3_STBY      A @BASEBOARD_FAB2_LIB.BASEBOARD_FAB2(SCH_1):P3V3_STBY
   2 SMB_OCP_LAN_STBY_LVC3_SCL_R      B @BASEBOARD_FAB2_LIB.BASEBOARD_FAB2(SCH_1):SMB_OCP_LAN_STBY_LVC3_SCL_R

RES_0402-2.26K,1.0%,1/16W,EMPTA  I212  R8G6
   1 P3V3_STBY      A @BASEBOARD_FAB2_LIB.BASEBOARD_FAB2(SCH_1):P3V3_STBY
   2 SMB_OCP_LAN_STBY_LVC3_SDA_R      B @BASEBOARD_FAB2_LIB.BASEBOARD_FAB2(SCH_1):SMB_OCP_LAN_STBY_LVC3_SDA_R

RES_0402-2.26K,1.0%,1/16W,CHIPA  I214  R2U5
   1 P3V3_STBY      A @BASEBOARD_FAB2_LIB.BASEBOARD_FAB2(SCH_1):P3V3_STBY
   2 SMB_OCP_FRU_STBY_LVC3_SCL_R      B @BASEBOARD_FAB2_LIB.BASEBOARD_FAB2(SCH_1):SMB_OCP_FRU_STBY_LVC3_SCL_R

RES_0402-2.26K,1.0%,1/16W,CHIPA  I216  R2U13
   1 P3V3_STBY      A @BASEBOARD_FAB2_LIB.BASEBOARD_FAB2(SCH_1):P3V3_STBY
   2 SMB_OCP_FRU_STBY_LVC3_SDA_R      B @BASEBOARD_FAB2_LIB.BASEBOARD_FAB2(SCH_1):SMB_OCP_FRU_STBY_LVC3_SDA_R

RES_0402-20.0,1%,1/16W,CHIP,G2A  I218  R2U1
   1 SMB_BMC_PMBUS_STBY_LVC3_SCL_R      A @BASEBOARD_FAB2_LIB.BASEBOARD_FAB2(SCH_1):SMB_BMC_PMBUS_STBY_LVC3_SCL_R
   2 SMB_BMC_PMBUS_STBY_LVC3_SCL      B @BASEBOARD_FAB2_LIB.BASEBOARD_FAB2(SCH_1):SMB_BMC_PMBUS_STBY_LVC3_SCL

RES_0402-20.0,1%,1/16W,CHIP,G2A  I219  R2T49
   1 SMB_BMC_PMBUS_STBY_LVC3_SDA_R      A @BASEBOARD_FAB2_LIB.BASEBOARD_FAB2(SCH_1):SMB_BMC_PMBUS_STBY_LVC3_SDA_R
   2 SMB_BMC_PMBUS_STBY_LVC3_SDA      B @BASEBOARD_FAB2_LIB.BASEBOARD_FAB2(SCH_1):SMB_BMC_PMBUS_STBY_LVC3_SDA

RES_0402-20.0,1%,1/16W,CHIP,G2A  I220  R2U7
   1 SMB_OCP_FRU_STBY_LVC3_SCL_R      A @BASEBOARD_FAB2_LIB.BASEBOARD_FAB2(SCH_1):SMB_OCP_FRU_STBY_LVC3_SCL_R
   2 SMB_OCP_FRU_STBY_LVC3_SCL      B @BASEBOARD_FAB2_LIB.BASEBOARD_FAB2(SCH_1):SMB_OCP_FRU_STBY_LVC3_SCL

RES_0402-20.0,1%,1/16W,CHIP,G2A  I221  R2U10
   1 SMB_OCP_FRU_STBY_LVC3_SDA_R      A @BASEBOARD_FAB2_LIB.BASEBOARD_FAB2(SCH_1):SMB_OCP_FRU_STBY_LVC3_SDA_R
   2 SMB_OCP_FRU_STBY_LVC3_SDA      B @BASEBOARD_FAB2_LIB.BASEBOARD_FAB2(SCH_1):SMB_OCP_FRU_STBY_LVC3_SDA

RES_0402-0.0,5%,1/16W,CHIP,G21A  I222  R1U11
   1 SMB_VR_STBY_LVC3_SCL_R      A @BASEBOARD_FAB2_LIB.BASEBOARD_FAB2(SCH_1):SMB_VR_STBY_LVC3_SCL_R
   2 SMB_VR_STBY_LVC3_SCL      B @BASEBOARD_FAB2_LIB.BASEBOARD_FAB2(SCH_1):SMB_VR_STBY_LVC3_SCL

RES_0402-0.0,5%,1/16W,CHIP,G21A  I223  R1U8
   1 SMB_VR_STBY_LVC3_SDA_R      A @BASEBOARD_FAB2_LIB.BASEBOARD_FAB2(SCH_1):SMB_VR_STBY_LVC3_SDA_R
   2 SMB_VR_STBY_LVC3_SDA      B @BASEBOARD_FAB2_LIB.BASEBOARD_FAB2(SCH_1):SMB_VR_STBY_LVC3_SDA

RES_0402-20.0,1%,1/16W,CHIP,G2A  I224  R9G12
   1 SMB_OCP_LAN_STBY_LVC3_SDA      A @BASEBOARD_FAB2_LIB.BASEBOARD_FAB2(SCH_1):SMB_OCP_LAN_STBY_LVC3_SDA
   2 SMB_SPRINGVILLE_STBY_LVC3_SDA      B @BASEBOARD_FAB2_LIB.BASEBOARD_FAB2(SCH_1):SMB_SPRINGVILLE_STBY_LVC3_SDA

RES_0402-20.0,1%,1/16W,CHIP,G2A  I225  R1U20
   1 SMB_SMLINK0_STBY_LVC3_SDA      A @BASEBOARD_FAB2_LIB.BASEBOARD_FAB2(SCH_1):SMB_SMLINK0_STBY_LVC3_SDA
   2 SMB_SPRINGVILLE_STBY_LVC3_SDA      B @BASEBOARD_FAB2_LIB.BASEBOARD_FAB2(SCH_1):SMB_SPRINGVILLE_STBY_LVC3_SDA

RES_0402-20.0,1%,1/16W,CHIP,G2A  I226  R1U19
   1 SMB_SMLINK0_STBY_LVC3_SCL      A @BASEBOARD_FAB2_LIB.BASEBOARD_FAB2(SCH_1):SMB_SMLINK0_STBY_LVC3_SCL
   2 SMB_SPRINGVILLE_STBY_LVC3_SCL      B @BASEBOARD_FAB2_LIB.BASEBOARD_FAB2(SCH_1):SMB_SPRINGVILLE_STBY_LVC3_SCL

RES_0402-20.0,1%,1/16W,CHIP,G2A  I227  R9G13
   1 SMB_OCP_LAN_STBY_LVC3_SCL      A @BASEBOARD_FAB2_LIB.BASEBOARD_FAB2(SCH_1):SMB_OCP_LAN_STBY_LVC3_SCL
   2 SMB_SPRINGVILLE_STBY_LVC3_SCL      B @BASEBOARD_FAB2_LIB.BASEBOARD_FAB2(SCH_1):SMB_SPRINGVILLE_STBY_LVC3_SCL

RES_0402-20.0,1%,1/16W,CHIP,G2A  I228  R8G5
   1 SMB_OCP_LAN_STBY_LVC3_SDA_R      A @BASEBOARD_FAB2_LIB.BASEBOARD_FAB2(SCH_1):SMB_OCP_LAN_STBY_LVC3_SDA_R
   2 SMB_OCP_LAN_STBY_LVC3_SDA      B @BASEBOARD_FAB2_LIB.BASEBOARD_FAB2(SCH_1):SMB_OCP_LAN_STBY_LVC3_SDA

RES_0402-20.0,1%,1/16W,CHIP,G2A  I229  R8G4
   1 SMB_OCP_LAN_STBY_LVC3_SCL_R      A @BASEBOARD_FAB2_LIB.BASEBOARD_FAB2(SCH_1):SMB_OCP_LAN_STBY_LVC3_SCL_R
   2 SMB_OCP_LAN_STBY_LVC3_SCL      B @BASEBOARD_FAB2_LIB.BASEBOARD_FAB2(SCH_1):SMB_OCP_LAN_STBY_LVC3_SCL

RES_0402-20.0,1%,1/16W,CHIP,G2A  I230  R2U34
   1 SMB_HOST_STBY_LVC3_SCL_R      A @BASEBOARD_FAB2_LIB.BASEBOARD_FAB2(SCH_1):SMB_HOST_STBY_LVC3_SCL_R
   2 SMB_HOST_STBY_LVC3_SCL      B @BASEBOARD_FAB2_LIB.BASEBOARD_FAB2(SCH_1):SMB_HOST_STBY_LVC3_SCL

RES_0402-20.0,1%,1/16W,CHIP,G2A  I231  R2U33
   1 SMB_HOST_STBY_LVC3_SDA_R      A @BASEBOARD_FAB2_LIB.BASEBOARD_FAB2(SCH_1):SMB_HOST_STBY_LVC3_SDA_R
   2 SMB_HOST_STBY_LVC3_SDA      B @BASEBOARD_FAB2_LIB.BASEBOARD_FAB2(SCH_1):SMB_HOST_STBY_LVC3_SDA

RES_0402-20.0,1%,1/16W,CHIP,G2A  I232  R1U9
   1 SMB_SMLINK0_STBY_LVC3_SCL_R      A @BASEBOARD_FAB2_LIB.BASEBOARD_FAB2(SCH_1):SMB_SMLINK0_STBY_LVC3_SCL_R
   2 SMB_SMLINK0_STBY_LVC3_SCL      B @BASEBOARD_FAB2_LIB.BASEBOARD_FAB2(SCH_1):SMB_SMLINK0_STBY_LVC3_SCL

RES_0402-20.0,1%,1/16W,CHIP,G2A  I233  R1U10
   1 SMB_SMLINK0_STBY_LVC3_SDA_R      A @BASEBOARD_FAB2_LIB.BASEBOARD_FAB2(SCH_1):SMB_SMLINK0_STBY_LVC3_SDA_R
   2 SMB_SMLINK0_STBY_LVC3_SDA      B @BASEBOARD_FAB2_LIB.BASEBOARD_FAB2(SCH_1):SMB_SMLINK0_STBY_LVC3_SDA


DRAWING: @BASEBOARD_FAB2_LIB.BASEBOARD_FAB2(SCH_1):PAGE160 

RES_0402-20.0,1%,1/16W,CHIP,G2A  I4  R1T8
   1 SMB_SLOTX24_STBY_LVC3_SDA_R      A @BASEBOARD_FAB2_LIB.BASEBOARD_FAB2(SCH_1):SMB_SLOTX24_STBY_LVC3_SDA_R
   2 SMB_SLOTX24_BMC_STBY_LVC3_SDA      B @BASEBOARD_FAB2_LIB.BASEBOARD_FAB2(SCH_1):SMB_SLOTX24_BMC_STBY_LVC3_SDA

RES_0402-665,1.0%,1/16W,CHIP,GA  I46  R1T3
   1 P3V3_STBY      A @BASEBOARD_FAB2_LIB.BASEBOARD_FAB2(SCH_1):P3V3_STBY
   2 SMB_SLOTX24_STBY_LVC3_SDA_R      B @BASEBOARD_FAB2_LIB.BASEBOARD_FAB2(SCH_1):SMB_SLOTX24_STBY_LVC3_SDA_R

RES_0402-665,1.0%,1/16W,CHIP,GA  I49  R1T2
   1 P3V3_STBY      A @BASEBOARD_FAB2_LIB.BASEBOARD_FAB2(SCH_1):P3V3_STBY
   2 SMB_SLOTX24_STBY_LVC3_SCL_R      B @BASEBOARD_FAB2_LIB.BASEBOARD_FAB2(SCH_1):SMB_SLOTX24_STBY_LVC3_SCL_R

RES_0402-20.0,1%,1/16W,CHIP,G2A  I50  R1T7
   1 SMB_SLOTX24_STBY_LVC3_SCL_R      A @BASEBOARD_FAB2_LIB.BASEBOARD_FAB2(SCH_1):SMB_SLOTX24_STBY_LVC3_SCL_R
   2 SMB_SLOTX24_BMC_STBY_LVC3_SCL      B @BASEBOARD_FAB2_LIB.BASEBOARD_FAB2(SCH_1):SMB_SLOTX24_BMC_STBY_LVC3_SCL

RES_0402-20.0,1%,1/16W,CHIP,G2A  I51  R9F23
   1 SMB_LAN_STBY_LVC3_SDA_R      A @BASEBOARD_FAB2_LIB.BASEBOARD_FAB2(SCH_1):SMB_LAN_STBY_LVC3_SDA_R
   2 SMB_LAN_STBY_LVC3_SDA      B @BASEBOARD_FAB2_LIB.BASEBOARD_FAB2(SCH_1):SMB_LAN_STBY_LVC3_SDA

RES_0402-20.0,1%,1/16W,CHIP,G2A  I52  R9F22
   1 SMB_LAN_STBY_LVC3_SCL_R      A @BASEBOARD_FAB2_LIB.BASEBOARD_FAB2(SCH_1):SMB_LAN_STBY_LVC3_SCL_R
   2 SMB_LAN_STBY_LVC3_SCL      B @BASEBOARD_FAB2_LIB.BASEBOARD_FAB2(SCH_1):SMB_LAN_STBY_LVC3_SCL


DRAWING: @BASEBOARD_FAB2_LIB.BASEBOARD_FAB2(SCH_1):PAGE161 

CONN6_C74770005_PIP-HDR,C74770A  I1  J1F2
   1    GND    IO1 @BASEBOARD_FAB2_LIB.BASEBOARD_FAB2(SCH_1):GND
   2 P12V_FAN    IO2 @BASEBOARD_FAB2_LIB.BASEBOARD_FAB2(SCH_1):P12V_FAN
   3 FAN_TACH0_CPU0_D1    IO3 @BASEBOARD_FAB2_LIB.BASEBOARD_FAB2(SCH_1):FAN_TACH0_CPU0_D1
   4 FAN_PWM_OUT_SYS0_R    IO4 @BASEBOARD_FAB2_LIB.BASEBOARD_FAB2(SCH_1):FAN_PWM_OUT_SYS0_R
   5 FAN_TACH1_CPU1_D1    IO5 @BASEBOARD_FAB2_LIB.BASEBOARD_FAB2(SCH_1):FAN_TACH1_CPU1_D1
   6 TP_FAN_0    IO6 @BASEBOARD_FAB2_LIB.BASEBOARD_FAB2(SCH_1):TP_FAN_0

CAP_0805-10UF,16V,10%,X6S,C953A  I3  C1E21
   1 P12V_FAN      A @BASEBOARD_FAB2_LIB.BASEBOARD_FAB2(SCH_1):P12V_FAN
   2    GND      B @BASEBOARD_FAB2_LIB.BASEBOARD_FAB2(SCH_1):GND

CAP_A_0402V-0.1UF,16V,10%,X7R,A  I4  C1E20
   1 P12V_FAN      A @BASEBOARD_FAB2_LIB.BASEBOARD_FAB2(SCH_1):P12V_FAN
   2    GND      B @BASEBOARD_FAB2_LIB.BASEBOARD_FAB2(SCH_1):GND

CAP_A_0402V-0.1UF,16V,10%,X7R,A  I26  C9M5
   1 P12V_FAN      A @BASEBOARD_FAB2_LIB.BASEBOARD_FAB2(SCH_1):P12V_FAN
   2    GND      B @BASEBOARD_FAB2_LIB.BASEBOARD_FAB2(SCH_1):GND

CAP_0805-10UF,16V,10%,X6S,C953A  I27  C9M4
   1 P12V_FAN      A @BASEBOARD_FAB2_LIB.BASEBOARD_FAB2(SCH_1):P12V_FAN
   2    GND      B @BASEBOARD_FAB2_LIB.BASEBOARD_FAB2(SCH_1):GND

CONN6_C74770005_PIP-HDR,C74770A  I32  J1B2
   1    GND    IO1 @BASEBOARD_FAB2_LIB.BASEBOARD_FAB2(SCH_1):GND
   2 P12V_FAN    IO2 @BASEBOARD_FAB2_LIB.BASEBOARD_FAB2(SCH_1):P12V_FAN
   3 FAN_TACH2_CPU1_D1    IO3 @BASEBOARD_FAB2_LIB.BASEBOARD_FAB2(SCH_1):FAN_TACH2_CPU1_D1
   4 FAN_PWM_OUT_SYS1_R    IO4 @BASEBOARD_FAB2_LIB.BASEBOARD_FAB2(SCH_1):FAN_PWM_OUT_SYS1_R
   5 FAN_TACH3_CPU1_D1    IO5 @BASEBOARD_FAB2_LIB.BASEBOARD_FAB2(SCH_1):FAN_TACH3_CPU1_D1
   6 TP_FAN_1    IO6 @BASEBOARD_FAB2_LIB.BASEBOARD_FAB2(SCH_1):TP_FAN_1

DIODE_SM-SDMK0340L,IC,H71799-0A  I42  CR1F1
   1 FAN_TACH0_CPU0_D1      C @BASEBOARD_FAB2_LIB.BASEBOARD_FAB2(SCH_1):FAN_TACH0_CPU0_D1
   2 FAN_TACH0_CPU0_D2      A @BASEBOARD_FAB2_LIB.BASEBOARD_FAB2(SCH_1):FAN_TACH0_CPU0_D2

RES_0402-100.0,1%,1/16W,CHIP,GA  I43  R1F2
   1 FAN_TACH0      A @BASEBOARD_FAB2_LIB.BASEBOARD_FAB2(SCH_1):FAN_TACH0
   2 FAN_TACH0_CPU0_D2      B @BASEBOARD_FAB2_LIB.BASEBOARD_FAB2(SCH_1):FAN_TACH0_CPU0_D2

RES_0402-4.75K,1%,1/16W,CHIP,GA  I45  R1F1
   1 P3V3_STBY      A @BASEBOARD_FAB2_LIB.BASEBOARD_FAB2(SCH_1):P3V3_STBY
   2 FAN_TACH0      B @BASEBOARD_FAB2_LIB.BASEBOARD_FAB2(SCH_1):FAN_TACH0

CAP_A_0402V-0.01UF,25V,10%,X7RA  I46  C1F9
   1 FAN_TACH0      A @BASEBOARD_FAB2_LIB.BASEBOARD_FAB2(SCH_1):FAN_TACH0
   2    GND      B @BASEBOARD_FAB2_LIB.BASEBOARD_FAB2(SCH_1):GND

DIODE_SM-SDMK0340L,EMPTY,H7179A  I50  CR1E1
   1 P5V_STBY      C @BASEBOARD_FAB2_LIB.BASEBOARD_FAB2(SCH_1):P5V_STBY
   2 FAN_PWM_OUT_SYS0_R      A @BASEBOARD_FAB2_LIB.BASEBOARD_FAB2(SCH_1):FAN_PWM_OUT_SYS0_R

RES_0402-4.75K,1%,1/16W,CHIP,GA  I51  R1E12
   1 P5V_STBY      A @BASEBOARD_FAB2_LIB.BASEBOARD_FAB2(SCH_1):P5V_STBY
   2 FAN_PWM_OUT_SYS0_R      B @BASEBOARD_FAB2_LIB.BASEBOARD_FAB2(SCH_1):FAN_PWM_OUT_SYS0_R

DIODE_SM-SDMK0340L,IC,H71799-0A  I62  CR1B2
   1 FAN_TACH2_CPU1_D1      C @BASEBOARD_FAB2_LIB.BASEBOARD_FAB2(SCH_1):FAN_TACH2_CPU1_D1
   2 FAN_TACH2_CPU1_D2      A @BASEBOARD_FAB2_LIB.BASEBOARD_FAB2(SCH_1):FAN_TACH2_CPU1_D2

DIODE_SM-SDMK0340L,EMPTY,H7179A  I64  CR1B1
   1 P5V_STBY      C @BASEBOARD_FAB2_LIB.BASEBOARD_FAB2(SCH_1):P5V_STBY
   2 FAN_PWM_OUT_SYS1_R      A @BASEBOARD_FAB2_LIB.BASEBOARD_FAB2(SCH_1):FAN_PWM_OUT_SYS1_R

RES_0402-4.75K,1%,1/16W,CHIP,GA  I65  R7F33
   1 P5V_STBY      A @BASEBOARD_FAB2_LIB.BASEBOARD_FAB2(SCH_1):P5V_STBY
   2 FAN_PWM_OUT_SYS1_R      B @BASEBOARD_FAB2_LIB.BASEBOARD_FAB2(SCH_1):FAN_PWM_OUT_SYS1_R

RES_0402-100.0,1%,1/16W,CHIP,GA  I67  R1B22
   1 FAN_TACH2      A @BASEBOARD_FAB2_LIB.BASEBOARD_FAB2(SCH_1):FAN_TACH2
   2 FAN_TACH2_CPU1_D2      B @BASEBOARD_FAB2_LIB.BASEBOARD_FAB2(SCH_1):FAN_TACH2_CPU1_D2

CAP_A_0402V-0.01UF,25V,10%,X7RA  I68  C1B15
   1 FAN_TACH2      A @BASEBOARD_FAB2_LIB.BASEBOARD_FAB2(SCH_1):FAN_TACH2
   2    GND      B @BASEBOARD_FAB2_LIB.BASEBOARD_FAB2(SCH_1):GND

RES_0402-4.75K,1%,1/16W,CHIP,GA  I70  R1B21
   1 P3V3_STBY      A @BASEBOARD_FAB2_LIB.BASEBOARD_FAB2(SCH_1):P3V3_STBY
   2 FAN_TACH2      B @BASEBOARD_FAB2_LIB.BASEBOARD_FAB2(SCH_1):FAN_TACH2

TTL1G07_A_SOP-74LVC1G07,IC,C88B  I88  U8G2
   2 FAN_PWM_OUT_SYS0      A @BASEBOARD_FAB2_LIB.BASEBOARD_FAB2(SCH_1):FAN_PWM_OUT_SYS0
   4 FAN_PWM_OUT_SYS0_BUF      Y @BASEBOARD_FAB2_LIB.BASEBOARD_FAB2(SCH_1):FAN_PWM_OUT_SYS0_BUF

CAP_A_0402V-0.1UF,16V,10%,X7R,A  I90  C2U27
   1 P3V3_STBY      A @BASEBOARD_FAB2_LIB.BASEBOARD_FAB2(SCH_1):P3V3_STBY
   2    GND      B @BASEBOARD_FAB2_LIB.BASEBOARD_FAB2(SCH_1):GND

TTL1G07_A_SOP-74LVC1G07,IC,C88B  I92  U8G3
   2 FAN_PWM_OUT_SYS1      A @BASEBOARD_FAB2_LIB.BASEBOARD_FAB2(SCH_1):FAN_PWM_OUT_SYS1
   4 FAN_PWM_OUT_SYS1_BUF      Y @BASEBOARD_FAB2_LIB.BASEBOARD_FAB2(SCH_1):FAN_PWM_OUT_SYS1_BUF

CAP_A_0402V-0.1UF,16V,10%,X7R,A  I93  C2U28
   1 P3V3_STBY      A @BASEBOARD_FAB2_LIB.BASEBOARD_FAB2(SCH_1):P3V3_STBY
   2    GND      B @BASEBOARD_FAB2_LIB.BASEBOARD_FAB2(SCH_1):GND

RES_0402-221,1.0%,1/16W,CHIP,GA  I99  R2U42
   1 FAN_PWM_OUT_SYS0_BUF      A @BASEBOARD_FAB2_LIB.BASEBOARD_FAB2(SCH_1):FAN_PWM_OUT_SYS0_BUF
   2 FAN_PWM_OUT_SYS0_R      B @BASEBOARD_FAB2_LIB.BASEBOARD_FAB2(SCH_1):FAN_PWM_OUT_SYS0_R

RES_0402-221,1.0%,1/16W,CHIP,GA  I102  R2U44
   1 FAN_PWM_OUT_SYS1_BUF      A @BASEBOARD_FAB2_LIB.BASEBOARD_FAB2(SCH_1):FAN_PWM_OUT_SYS1_BUF
   2 FAN_PWM_OUT_SYS1_R      B @BASEBOARD_FAB2_LIB.BASEBOARD_FAB2(SCH_1):FAN_PWM_OUT_SYS1_R

CAP_A_0402V-0.1UF,16V,10%,X7R,A  I113  C1E22
   1 P3V3_STBY      A @BASEBOARD_FAB2_LIB.BASEBOARD_FAB2(SCH_1):P3V3_STBY
   2    GND      B @BASEBOARD_FAB2_LIB.BASEBOARD_FAB2(SCH_1):GND

RES_0402-10.0K,1%,1/16W,EMPTY,A  I120  R1E11
   1 P3V3_STBY      A @BASEBOARD_FAB2_LIB.BASEBOARD_FAB2(SCH_1):P3V3_STBY
   2 FM_ENABLE_FAN_POWER      B @BASEBOARD_FAB2_LIB.BASEBOARD_FAB2(SCH_1):FM_ENABLE_FAN_POWER

TTL1G08_SOTLF-NC7SZ08,IC,D1032B  I121  U1E2
   4 FM_ENABLE_FAN_POWER   Y<0> @BASEBOARD_FAB2_LIB.BASEBOARD_FAB2(SCH_1):FM_ENABLE_FAN_POWER
   1 FM_CTNR_PS_ON   A<0> @BASEBOARD_FAB2_LIB.BASEBOARD_FAB2(SCH_1):FM_CTNR_PS_ON
   2 FM_DISABLE_FAN_N   B<0> @BASEBOARD_FAB2_LIB.BASEBOARD_FAB2(SCH_1):FM_DISABLE_FAN_N

DIODE_SM-SDMK0340L,IC,H71799-0A  I123  CR1B3
   1 FAN_TACH3_CPU1_D1      C @BASEBOARD_FAB2_LIB.BASEBOARD_FAB2(SCH_1):FAN_TACH3_CPU1_D1
   2 FAN_TACH3_CPU1_D2      A @BASEBOARD_FAB2_LIB.BASEBOARD_FAB2(SCH_1):FAN_TACH3_CPU1_D2

RES_0402-100.0,1%,1/16W,CHIP,GA  I124  R1B23
   1 FAN_TACH3      A @BASEBOARD_FAB2_LIB.BASEBOARD_FAB2(SCH_1):FAN_TACH3
   2 FAN_TACH3_CPU1_D2      B @BASEBOARD_FAB2_LIB.BASEBOARD_FAB2(SCH_1):FAN_TACH3_CPU1_D2

RES_0402-4.75K,1%,1/16W,CHIP,GA  I126  R1B24
   1 P3V3_STBY      A @BASEBOARD_FAB2_LIB.BASEBOARD_FAB2(SCH_1):P3V3_STBY
   2 FAN_TACH3      B @BASEBOARD_FAB2_LIB.BASEBOARD_FAB2(SCH_1):FAN_TACH3

CAP_A_0402V-0.01UF,25V,10%,X7RA  I128  C1B17
   1 FAN_TACH3      A @BASEBOARD_FAB2_LIB.BASEBOARD_FAB2(SCH_1):FAN_TACH3
   2    GND      B @BASEBOARD_FAB2_LIB.BASEBOARD_FAB2(SCH_1):GND

DIODE_SM-SDMK0340L,IC,H71799-0A  I133  CR1F2
   1 FAN_TACH1_CPU1_D1      C @BASEBOARD_FAB2_LIB.BASEBOARD_FAB2(SCH_1):FAN_TACH1_CPU1_D1
   2 FAN_TACH1_CPU1_D2      A @BASEBOARD_FAB2_LIB.BASEBOARD_FAB2(SCH_1):FAN_TACH1_CPU1_D2

RES_0402-100.0,1%,1/16W,CHIP,GA  I134  R9T7
   1 FAN_TACH1      A @BASEBOARD_FAB2_LIB.BASEBOARD_FAB2(SCH_1):FAN_TACH1
   2 FAN_TACH1_CPU1_D2      B @BASEBOARD_FAB2_LIB.BASEBOARD_FAB2(SCH_1):FAN_TACH1_CPU1_D2

RES_0402-4.75K,1%,1/16W,CHIP,GA  I135  R9T5
   1 P3V3_STBY      A @BASEBOARD_FAB2_LIB.BASEBOARD_FAB2(SCH_1):P3V3_STBY
   2 FAN_TACH1      B @BASEBOARD_FAB2_LIB.BASEBOARD_FAB2(SCH_1):FAN_TACH1

CAP_A_0402V-0.01UF,25V,10%,X7RA  I137  C9T1
   1 FAN_TACH1      A @BASEBOARD_FAB2_LIB.BASEBOARD_FAB2(SCH_1):FAN_TACH1
   2    GND      B @BASEBOARD_FAB2_LIB.BASEBOARD_FAB2(SCH_1):GND


DRAWING: @BASEBOARD_FAB2_LIB.BASEBOARD_FAB2(SCH_1):PAGE162 

RES_0402-4.75K,1%,1/16W,EMPTY,A  I8  R8F16
   1 P3V3_STBY      A @BASEBOARD_FAB2_LIB.BASEBOARD_FAB2(SCH_1):P3V3_STBY
   2 PU_SPI_FLASH_RESET_2_N      B @BASEBOARD_FAB2_LIB.BASEBOARD_FAB2(SCH_1):PU_SPI_FLASH_RESET_2_N

RES_0402-4.75K,1%,1/16W,CHIP,GA  I9  R8F14
   1 P3V3_STBY      A @BASEBOARD_FAB2_LIB.BASEBOARD_FAB2(SCH_1):P3V3_STBY
   2 PU_SPI_BMC_BT_HOLD_N      B @BASEBOARD_FAB2_LIB.BASEBOARD_FAB2(SCH_1):PU_SPI_BMC_BT_HOLD_N

RES_0402-33.2,1%,1/16W,CHIP,G2A  I13  R8F12
   1 SPI_BMC_BT_DI      A @BASEBOARD_FAB2_LIB.BASEBOARD_FAB2(SCH_1):SPI_BMC_BT_DI
   2 SPI_BMC_BT_DI_R      B @BASEBOARD_FAB2_LIB.BASEBOARD_FAB2(SCH_1):SPI_BMC_BT_DI_R

RES_0402-4.75K,1%,1/16W,CHIP,GA  I22  R8F34
   1 P3V3_STBY      A @BASEBOARD_FAB2_LIB.BASEBOARD_FAB2(SCH_1):P3V3_STBY
   2 PU_SPI_BMC_BT_WP_N      B @BASEBOARD_FAB2_LIB.BASEBOARD_FAB2(SCH_1):PU_SPI_BMC_BT_WP_N

RES_0402-4.75K,1%,1/16W,CHIP,GA  I23  R8F13
   1 P3V3_STBY      A @BASEBOARD_FAB2_LIB.BASEBOARD_FAB2(SCH_1):P3V3_STBY
   2 SPI_BMC_BT_CS_N      B @BASEBOARD_FAB2_LIB.BASEBOARD_FAB2(SCH_1):SPI_BMC_BT_CS_N

RES_0402-1.00K,1%,1/16W,EMPTY,A  I24  R8F35
   1 PU_SPI_BMC_BT_WP_N      A @BASEBOARD_FAB2_LIB.BASEBOARD_FAB2(SCH_1):PU_SPI_BMC_BT_WP_N
   2    GND      B @BASEBOARD_FAB2_LIB.BASEBOARD_FAB2(SCH_1):GND

CAP_A_0402V-0.01UF,25V,10%,X7RA  I28  C8F5
   1 P3V3_STBY      A @BASEBOARD_FAB2_LIB.BASEBOARD_FAB2(SCH_1):P3V3_STBY
   2    GND      B @BASEBOARD_FAB2_LIB.BASEBOARD_FAB2(SCH_1):GND

CAP_A_0402V-1.0UF,6.3V,10%,X6SA  I30  C8F4
   1 P3V3_STBY      A @BASEBOARD_FAB2_LIB.BASEBOARD_FAB2(SCH_1):P3V3_STBY
   2    GND      B @BASEBOARD_FAB2_LIB.BASEBOARD_FAB2(SCH_1):GND

W25Q128_SKT16-IC,H12709-001  I32  U8F2
   1 PU_SPI_BMC_BT_HOLD_N HOLD_N_IO<3> @BASEBOARD_FAB2_LIB.BASEBOARD_FAB2(SCH_1):PU_SPI_BMC_BT_HOLD_N
   2 P3V3_STBY    VCC @BASEBOARD_FAB2_LIB.BASEBOARD_FAB2(SCH_1):P3V3_STBY
   3 PU_SPI_FLASH_RESET_2_N RESET_N @BASEBOARD_FAB2_LIB.BASEBOARD_FAB2(SCH_1):PU_SPI_FLASH_RESET_2_N
   4 TP_SPI_2_0  NC<0> @BASEBOARD_FAB2_LIB.BASEBOARD_FAB2(SCH_1):TP_SPI_2_0
   5 TP_SPI_2_1  NC<1> @BASEBOARD_FAB2_LIB.BASEBOARD_FAB2(SCH_1):TP_SPI_2_1
   6 TP_SPI_2_2  NC<2> @BASEBOARD_FAB2_LIB.BASEBOARD_FAB2(SCH_1):TP_SPI_2_2
   7 SPI_BMC_BT_CS_N   CS_N @BASEBOARD_FAB2_LIB.BASEBOARD_FAB2(SCH_1):SPI_BMC_BT_CS_N
   8 SPI_BMC_BT_DI_R DO_IO<1> @BASEBOARD_FAB2_LIB.BASEBOARD_FAB2(SCH_1):SPI_BMC_BT_DI_R
   9 PU_SPI_BMC_BT_WP_N WP_N_IO<2> @BASEBOARD_FAB2_LIB.BASEBOARD_FAB2(SCH_1):PU_SPI_BMC_BT_WP_N
  10    GND    GND @BASEBOARD_FAB2_LIB.BASEBOARD_FAB2(SCH_1):GND
  11 TP_SPI_2_3  NC<3> @BASEBOARD_FAB2_LIB.BASEBOARD_FAB2(SCH_1):TP_SPI_2_3
  12 TP_SPI_2_4  NC<4> @BASEBOARD_FAB2_LIB.BASEBOARD_FAB2(SCH_1):TP_SPI_2_4
  13 TP_SPI_2_5  NC<5> @BASEBOARD_FAB2_LIB.BASEBOARD_FAB2(SCH_1):TP_SPI_2_5
  14 TP_SPI_2_6  NC<6> @BASEBOARD_FAB2_LIB.BASEBOARD_FAB2(SCH_1):TP_SPI_2_6
  15 SPI_BMC_BT_DO DI_IO<0> @BASEBOARD_FAB2_LIB.BASEBOARD_FAB2(SCH_1):SPI_BMC_BT_DO
  16 SPI_BMC_BT_CLK    CLK @BASEBOARD_FAB2_LIB.BASEBOARD_FAB2(SCH_1):SPI_BMC_BT_CLK


DRAWING: @BASEBOARD_FAB2_LIB.BASEBOARD_FAB2(SCH_1):PAGE163 

PCA9517_SM-IC,G77073-001-GND=GA  I1  U1B2
   5 TP_SMB_PEHPCPU1_EN     EN @BASEBOARD_FAB2_LIB.BASEBOARD_FAB2(SCH_1):TP_SMB_PEHPCPU1_EN
   2 SMB_CPU1_PE_HP_GTL_R_SCL   SCLA @BASEBOARD_FAB2_LIB.BASEBOARD_FAB2(SCH_1):SMB_CPU1_PE_HP_GTL_R_SCL
   7 SMB_PEHPCPU1_STBY_LVC3_R_SCL   SCLB @BASEBOARD_FAB2_LIB.BASEBOARD_FAB2(SCH_1):SMB_PEHPCPU1_STBY_LVC3_R_SCL
   3 SMB_CPU1_PE_HP_GTL_R_SDA   SDAA @BASEBOARD_FAB2_LIB.BASEBOARD_FAB2(SCH_1):SMB_CPU1_PE_HP_GTL_R_SDA
   6 SMB_PEHPCPU1_STBY_LVC3_R_SDA   SDAB @BASEBOARD_FAB2_LIB.BASEBOARD_FAB2(SCH_1):SMB_PEHPCPU1_STBY_LVC3_R_SDA
   1 PVCCIO_CPU1   VCCA @BASEBOARD_FAB2_LIB.BASEBOARD_FAB2(SCH_1):PVCCIO_CPU1
   8 P3V3_STBY   VCCB @BASEBOARD_FAB2_LIB.BASEBOARD_FAB2(SCH_1):P3V3_STBY

RES_0402-10.0,1%,1/16W,CHIP,G2A  I2  R6N8
   1 SMB_CPU1_PE_HP_GTL_SCL      A @BASEBOARD_FAB2_LIB.BASEBOARD_FAB2(SCH_1):SMB_CPU1_PE_HP_GTL_SCL
   2 SMB_CPU1_PE_HP_GTL_R_SCL      B @BASEBOARD_FAB2_LIB.BASEBOARD_FAB2(SCH_1):SMB_CPU1_PE_HP_GTL_R_SCL

RES_0402-10.0,1%,1/16W,CHIP,G2A  I3  R6N9
   1 SMB_CPU1_PE_HP_GTL_SDA      A @BASEBOARD_FAB2_LIB.BASEBOARD_FAB2(SCH_1):SMB_CPU1_PE_HP_GTL_SDA
   2 SMB_CPU1_PE_HP_GTL_R_SDA      B @BASEBOARD_FAB2_LIB.BASEBOARD_FAB2(SCH_1):SMB_CPU1_PE_HP_GTL_R_SDA

RES_0402-240,1.0%,1/16W,CHIP,GA  I6  R9M18
   1 PVCCIO_CPU1      A @BASEBOARD_FAB2_LIB.BASEBOARD_FAB2(SCH_1):PVCCIO_CPU1
   2 SMB_CPU1_PE_HP_GTL_R_SDA      B @BASEBOARD_FAB2_LIB.BASEBOARD_FAB2(SCH_1):SMB_CPU1_PE_HP_GTL_R_SDA

RES_0402-240,1.0%,1/16W,CHIP,GA  I7  R9M19
   1 PVCCIO_CPU1      A @BASEBOARD_FAB2_LIB.BASEBOARD_FAB2(SCH_1):PVCCIO_CPU1
   2 SMB_CPU1_PE_HP_GTL_R_SCL      B @BASEBOARD_FAB2_LIB.BASEBOARD_FAB2(SCH_1):SMB_CPU1_PE_HP_GTL_R_SCL

CAP_A_0402V-0.1UF,16V,10%,X7R,A  I10  C9M8
   1 PVCCIO_CPU1      A @BASEBOARD_FAB2_LIB.BASEBOARD_FAB2(SCH_1):PVCCIO_CPU1
   2    GND      B @BASEBOARD_FAB2_LIB.BASEBOARD_FAB2(SCH_1):GND

CAP_A_0402V-0.1UF,16V,10%,X7R,A  I12  C9M7
   1 P3V3_STBY      A @BASEBOARD_FAB2_LIB.BASEBOARD_FAB2(SCH_1):P3V3_STBY
   2    GND      B @BASEBOARD_FAB2_LIB.BASEBOARD_FAB2(SCH_1):GND

RES_0402-2.0K,1%,1/16W,CHIP,G2A  I15  R9M17
   1 P3V3_STBY      A @BASEBOARD_FAB2_LIB.BASEBOARD_FAB2(SCH_1):P3V3_STBY
   2 SMB_PEHPCPU1_STBY_LVC3_R_SCL      B @BASEBOARD_FAB2_LIB.BASEBOARD_FAB2(SCH_1):SMB_PEHPCPU1_STBY_LVC3_R_SCL

RES_0402-2.0K,1%,1/16W,CHIP,G2A  I16  R9M16
   1 P3V3_STBY      A @BASEBOARD_FAB2_LIB.BASEBOARD_FAB2(SCH_1):P3V3_STBY
   2 SMB_PEHPCPU1_STBY_LVC3_R_SDA      B @BASEBOARD_FAB2_LIB.BASEBOARD_FAB2(SCH_1):SMB_PEHPCPU1_STBY_LVC3_R_SDA

RES_0402-20.0,1%,1/16W,CHIP,G2A  I20  R9M14
   1 SMB_PEHPCPU1_STBY_LVC3_R_SCL      A @BASEBOARD_FAB2_LIB.BASEBOARD_FAB2(SCH_1):SMB_PEHPCPU1_STBY_LVC3_R_SCL
   2 SMB_PEHPCPU1_STBY_LVC3_SCL      B @BASEBOARD_FAB2_LIB.BASEBOARD_FAB2(SCH_1):SMB_PEHPCPU1_STBY_LVC3_SCL

RES_0402-20.0,1%,1/16W,CHIP,G2A  I21  R9M13
   1 SMB_PEHPCPU1_STBY_LVC3_R_SDA      A @BASEBOARD_FAB2_LIB.BASEBOARD_FAB2(SCH_1):SMB_PEHPCPU1_STBY_LVC3_R_SDA
   2 SMB_PEHPCPU1_STBY_LVC3_SDA      B @BASEBOARD_FAB2_LIB.BASEBOARD_FAB2(SCH_1):SMB_PEHPCPU1_STBY_LVC3_SDA

RES_0402-20.0,1%,1/16W,CHIP,G2A  I24  R9M12
   1 SMB_PEHPCPU1_STBY_LVC3_R_SDA      A @BASEBOARD_FAB2_LIB.BASEBOARD_FAB2(SCH_1):SMB_PEHPCPU1_STBY_LVC3_R_SDA
   2 SMB_SLOTX24_BMC_STBY_LVC3_SDA      B @BASEBOARD_FAB2_LIB.BASEBOARD_FAB2(SCH_1):SMB_SLOTX24_BMC_STBY_LVC3_SDA

RES_0402-20.0,1%,1/16W,CHIP,G2A  I25  R9M15
   1 SMB_PEHPCPU1_STBY_LVC3_R_SCL      A @BASEBOARD_FAB2_LIB.BASEBOARD_FAB2(SCH_1):SMB_PEHPCPU1_STBY_LVC3_R_SCL
   2 SMB_SLOTX24_BMC_STBY_LVC3_SCL      B @BASEBOARD_FAB2_LIB.BASEBOARD_FAB2(SCH_1):SMB_SLOTX24_BMC_STBY_LVC3_SCL


DRAWING: @BASEBOARD_FAB2_LIB.BASEBOARD_FAB2(SCH_1):PAGE164 

RES_0402-1.00K,1%,1/16W,EMPTY,A  I5  R1T10
   1 FM_BOARD_REV_ID0      A @BASEBOARD_FAB2_LIB.BASEBOARD_FAB2(SCH_1):FM_BOARD_REV_ID0
   2    GND      B @BASEBOARD_FAB2_LIB.BASEBOARD_FAB2(SCH_1):GND

RES_0402-1.00K,1%,1/16W,CHIP,GA  I6  R1T12
   1 FM_BOARD_REV_ID1      A @BASEBOARD_FAB2_LIB.BASEBOARD_FAB2(SCH_1):FM_BOARD_REV_ID1
   2    GND      B @BASEBOARD_FAB2_LIB.BASEBOARD_FAB2(SCH_1):GND

RES_0402-1.00K,1%,1/16W,CHIP,GA  I7  R1T11
   1 FM_BOARD_REV_ID2      A @BASEBOARD_FAB2_LIB.BASEBOARD_FAB2(SCH_1):FM_BOARD_REV_ID2
   2    GND      B @BASEBOARD_FAB2_LIB.BASEBOARD_FAB2(SCH_1):GND

RES_0402-2.7K,1%,1/16W,EMPTY,GA  I11  R1T5
   1 P3V3_STBY      A @BASEBOARD_FAB2_LIB.BASEBOARD_FAB2(SCH_1):P3V3_STBY
   2 FM_BOARD_REV_ID2      B @BASEBOARD_FAB2_LIB.BASEBOARD_FAB2(SCH_1):FM_BOARD_REV_ID2

RES_0402-2.7K,1%,1/16W,EMPTY,GA  I13  R1T6
   1 P3V3_STBY      A @BASEBOARD_FAB2_LIB.BASEBOARD_FAB2(SCH_1):P3V3_STBY
   2 FM_BOARD_REV_ID1      B @BASEBOARD_FAB2_LIB.BASEBOARD_FAB2(SCH_1):FM_BOARD_REV_ID1

RES_0402-2.7K,1%,1/16W,CHIP,G2A  I14  R1T4
   1 P3V3_STBY      A @BASEBOARD_FAB2_LIB.BASEBOARD_FAB2(SCH_1):P3V3_STBY
   2 FM_BOARD_REV_ID0      B @BASEBOARD_FAB2_LIB.BASEBOARD_FAB2(SCH_1):FM_BOARD_REV_ID0

RES_0402-1.00K,1%,1/16W,CHIP,GA  I19  R1U18
   1 FM_BOARD_SKU_ID0      A @BASEBOARD_FAB2_LIB.BASEBOARD_FAB2(SCH_1):FM_BOARD_SKU_ID0
   2    GND      B @BASEBOARD_FAB2_LIB.BASEBOARD_FAB2(SCH_1):GND

RES_0402-1.00K,1%,1/16W,EMPTY,A  I20  R1U16
   1 FM_BOARD_SKU_ID1      A @BASEBOARD_FAB2_LIB.BASEBOARD_FAB2(SCH_1):FM_BOARD_SKU_ID1
   2    GND      B @BASEBOARD_FAB2_LIB.BASEBOARD_FAB2(SCH_1):GND

RES_0402-1.00K,1%,1/16W,CHIP,GA  I21  R1U17
   1 FM_BOARD_SKU_ID2      A @BASEBOARD_FAB2_LIB.BASEBOARD_FAB2(SCH_1):FM_BOARD_SKU_ID2
   2    GND      B @BASEBOARD_FAB2_LIB.BASEBOARD_FAB2(SCH_1):GND

RES_0402-1.00K,1%,1/16W,EMPTY,A  I22  R1U15
   1 FM_BOARD_SKU_ID3      A @BASEBOARD_FAB2_LIB.BASEBOARD_FAB2(SCH_1):FM_BOARD_SKU_ID3
   2    GND      B @BASEBOARD_FAB2_LIB.BASEBOARD_FAB2(SCH_1):GND

RES_0402-2.7K,1%,1/16W,CHIP,G2A  I24  R1U21
   1 P3V3_STBY      A @BASEBOARD_FAB2_LIB.BASEBOARD_FAB2(SCH_1):P3V3_STBY
   2 FM_BOARD_SKU_ID3      B @BASEBOARD_FAB2_LIB.BASEBOARD_FAB2(SCH_1):FM_BOARD_SKU_ID3

RES_0402-2.7K,1%,1/16W,EMPTY,GA  I25  R1U24
   1 P3V3_STBY      A @BASEBOARD_FAB2_LIB.BASEBOARD_FAB2(SCH_1):P3V3_STBY
   2 FM_BOARD_SKU_ID2      B @BASEBOARD_FAB2_LIB.BASEBOARD_FAB2(SCH_1):FM_BOARD_SKU_ID2

RES_0402-2.7K,1%,1/16W,CHIP,G2A  I27  R1U22
   1 P3V3_STBY      A @BASEBOARD_FAB2_LIB.BASEBOARD_FAB2(SCH_1):P3V3_STBY
   2 FM_BOARD_SKU_ID1      B @BASEBOARD_FAB2_LIB.BASEBOARD_FAB2(SCH_1):FM_BOARD_SKU_ID1

RES_0402-2.7K,1%,1/16W,EMPTY,GA  I28  R1U23
   1 P3V3_STBY      A @BASEBOARD_FAB2_LIB.BASEBOARD_FAB2(SCH_1):P3V3_STBY
   2 FM_BOARD_SKU_ID0      B @BASEBOARD_FAB2_LIB.BASEBOARD_FAB2(SCH_1):FM_BOARD_SKU_ID0

RES_0402-2.7K,1%,1/16W,EMPTY,GA  I29  R2N17
   1 P3V3_STBY      A @BASEBOARD_FAB2_LIB.BASEBOARD_FAB2(SCH_1):P3V3_STBY
   2 FM_BOARD_SKU_ID4      B @BASEBOARD_FAB2_LIB.BASEBOARD_FAB2(SCH_1):FM_BOARD_SKU_ID4

RES_0402-1.00K,1%,1/16W,CHIP,GA  I32  R2N18
   1 FM_BOARD_SKU_ID4      A @BASEBOARD_FAB2_LIB.BASEBOARD_FAB2(SCH_1):FM_BOARD_SKU_ID4
   2    GND      B @BASEBOARD_FAB2_LIB.BASEBOARD_FAB2(SCH_1):GND


DRAWING: @BASEBOARD_FAB2_LIB.BASEBOARD_FAB2(SCH_1):PAGE165 

ADC128D818_SM-IC,H63642-001  I52  EU9G1
   7 FM_ADC128_A0     A0 @BASEBOARD_FAB2_LIB.BASEBOARD_FAB2(SCH_1):FM_ADC128_A0
   8 FM_ADC128_A1     A1 @BASEBOARD_FAB2_LIB.BASEBOARD_FAB2(SCH_1):FM_ADC128_A1
   4    GND    GND @BASEBOARD_FAB2_LIB.BASEBOARD_FAB2(SCH_1):GND
  16 A_P3V3_SCALED    IN0 @BASEBOARD_FAB2_LIB.BASEBOARD_FAB2(SCH_1):A_P3V3_SCALED
  15 A_P5V_SCALED    IN1 @BASEBOARD_FAB2_LIB.BASEBOARD_FAB2(SCH_1):A_P5V_SCALED
  14 A_P12V_STBY_SCALED    IN2 @BASEBOARD_FAB2_LIB.BASEBOARD_FAB2(SCH_1):A_P12V_STBY_SCALED
  13 A_P1V05_STBY_PCH_SENSOR    IN3 @BASEBOARD_FAB2_LIB.BASEBOARD_FAB2(SCH_1):A_P1V05_STBY_PCH_SENSOR
  12 A_PVNN_STBY_PCH_SENSOR    IN4 @BASEBOARD_FAB2_LIB.BASEBOARD_FAB2(SCH_1):A_PVNN_STBY_PCH_SENSOR
  11 A_P3V3_STBY_SCALED    IN5 @BASEBOARD_FAB2_LIB.BASEBOARD_FAB2(SCH_1):A_P3V3_STBY_SCALED
  10 A_P5V_STBY_SCALED    IN6 @BASEBOARD_FAB2_LIB.BASEBOARD_FAB2(SCH_1):A_P5V_STBY_SCALED
   9 A_P3V_BAT_SCALED    IN7 @BASEBOARD_FAB2_LIB.BASEBOARD_FAB2(SCH_1):A_P3V_BAT_SCALED
   6 IRQ_VM_INT_R_N  INT_N @BASEBOARD_FAB2_LIB.BASEBOARD_FAB2(SCH_1):IRQ_VM_INT_R_N
   3 SMB_SENSOR_PCH_STBY_LVC3_SCL    SCL @BASEBOARD_FAB2_LIB.BASEBOARD_FAB2(SCH_1):SMB_SENSOR_PCH_STBY_LVC3_SCL
   2 SMB_SENSOR_PCH_STBY_LVC3_SDA    SDA @BASEBOARD_FAB2_LIB.BASEBOARD_FAB2(SCH_1):SMB_SENSOR_PCH_STBY_LVC3_SDA
   5 P3V3_FB_ADC128_VCC     VP @BASEBOARD_FAB2_LIB.BASEBOARD_FAB2(SCH_1):P3V3_FB_ADC128_VCC
   1 TP_ADC128_VREF   VREF @BASEBOARD_FAB2_LIB.BASEBOARD_FAB2(SCH_1):TP_ADC128_VREF

RES_0402-4.75K,1%,1/16W,CHIP,GA  I55  R1U45
   1 FM_ADC128_A0      A @BASEBOARD_FAB2_LIB.BASEBOARD_FAB2(SCH_1):FM_ADC128_A0
   2    GND      B @BASEBOARD_FAB2_LIB.BASEBOARD_FAB2(SCH_1):GND

RES_0402-4.75K,1%,1/16W,CHIP,GA  I56  R1U48
   1 FM_ADC128_A1      A @BASEBOARD_FAB2_LIB.BASEBOARD_FAB2(SCH_1):FM_ADC128_A1
   2    GND      B @BASEBOARD_FAB2_LIB.BASEBOARD_FAB2(SCH_1):GND

RES_0402-4.75K,1%,1/16W,EMPTY,A  I57  R9G23
   1 P3V3_STBY      A @BASEBOARD_FAB2_LIB.BASEBOARD_FAB2(SCH_1):P3V3_STBY
   2 FM_ADC128_A0      B @BASEBOARD_FAB2_LIB.BASEBOARD_FAB2(SCH_1):FM_ADC128_A0

RES_0402-4.75K,1%,1/16W,EMPTY,A  I58  R9G25
   1 P3V3_STBY      A @BASEBOARD_FAB2_LIB.BASEBOARD_FAB2(SCH_1):P3V3_STBY
   2 FM_ADC128_A1      B @BASEBOARD_FAB2_LIB.BASEBOARD_FAB2(SCH_1):FM_ADC128_A1

CAP_A_0402V-0.1UF,16V,10%,X7R,A  I61  C9G19
   1 P3V3_FB_ADC128_VCC      A @BASEBOARD_FAB2_LIB.BASEBOARD_FAB2(SCH_1):P3V3_FB_ADC128_VCC
   2    GND      B @BASEBOARD_FAB2_LIB.BASEBOARD_FAB2(SCH_1):GND

CAP_0805-10UF,16V,10%,X7R,G106A  I67  C1U20
   1 P3V3_FB_ADC128_VCC      A @BASEBOARD_FAB2_LIB.BASEBOARD_FAB2(SCH_1):P3V3_FB_ADC128_VCC
   2    GND      B @BASEBOARD_FAB2_LIB.BASEBOARD_FAB2(SCH_1):GND

RES_0402-4.75K,1%,1/16W,CHIP,GA  I69  R9G21
   1 P3V3_STBY      A @BASEBOARD_FAB2_LIB.BASEBOARD_FAB2(SCH_1):P3V3_STBY
   2 IRQ_VM_INT_R_N      B @BASEBOARD_FAB2_LIB.BASEBOARD_FAB2(SCH_1):IRQ_VM_INT_R_N

FERRITE_SMLF-60,FB,693286-001  I79  FB1U2
   1 P3V3_STBY      A @BASEBOARD_FAB2_LIB.BASEBOARD_FAB2(SCH_1):P3V3_STBY
   2 P3V3_FB_ADC128_VCC      B @BASEBOARD_FAB2_LIB.BASEBOARD_FAB2(SCH_1):P3V3_FB_ADC128_VCC

RES_0402-33.2,1%,1/16W,CHIP,G2A  I81  R1U40
   1 IRQ_VM_INT_R_N      A @BASEBOARD_FAB2_LIB.BASEBOARD_FAB2(SCH_1):IRQ_VM_INT_R_N
   2 IRQ_VM_INT_N      B @BASEBOARD_FAB2_LIB.BASEBOARD_FAB2(SCH_1):IRQ_VM_INT_N


DRAWING: @BASEBOARD_FAB2_LIB.BASEBOARD_FAB2(SCH_1):PAGE166 

RES_0402-0.0,5%,1/16W,EMPTY,G2A  I11  R7C18
   1 PECI_BMC      A @BASEBOARD_FAB2_LIB.BASEBOARD_FAB2(SCH_1):PECI_BMC
   2 PECI_CPU_G      B @BASEBOARD_FAB2_LIB.BASEBOARD_FAB2(SCH_1):PECI_CPU_G

RES_0402-4.75K,1%,1/16W,EMPTY,A  I14  R7C22
   1 PVCCIO_CPU0      A @BASEBOARD_FAB2_LIB.BASEBOARD_FAB2(SCH_1):PVCCIO_CPU0
   2 PECI_PCH      B @BASEBOARD_FAB2_LIB.BASEBOARD_FAB2(SCH_1):PECI_PCH

RES_0402-0.0,5%,1/16W,CHIP,G21A  I15  R7C19
   1 PECI_PCH      A @BASEBOARD_FAB2_LIB.BASEBOARD_FAB2(SCH_1):PECI_PCH
   2 PECI_CPU_G      B @BASEBOARD_FAB2_LIB.BASEBOARD_FAB2(SCH_1):PECI_CPU_G

RES_0402-4.75K,1%,1/16W,CHIP,GA  I28  R7C17
   1 PVCCIO_CPU0      A @BASEBOARD_FAB2_LIB.BASEBOARD_FAB2(SCH_1):PVCCIO_CPU0
   2 PECI_BMC      B @BASEBOARD_FAB2_LIB.BASEBOARD_FAB2(SCH_1):PECI_BMC

RES_0402-348,1%,1/16W,CHIP,G21A  I32  R7D15
   1 PECI_CPU_G      A @BASEBOARD_FAB2_LIB.BASEBOARD_FAB2(SCH_1):PECI_CPU_G
   2    GND      B @BASEBOARD_FAB2_LIB.BASEBOARD_FAB2(SCH_1):GND


DRAWING: @BASEBOARD_FAB2_LIB.BASEBOARD_FAB2(SCH_1):PAGE167 

TMP421_TSSOP-IC,G62962-001  I1  U9B4
   3 PU_TMP421_1_A1   A<1> @BASEBOARD_FAB2_LIB.BASEBOARD_FAB2(SCH_1):PU_TMP421_1_A1
   4 PD_TMP421_1_A0   A<0> @BASEBOARD_FAB2_LIB.BASEBOARD_FAB2(SCH_1):PD_TMP421_1_A0
   2 ISENSE_TMP421_1_DXN    DXN @BASEBOARD_FAB2_LIB.BASEBOARD_FAB2(SCH_1):ISENSE_TMP421_1_DXN
   1 ISENSE_TMP421_1_DXP    DXP @BASEBOARD_FAB2_LIB.BASEBOARD_FAB2(SCH_1):ISENSE_TMP421_1_DXP
   5    GND    GND @BASEBOARD_FAB2_LIB.BASEBOARD_FAB2(SCH_1):GND
   7 SMB_SENSOR_TMP421_1_SCL    SCL @BASEBOARD_FAB2_LIB.BASEBOARD_FAB2(SCH_1):SMB_SENSOR_TMP421_1_SCL
   6 SMB_SENSOR_TMP421_1_SDA    SDA @BASEBOARD_FAB2_LIB.BASEBOARD_FAB2(SCH_1):SMB_SENSOR_TMP421_1_SDA
   8 P3V3_STBY     VP @BASEBOARD_FAB2_LIB.BASEBOARD_FAB2(SCH_1):P3V3_STBY

PNP_TO92-MPS2907,IC,G73554-001  I3  Q9B1
   1 ISENSE_TMP421_1_BC      B @BASEBOARD_FAB2_LIB.BASEBOARD_FAB2(SCH_1):ISENSE_TMP421_1_BC
   3 ISENSE_TMP421_1_BC      C @BASEBOARD_FAB2_LIB.BASEBOARD_FAB2(SCH_1):ISENSE_TMP421_1_BC
   2 ISENSE_TMP421_1_E      E @BASEBOARD_FAB2_LIB.BASEBOARD_FAB2(SCH_1):ISENSE_TMP421_1_E

RES_0402-49.9,1%,1/16W,CHIP,G2A  I5  R9B5
   1 ISENSE_TMP421_1_BC      A @BASEBOARD_FAB2_LIB.BASEBOARD_FAB2(SCH_1):ISENSE_TMP421_1_BC
   2 ISENSE_TMP421_1_DXN      B @BASEBOARD_FAB2_LIB.BASEBOARD_FAB2(SCH_1):ISENSE_TMP421_1_DXN

RES_0402-49.9,1%,1/16W,CHIP,G2A  I6  R9B4
   1 ISENSE_TMP421_1_E      A @BASEBOARD_FAB2_LIB.BASEBOARD_FAB2(SCH_1):ISENSE_TMP421_1_E
   2 ISENSE_TMP421_1_DXP      B @BASEBOARD_FAB2_LIB.BASEBOARD_FAB2(SCH_1):ISENSE_TMP421_1_DXP

CAP_0402LF-47.0PF,50V,5%,EMPTYA  I7  C1M4
   1 ISENSE_TMP421_1_DXP      A @BASEBOARD_FAB2_LIB.BASEBOARD_FAB2(SCH_1):ISENSE_TMP421_1_DXP
   2 ISENSE_TMP421_1_DXN      B @BASEBOARD_FAB2_LIB.BASEBOARD_FAB2(SCH_1):ISENSE_TMP421_1_DXN

RES_0402-20.0,1%,1/16W,CHIP,G2A  I8  R1M9
   1 SMB_SENSOR_TMP421_1_SDA      A @BASEBOARD_FAB2_LIB.BASEBOARD_FAB2(SCH_1):SMB_SENSOR_TMP421_1_SDA
   2 SMB_SENSOR_STBY_LVC3_SDA      B @BASEBOARD_FAB2_LIB.BASEBOARD_FAB2(SCH_1):SMB_SENSOR_STBY_LVC3_SDA

RES_0402-1.00K,1%,1/16W,CHIP,GA  I10  R9B8
   1 PD_TMP421_1_A0      A @BASEBOARD_FAB2_LIB.BASEBOARD_FAB2(SCH_1):PD_TMP421_1_A0
   2    GND      B @BASEBOARD_FAB2_LIB.BASEBOARD_FAB2(SCH_1):GND

CAP_0402LF-47.0PF,50V,5%,EMPTYA  I24  C1E19
   1 ISENSE_TMP421_2_DXP      A @BASEBOARD_FAB2_LIB.BASEBOARD_FAB2(SCH_1):ISENSE_TMP421_2_DXP
   2 ISENSE_TMP421_2_DXN      B @BASEBOARD_FAB2_LIB.BASEBOARD_FAB2(SCH_1):ISENSE_TMP421_2_DXN

RES_0402-49.9,1%,1/16W,CHIP,G2A  I25  R9R5
   1 ISENSE_TMP421_2_E      A @BASEBOARD_FAB2_LIB.BASEBOARD_FAB2(SCH_1):ISENSE_TMP421_2_E
   2 ISENSE_TMP421_2_DXP      B @BASEBOARD_FAB2_LIB.BASEBOARD_FAB2(SCH_1):ISENSE_TMP421_2_DXP

RES_0402-49.9,1%,1/16W,CHIP,G2A  I26  R9R6
   1 ISENSE_TMP421_2_BC      A @BASEBOARD_FAB2_LIB.BASEBOARD_FAB2(SCH_1):ISENSE_TMP421_2_BC
   2 ISENSE_TMP421_2_DXN      B @BASEBOARD_FAB2_LIB.BASEBOARD_FAB2(SCH_1):ISENSE_TMP421_2_DXN

PNP_TO92-MPS2907,IC,G73554-001  I27  Q1E1
   1 ISENSE_TMP421_2_BC      B @BASEBOARD_FAB2_LIB.BASEBOARD_FAB2(SCH_1):ISENSE_TMP421_2_BC
   3 ISENSE_TMP421_2_BC      C @BASEBOARD_FAB2_LIB.BASEBOARD_FAB2(SCH_1):ISENSE_TMP421_2_BC
   2 ISENSE_TMP421_2_E      E @BASEBOARD_FAB2_LIB.BASEBOARD_FAB2(SCH_1):ISENSE_TMP421_2_E

TMP421_TSSOP-IC,G62962-001  I30  U1E1
   3 PD_TMP421_2_A1   A<1> @BASEBOARD_FAB2_LIB.BASEBOARD_FAB2(SCH_1):PD_TMP421_2_A1
   4 PU_TMP421_2_A0   A<0> @BASEBOARD_FAB2_LIB.BASEBOARD_FAB2(SCH_1):PU_TMP421_2_A0
   2 ISENSE_TMP421_2_DXN    DXN @BASEBOARD_FAB2_LIB.BASEBOARD_FAB2(SCH_1):ISENSE_TMP421_2_DXN
   1 ISENSE_TMP421_2_DXP    DXP @BASEBOARD_FAB2_LIB.BASEBOARD_FAB2(SCH_1):ISENSE_TMP421_2_DXP
   5    GND    GND @BASEBOARD_FAB2_LIB.BASEBOARD_FAB2(SCH_1):GND
   7 SMB_SENSOR_TMP421_2_SCL    SCL @BASEBOARD_FAB2_LIB.BASEBOARD_FAB2(SCH_1):SMB_SENSOR_TMP421_2_SCL
   6 SMB_SENSOR_TMP421_2_SDA    SDA @BASEBOARD_FAB2_LIB.BASEBOARD_FAB2(SCH_1):SMB_SENSOR_TMP421_2_SDA
   8 P3V3_STBY     VP @BASEBOARD_FAB2_LIB.BASEBOARD_FAB2(SCH_1):P3V3_STBY

RES_0402-1.00K,1%,1/16W,CHIP,GA  I34  R1E9
   1 P3V3_STBY      A @BASEBOARD_FAB2_LIB.BASEBOARD_FAB2(SCH_1):P3V3_STBY
   2 PU_TMP421_2_A0      B @BASEBOARD_FAB2_LIB.BASEBOARD_FAB2(SCH_1):PU_TMP421_2_A0

RES_0402-1.00K,1%,1/16W,CHIP,GA  I35  R9B6
   1 P3V3_STBY      A @BASEBOARD_FAB2_LIB.BASEBOARD_FAB2(SCH_1):P3V3_STBY
   2 PU_TMP421_1_A1      B @BASEBOARD_FAB2_LIB.BASEBOARD_FAB2(SCH_1):PU_TMP421_1_A1

RES_0402-1.00K,1%,1/16W,CHIP,GA  I38  R1E10
   1 P3V3_STBY      A @BASEBOARD_FAB2_LIB.BASEBOARD_FAB2(SCH_1):P3V3_STBY
   2 PD_TMP421_2_A1      B @BASEBOARD_FAB2_LIB.BASEBOARD_FAB2(SCH_1):PD_TMP421_2_A1

CAP_A_0402V-0.1UF,16V,10%,X7R,A  I39  C9B7
   1 P3V3_STBY      A @BASEBOARD_FAB2_LIB.BASEBOARD_FAB2(SCH_1):P3V3_STBY
   2    GND      B @BASEBOARD_FAB2_LIB.BASEBOARD_FAB2(SCH_1):GND

CAP_A_0402V-0.1UF,16V,10%,X7R,A  I41  C9R14
   1 P3V3_STBY      A @BASEBOARD_FAB2_LIB.BASEBOARD_FAB2(SCH_1):P3V3_STBY
   2    GND      B @BASEBOARD_FAB2_LIB.BASEBOARD_FAB2(SCH_1):GND

CAP_A_0402V-0.1UF,16V,10%,X7R,A  I42  C9R13
   1 P3V3_STBY      A @BASEBOARD_FAB2_LIB.BASEBOARD_FAB2(SCH_1):P3V3_STBY
   2    GND      B @BASEBOARD_FAB2_LIB.BASEBOARD_FAB2(SCH_1):GND

AT24C64_SOICLF-IC,C47049-001-GA  I49  U8D4
   1    GND     A0 @BASEBOARD_FAB2_LIB.BASEBOARD_FAB2(SCH_1):GND
   2    GND     A1 @BASEBOARD_FAB2_LIB.BASEBOARD_FAB2(SCH_1):GND
   3 PU_AT24C64_A2     A2 @BASEBOARD_FAB2_LIB.BASEBOARD_FAB2(SCH_1):PU_AT24C64_A2
   6 SMB_SENSOR_STBY_LVC3_SCL_R2    SCL @BASEBOARD_FAB2_LIB.BASEBOARD_FAB2(SCH_1):SMB_SENSOR_STBY_LVC3_SCL_R2
   7 PD_FRU_WP     WP @BASEBOARD_FAB2_LIB.BASEBOARD_FAB2(SCH_1):PD_FRU_WP
   5 SMB_SENSOR_STBY_LVC3_SDA_R2    SDA @BASEBOARD_FAB2_LIB.BASEBOARD_FAB2(SCH_1):SMB_SENSOR_STBY_LVC3_SDA_R2

RES_0402-1.00K,1%,1/16W,CHIP,GA  I50  R8D27
   1 PD_FRU_WP      A @BASEBOARD_FAB2_LIB.BASEBOARD_FAB2(SCH_1):PD_FRU_WP
   2    GND      B @BASEBOARD_FAB2_LIB.BASEBOARD_FAB2(SCH_1):GND

RES_0402-20.0,1%,1/16W,CHIP,G2A  I58  R9G15
   1 SMB_SENSOR_BMC_STBY_LVC3_SDA      A @BASEBOARD_FAB2_LIB.BASEBOARD_FAB2(SCH_1):SMB_SENSOR_BMC_STBY_LVC3_SDA
   2 SMB_SENSOR_STBY_LVC3_SDA      B @BASEBOARD_FAB2_LIB.BASEBOARD_FAB2(SCH_1):SMB_SENSOR_STBY_LVC3_SDA

RES_0402-1.00K,1%,1/16W,CHIP,GA  I70  R8D28
   1 P3V3_STBY      A @BASEBOARD_FAB2_LIB.BASEBOARD_FAB2(SCH_1):P3V3_STBY
   2 PU_AT24C64_A2      B @BASEBOARD_FAB2_LIB.BASEBOARD_FAB2(SCH_1):PU_AT24C64_A2

RES_0402-20.0,1%,1/16W,CHIP,G2A  I74  R1M8
   1 SMB_SENSOR_TMP421_1_SCL      A @BASEBOARD_FAB2_LIB.BASEBOARD_FAB2(SCH_1):SMB_SENSOR_TMP421_1_SCL
   2 SMB_SENSOR_STBY_LVC3_SCL      B @BASEBOARD_FAB2_LIB.BASEBOARD_FAB2(SCH_1):SMB_SENSOR_STBY_LVC3_SCL

RES_0402-20.0,1%,1/16W,CHIP,G2A  I75  R9R7
   1 SMB_SENSOR_TMP421_2_SCL      A @BASEBOARD_FAB2_LIB.BASEBOARD_FAB2(SCH_1):SMB_SENSOR_TMP421_2_SCL
   2 SMB_SENSOR_STBY_LVC3_SCL      B @BASEBOARD_FAB2_LIB.BASEBOARD_FAB2(SCH_1):SMB_SENSOR_STBY_LVC3_SCL

RES_0402-20.0,1%,1/16W,CHIP,G2A  I76  R9R8
   1 SMB_SENSOR_TMP421_2_SDA      A @BASEBOARD_FAB2_LIB.BASEBOARD_FAB2(SCH_1):SMB_SENSOR_TMP421_2_SDA
   2 SMB_SENSOR_STBY_LVC3_SDA      B @BASEBOARD_FAB2_LIB.BASEBOARD_FAB2(SCH_1):SMB_SENSOR_STBY_LVC3_SDA

RES_0402-20.0,1%,1/16W,CHIP,G2A  I77  R9G14
   1 SMB_SENSOR_BMC_STBY_LVC3_SCL      A @BASEBOARD_FAB2_LIB.BASEBOARD_FAB2(SCH_1):SMB_SENSOR_BMC_STBY_LVC3_SCL
   2 SMB_SENSOR_STBY_LVC3_SCL      B @BASEBOARD_FAB2_LIB.BASEBOARD_FAB2(SCH_1):SMB_SENSOR_STBY_LVC3_SCL

RES_0402-20.0,1%,1/16W,CHIP,G2A  I78  R1U31
   1 SMB_SENSOR_PCH_STBY_LVC3_SDA      A @BASEBOARD_FAB2_LIB.BASEBOARD_FAB2(SCH_1):SMB_SENSOR_PCH_STBY_LVC3_SDA
   2 SMB_SENSOR_STBY_LVC3_SDA      B @BASEBOARD_FAB2_LIB.BASEBOARD_FAB2(SCH_1):SMB_SENSOR_STBY_LVC3_SDA

RES_0402-20.0,1%,1/16W,CHIP,G2A  I79  R1U25
   1 SMB_SENSOR_PCH_STBY_LVC3_SCL      A @BASEBOARD_FAB2_LIB.BASEBOARD_FAB2(SCH_1):SMB_SENSOR_PCH_STBY_LVC3_SCL
   2 SMB_SENSOR_STBY_LVC3_SCL      B @BASEBOARD_FAB2_LIB.BASEBOARD_FAB2(SCH_1):SMB_SENSOR_STBY_LVC3_SCL

RES_0402-665,1.0%,1/16W,CHIP,GA  I80  R2U38
   1 P3V3_STBY      A @BASEBOARD_FAB2_LIB.BASEBOARD_FAB2(SCH_1):P3V3_STBY
   2 SMB_SENSOR_STBY_LVC3_SCL      B @BASEBOARD_FAB2_LIB.BASEBOARD_FAB2(SCH_1):SMB_SENSOR_STBY_LVC3_SCL

RES_0402-665,1.0%,1/16W,CHIP,GA  I83  R2U39
   1 P3V3_STBY      A @BASEBOARD_FAB2_LIB.BASEBOARD_FAB2(SCH_1):P3V3_STBY
   2 SMB_SENSOR_STBY_LVC3_SDA      B @BASEBOARD_FAB2_LIB.BASEBOARD_FAB2(SCH_1):SMB_SENSOR_STBY_LVC3_SDA

RES_0402-20.0,1%,1/16W,CHIP,G2A  I84  R8D24
   1 SMB_SENSOR_STBY_LVC3_SCL      A @BASEBOARD_FAB2_LIB.BASEBOARD_FAB2(SCH_1):SMB_SENSOR_STBY_LVC3_SCL
   2 SMB_SENSOR_STBY_LVC3_SCL_R2      B @BASEBOARD_FAB2_LIB.BASEBOARD_FAB2(SCH_1):SMB_SENSOR_STBY_LVC3_SCL_R2

RES_0402-20.0,1%,1/16W,CHIP,G2A  I85  R8D23
   1 SMB_SENSOR_STBY_LVC3_SDA_R2      A @BASEBOARD_FAB2_LIB.BASEBOARD_FAB2(SCH_1):SMB_SENSOR_STBY_LVC3_SDA_R2
   2 SMB_SENSOR_STBY_LVC3_SDA      B @BASEBOARD_FAB2_LIB.BASEBOARD_FAB2(SCH_1):SMB_SENSOR_STBY_LVC3_SDA


DRAWING: @BASEBOARD_FAB2_LIB.BASEBOARD_FAB2(SCH_1):PAGE168 

DIODE_SM-1N4148W,IC,D89194-001  I2  CR1L1
   1 FM_DB_UART_SEL1_N      C @BASEBOARD_FAB2_LIB.BASEBOARD_FAB2(SCH_1):FM_DB_UART_SEL1_N
   2 FM_DB_UART_SEL0_N      A @BASEBOARD_FAB2_LIB.BASEBOARD_FAB2(SCH_1):FM_DB_UART_SEL0_N

DIODE_SM-1N4148W,IC,D89194-001  I3  CR1L2
   1 FM_DB_UART_SEL2_N      C @BASEBOARD_FAB2_LIB.BASEBOARD_FAB2(SCH_1):FM_DB_UART_SEL2_N
   2 FM_DB_UART_SEL1_N      A @BASEBOARD_FAB2_LIB.BASEBOARD_FAB2(SCH_1):FM_DB_UART_SEL1_N

DIODE_SM-1N4148W,IC,D89194-001  I4  CR1L3
   1 FM_DB_UART_SEL3_N      C @BASEBOARD_FAB2_LIB.BASEBOARD_FAB2(SCH_1):FM_DB_UART_SEL3_N
   2 FM_DB_UART_SEL2_N      A @BASEBOARD_FAB2_LIB.BASEBOARD_FAB2(SCH_1):FM_DB_UART_SEL2_N

DIODE_SM-1N4148W,IC,D89194-001  I5  CR1L4
   1 FM_DB_UART_SEL4_N      C @BASEBOARD_FAB2_LIB.BASEBOARD_FAB2(SCH_1):FM_DB_UART_SEL4_N
   2 FM_DB_UART_SEL3_N      A @BASEBOARD_FAB2_LIB.BASEBOARD_FAB2(SCH_1):FM_DB_UART_SEL3_N

RES_0402-0.0,5%,1/16W,CHIP,G21A  I6  R1L6
   1 FM_UART_SWITCH_N      A @BASEBOARD_FAB2_LIB.BASEBOARD_FAB2(SCH_1):FM_UART_SWITCH_N
   2 FM_DB_UART_SEL0_N      B @BASEBOARD_FAB2_LIB.BASEBOARD_FAB2(SCH_1):FM_DB_UART_SEL0_N

NPN_SM-MMBT3904,IC,C52245-001  I8  Q1L3
   1 FM_DB_UART_SEL4_N      B @BASEBOARD_FAB2_LIB.BASEBOARD_FAB2(SCH_1):FM_DB_UART_SEL4_N
   3 FM_DB_PRESENT      C @BASEBOARD_FAB2_LIB.BASEBOARD_FAB2(SCH_1):FM_DB_PRESENT
   2    GND      E @BASEBOARD_FAB2_LIB.BASEBOARD_FAB2(SCH_1):GND

RES_0402-1.00K,1%,1/16W,CHIP,GA  I11  R1L36
   1 P3V3_STBY      A @BASEBOARD_FAB2_LIB.BASEBOARD_FAB2(SCH_1):P3V3_STBY
   2 FM_DB_PRESENT      B @BASEBOARD_FAB2_LIB.BASEBOARD_FAB2(SCH_1):FM_DB_PRESENT

FET_N_DUAL_SMLF-2N7002DW,FET,DA  I18  Q1L4
   5 TP_FET_Q56_4 GATE<0> @BASEBOARD_FAB2_LIB.BASEBOARD_FAB2(SCH_1):TP_FET_Q56_4
   4 TP_FET_Q56_4 SOURCE<0> @BASEBOARD_FAB2_LIB.BASEBOARD_FAB2(SCH_1):TP_FET_Q56_4
   3 TP_FET_Q56_3 DRAIN<0> @BASEBOARD_FAB2_LIB.BASEBOARD_FAB2(SCH_1):TP_FET_Q56_3

FET_N_DUAL_SMLF-2N7002DW,FET,DA  I19  Q1L4
   2 FM_DB_PRESENT GATE<0> @BASEBOARD_FAB2_LIB.BASEBOARD_FAB2(SCH_1):FM_DB_PRESENT
   1    GND SOURCE<0> @BASEBOARD_FAB2_LIB.BASEBOARD_FAB2(SCH_1):GND
   6 FM_POST_CARD_PRES_BMC_N DRAIN<0> @BASEBOARD_FAB2_LIB.BASEBOARD_FAB2(SCH_1):FM_POST_CARD_PRES_BMC_N

RES_0402-1.00K,1%,1/16W,CHIP,GA  I22  R1L38
   1 P3V3_STBY      A @BASEBOARD_FAB2_LIB.BASEBOARD_FAB2(SCH_1):P3V3_STBY
   2 FM_POST_CARD_PRES_BMC_N      B @BASEBOARD_FAB2_LIB.BASEBOARD_FAB2(SCH_1):FM_POST_CARD_PRES_BMC_N

FET_N_DUAL_SMLF-2N7002DW,FET,DA  I30  Q6W2
   2 FM_UART_SEL_N GATE<0> @BASEBOARD_FAB2_LIB.BASEBOARD_FAB2(SCH_1):FM_UART_SEL_N
   1    GND SOURCE<0> @BASEBOARD_FAB2_LIB.BASEBOARD_FAB2(SCH_1):GND
   6 FM_SOL_UART_CH_SEL DRAIN<0> @BASEBOARD_FAB2_LIB.BASEBOARD_FAB2(SCH_1):FM_SOL_UART_CH_SEL

RES_0402-5.11K,1%,1/16W,CHIP,GA  I33  R6W14
   1 UART_SELECT_Q      A @BASEBOARD_FAB2_LIB.BASEBOARD_FAB2(SCH_1):UART_SELECT_Q
   2    GND      B @BASEBOARD_FAB2_LIB.BASEBOARD_FAB2(SCH_1):GND

RES_0402-15.0K,1%,1/16W,CHIP,GA  I34  R6W13
   1 P5V_STBY      A @BASEBOARD_FAB2_LIB.BASEBOARD_FAB2(SCH_1):P5V_STBY
   2 UART_SELECT_Q      B @BASEBOARD_FAB2_LIB.BASEBOARD_FAB2(SCH_1):UART_SELECT_Q

NPN_SM-MMBT3904,IC,C52245-001  I37  Q6W3
   1 UART_SELECT_Q      B @BASEBOARD_FAB2_LIB.BASEBOARD_FAB2(SCH_1):UART_SELECT_Q
   3 FM_UART_SEL_N      C @BASEBOARD_FAB2_LIB.BASEBOARD_FAB2(SCH_1):FM_UART_SEL_N
   2 FM_UART_SWITCH_N      E @BASEBOARD_FAB2_LIB.BASEBOARD_FAB2(SCH_1):FM_UART_SWITCH_N

RES_0402-10.0K,1%,1/16W,CHIP,GA  I39  R6W16
   1 P3V3_STBY      A @BASEBOARD_FAB2_LIB.BASEBOARD_FAB2(SCH_1):P3V3_STBY
   2 FM_SOL_UART_CH_SEL      B @BASEBOARD_FAB2_LIB.BASEBOARD_FAB2(SCH_1):FM_SOL_UART_CH_SEL

RES_0402-10.0K,1%,1/16W,CHIP,GA  I40  R6W15
   1 P3V3_STBY      A @BASEBOARD_FAB2_LIB.BASEBOARD_FAB2(SCH_1):P3V3_STBY
   2 FM_UART_SEL_N      B @BASEBOARD_FAB2_LIB.BASEBOARD_FAB2(SCH_1):FM_UART_SEL_N


DRAWING: @BASEBOARD_FAB2_LIB.BASEBOARD_FAB2(SCH_1):PAGE169 

CAP_0402LF-47.0PF,50V,5%,COG,AA  I56  C1U21
   1 A_P1V05_STBY_PCH_SENSOR      A @BASEBOARD_FAB2_LIB.BASEBOARD_FAB2(SCH_1):A_P1V05_STBY_PCH_SENSOR
   2    GND      B @BASEBOARD_FAB2_LIB.BASEBOARD_FAB2(SCH_1):GND

FERRITE_SMLF-30,FB,693286-021  I57  FB1U3
   1 A_P1V05_STBY_PCH_SENSOR      A @BASEBOARD_FAB2_LIB.BASEBOARD_FAB2(SCH_1):A_P1V05_STBY_PCH_SENSOR
   2 P1V05_PCH_STBY      B @BASEBOARD_FAB2_LIB.BASEBOARD_FAB2(SCH_1):P1V05_PCH_STBY

CAP_0402LF-47.0PF,50V,5%,COG,AA  I68  C9G21
   1 A_P5V_STBY_SCALED      A @BASEBOARD_FAB2_LIB.BASEBOARD_FAB2(SCH_1):A_P5V_STBY_SCALED
   2    GND      B @BASEBOARD_FAB2_LIB.BASEBOARD_FAB2(SCH_1):GND

CAP_0402LF-47.0PF,50V,5%,COG,AA  I80  C9G17
   1 A_P12V_STBY_SCALED      A @BASEBOARD_FAB2_LIB.BASEBOARD_FAB2(SCH_1):A_P12V_STBY_SCALED
   2    GND      B @BASEBOARD_FAB2_LIB.BASEBOARD_FAB2(SCH_1):GND

RES_0402-5.11K,1%,1/16W,CHIP,GA  I82  R1U32
   1 P12V_STBY      A @BASEBOARD_FAB2_LIB.BASEBOARD_FAB2(SCH_1):P12V_STBY
   2 A_P12V_STBY_SCALED      B @BASEBOARD_FAB2_LIB.BASEBOARD_FAB2(SCH_1):A_P12V_STBY_SCALED

RES_0402-1.00K,1%,1/16W,CHIP,GA  I83  R1U33
   1 A_P12V_STBY_SCALED      A @BASEBOARD_FAB2_LIB.BASEBOARD_FAB2(SCH_1):A_P12V_STBY_SCALED
   2    GND      B @BASEBOARD_FAB2_LIB.BASEBOARD_FAB2(SCH_1):GND

CAP_0402LF-47.0PF,50V,5%,COG,AA  I86  C9G20
   1 A_P3V3_STBY_SCALED      A @BASEBOARD_FAB2_LIB.BASEBOARD_FAB2(SCH_1):A_P3V3_STBY_SCALED
   2    GND      B @BASEBOARD_FAB2_LIB.BASEBOARD_FAB2(SCH_1):GND

RES_0402-5.11K,1%,1/16W,CHIP,GA  I88  R1U39
   1 P3V3_STBY      A @BASEBOARD_FAB2_LIB.BASEBOARD_FAB2(SCH_1):P3V3_STBY
   2 A_P3V3_STBY_SCALED      B @BASEBOARD_FAB2_LIB.BASEBOARD_FAB2(SCH_1):A_P3V3_STBY_SCALED

RES_0402-100.0K,1%,1/16W,CHIP,A  I106  R9G26
   1 A_P3V_BAT_SCALED      A @BASEBOARD_FAB2_LIB.BASEBOARD_FAB2(SCH_1):A_P3V_BAT_SCALED
   2    GND      B @BASEBOARD_FAB2_LIB.BASEBOARD_FAB2(SCH_1):GND

CAP_0402LF-10.0PF,50V,5%,COG,AA  I108  C9G22
   1 A_P3V_BAT_SCALED      A @BASEBOARD_FAB2_LIB.BASEBOARD_FAB2(SCH_1):A_P3V_BAT_SCALED
   2    GND      B @BASEBOARD_FAB2_LIB.BASEBOARD_FAB2(SCH_1):GND

RES_0402-8.2K,1%,1/16W,CHIP,G2A  I114  R1U38
   1 A_P3V3_STBY_SCALED      A @BASEBOARD_FAB2_LIB.BASEBOARD_FAB2(SCH_1):A_P3V3_STBY_SCALED
   2    GND      B @BASEBOARD_FAB2_LIB.BASEBOARD_FAB2(SCH_1):GND

RES_0402-5.11K,1%,1/16W,CHIP,GA  I115  R1U47
   1 P5V_STBY      A @BASEBOARD_FAB2_LIB.BASEBOARD_FAB2(SCH_1):P5V_STBY
   2 A_P5V_STBY_SCALED      B @BASEBOARD_FAB2_LIB.BASEBOARD_FAB2(SCH_1):A_P5V_STBY_SCALED

RES_0402-3.48K,1.0%,1/16W,CHIPA  I116  R1U44
   1 A_P5V_STBY_SCALED      A @BASEBOARD_FAB2_LIB.BASEBOARD_FAB2(SCH_1):A_P5V_STBY_SCALED
   2    GND      B @BASEBOARD_FAB2_LIB.BASEBOARD_FAB2(SCH_1):GND

RES_0402-200.0K,1%,1/16W,CHIP,A  I126  R1U50
   1 A_P3V_BAT_R      A @BASEBOARD_FAB2_LIB.BASEBOARD_FAB2(SCH_1):A_P3V_BAT_R
   2 P3V_BAT_SOURCE_R      B @BASEBOARD_FAB2_LIB.BASEBOARD_FAB2(SCH_1):P3V_BAT_SOURCE_R

CAP_0402LF-47.0PF,50V,5%,COG,AA  I139  C9G15
   1 A_P5V_SCALED      A @BASEBOARD_FAB2_LIB.BASEBOARD_FAB2(SCH_1):A_P5V_SCALED
   2    GND      B @BASEBOARD_FAB2_LIB.BASEBOARD_FAB2(SCH_1):GND

RES_0402-5.11K,1%,1/16W,CHIP,GA  I141  R1U29
   1    P5V      A @BASEBOARD_FAB2_LIB.BASEBOARD_FAB2(SCH_1):P5V
   2 A_P5V_SCALED      B @BASEBOARD_FAB2_LIB.BASEBOARD_FAB2(SCH_1):A_P5V_SCALED

RES_0402-3.48K,1.0%,1/16W,CHIPA  I142  R1U28
   1 A_P5V_SCALED      A @BASEBOARD_FAB2_LIB.BASEBOARD_FAB2(SCH_1):A_P5V_SCALED
   2    GND      B @BASEBOARD_FAB2_LIB.BASEBOARD_FAB2(SCH_1):GND

CAP_0402LF-47.0PF,50V,5%,COG,AA  I146  C9G14
   1 A_P3V3_SCALED      A @BASEBOARD_FAB2_LIB.BASEBOARD_FAB2(SCH_1):A_P3V3_SCALED
   2    GND      B @BASEBOARD_FAB2_LIB.BASEBOARD_FAB2(SCH_1):GND

RES_0402-5.11K,1%,1/16W,CHIP,GA  I148  R1U26
   1   P3V3      A @BASEBOARD_FAB2_LIB.BASEBOARD_FAB2(SCH_1):P3V3
   2 A_P3V3_SCALED      B @BASEBOARD_FAB2_LIB.BASEBOARD_FAB2(SCH_1):A_P3V3_SCALED

RES_0402-8.2K,1%,1/16W,CHIP,G2A  I149  R1U27
   1 A_P3V3_SCALED      A @BASEBOARD_FAB2_LIB.BASEBOARD_FAB2(SCH_1):A_P3V3_SCALED
   2    GND      B @BASEBOARD_FAB2_LIB.BASEBOARD_FAB2(SCH_1):GND

CAP_0402LF-47.0PF,50V,5%,COG,AA  I153  C9G18
   1 A_PVNN_STBY_PCH_SENSOR      A @BASEBOARD_FAB2_LIB.BASEBOARD_FAB2(SCH_1):A_PVNN_STBY_PCH_SENSOR
   2    GND      B @BASEBOARD_FAB2_LIB.BASEBOARD_FAB2(SCH_1):GND

FERRITE_SMLF-30,FB,693286-021  I155  FB1U4
   1 A_PVNN_STBY_PCH_SENSOR      A @BASEBOARD_FAB2_LIB.BASEBOARD_FAB2(SCH_1):A_PVNN_STBY_PCH_SENSOR
   2 PVNN_PCH_STBY      B @BASEBOARD_FAB2_LIB.BASEBOARD_FAB2(SCH_1):PVNN_PCH_STBY

FET_N_DUAL_SMLF-NTJD4001N,FET,A  I157  Q9G1
   5 FM_BATTERY_SENSE_EN GATE<0> @BASEBOARD_FAB2_LIB.BASEBOARD_FAB2(SCH_1):FM_BATTERY_SENSE_EN
   4 A_P3V_BAT_SCALED SOURCE<0> @BASEBOARD_FAB2_LIB.BASEBOARD_FAB2(SCH_1):A_P3V_BAT_SCALED
   3 P3V_BAT_SOURCE_R DRAIN<0> @BASEBOARD_FAB2_LIB.BASEBOARD_FAB2(SCH_1):P3V_BAT_SOURCE_R

FET_N_DUAL_SMLF-NTJD4001N,FET,A  I162  Q9G1
   2 FM_BATTERY_SENSE_EN_N GATE<0> @BASEBOARD_FAB2_LIB.BASEBOARD_FAB2(SCH_1):FM_BATTERY_SENSE_EN_N
   1    GND SOURCE<0> @BASEBOARD_FAB2_LIB.BASEBOARD_FAB2(SCH_1):GND
   6 FM_BATTERY_SENSE_EN DRAIN<0> @BASEBOARD_FAB2_LIB.BASEBOARD_FAB2(SCH_1):FM_BATTERY_SENSE_EN

RES_0402-2.7K,1%,1/16W,CHIP,G2A  I163  R1U49
   1 P3V3_STBY      A @BASEBOARD_FAB2_LIB.BASEBOARD_FAB2(SCH_1):P3V3_STBY
   2 FM_BATTERY_SENSE_EN      B @BASEBOARD_FAB2_LIB.BASEBOARD_FAB2(SCH_1):FM_BATTERY_SENSE_EN

RES_0402-2.7K,1%,1/16W,CHIP,G2A  I164  R9G35
   1 P3V3_STBY      A @BASEBOARD_FAB2_LIB.BASEBOARD_FAB2(SCH_1):P3V3_STBY
   2 FM_BATTERY_SENSE_EN_N      B @BASEBOARD_FAB2_LIB.BASEBOARD_FAB2(SCH_1):FM_BATTERY_SENSE_EN_N


DRAWING: @BASEBOARD_FAB2_LIB.BASEBOARD_FAB2(SCH_1):PAGE170 

RES_0402-4.75K,1%,1/16W,CHIP,GA  I2  R2P3
   1 P3V3_STBY      A @BASEBOARD_FAB2_LIB.BASEBOARD_FAB2(SCH_1):P3V3_STBY
   2 IRQ_FORCE_NM_THROTTLE_R_N      B @BASEBOARD_FAB2_LIB.BASEBOARD_FAB2(SCH_1):IRQ_FORCE_NM_THROTTLE_R_N

TTL1G07_A_SOP-74LVC1G07,IC,C88B  I4  U8D3
   2 IRQ_SML1_PMBUS_ALERT_BUF_N      A @BASEBOARD_FAB2_LIB.BASEBOARD_FAB2(SCH_1):IRQ_SML1_PMBUS_ALERT_BUF_N
   4 IRQ_FORCE_NM_THROTTLE_R_N      Y @BASEBOARD_FAB2_LIB.BASEBOARD_FAB2(SCH_1):IRQ_FORCE_NM_THROTTLE_R_N

CAP_A_0402V-0.1UF,16V,10%,X7R,A  I8  C2P1
   1 P3V3_STBY      A @BASEBOARD_FAB2_LIB.BASEBOARD_FAB2(SCH_1):P3V3_STBY
   2    GND      B @BASEBOARD_FAB2_LIB.BASEBOARD_FAB2(SCH_1):GND

TTL08_QFN15-74LVC08A,IC,D90404B  I10  U8E1
   3 FM_FAST_PROCHOT_AND_OUT_0_N   Y<0> @BASEBOARD_FAB2_LIB.BASEBOARD_FAB2(SCH_1):FM_FAST_PROCHOT_AND_OUT_0_N
   2 FM_OC_DETECT_N   B<0> @BASEBOARD_FAB2_LIB.BASEBOARD_FAB2(SCH_1):FM_OC_DETECT_N
   1 IRQ_FORCE_NM_THROTTLE_N   A<0> @BASEBOARD_FAB2_LIB.BASEBOARD_FAB2(SCH_1):IRQ_FORCE_NM_THROTTLE_N

TTL08_QFN15-74LVC08A,IC,D90404B  I11  U8E1
   6 FM_FAST_PROCHOT_AND_OUT_1_N   Y<0> @BASEBOARD_FAB2_LIB.BASEBOARD_FAB2(SCH_1):FM_FAST_PROCHOT_AND_OUT_1_N
   5 FM_HSC_TIMER_EXP_N   B<0> @BASEBOARD_FAB2_LIB.BASEBOARD_FAB2(SCH_1):FM_HSC_TIMER_EXP_N
   4 IRQ_UV_DETECT_N   A<0> @BASEBOARD_FAB2_LIB.BASEBOARD_FAB2(SCH_1):IRQ_UV_DETECT_N

TTL08_QFN15-74LVC08A,IC,D90404B  I12  U8E1
  11 FM_FAST_PROCHOT_THROTTLE_IN_N   Y<0> @BASEBOARD_FAB2_LIB.BASEBOARD_FAB2(SCH_1):FM_FAST_PROCHOT_THROTTLE_IN_N
  13 FM_FAST_PROCHOT_AND_OUT_1_N   B<0> @BASEBOARD_FAB2_LIB.BASEBOARD_FAB2(SCH_1):FM_FAST_PROCHOT_AND_OUT_1_N
  12 FM_FAST_PROCHOT_AND_OUT_0_N   A<0> @BASEBOARD_FAB2_LIB.BASEBOARD_FAB2(SCH_1):FM_FAST_PROCHOT_AND_OUT_0_N

TTL1G126_A_SOT-74HC1G126,IC,A7B  I20  U1R2
   1 FM_FAST_PROCHOT_EN     OE @BASEBOARD_FAB2_LIB.BASEBOARD_FAB2(SCH_1):FM_FAST_PROCHOT_EN
   2 FM_FAST_PROCHOT_THROTTLE_DLY_N      A @BASEBOARD_FAB2_LIB.BASEBOARD_FAB2(SCH_1):FM_FAST_PROCHOT_THROTTLE_DLY_N
   4 FM_FAST_PROCHOT_THROTTLE_DLY_BU      Y @BASEBOARD_FAB2_LIB.BASEBOARD_FAB2(SCH_1):FM_FAST_PROCHOT_THROTTLE_DLY_BUF_N

CAP_A_0402V-0.1UF,16V,10%,X7R,A  I30  C1R27
   1 P3V3_STBY      A @BASEBOARD_FAB2_LIB.BASEBOARD_FAB2(SCH_1):P3V3_STBY
   2    GND      B @BASEBOARD_FAB2_LIB.BASEBOARD_FAB2(SCH_1):GND

CAP_A_0402V-0.1UF,16V,10%,X7R,A  I33  C8D2
   1 P3V3_STBY      A @BASEBOARD_FAB2_LIB.BASEBOARD_FAB2(SCH_1):P3V3_STBY
   2    GND      B @BASEBOARD_FAB2_LIB.BASEBOARD_FAB2(SCH_1):GND

TTL1G126_A_SOT-74HC1G126,IC,A7B  I38  U8D5
   1 FM_PMBUS_ALERT_BUF_EN     OE @BASEBOARD_FAB2_LIB.BASEBOARD_FAB2(SCH_1):FM_PMBUS_ALERT_BUF_EN
   2 IRQ_SML1_PMBUS_ALERT_N      A @BASEBOARD_FAB2_LIB.BASEBOARD_FAB2(SCH_1):IRQ_SML1_PMBUS_ALERT_N
   4 IRQ_SML1_PMBUS_ALERT_BUF_N      Y @BASEBOARD_FAB2_LIB.BASEBOARD_FAB2(SCH_1):IRQ_SML1_PMBUS_ALERT_BUF_N

CAP_A_0402V-0.1UF,16V,10%,X7R,A  I40  C8E2
   1 P3V3_STBY      A @BASEBOARD_FAB2_LIB.BASEBOARD_FAB2(SCH_1):P3V3_STBY
   2    GND      B @BASEBOARD_FAB2_LIB.BASEBOARD_FAB2(SCH_1):GND

CAP_0402LF-470PF,50V,10%,EMPTYA  I42  C8D3
   1 IRQ_SML1_PMBUS_ALERT_N      A @BASEBOARD_FAB2_LIB.BASEBOARD_FAB2(SCH_1):IRQ_SML1_PMBUS_ALERT_N
   2    GND      B @BASEBOARD_FAB2_LIB.BASEBOARD_FAB2(SCH_1):GND

TTL1G07_A_SOP-74LVC1G07,IC,C88B  I46  U1R1
   2 FM_FAST_PROCHOT_THROTTLE_DLY_BU      A @BASEBOARD_FAB2_LIB.BASEBOARD_FAB2(SCH_1):FM_FAST_PROCHOT_THROTTLE_DLY_BUF_N
   4 FM_THROTTLE_R1_N      Y @BASEBOARD_FAB2_LIB.BASEBOARD_FAB2(SCH_1):FM_THROTTLE_R1_N

CAP_A_0402V-0.1UF,16V,10%,X7R,A  I49  C1R28
   1 P3V3_STBY      A @BASEBOARD_FAB2_LIB.BASEBOARD_FAB2(SCH_1):P3V3_STBY
   2    GND      B @BASEBOARD_FAB2_LIB.BASEBOARD_FAB2(SCH_1):GND

RES_0402-0.0,5%,1/16W,CHIP,G21A  I51  R1R8
   1 FM_THROTTLE_R1_N      A @BASEBOARD_FAB2_LIB.BASEBOARD_FAB2(SCH_1):FM_THROTTLE_R1_N
   2 FM_THROTTLE_N      B @BASEBOARD_FAB2_LIB.BASEBOARD_FAB2(SCH_1):FM_THROTTLE_N

RES_0402-560,5%,1/16W,CHIP,G21A  I52  R2P8
   1 P3V3_STBY      A @BASEBOARD_FAB2_LIB.BASEBOARD_FAB2(SCH_1):P3V3_STBY
   2 IRQ_SML1_PMBUS_ALERT_N      B @BASEBOARD_FAB2_LIB.BASEBOARD_FAB2(SCH_1):IRQ_SML1_PMBUS_ALERT_N

RES_0402-4.75K,1%,1/16W,CHIP,GA  I54  R2T3
   1 P3V3_STBY      A @BASEBOARD_FAB2_LIB.BASEBOARD_FAB2(SCH_1):P3V3_STBY
   2 FM_FAST_PROCHOT_EN_N      B @BASEBOARD_FAB2_LIB.BASEBOARD_FAB2(SCH_1):FM_FAST_PROCHOT_EN_N

RES_0402-4.75K,1%,1/16W,CHIP,GA  I56  R2P5
   1 P3V3_STBY      A @BASEBOARD_FAB2_LIB.BASEBOARD_FAB2(SCH_1):P3V3_STBY
   2 FM_PMBUS_ALERT_BUF_EN      B @BASEBOARD_FAB2_LIB.BASEBOARD_FAB2(SCH_1):FM_PMBUS_ALERT_BUF_EN

FET_N_SOT23LF-2N7002,FET,C7925A  I58  Q2P1
   1 FM_PMBUS_ALERT_BUF_EN_N   GATE @BASEBOARD_FAB2_LIB.BASEBOARD_FAB2(SCH_1):FM_PMBUS_ALERT_BUF_EN_N
   2    GND    SRC @BASEBOARD_FAB2_LIB.BASEBOARD_FAB2(SCH_1):GND
   3 FM_PMBUS_ALERT_BUF_EN    DRN @BASEBOARD_FAB2_LIB.BASEBOARD_FAB2(SCH_1):FM_PMBUS_ALERT_BUF_EN

RES_0402-4.75K,1%,1/16W,CHIP,GA  I61  R2P13
   1 P3V3_STBY      A @BASEBOARD_FAB2_LIB.BASEBOARD_FAB2(SCH_1):P3V3_STBY
   2 FM_PMBUS_ALERT_BUF_EN_N      B @BASEBOARD_FAB2_LIB.BASEBOARD_FAB2(SCH_1):FM_PMBUS_ALERT_BUF_EN_N

RES_0402-1.00K,1%,1/16W,EMPTY,A  I63  R2P11
   1 FM_PMBUS_ALERT_BUF_EN_N      A @BASEBOARD_FAB2_LIB.BASEBOARD_FAB2(SCH_1):FM_PMBUS_ALERT_BUF_EN_N
   2    GND      B @BASEBOARD_FAB2_LIB.BASEBOARD_FAB2(SCH_1):GND

RES_0402-4.75K,1%,1/16W,CHIP,GA  I65  R9F3
   1 P3V3_STBY      A @BASEBOARD_FAB2_LIB.BASEBOARD_FAB2(SCH_1):P3V3_STBY
   2 FM_FAST_PROCHOT_EN      B @BASEBOARD_FAB2_LIB.BASEBOARD_FAB2(SCH_1):FM_FAST_PROCHOT_EN

FET_N_SOT23LF-2N7002,FET,C7925A  I67  Q8F2
   1 FM_FAST_PROCHOT_EN_N   GATE @BASEBOARD_FAB2_LIB.BASEBOARD_FAB2(SCH_1):FM_FAST_PROCHOT_EN_N
   2    GND    SRC @BASEBOARD_FAB2_LIB.BASEBOARD_FAB2(SCH_1):GND
   3 FM_FAST_PROCHOT_EN    DRN @BASEBOARD_FAB2_LIB.BASEBOARD_FAB2(SCH_1):FM_FAST_PROCHOT_EN

RES_0402-4.75K,1%,1/16W,CHIP,GA  I71  R8D26
   1 P3V3_STBY      A @BASEBOARD_FAB2_LIB.BASEBOARD_FAB2(SCH_1):P3V3_STBY
   2 IRQ_SML1_PMBUS_ALERT_BUF_N      B @BASEBOARD_FAB2_LIB.BASEBOARD_FAB2(SCH_1):IRQ_SML1_PMBUS_ALERT_BUF_N

RES_0402-4.75K,1%,1/16W,CHIP,GA  I73  R1R5
   1 P3V3_STBY      A @BASEBOARD_FAB2_LIB.BASEBOARD_FAB2(SCH_1):P3V3_STBY
   2 FM_FAST_PROCHOT_THROTTLE_DLY_BU      B @BASEBOARD_FAB2_LIB.BASEBOARD_FAB2(SCH_1):FM_FAST_PROCHOT_THROTTLE_DLY_BUF_N

RES_0402-33.2,1%,1/16W,CHIP,G2A  I74  R2P4
   1 IRQ_FORCE_NM_THROTTLE_R_N      A @BASEBOARD_FAB2_LIB.BASEBOARD_FAB2(SCH_1):IRQ_FORCE_NM_THROTTLE_R_N
   2 IRQ_FORCE_NM_THROTTLE_N      B @BASEBOARD_FAB2_LIB.BASEBOARD_FAB2(SCH_1):IRQ_FORCE_NM_THROTTLE_N


DRAWING: @BASEBOARD_FAB2_LIB.BASEBOARD_FAB2(SCH_1):PAGE172 

CAP_A_0402V-0.01UF,25V,10%,X7RA  I5  C2L49
   1 SATA6G_S1_RX_C_DP      A @BASEBOARD_FAB2_LIB.BASEBOARD_FAB2(SCH_1):SATA6G_S1_RX_C_DP
   2 SATA6G_S1_RX_DP      B @BASEBOARD_FAB2_LIB.BASEBOARD_FAB2(SCH_1):SATA6G_S1_RX_DP

CAP_A_0402V-0.01UF,25V,10%,X7RA  I6  C2L52
   1 SATA6G_S1_TX_C_DP      A @BASEBOARD_FAB2_LIB.BASEBOARD_FAB2(SCH_1):SATA6G_S1_TX_C_DP
   2 SATA6G_S1_TX_DP      B @BASEBOARD_FAB2_LIB.BASEBOARD_FAB2(SCH_1):SATA6G_S1_TX_DP

CAP_A_0402V-0.01UF,25V,10%,X7RA  I7  C2L50
   1 SATA6G_S1_RX_C_DN      A @BASEBOARD_FAB2_LIB.BASEBOARD_FAB2(SCH_1):SATA6G_S1_RX_C_DN
   2 SATA6G_S1_RX_DN      B @BASEBOARD_FAB2_LIB.BASEBOARD_FAB2(SCH_1):SATA6G_S1_RX_DN

CAP_A_0402V-0.01UF,25V,10%,X7RA  I8  C2L51
   1 SATA6G_S1_TX_C_DN      A @BASEBOARD_FAB2_LIB.BASEBOARD_FAB2(SCH_1):SATA6G_S1_TX_C_DN
   2 SATA6G_S1_TX_DN      B @BASEBOARD_FAB2_LIB.BASEBOARD_FAB2(SCH_1):SATA6G_S1_TX_DN

CONN7_E82125014_PIP_TH-EMPTY,EA  I17  J8A3
   1    GND GND<2> @BASEBOARD_FAB2_LIB.BASEBOARD_FAB2(SCH_1):GND
   4    GND GND<1> @BASEBOARD_FAB2_LIB.BASEBOARD_FAB2(SCH_1):GND
   7    GND GND<0> @BASEBOARD_FAB2_LIB.BASEBOARD_FAB2(SCH_1):GND
 MH1    GND    MH1 @BASEBOARD_FAB2_LIB.BASEBOARD_FAB2(SCH_1):GND
 MH2    GND    MH2 @BASEBOARD_FAB2_LIB.BASEBOARD_FAB2(SCH_1):GND
   5 SATA6G_S1_RX_C_DN SATA_RXN @BASEBOARD_FAB2_LIB.BASEBOARD_FAB2(SCH_1):SATA6G_S1_RX_C_DN
   6 SATA6G_S1_RX_C_DP SATA_RXP @BASEBOARD_FAB2_LIB.BASEBOARD_FAB2(SCH_1):SATA6G_S1_RX_C_DP
   3 SATA6G_S1_TX_C_DN SATA_TXN @BASEBOARD_FAB2_LIB.BASEBOARD_FAB2(SCH_1):SATA6G_S1_TX_C_DN
   2 SATA6G_S1_TX_C_DP SATA_TXP @BASEBOARD_FAB2_LIB.BASEBOARD_FAB2(SCH_1):SATA6G_S1_TX_C_DP

CONN4_H73295001_PIP-EMPTY,H732A  I25  J8A4
   1 P5V_HDD_SATA    IO1 @BASEBOARD_FAB2_LIB.BASEBOARD_FAB2(SCH_1):P5V_HDD_SATA
   2    GND    IO2 @BASEBOARD_FAB2_LIB.BASEBOARD_FAB2(SCH_1):GND
   3    GND    IO3 @BASEBOARD_FAB2_LIB.BASEBOARD_FAB2(SCH_1):GND
   4 P12V_HDD_SATA    IO4 @BASEBOARD_FAB2_LIB.BASEBOARD_FAB2(SCH_1):P12V_HDD_SATA

CAP_0805-10UF,16V,10%,X6S,C953A  I36  C9B2
   1 P12V_HDD_SATA      A @BASEBOARD_FAB2_LIB.BASEBOARD_FAB2(SCH_1):P12V_HDD_SATA
   2    GND      B @BASEBOARD_FAB2_LIB.BASEBOARD_FAB2(SCH_1):GND

FUSE_SM-IC,C94311-016  I38  F9B1
   1   P12V   A<0> @BASEBOARD_FAB2_LIB.BASEBOARD_FAB2(SCH_1):P12V
   2 P12V_HDD_SATA   B<0> @BASEBOARD_FAB2_LIB.BASEBOARD_FAB2(SCH_1):P12V_HDD_SATA

CAP_0805-10UF,16V,10%,X6S,C953A  I39  C9B1
   1 P5V_HDD_SATA      A @BASEBOARD_FAB2_LIB.BASEBOARD_FAB2(SCH_1):P5V_HDD_SATA
   2    GND      B @BASEBOARD_FAB2_LIB.BASEBOARD_FAB2(SCH_1):GND

FUSE_SMLF-IC,C94311-006  I41  F8B1
   1    P5V   A<0> @BASEBOARD_FAB2_LIB.BASEBOARD_FAB2(SCH_1):P5V
   2 P5V_HDD_SATA   B<0> @BASEBOARD_FAB2_LIB.BASEBOARD_FAB2(SCH_1):P5V_HDD_SATA

CONN7_E82125014_PIP_TH-CONN,E8A  I52  J2M1
   1    GND GND<2> @BASEBOARD_FAB2_LIB.BASEBOARD_FAB2(SCH_1):GND
   4    GND GND<1> @BASEBOARD_FAB2_LIB.BASEBOARD_FAB2(SCH_1):GND
   7    GND GND<0> @BASEBOARD_FAB2_LIB.BASEBOARD_FAB2(SCH_1):GND
 MH1    GND    MH1 @BASEBOARD_FAB2_LIB.BASEBOARD_FAB2(SCH_1):GND
 MH2    GND    MH2 @BASEBOARD_FAB2_LIB.BASEBOARD_FAB2(SCH_1):GND
   5 SATA6G_S1_RX_C_DN SATA_RXN @BASEBOARD_FAB2_LIB.BASEBOARD_FAB2(SCH_1):SATA6G_S1_RX_C_DN
   6 SATA6G_S1_RX_C_DP SATA_RXP @BASEBOARD_FAB2_LIB.BASEBOARD_FAB2(SCH_1):SATA6G_S1_RX_C_DP
   3 SATA6G_S1_TX_C_DN SATA_TXN @BASEBOARD_FAB2_LIB.BASEBOARD_FAB2(SCH_1):SATA6G_S1_TX_C_DN
   2 SATA6G_S1_TX_C_DP SATA_TXP @BASEBOARD_FAB2_LIB.BASEBOARD_FAB2(SCH_1):SATA6G_S1_TX_C_DP

CONN4_H73295001_PIP-CONN,H7329A  I53  J2L1
   1 P5V_HDD_SATA    IO1 @BASEBOARD_FAB2_LIB.BASEBOARD_FAB2(SCH_1):P5V_HDD_SATA
   2    GND    IO2 @BASEBOARD_FAB2_LIB.BASEBOARD_FAB2(SCH_1):GND
   3    GND    IO3 @BASEBOARD_FAB2_LIB.BASEBOARD_FAB2(SCH_1):GND
   4 P12V_HDD_SATA    IO4 @BASEBOARD_FAB2_LIB.BASEBOARD_FAB2(SCH_1):P12V_HDD_SATA


DRAWING: @BASEBOARD_FAB2_LIB.BASEBOARD_FAB2(SCH_1):PAGE173 

CONN72_G97614002_A_CP-CONN,G97A  I163  J8A1
 1A3    GND GND<23> @BASEBOARD_FAB2_LIB.BASEBOARD_FAB2(SCH_1):GND
 1A6    GND GND<22> @BASEBOARD_FAB2_LIB.BASEBOARD_FAB2(SCH_1):GND
 1A9    GND GND<21> @BASEBOARD_FAB2_LIB.BASEBOARD_FAB2(SCH_1):GND
 1B3    GND GND<20> @BASEBOARD_FAB2_LIB.BASEBOARD_FAB2(SCH_1):GND
 1B6    GND GND<19> @BASEBOARD_FAB2_LIB.BASEBOARD_FAB2(SCH_1):GND
 1B9    GND GND<18> @BASEBOARD_FAB2_LIB.BASEBOARD_FAB2(SCH_1):GND
 1C3    GND GND<17> @BASEBOARD_FAB2_LIB.BASEBOARD_FAB2(SCH_1):GND
 1C6    GND GND<16> @BASEBOARD_FAB2_LIB.BASEBOARD_FAB2(SCH_1):GND
 1C9    GND GND<15> @BASEBOARD_FAB2_LIB.BASEBOARD_FAB2(SCH_1):GND
 1D3    GND GND<14> @BASEBOARD_FAB2_LIB.BASEBOARD_FAB2(SCH_1):GND
 1D6    GND GND<13> @BASEBOARD_FAB2_LIB.BASEBOARD_FAB2(SCH_1):GND
 1D9    GND GND<12> @BASEBOARD_FAB2_LIB.BASEBOARD_FAB2(SCH_1):GND
 2A3    GND GND<11> @BASEBOARD_FAB2_LIB.BASEBOARD_FAB2(SCH_1):GND
 2A6    GND GND<10> @BASEBOARD_FAB2_LIB.BASEBOARD_FAB2(SCH_1):GND
 2A9    GND GND<9> @BASEBOARD_FAB2_LIB.BASEBOARD_FAB2(SCH_1):GND
 2B3    GND GND<8> @BASEBOARD_FAB2_LIB.BASEBOARD_FAB2(SCH_1):GND
 2B6    GND GND<7> @BASEBOARD_FAB2_LIB.BASEBOARD_FAB2(SCH_1):GND
 2B9    GND GND<6> @BASEBOARD_FAB2_LIB.BASEBOARD_FAB2(SCH_1):GND
 2C3    GND GND<5> @BASEBOARD_FAB2_LIB.BASEBOARD_FAB2(SCH_1):GND
 2C6    GND GND<4> @BASEBOARD_FAB2_LIB.BASEBOARD_FAB2(SCH_1):GND
 2C9    GND GND<3> @BASEBOARD_FAB2_LIB.BASEBOARD_FAB2(SCH_1):GND
 2D3    GND GND<2> @BASEBOARD_FAB2_LIB.BASEBOARD_FAB2(SCH_1):GND
 2D6    GND GND<1> @BASEBOARD_FAB2_LIB.BASEBOARD_FAB2(SCH_1):GND
 2D9    GND GND<0> @BASEBOARD_FAB2_LIB.BASEBOARD_FAB2(SCH_1):GND
 1B5 SATA6G_P0_RX_C_DN RXA0_DN @BASEBOARD_FAB2_LIB.BASEBOARD_FAB2(SCH_1):SATA6G_P0_RX_C_DN
 1B4 SATA6G_P0_RX_C_DP RXA0_DP @BASEBOARD_FAB2_LIB.BASEBOARD_FAB2(SCH_1):SATA6G_P0_RX_C_DP
 1A5 SATA6G_P1_RX_C_DN RXA1_DN @BASEBOARD_FAB2_LIB.BASEBOARD_FAB2(SCH_1):SATA6G_P1_RX_C_DN
 1A4 SATA6G_P1_RX_C_DP RXA1_DP @BASEBOARD_FAB2_LIB.BASEBOARD_FAB2(SCH_1):SATA6G_P1_RX_C_DP
 1B8 SATA6G_P2_RX_C_DN RXA2_DN @BASEBOARD_FAB2_LIB.BASEBOARD_FAB2(SCH_1):SATA6G_P2_RX_C_DN
 1B7 SATA6G_P2_RX_C_DP RXA2_DP @BASEBOARD_FAB2_LIB.BASEBOARD_FAB2(SCH_1):SATA6G_P2_RX_C_DP
 1A8 SATA6G_P3_RX_C_DN RXA3_DN @BASEBOARD_FAB2_LIB.BASEBOARD_FAB2(SCH_1):SATA6G_P3_RX_C_DN
 1A7 SATA6G_P3_RX_C_DP RXA3_DP @BASEBOARD_FAB2_LIB.BASEBOARD_FAB2(SCH_1):SATA6G_P3_RX_C_DP
 2B5 SATA6G_P4_RX_C_DN RXB0_DN @BASEBOARD_FAB2_LIB.BASEBOARD_FAB2(SCH_1):SATA6G_P4_RX_C_DN
 2B4 SATA6G_P4_RX_C_DP RXB0_DP @BASEBOARD_FAB2_LIB.BASEBOARD_FAB2(SCH_1):SATA6G_P4_RX_C_DP
 2A5 SATA6G_P5_RX_C_DN RXB1_DN @BASEBOARD_FAB2_LIB.BASEBOARD_FAB2(SCH_1):SATA6G_P5_RX_C_DN
 2A4 SATA6G_P5_RX_C_DP RXB1_DP @BASEBOARD_FAB2_LIB.BASEBOARD_FAB2(SCH_1):SATA6G_P5_RX_C_DP
 2B8 SATA6G_P6_RX_C_DN RXB2_DN @BASEBOARD_FAB2_LIB.BASEBOARD_FAB2(SCH_1):SATA6G_P6_RX_C_DN
 2B7 SATA6G_P6_RX_C_DP RXB2_DP @BASEBOARD_FAB2_LIB.BASEBOARD_FAB2(SCH_1):SATA6G_P6_RX_C_DP
 2A8 SATA6G_P7_RX_C_DN RXB3_DN @BASEBOARD_FAB2_LIB.BASEBOARD_FAB2(SCH_1):SATA6G_P7_RX_C_DN
 2A7 SATA6G_P7_RX_C_DP RXB3_DP @BASEBOARD_FAB2_LIB.BASEBOARD_FAB2(SCH_1):SATA6G_P7_RX_C_DP
 1A2 SGPIO_PCH_SATA_CLOCK_R SIDEBANDA_0 @BASEBOARD_FAB2_LIB.BASEBOARD_FAB2(SCH_1):SGPIO_PCH_SATA_CLOCK_R
 1B2 SGPIO_PCH_SATA_LOAD_R SIDEBANDA_1 @BASEBOARD_FAB2_LIB.BASEBOARD_FAB2(SCH_1):SGPIO_PCH_SATA_LOAD_R
 1C2    GND SIDEBANDA_2 @BASEBOARD_FAB2_LIB.BASEBOARD_FAB2(SCH_1):GND
 1B1    GND SIDEBANDA_3 @BASEBOARD_FAB2_LIB.BASEBOARD_FAB2(SCH_1):GND
 1C1 SGPIO_PCH_SATA_DOUT0_R SIDEBANDA_4 @BASEBOARD_FAB2_LIB.BASEBOARD_FAB2(SCH_1):SGPIO_PCH_SATA_DOUT0_R
 1D1 PU_DATAIN1_SATA_0_R SIDEBANDA_5 @BASEBOARD_FAB2_LIB.BASEBOARD_FAB2(SCH_1):PU_DATAIN1_SATA_0_R
 1D2 PD_SATA0_CONTROLLER_TYPE_R SIDEBANDA_6 @BASEBOARD_FAB2_LIB.BASEBOARD_FAB2(SCH_1):PD_SATA0_CONTROLLER_TYPE_R
 1A1 TP_FM_QAT_CBL_PRSNT0_R_N SIDEBANDA_7 @BASEBOARD_FAB2_LIB.BASEBOARD_FAB2(SCH_1):TP_FM_QAT_CBL_PRSNT0_R_N
 2A2 TP_SGPIO_SATA_CLOCK1_R SIDEBANDB_0 @BASEBOARD_FAB2_LIB.BASEBOARD_FAB2(SCH_1):TP_SGPIO_SATA_CLOCK1_R
 2B2 TP_SGPIO_SATA_LOAD1_R SIDEBANDB_1 @BASEBOARD_FAB2_LIB.BASEBOARD_FAB2(SCH_1):TP_SGPIO_SATA_LOAD1_R
 2C2    GND SIDEBANDB_2 @BASEBOARD_FAB2_LIB.BASEBOARD_FAB2(SCH_1):GND
 2B1    GND SIDEBANDB_3 @BASEBOARD_FAB2_LIB.BASEBOARD_FAB2(SCH_1):GND
 2C1 TP_SGPIO_SATA_DATA1_R SIDEBANDB_4 @BASEBOARD_FAB2_LIB.BASEBOARD_FAB2(SCH_1):TP_SGPIO_SATA_DATA1_R
 2D1 PU_DATAIN1_SATA_1_R SIDEBANDB_5 @BASEBOARD_FAB2_LIB.BASEBOARD_FAB2(SCH_1):PU_DATAIN1_SATA_1_R
 2D2 PD_SATA1_CONTROLLER_TYPE_R SIDEBANDB_6 @BASEBOARD_FAB2_LIB.BASEBOARD_FAB2(SCH_1):PD_SATA1_CONTROLLER_TYPE_R
 2A1 TP_FM_QAT_CBL_PRSNT1_N_R SIDEBANDB_7 @BASEBOARD_FAB2_LIB.BASEBOARD_FAB2(SCH_1):TP_FM_QAT_CBL_PRSNT1_N_R
 1D5 SATA6G_P0_TX_C_DN TXA0_DN @BASEBOARD_FAB2_LIB.BASEBOARD_FAB2(SCH_1):SATA6G_P0_TX_C_DN
 1D4 SATA6G_P0_TX_C_DP TXA0_DP @BASEBOARD_FAB2_LIB.BASEBOARD_FAB2(SCH_1):SATA6G_P0_TX_C_DP
 1C5 SATA6G_P1_TX_C_DN TXA1_DN @BASEBOARD_FAB2_LIB.BASEBOARD_FAB2(SCH_1):SATA6G_P1_TX_C_DN
 1C4 SATA6G_P1_TX_C_DP TXA1_DP @BASEBOARD_FAB2_LIB.BASEBOARD_FAB2(SCH_1):SATA6G_P1_TX_C_DP
 1D8 SATA6G_P2_TX_C_DN TXA2_DN @BASEBOARD_FAB2_LIB.BASEBOARD_FAB2(SCH_1):SATA6G_P2_TX_C_DN
 1D7 SATA6G_P2_TX_C_DP TXA2_DP @BASEBOARD_FAB2_LIB.BASEBOARD_FAB2(SCH_1):SATA6G_P2_TX_C_DP
 1C8 SATA6G_P3_TX_C_DN TXA3_DN @BASEBOARD_FAB2_LIB.BASEBOARD_FAB2(SCH_1):SATA6G_P3_TX_C_DN
 1C7 SATA6G_P3_TX_C_DP TXA3_DP @BASEBOARD_FAB2_LIB.BASEBOARD_FAB2(SCH_1):SATA6G_P3_TX_C_DP
 2D5 SATA6G_P4_TX_C_DN TXB0_DN @BASEBOARD_FAB2_LIB.BASEBOARD_FAB2(SCH_1):SATA6G_P4_TX_C_DN
 2D4 SATA6G_P4_TX_C_DP TXB0_DP @BASEBOARD_FAB2_LIB.BASEBOARD_FAB2(SCH_1):SATA6G_P4_TX_C_DP
 2C5 SATA6G_P5_TX_C_DN TXB1_DN @BASEBOARD_FAB2_LIB.BASEBOARD_FAB2(SCH_1):SATA6G_P5_TX_C_DN
 2C4 SATA6G_P5_TX_C_DP TXB1_DP @BASEBOARD_FAB2_LIB.BASEBOARD_FAB2(SCH_1):SATA6G_P5_TX_C_DP
 2D8 SATA6G_P6_TX_C_DN TXB2_DN @BASEBOARD_FAB2_LIB.BASEBOARD_FAB2(SCH_1):SATA6G_P6_TX_C_DN
 2D7 SATA6G_P6_TX_C_DP TXB2_DP @BASEBOARD_FAB2_LIB.BASEBOARD_FAB2(SCH_1):SATA6G_P6_TX_C_DP
 2C8 SATA6G_P7_TX_C_DN TXB3_DN @BASEBOARD_FAB2_LIB.BASEBOARD_FAB2(SCH_1):SATA6G_P7_TX_C_DN
 2C7 SATA6G_P7_TX_C_DP TXB3_DP @BASEBOARD_FAB2_LIB.BASEBOARD_FAB2(SCH_1):SATA6G_P7_TX_C_DP

CAP_A_0402V-0.01UF,25V,10%,X7RA  I165  C2L13
   1 SATA6G_PCH_PCIE_UP_SATA_RXN<2>      A @BASEBOARD_FAB2_LIB.BASEBOARD_FAB2(SCH_1):SATA6G_PCH_PCIE_UP_SATA_RXN(2)
   2 SATA6G_P2_RX_C_DN      B @BASEBOARD_FAB2_LIB.BASEBOARD_FAB2(SCH_1):SATA6G_P2_RX_C_DN

CAP_A_0402V-0.01UF,25V,10%,X7RA  I166  C2L6
   1 SATA6G_PCH_PCIE_UP_SATA_RXN<1>      A @BASEBOARD_FAB2_LIB.BASEBOARD_FAB2(SCH_1):SATA6G_PCH_PCIE_UP_SATA_RXN(1)
   2 SATA6G_P1_RX_C_DN      B @BASEBOARD_FAB2_LIB.BASEBOARD_FAB2(SCH_1):SATA6G_P1_RX_C_DN

CAP_A_0402V-0.01UF,25V,10%,X7RA  I172  C2L19
   1 SATA6G_PCH_PCIE_UP_SATA_RXP<0>      A @BASEBOARD_FAB2_LIB.BASEBOARD_FAB2(SCH_1):SATA6G_PCH_PCIE_UP_SATA_RXP(0)
   2 SATA6G_P0_RX_C_DP      B @BASEBOARD_FAB2_LIB.BASEBOARD_FAB2(SCH_1):SATA6G_P0_RX_C_DP

CAP_A_0402V-0.01UF,25V,10%,X7RA  I173  C2L10
   1 SATA6G_PCH_PCIE_UP_SATA_RXP<1>      A @BASEBOARD_FAB2_LIB.BASEBOARD_FAB2(SCH_1):SATA6G_PCH_PCIE_UP_SATA_RXP(1)
   2 SATA6G_P1_RX_C_DP      B @BASEBOARD_FAB2_LIB.BASEBOARD_FAB2(SCH_1):SATA6G_P1_RX_C_DP

CAP_A_0402V-0.01UF,25V,10%,X7RA  I174  C2L17
   1 SATA6G_PCH_PCIE_UP_SATA_RXN<0>      A @BASEBOARD_FAB2_LIB.BASEBOARD_FAB2(SCH_1):SATA6G_PCH_PCIE_UP_SATA_RXN(0)
   2 SATA6G_P0_RX_C_DN      B @BASEBOARD_FAB2_LIB.BASEBOARD_FAB2(SCH_1):SATA6G_P0_RX_C_DN

CAP_A_0402V-0.01UF,25V,10%,X7RA  I191  C2L15
   1 SATA6G_PCH_PCIE_UP_SATA_RXP<2>      A @BASEBOARD_FAB2_LIB.BASEBOARD_FAB2(SCH_1):SATA6G_PCH_PCIE_UP_SATA_RXP(2)
   2 SATA6G_P2_RX_C_DP      B @BASEBOARD_FAB2_LIB.BASEBOARD_FAB2(SCH_1):SATA6G_P2_RX_C_DP

CAP_A_0402V-0.01UF,25V,10%,X7RA  I192  C2L4
   1 SATA6G_PCH_PCIE_UP_SATA_RXP<3>      A @BASEBOARD_FAB2_LIB.BASEBOARD_FAB2(SCH_1):SATA6G_PCH_PCIE_UP_SATA_RXP(3)
   2 SATA6G_P3_RX_C_DP      B @BASEBOARD_FAB2_LIB.BASEBOARD_FAB2(SCH_1):SATA6G_P3_RX_C_DP

CAP_A_0402V-0.01UF,25V,10%,X7RA  I194  C2L3
   1 SATA6G_PCH_PCIE_UP_SATA_RXN<3>      A @BASEBOARD_FAB2_LIB.BASEBOARD_FAB2(SCH_1):SATA6G_PCH_PCIE_UP_SATA_RXN(3)
   2 SATA6G_P3_RX_C_DN      B @BASEBOARD_FAB2_LIB.BASEBOARD_FAB2(SCH_1):SATA6G_P3_RX_C_DN

CAP_A_0402V-0.01UF,25V,10%,X7RA  I195  C2L20
   1 SATA6G_PCH_PCIE_UP_SATA_RXP<4>      A @BASEBOARD_FAB2_LIB.BASEBOARD_FAB2(SCH_1):SATA6G_PCH_PCIE_UP_SATA_RXP(4)
   2 SATA6G_P4_RX_C_DP      B @BASEBOARD_FAB2_LIB.BASEBOARD_FAB2(SCH_1):SATA6G_P4_RX_C_DP

CAP_A_0402V-0.01UF,25V,10%,X7RA  I196  C2L12
   1 SATA6G_PCH_PCIE_UP_SATA_RXP<5>      A @BASEBOARD_FAB2_LIB.BASEBOARD_FAB2(SCH_1):SATA6G_PCH_PCIE_UP_SATA_RXP(5)
   2 SATA6G_P5_RX_C_DP      B @BASEBOARD_FAB2_LIB.BASEBOARD_FAB2(SCH_1):SATA6G_P5_RX_C_DP

CAP_A_0402V-0.01UF,25V,10%,X7RA  I197  C2L18
   1 SATA6G_PCH_PCIE_UP_SATA_RXN<4>      A @BASEBOARD_FAB2_LIB.BASEBOARD_FAB2(SCH_1):SATA6G_PCH_PCIE_UP_SATA_RXN(4)
   2 SATA6G_P4_RX_C_DN      B @BASEBOARD_FAB2_LIB.BASEBOARD_FAB2(SCH_1):SATA6G_P4_RX_C_DN

CAP_A_0402V-0.01UF,25V,10%,X7RA  I205  C2L16
   1 SATA6G_PCH_PCIE_UP_SATA_RXP<6>      A @BASEBOARD_FAB2_LIB.BASEBOARD_FAB2(SCH_1):SATA6G_PCH_PCIE_UP_SATA_RXP(6)
   2 SATA6G_P6_RX_C_DP      B @BASEBOARD_FAB2_LIB.BASEBOARD_FAB2(SCH_1):SATA6G_P6_RX_C_DP

CAP_A_0402V-0.01UF,25V,10%,X7RA  I206  C2L7
   1 SATA6G_PCH_PCIE_UP_SATA_RXP<7>      A @BASEBOARD_FAB2_LIB.BASEBOARD_FAB2(SCH_1):SATA6G_PCH_PCIE_UP_SATA_RXP(7)
   2 SATA6G_P7_RX_C_DP      B @BASEBOARD_FAB2_LIB.BASEBOARD_FAB2(SCH_1):SATA6G_P7_RX_C_DP

CAP_A_0402V-0.01UF,25V,10%,X7RA  I207  C2L9
   1 SATA6G_PCH_PCIE_UP_SATA_RXN<5>      A @BASEBOARD_FAB2_LIB.BASEBOARD_FAB2(SCH_1):SATA6G_PCH_PCIE_UP_SATA_RXN(5)
   2 SATA6G_P5_RX_C_DN      B @BASEBOARD_FAB2_LIB.BASEBOARD_FAB2(SCH_1):SATA6G_P5_RX_C_DN

CAP_A_0402V-0.01UF,25V,10%,X7RA  I208  C2L14
   1 SATA6G_PCH_PCIE_UP_SATA_RXN<6>      A @BASEBOARD_FAB2_LIB.BASEBOARD_FAB2(SCH_1):SATA6G_PCH_PCIE_UP_SATA_RXN(6)
   2 SATA6G_P6_RX_C_DN      B @BASEBOARD_FAB2_LIB.BASEBOARD_FAB2(SCH_1):SATA6G_P6_RX_C_DN

CAP_A_0402V-0.01UF,25V,10%,X7RA  I209  C2L5
   1 SATA6G_PCH_PCIE_UP_SATA_RXN<7>      A @BASEBOARD_FAB2_LIB.BASEBOARD_FAB2(SCH_1):SATA6G_PCH_PCIE_UP_SATA_RXN(7)
   2 SATA6G_P7_RX_C_DN      B @BASEBOARD_FAB2_LIB.BASEBOARD_FAB2(SCH_1):SATA6G_P7_RX_C_DN

CAP_A_0402V-0.01UF,25V,10%,X7RA  I220  C2L40
   1 SATA6G_P0_TX_C_DN      A @BASEBOARD_FAB2_LIB.BASEBOARD_FAB2(SCH_1):SATA6G_P0_TX_C_DN
   2 SATA6G_PCH_PCIE_UP_SATA_TXN<0>      B @BASEBOARD_FAB2_LIB.BASEBOARD_FAB2(SCH_1):SATA6G_PCH_PCIE_UP_SATA_TXN(0)

CAP_A_0402V-0.01UF,25V,10%,X7RA  I221  C2L39
   1 SATA6G_P0_TX_C_DP      A @BASEBOARD_FAB2_LIB.BASEBOARD_FAB2(SCH_1):SATA6G_P0_TX_C_DP
   2 SATA6G_PCH_PCIE_UP_SATA_TXP<0>      B @BASEBOARD_FAB2_LIB.BASEBOARD_FAB2(SCH_1):SATA6G_PCH_PCIE_UP_SATA_TXP(0)

CAP_A_0402V-0.01UF,25V,10%,X7RA  I222  C2L43
   1 SATA6G_P1_TX_C_DP      A @BASEBOARD_FAB2_LIB.BASEBOARD_FAB2(SCH_1):SATA6G_P1_TX_C_DP
   2 SATA6G_PCH_PCIE_UP_SATA_TXP<1>      B @BASEBOARD_FAB2_LIB.BASEBOARD_FAB2(SCH_1):SATA6G_PCH_PCIE_UP_SATA_TXP(1)

CAP_A_0402V-0.01UF,25V,10%,X7RA  I228  C2L44
   1 SATA6G_P1_TX_C_DN      A @BASEBOARD_FAB2_LIB.BASEBOARD_FAB2(SCH_1):SATA6G_P1_TX_C_DN
   2 SATA6G_PCH_PCIE_UP_SATA_TXN<1>      B @BASEBOARD_FAB2_LIB.BASEBOARD_FAB2(SCH_1):SATA6G_PCH_PCIE_UP_SATA_TXN(1)

CAP_A_0402V-0.01UF,25V,10%,X7RA  I233  C2L42
   1 SATA6G_P2_TX_C_DN      A @BASEBOARD_FAB2_LIB.BASEBOARD_FAB2(SCH_1):SATA6G_P2_TX_C_DN
   2 SATA6G_PCH_PCIE_UP_SATA_TXN<2>      B @BASEBOARD_FAB2_LIB.BASEBOARD_FAB2(SCH_1):SATA6G_PCH_PCIE_UP_SATA_TXN(2)

CAP_A_0402V-0.01UF,25V,10%,X7RA  I234  C2L22
   1 SATA6G_P3_TX_C_DN      A @BASEBOARD_FAB2_LIB.BASEBOARD_FAB2(SCH_1):SATA6G_P3_TX_C_DN
   2 SATA6G_PCH_PCIE_UP_SATA_TXN<3>      B @BASEBOARD_FAB2_LIB.BASEBOARD_FAB2(SCH_1):SATA6G_PCH_PCIE_UP_SATA_TXN(3)

CAP_A_0402V-0.01UF,25V,10%,X7RA  I238  C2L37
   1 SATA6G_P4_TX_C_DN      A @BASEBOARD_FAB2_LIB.BASEBOARD_FAB2(SCH_1):SATA6G_P4_TX_C_DN
   2 SATA6G_PCH_PCIE_UP_SATA_TXN<4>      B @BASEBOARD_FAB2_LIB.BASEBOARD_FAB2(SCH_1):SATA6G_PCH_PCIE_UP_SATA_TXN(4)

CAP_A_0402V-0.01UF,25V,10%,X7RA  I239  C2L47
   1 SATA6G_P4_TX_C_DP      A @BASEBOARD_FAB2_LIB.BASEBOARD_FAB2(SCH_1):SATA6G_P4_TX_C_DP
   2 SATA6G_PCH_PCIE_UP_SATA_TXP<4>      B @BASEBOARD_FAB2_LIB.BASEBOARD_FAB2(SCH_1):SATA6G_PCH_PCIE_UP_SATA_TXP(4)

CAP_A_0402V-0.01UF,25V,10%,X7RA  I240  C2L27
   1 SATA6G_P5_TX_C_DP      A @BASEBOARD_FAB2_LIB.BASEBOARD_FAB2(SCH_1):SATA6G_P5_TX_C_DP
   2 SATA6G_PCH_PCIE_UP_SATA_TXP<5>      B @BASEBOARD_FAB2_LIB.BASEBOARD_FAB2(SCH_1):SATA6G_PCH_PCIE_UP_SATA_TXP(5)

CAP_A_0402V-0.01UF,25V,10%,X7RA  I241  C2L23
   1 SATA6G_P3_TX_C_DP      A @BASEBOARD_FAB2_LIB.BASEBOARD_FAB2(SCH_1):SATA6G_P3_TX_C_DP
   2 SATA6G_PCH_PCIE_UP_SATA_TXP<3>      B @BASEBOARD_FAB2_LIB.BASEBOARD_FAB2(SCH_1):SATA6G_PCH_PCIE_UP_SATA_TXP(3)

CAP_A_0402V-0.01UF,25V,10%,X7RA  I242  C2L41
   1 SATA6G_P2_TX_C_DP      A @BASEBOARD_FAB2_LIB.BASEBOARD_FAB2(SCH_1):SATA6G_P2_TX_C_DP
   2 SATA6G_PCH_PCIE_UP_SATA_TXP<2>      B @BASEBOARD_FAB2_LIB.BASEBOARD_FAB2(SCH_1):SATA6G_PCH_PCIE_UP_SATA_TXP(2)

CAP_A_0402V-0.01UF,25V,10%,X7RA  I255  C2L26
   1 SATA6G_P5_TX_C_DN      A @BASEBOARD_FAB2_LIB.BASEBOARD_FAB2(SCH_1):SATA6G_P5_TX_C_DN
   2 SATA6G_PCH_PCIE_UP_SATA_TXN<5>      B @BASEBOARD_FAB2_LIB.BASEBOARD_FAB2(SCH_1):SATA6G_PCH_PCIE_UP_SATA_TXN(5)

CAP_A_0402V-0.01UF,25V,10%,X7RA  I256  C2L38
   1 SATA6G_P6_TX_C_DN      A @BASEBOARD_FAB2_LIB.BASEBOARD_FAB2(SCH_1):SATA6G_P6_TX_C_DN
   2 SATA6G_PCH_PCIE_UP_SATA_TXN<6>      B @BASEBOARD_FAB2_LIB.BASEBOARD_FAB2(SCH_1):SATA6G_PCH_PCIE_UP_SATA_TXN(6)

CAP_A_0402V-0.01UF,25V,10%,X7RA  I257  C2L48
   1 SATA6G_P6_TX_C_DP      A @BASEBOARD_FAB2_LIB.BASEBOARD_FAB2(SCH_1):SATA6G_P6_TX_C_DP
   2 SATA6G_PCH_PCIE_UP_SATA_TXP<6>      B @BASEBOARD_FAB2_LIB.BASEBOARD_FAB2(SCH_1):SATA6G_PCH_PCIE_UP_SATA_TXP(6)

CAP_A_0402V-0.01UF,25V,10%,X7RA  I258  C2L24
   1 SATA6G_P7_TX_C_DP      A @BASEBOARD_FAB2_LIB.BASEBOARD_FAB2(SCH_1):SATA6G_P7_TX_C_DP
   2 SATA6G_PCH_PCIE_UP_SATA_TXP<7>      B @BASEBOARD_FAB2_LIB.BASEBOARD_FAB2(SCH_1):SATA6G_PCH_PCIE_UP_SATA_TXP(7)

CAP_A_0402V-0.01UF,25V,10%,X7RA  I259  C2L21
   1 SATA6G_P7_TX_C_DN      A @BASEBOARD_FAB2_LIB.BASEBOARD_FAB2(SCH_1):SATA6G_P7_TX_C_DN
   2 SATA6G_PCH_PCIE_UP_SATA_TXN<7>      B @BASEBOARD_FAB2_LIB.BASEBOARD_FAB2(SCH_1):SATA6G_PCH_PCIE_UP_SATA_TXN(7)

RES_0402-2.0K,1%,1/16W,CHIP,G2A  I261  R2L23
   1   P3V3      A @BASEBOARD_FAB2_LIB.BASEBOARD_FAB2(SCH_1):P3V3
   2 PU_DATAIN1_SATA_1_R      B @BASEBOARD_FAB2_LIB.BASEBOARD_FAB2(SCH_1):PU_DATAIN1_SATA_1_R

RES_0402-2.0K,1%,1/16W,CHIP,G2A  I263  R2L21
   1   P3V3      A @BASEBOARD_FAB2_LIB.BASEBOARD_FAB2(SCH_1):P3V3
   2 PU_DATAIN1_SATA_0_R      B @BASEBOARD_FAB2_LIB.BASEBOARD_FAB2(SCH_1):PU_DATAIN1_SATA_0_R

RES_0402-1.00K,1%,1/16W,CHIP,GA  I264  R2L22
   1 PD_SATA1_CONTROLLER_TYPE_R      A @BASEBOARD_FAB2_LIB.BASEBOARD_FAB2(SCH_1):PD_SATA1_CONTROLLER_TYPE_R
   2    GND      B @BASEBOARD_FAB2_LIB.BASEBOARD_FAB2(SCH_1):GND

RES_0402-1.00K,1%,1/16W,CHIP,GA  I266  R2L18
   1 PD_SATA0_CONTROLLER_TYPE_R      A @BASEBOARD_FAB2_LIB.BASEBOARD_FAB2(SCH_1):PD_SATA0_CONTROLLER_TYPE_R
   2    GND      B @BASEBOARD_FAB2_LIB.BASEBOARD_FAB2(SCH_1):GND


DRAWING: @BASEBOARD_FAB2_LIB.BASEBOARD_FAB2(SCH_1):PAGE174 

RES_0402-1.00K,1%,1/16W,CHIP,GA  I5  R1L3
   1 PD_SATA2_CONTROLLER_TYPE      A @BASEBOARD_FAB2_LIB.BASEBOARD_FAB2(SCH_1):PD_SATA2_CONTROLLER_TYPE
   2    GND      B @BASEBOARD_FAB2_LIB.BASEBOARD_FAB2(SCH_1):GND

CAP_A_0402V-0.01UF,25V,10%,X7RA  I8  C1L3
   1 SATA6G_P8_TX_C_DN      A @BASEBOARD_FAB2_LIB.BASEBOARD_FAB2(SCH_1):SATA6G_P8_TX_C_DN
   2 SATA6G_TX_DN<0>      B @BASEBOARD_FAB2_LIB.BASEBOARD_FAB2(SCH_1):SATA6G_TX_DN(0)

CAP_A_0402V-0.01UF,25V,10%,X7RA  I9  C1L2
   1 SATA6G_P8_TX_C_DP      A @BASEBOARD_FAB2_LIB.BASEBOARD_FAB2(SCH_1):SATA6G_P8_TX_C_DP
   2 SATA6G_TX_DP<0>      B @BASEBOARD_FAB2_LIB.BASEBOARD_FAB2(SCH_1):SATA6G_TX_DP(0)

CAP_A_0402V-0.01UF,25V,10%,X7RA  I12  C1L7
   1 SATA6G_P9_TX_C_DN      A @BASEBOARD_FAB2_LIB.BASEBOARD_FAB2(SCH_1):SATA6G_P9_TX_C_DN
   2 SATA6G_TX_DN<1>      B @BASEBOARD_FAB2_LIB.BASEBOARD_FAB2(SCH_1):SATA6G_TX_DN(1)

CAP_A_0402V-0.01UF,25V,10%,X7RA  I13  C1L6
   1 SATA6G_P9_TX_C_DP      A @BASEBOARD_FAB2_LIB.BASEBOARD_FAB2(SCH_1):SATA6G_P9_TX_C_DP
   2 SATA6G_TX_DP<1>      B @BASEBOARD_FAB2_LIB.BASEBOARD_FAB2(SCH_1):SATA6G_TX_DP(1)

CAP_A_0402V-0.01UF,25V,10%,X7RA  I14  C1L13
   1 SATA6G_P10_TX_C_DN      A @BASEBOARD_FAB2_LIB.BASEBOARD_FAB2(SCH_1):SATA6G_P10_TX_C_DN
   2 SATA6G_TX_DN<2>      B @BASEBOARD_FAB2_LIB.BASEBOARD_FAB2(SCH_1):SATA6G_TX_DN(2)

CAP_A_0402V-0.01UF,25V,10%,X7RA  I18  C1L15
   1 SATA6G_P11_TX_C_DN      A @BASEBOARD_FAB2_LIB.BASEBOARD_FAB2(SCH_1):SATA6G_P11_TX_C_DN
   2 SATA6G_TX_DN<3>      B @BASEBOARD_FAB2_LIB.BASEBOARD_FAB2(SCH_1):SATA6G_TX_DN(3)

CAP_A_0402V-0.01UF,25V,10%,X7RA  I19  C1L12
   1 SATA6G_P10_TX_C_DP      A @BASEBOARD_FAB2_LIB.BASEBOARD_FAB2(SCH_1):SATA6G_P10_TX_C_DP
   2 SATA6G_TX_DP<2>      B @BASEBOARD_FAB2_LIB.BASEBOARD_FAB2(SCH_1):SATA6G_TX_DP(2)

CAP_A_0402V-0.01UF,25V,10%,X7RA  I20  C1L14
   1 SATA6G_P11_TX_C_DP      A @BASEBOARD_FAB2_LIB.BASEBOARD_FAB2(SCH_1):SATA6G_P11_TX_C_DP
   2 SATA6G_TX_DP<3>      B @BASEBOARD_FAB2_LIB.BASEBOARD_FAB2(SCH_1):SATA6G_TX_DP(3)

RES_0402-2.0K,1%,1/16W,CHIP,G2A  I25  R1L1
   1   P3V3      A @BASEBOARD_FAB2_LIB.BASEBOARD_FAB2(SCH_1):P3V3
   2 PU_DATAIN1_SATA_2      B @BASEBOARD_FAB2_LIB.BASEBOARD_FAB2(SCH_1):PU_DATAIN1_SATA_2

CONN36_G97614001_CP-CONN,G9761A  I26  J8A2
  A3    GND   GND1 @BASEBOARD_FAB2_LIB.BASEBOARD_FAB2(SCH_1):GND
  D3    GND  GND10 @BASEBOARD_FAB2_LIB.BASEBOARD_FAB2(SCH_1):GND
  D6    GND  GND11 @BASEBOARD_FAB2_LIB.BASEBOARD_FAB2(SCH_1):GND
  D9    GND  GND12 @BASEBOARD_FAB2_LIB.BASEBOARD_FAB2(SCH_1):GND
  A6    GND   GND2 @BASEBOARD_FAB2_LIB.BASEBOARD_FAB2(SCH_1):GND
  A9    GND   GND3 @BASEBOARD_FAB2_LIB.BASEBOARD_FAB2(SCH_1):GND
  B3    GND   GND4 @BASEBOARD_FAB2_LIB.BASEBOARD_FAB2(SCH_1):GND
  B6    GND   GND5 @BASEBOARD_FAB2_LIB.BASEBOARD_FAB2(SCH_1):GND
  B9    GND   GND6 @BASEBOARD_FAB2_LIB.BASEBOARD_FAB2(SCH_1):GND
  C3    GND   GND7 @BASEBOARD_FAB2_LIB.BASEBOARD_FAB2(SCH_1):GND
  C6    GND   GND8 @BASEBOARD_FAB2_LIB.BASEBOARD_FAB2(SCH_1):GND
  C9    GND   GND9 @BASEBOARD_FAB2_LIB.BASEBOARD_FAB2(SCH_1):GND
  B5 SATA6G_P8_RX_C_DN RXA0_DN @BASEBOARD_FAB2_LIB.BASEBOARD_FAB2(SCH_1):SATA6G_P8_RX_C_DN
  B4 SATA6G_P8_RX_C_DP RXA0_DP @BASEBOARD_FAB2_LIB.BASEBOARD_FAB2(SCH_1):SATA6G_P8_RX_C_DP
  A5 SATA6G_P9_RX_C_DN RXA1_DN @BASEBOARD_FAB2_LIB.BASEBOARD_FAB2(SCH_1):SATA6G_P9_RX_C_DN
  A4 SATA6G_P9_RX_C_DP RXA1_DP @BASEBOARD_FAB2_LIB.BASEBOARD_FAB2(SCH_1):SATA6G_P9_RX_C_DP
  B8 SATA6G_P10_RX_C_DN RXA2_DN @BASEBOARD_FAB2_LIB.BASEBOARD_FAB2(SCH_1):SATA6G_P10_RX_C_DN
  B7 SATA6G_P10_RX_C_DP RXA2_DP @BASEBOARD_FAB2_LIB.BASEBOARD_FAB2(SCH_1):SATA6G_P10_RX_C_DP
  A8 SATA6G_P11_RX_C_DN RXA3_DN @BASEBOARD_FAB2_LIB.BASEBOARD_FAB2(SCH_1):SATA6G_P11_RX_C_DN
  A7 SATA6G_P11_RX_C_DP RXA3_DP @BASEBOARD_FAB2_LIB.BASEBOARD_FAB2(SCH_1):SATA6G_P11_RX_C_DP
  A2 SGPIO_PCH_SSATA_CLOCK_R SIDEBAND0 @BASEBOARD_FAB2_LIB.BASEBOARD_FAB2(SCH_1):SGPIO_PCH_SSATA_CLOCK_R
  B2 SGPIO_PCH_SSATA_LOAD_R SIDEBAND1 @BASEBOARD_FAB2_LIB.BASEBOARD_FAB2(SCH_1):SGPIO_PCH_SSATA_LOAD_R
  C2    GND SIDEBAND2 @BASEBOARD_FAB2_LIB.BASEBOARD_FAB2(SCH_1):GND
  B1    GND SIDEBAND3 @BASEBOARD_FAB2_LIB.BASEBOARD_FAB2(SCH_1):GND
  C1 SGPIO_PCH_SSATA_DOUT0_R SIDEBAND4 @BASEBOARD_FAB2_LIB.BASEBOARD_FAB2(SCH_1):SGPIO_PCH_SSATA_DOUT0_R
  D1 PU_DATAIN1_SATA_2 SIDEBAND5 @BASEBOARD_FAB2_LIB.BASEBOARD_FAB2(SCH_1):PU_DATAIN1_SATA_2
  D2 PD_SATA2_CONTROLLER_TYPE SIDEBAND6 @BASEBOARD_FAB2_LIB.BASEBOARD_FAB2(SCH_1):PD_SATA2_CONTROLLER_TYPE
  A1 TP_FM_QAT_CBL_PRSNT2_N SIDEBAND7 @BASEBOARD_FAB2_LIB.BASEBOARD_FAB2(SCH_1):TP_FM_QAT_CBL_PRSNT2_N
  D5 SATA6G_P8_TX_C_DN TXA0_DN @BASEBOARD_FAB2_LIB.BASEBOARD_FAB2(SCH_1):SATA6G_P8_TX_C_DN
  D4 SATA6G_P8_TX_C_DP TXA0_DP @BASEBOARD_FAB2_LIB.BASEBOARD_FAB2(SCH_1):SATA6G_P8_TX_C_DP
  C5 SATA6G_P9_TX_C_DN TXA1_DN @BASEBOARD_FAB2_LIB.BASEBOARD_FAB2(SCH_1):SATA6G_P9_TX_C_DN
  C4 SATA6G_P9_TX_C_DP TXA1_DP @BASEBOARD_FAB2_LIB.BASEBOARD_FAB2(SCH_1):SATA6G_P9_TX_C_DP
  D8 SATA6G_P10_TX_C_DN TXA2_DN @BASEBOARD_FAB2_LIB.BASEBOARD_FAB2(SCH_1):SATA6G_P10_TX_C_DN
  D7 SATA6G_P10_TX_C_DP TXA2_DP @BASEBOARD_FAB2_LIB.BASEBOARD_FAB2(SCH_1):SATA6G_P10_TX_C_DP
  C8 SATA6G_P11_TX_C_DN TXA3_DN @BASEBOARD_FAB2_LIB.BASEBOARD_FAB2(SCH_1):SATA6G_P11_TX_C_DN
  C7 SATA6G_P11_TX_C_DP TXA3_DP @BASEBOARD_FAB2_LIB.BASEBOARD_FAB2(SCH_1):SATA6G_P11_TX_C_DP

CAP_A_0402V-0.01UF,25V,10%,X7RA  I28  C2L30
   1 SATA6G_RX_DP<0>      A @BASEBOARD_FAB2_LIB.BASEBOARD_FAB2(SCH_1):SATA6G_RX_DP(0)
   2 SATA6G_P8_RX_C_DP      B @BASEBOARD_FAB2_LIB.BASEBOARD_FAB2(SCH_1):SATA6G_P8_RX_C_DP

CAP_A_0402V-0.01UF,25V,10%,X7RA  I29  C2L31
   1 SATA6G_RX_DN<0>      A @BASEBOARD_FAB2_LIB.BASEBOARD_FAB2(SCH_1):SATA6G_RX_DN(0)
   2 SATA6G_P8_RX_C_DN      B @BASEBOARD_FAB2_LIB.BASEBOARD_FAB2(SCH_1):SATA6G_P8_RX_C_DN

CAP_A_0402V-0.01UF,25V,10%,X7RA  I30  C2L28
   1 SATA6G_RX_DP<1>      A @BASEBOARD_FAB2_LIB.BASEBOARD_FAB2(SCH_1):SATA6G_RX_DP(1)
   2 SATA6G_P9_RX_C_DP      B @BASEBOARD_FAB2_LIB.BASEBOARD_FAB2(SCH_1):SATA6G_P9_RX_C_DP

CAP_A_0402V-0.01UF,25V,10%,X7RA  I31  C2L35
   1 SATA6G_RX_DP<2>      A @BASEBOARD_FAB2_LIB.BASEBOARD_FAB2(SCH_1):SATA6G_RX_DP(2)
   2 SATA6G_P10_RX_C_DP      B @BASEBOARD_FAB2_LIB.BASEBOARD_FAB2(SCH_1):SATA6G_P10_RX_C_DP

CAP_A_0402V-0.01UF,25V,10%,X7RA  I32  C2L29
   1 SATA6G_RX_DN<1>      A @BASEBOARD_FAB2_LIB.BASEBOARD_FAB2(SCH_1):SATA6G_RX_DN(1)
   2 SATA6G_P9_RX_C_DN      B @BASEBOARD_FAB2_LIB.BASEBOARD_FAB2(SCH_1):SATA6G_P9_RX_C_DN

CAP_A_0402V-0.01UF,25V,10%,X7RA  I39  C2L36
   1 SATA6G_RX_DN<2>      A @BASEBOARD_FAB2_LIB.BASEBOARD_FAB2(SCH_1):SATA6G_RX_DN(2)
   2 SATA6G_P10_RX_C_DN      B @BASEBOARD_FAB2_LIB.BASEBOARD_FAB2(SCH_1):SATA6G_P10_RX_C_DN

CAP_A_0402V-0.01UF,25V,10%,X7RA  I40  C2L33
   1 SATA6G_RX_DP<3>      A @BASEBOARD_FAB2_LIB.BASEBOARD_FAB2(SCH_1):SATA6G_RX_DP(3)
   2 SATA6G_P11_RX_C_DP      B @BASEBOARD_FAB2_LIB.BASEBOARD_FAB2(SCH_1):SATA6G_P11_RX_C_DP

CAP_A_0402V-0.01UF,25V,10%,X7RA  I41  C2L34
   1 SATA6G_RX_DN<3>      A @BASEBOARD_FAB2_LIB.BASEBOARD_FAB2(SCH_1):SATA6G_RX_DN(3)
   2 SATA6G_P11_RX_C_DN      B @BASEBOARD_FAB2_LIB.BASEBOARD_FAB2(SCH_1):SATA6G_P11_RX_C_DN


DRAWING: @BASEBOARD_FAB2_LIB.BASEBOARD_FAB2(SCH_1):PAGE175 

RES_0402-200.0,1%,1/16W,CHIP,GA  I4  R1L31
   1 FP_PWR_BTN_R_N      A @BASEBOARD_FAB2_LIB.BASEBOARD_FAB2(SCH_1):FP_PWR_BTN_R_N
   2 FP_PWR_BTN_R1_N      B @BASEBOARD_FAB2_LIB.BASEBOARD_FAB2(SCH_1):FP_PWR_BTN_R1_N

RES_0402-4.75K,1%,1/16W,CHIP,GA  I5  R1L27
   1 P3V3_STBY      A @BASEBOARD_FAB2_LIB.BASEBOARD_FAB2(SCH_1):P3V3_STBY
   2 FP_PWR_BTN_R_N      B @BASEBOARD_FAB2_LIB.BASEBOARD_FAB2(SCH_1):FP_PWR_BTN_R_N

TTL2G14_SMLF-74LVC2G14,IC,D184B  I9  U9A4
   1 FP_PWR_BTN_R1_N   A<0> @BASEBOARD_FAB2_LIB.BASEBOARD_FAB2(SCH_1):FP_PWR_BTN_R1_N
   6 FP_PWR_BTN_BUF1_N   Y<0> @BASEBOARD_FAB2_LIB.BASEBOARD_FAB2(SCH_1):FP_PWR_BTN_BUF1_N

TTL2G14_SMLF-74LVC2G14,IC,D184B  I10  U9A4
   3 FP_PWR_BTN_BUF1_N   A<0> @BASEBOARD_FAB2_LIB.BASEBOARD_FAB2(SCH_1):FP_PWR_BTN_BUF1_N
   4 FM_PWR_BTN_R_N   Y<0> @BASEBOARD_FAB2_LIB.BASEBOARD_FAB2(SCH_1):FM_PWR_BTN_R_N

CAP_A_0402V-1.0UF,6.3V,10%,X6SA  I11  C1L18
   1 FP_PWR_BTN_R1_N      A @BASEBOARD_FAB2_LIB.BASEBOARD_FAB2(SCH_1):FP_PWR_BTN_R1_N
   2    GND      B @BASEBOARD_FAB2_LIB.BASEBOARD_FAB2(SCH_1):GND

RES_0402-33.2,1%,1/16W,CHIP,G2A  I13  R1L26
   1 FM_PWR_BTN_R_N      A @BASEBOARD_FAB2_LIB.BASEBOARD_FAB2(SCH_1):FM_PWR_BTN_R_N
   2 FM_PWR_BTN_N      B @BASEBOARD_FAB2_LIB.BASEBOARD_FAB2(SCH_1):FM_PWR_BTN_N

TTL2G14_SMLF-74LVC2G14,IC,D184B  I15  U9A3
   3 FP_RST_BTN_BUF1_N   A<0> @BASEBOARD_FAB2_LIB.BASEBOARD_FAB2(SCH_1):FP_RST_BTN_BUF1_N
   4 RST_SYSTEM_BTN_BUF_N   Y<0> @BASEBOARD_FAB2_LIB.BASEBOARD_FAB2(SCH_1):RST_SYSTEM_BTN_BUF_N

TTL2G14_SMLF-74LVC2G14,IC,D184B  I18  U9A3
   1 FP_RST_BTN_R_N   A<0> @BASEBOARD_FAB2_LIB.BASEBOARD_FAB2(SCH_1):FP_RST_BTN_R_N
   6 FP_RST_BTN_BUF1_N   Y<0> @BASEBOARD_FAB2_LIB.BASEBOARD_FAB2(SCH_1):FP_RST_BTN_BUF1_N

CAP_A_0402V-1.0UF,6.3V,10%,X6SA  I19  C1L10
   1 FP_RST_BTN_R_N      A @BASEBOARD_FAB2_LIB.BASEBOARD_FAB2(SCH_1):FP_RST_BTN_R_N
   2    GND      B @BASEBOARD_FAB2_LIB.BASEBOARD_FAB2(SCH_1):GND

RES_0402-200.0,1%,1/16W,CHIP,GA  I22  R1L22
   1 FM_DEBUG_RST_BTN_N      A @BASEBOARD_FAB2_LIB.BASEBOARD_FAB2(SCH_1):FM_DEBUG_RST_BTN_N
   2 FP_RST_BTN_R_N      B @BASEBOARD_FAB2_LIB.BASEBOARD_FAB2(SCH_1):FP_RST_BTN_R_N

RES_0402-4.75K,1%,1/16W,EMPTY,A  I24  R1L19
   1 P3V3_STBY      A @BASEBOARD_FAB2_LIB.BASEBOARD_FAB2(SCH_1):P3V3_STBY
   2 FM_DEBUG_RST_BTN_N      B @BASEBOARD_FAB2_LIB.BASEBOARD_FAB2(SCH_1):FM_DEBUG_RST_BTN_N

RES_0402-100.0,1%,1/16W,CHIP,GA  I35  R9A9
   1 RST_SYSTEM_BTN_BUF_N      A @BASEBOARD_FAB2_LIB.BASEBOARD_FAB2(SCH_1):RST_SYSTEM_BTN_BUF_N
   2 RST_SYSTEM_BTN_N      B @BASEBOARD_FAB2_LIB.BASEBOARD_FAB2(SCH_1):RST_SYSTEM_BTN_N

CAP_A_0402V-0.1UF,16V,10%,X7R,A  I37  C1L17
   1 P3V3_STBY      A @BASEBOARD_FAB2_LIB.BASEBOARD_FAB2(SCH_1):P3V3_STBY
   2    GND      B @BASEBOARD_FAB2_LIB.BASEBOARD_FAB2(SCH_1):GND

CAP_A_0402V-0.1UF,16V,10%,X7R,A  I38  C1L9
   1 P3V3_STBY      A @BASEBOARD_FAB2_LIB.BASEBOARD_FAB2(SCH_1):P3V3_STBY
   2    GND      B @BASEBOARD_FAB2_LIB.BASEBOARD_FAB2(SCH_1):GND

CAP_A_0402V-0.1UF,16V,10%,X7R,A  I40  C9A3
   1 P3V3_STBY      A @BASEBOARD_FAB2_LIB.BASEBOARD_FAB2(SCH_1):P3V3_STBY
   2    GND      B @BASEBOARD_FAB2_LIB.BASEBOARD_FAB2(SCH_1):GND

RES_0402-221,1.0%,1/16W,CHIP,GA  I45  R1L33
   1 FM_BEEP_LED_P      A @BASEBOARD_FAB2_LIB.BASEBOARD_FAB2(SCH_1):FM_BEEP_LED_P
   2 P3V3_STBY      B @BASEBOARD_FAB2_LIB.BASEBOARD_FAB2(SCH_1):P3V3_STBY

FET_N_SOT23LF-2N7002,FET,C7925A  I49  Q9A3
   1 FM_BIOS_TOP_SWAP_SPKR   GATE @BASEBOARD_FAB2_LIB.BASEBOARD_FAB2(SCH_1):FM_BIOS_TOP_SWAP_SPKR
   2    GND    SRC @BASEBOARD_FAB2_LIB.BASEBOARD_FAB2(SCH_1):GND
   3 FM_SPEAKER_PCH_N_R    DRN @BASEBOARD_FAB2_LIB.BASEBOARD_FAB2(SCH_1):FM_SPEAKER_PCH_N_R

LED_1NC-BLUE,IC,C96565-012  I50  DS9A1
   1 FP_ID_LED_P5V_STBY_N      C @BASEBOARD_FAB2_LIB.BASEBOARD_FAB2(SCH_1):FP_ID_LED_P5V_STBY_N
   2 FP_ID_LED_XOR_R      A @BASEBOARD_FAB2_LIB.BASEBOARD_FAB2(SCH_1):FP_ID_LED_XOR_R

TTL1G86_SOTLF-74AHCT1G86,IC,D3B  I57  U1L2
   1 PWRGD_P3V3_R      A @BASEBOARD_FAB2_LIB.BASEBOARD_FAB2(SCH_1):PWRGD_P3V3_R
   2 FP_PWR_ID_LED_N      B @BASEBOARD_FAB2_LIB.BASEBOARD_FAB2(SCH_1):FP_PWR_ID_LED_N
   4 FP_ID_LED_P5V_STBY_N      Y @BASEBOARD_FAB2_LIB.BASEBOARD_FAB2(SCH_1):FP_ID_LED_P5V_STBY_N

RES_0402-470.0,5%,1/16W,CHIP,GA  I58  R1L8
   1 P5V_STBY      A @BASEBOARD_FAB2_LIB.BASEBOARD_FAB2(SCH_1):P5V_STBY
   2 FP_ID_LED_XOR_R      B @BASEBOARD_FAB2_LIB.BASEBOARD_FAB2(SCH_1):FP_ID_LED_XOR_R

RES_0402-0.0,5%,1/16W,CHIP,G21A  I63  R1L12
   1 PWRGD_P3V3      A @BASEBOARD_FAB2_LIB.BASEBOARD_FAB2(SCH_1):PWRGD_P3V3
   2 PWRGD_P3V3_R      B @BASEBOARD_FAB2_LIB.BASEBOARD_FAB2(SCH_1):PWRGD_P3V3_R

CAP_A_0402V-0.1UF,16V,10%,X7R,A  I64  C1L4
   1 P5V_STBY      A @BASEBOARD_FAB2_LIB.BASEBOARD_FAB2(SCH_1):P5V_STBY
   2    GND      B @BASEBOARD_FAB2_LIB.BASEBOARD_FAB2(SCH_1):GND

LED_1NCLF-YELLOW,IC,C96565-003  I67  DS9A3
   1 FM_SPEAKER_PCH_N_R      C @BASEBOARD_FAB2_LIB.BASEBOARD_FAB2(SCH_1):FM_SPEAKER_PCH_N_R
   2 FM_BEEP_LED_P      A @BASEBOARD_FAB2_LIB.BASEBOARD_FAB2(SCH_1):FM_BEEP_LED_P

SWITCH_D37771002_SM-IC,D37771-A  I78  S9A1
   4    GND   PIN4 @BASEBOARD_FAB2_LIB.BASEBOARD_FAB2(SCH_1):GND
   3    GND   PIN3 @BASEBOARD_FAB2_LIB.BASEBOARD_FAB2(SCH_1):GND
   1 FM_DEBUG_RST_BTN_N   PIN1 @BASEBOARD_FAB2_LIB.BASEBOARD_FAB2(SCH_1):FM_DEBUG_RST_BTN_N
   2 FM_DEBUG_RST_BTN_N   PIN2 @BASEBOARD_FAB2_LIB.BASEBOARD_FAB2(SCH_1):FM_DEBUG_RST_BTN_N

SW_H67881001_SM-IC,H67881-001  I84  S9A2
   1 FP_PWR_BTN_R_N    IO1 @BASEBOARD_FAB2_LIB.BASEBOARD_FAB2(SCH_1):FP_PWR_BTN_R_N
   2 FP_PWR_BTN_R_N    IO2 @BASEBOARD_FAB2_LIB.BASEBOARD_FAB2(SCH_1):FP_PWR_BTN_R_N
   3    GND    IO3 @BASEBOARD_FAB2_LIB.BASEBOARD_FAB2(SCH_1):GND
   4    GND    IO4 @BASEBOARD_FAB2_LIB.BASEBOARD_FAB2(SCH_1):GND

0R2J-L-GP_SMD-RG5-0R2J-L-GP,63A  I89  R1L45
   1 FM_SPEAKER_PCH_N      1 @BASEBOARD_FAB2_LIB.BASEBOARD_FAB2(SCH_1):FM_SPEAKER_PCH_N
   2 FM_SPEAKER_PCH_N_R      2 @BASEBOARD_FAB2_LIB.BASEBOARD_FAB2(SCH_1):FM_SPEAKER_PCH_N_R


DRAWING: @BASEBOARD_FAB2_LIB.BASEBOARD_FAB2(SCH_1):PAGE176 

RES_0402-0.0,5%,1/16W,CHIP,G21A  I16  R1M5
   1 USB2_P01_DP      A @BASEBOARD_FAB2_LIB.BASEBOARD_FAB2(SCH_1):USB2_P01_DP
   2 USB2_P01_ESD_DP      B @BASEBOARD_FAB2_LIB.BASEBOARD_FAB2(SCH_1):USB2_P01_ESD_DP

CHOKE_4PIN_SMLF-90 OHM,EMPTY,7A  I30  L1M2
   1 USB2_P01_DN     A1 @BASEBOARD_FAB2_LIB.BASEBOARD_FAB2(SCH_1):USB2_P01_DN
   2 USB2_P01_DP     A2 @BASEBOARD_FAB2_LIB.BASEBOARD_FAB2(SCH_1):USB2_P01_DP
   3 USB2_P01_ESD_DP     B1 @BASEBOARD_FAB2_LIB.BASEBOARD_FAB2(SCH_1):USB2_P01_ESD_DP
   4 USB2_P01_ESD_DN     B2 @BASEBOARD_FAB2_LIB.BASEBOARD_FAB2(SCH_1):USB2_P01_ESD_DN

RES_0402-0.0,5%,1/16W,CHIP,G21A  I31  R1M6
   1 USB2_P01_DN      A @BASEBOARD_FAB2_LIB.BASEBOARD_FAB2(SCH_1):USB2_P01_DN
   2 USB2_P01_ESD_DN      B @BASEBOARD_FAB2_LIB.BASEBOARD_FAB2(SCH_1):USB2_P01_ESD_DN

CONN9_H51826001_PIP2-CONN,H518A  I69  J9B1
   2 USB2_P01_ESD_DN     DN @BASEBOARD_FAB2_LIB.BASEBOARD_FAB2(SCH_1):USB2_P01_ESD_DN
   3 USB2_P01_ESD_DP     DP @BASEBOARD_FAB2_LIB.BASEBOARD_FAB2(SCH_1):USB2_P01_ESD_DP
   4    GND    GND @BASEBOARD_FAB2_LIB.BASEBOARD_FAB2(SCH_1):GND
   7 FM_UART_SWITCH_N GND_DRAIN @BASEBOARD_FAB2_LIB.BASEBOARD_FAB2(SCH_1):FM_UART_SWITCH_N
 MH1    GND    MH1 @BASEBOARD_FAB2_LIB.BASEBOARD_FAB2(SCH_1):GND
 MH2    GND    MH2 @BASEBOARD_FAB2_LIB.BASEBOARD_FAB2(SCH_1):GND
 MH3    GND    MH3 @BASEBOARD_FAB2_LIB.BASEBOARD_FAB2(SCH_1):GND
 MH4    GND    MH4 @BASEBOARD_FAB2_LIB.BASEBOARD_FAB2(SCH_1):GND
   5 SMB_IPMB_3V3AUX_SCL STDA_SSRXN @BASEBOARD_FAB2_LIB.BASEBOARD_FAB2(SCH_1):SMB_IPMB_3V3AUX_SCL
   6 SMB_IPMB_3V3AUX_SDA STDA_SSRXP @BASEBOARD_FAB2_LIB.BASEBOARD_FAB2(SCH_1):SMB_IPMB_3V3AUX_SDA
   8 SPA_MID_DBG_TX STDA_SSTXN @BASEBOARD_FAB2_LIB.BASEBOARD_FAB2(SCH_1):SPA_MID_DBG_TX
   9 SPA_MID_DBG2_RX STDA_SSTXP @BASEBOARD_FAB2_LIB.BASEBOARD_FAB2(SCH_1):SPA_MID_DBG2_RX
   1 P5V_USB   VBUS @BASEBOARD_FAB2_LIB.BASEBOARD_FAB2(SCH_1):P5V_USB

DIODEAC_DUAL_ARRAY_SM9-ESD3V3UA  I98  CR1M2
   1 USB2_P01_ESD_DP    AC0 @BASEBOARD_FAB2_LIB.BASEBOARD_FAB2(SCH_1):USB2_P01_ESD_DP
   2 USB2_P01_ESD_DN    AC1 @BASEBOARD_FAB2_LIB.BASEBOARD_FAB2(SCH_1):USB2_P01_ESD_DN
   4 TP_USB_ESD_AC2    AC2 @BASEBOARD_FAB2_LIB.BASEBOARD_FAB2(SCH_1):TP_USB_ESD_AC2
   5 TP_USB_ESD_AC3    AC3 @BASEBOARD_FAB2_LIB.BASEBOARD_FAB2(SCH_1):TP_USB_ESD_AC3
   3    GND GND<0> @BASEBOARD_FAB2_LIB.BASEBOARD_FAB2(SCH_1):GND
   9 USB2_P01_ESD_DP   OUT0 @BASEBOARD_FAB2_LIB.BASEBOARD_FAB2(SCH_1):USB2_P01_ESD_DP
   8 USB2_P01_ESD_DN   OUT1 @BASEBOARD_FAB2_LIB.BASEBOARD_FAB2(SCH_1):USB2_P01_ESD_DN
   7 TP_USB_ESD_OUT2   OUT2 @BASEBOARD_FAB2_LIB.BASEBOARD_FAB2(SCH_1):TP_USB_ESD_OUT2
   6 TP_USB_ESD_OUT3   OUT3 @BASEBOARD_FAB2_LIB.BASEBOARD_FAB2(SCH_1):TP_USB_ESD_OUT3

TPS2061_SM-IC,H66405-001  I100  U1M3
   4 FM_USB_P0_EN_BOOT_BIOS_STRAP_N   EN_N @BASEBOARD_FAB2_LIB.BASEBOARD_FAB2(SCH_1):FM_USB_P0_EN_BOOT_BIOS_STRAP_N
   2    GND    GND @BASEBOARD_FAB2_LIB.BASEBOARD_FAB2(SCH_1):GND
   5    P5V     IN @BASEBOARD_FAB2_LIB.BASEBOARD_FAB2(SCH_1):P5V
   3 FM_OC0_USB_N   OC_N @BASEBOARD_FAB2_LIB.BASEBOARD_FAB2(SCH_1):FM_OC0_USB_N
   1 P5V_USB    OUT @BASEBOARD_FAB2_LIB.BASEBOARD_FAB2(SCH_1):P5V_USB

RES_0402-10.0K,1%,1/16W,CHIP,GA  I105  R1M24
   1 P3V3_STBY      A @BASEBOARD_FAB2_LIB.BASEBOARD_FAB2(SCH_1):P3V3_STBY
   2 FM_OC0_USB_N      B @BASEBOARD_FAB2_LIB.BASEBOARD_FAB2(SCH_1):FM_OC0_USB_N

CAP_A_0402V-0.1UF,16V,10%,X7R,A  I108  C1M38
   1    P5V      A @BASEBOARD_FAB2_LIB.BASEBOARD_FAB2(SCH_1):P5V
   2    GND      B @BASEBOARD_FAB2_LIB.BASEBOARD_FAB2(SCH_1):GND

RES_0402-10.0K,1%,1/16W,CHIP,GA  I111  R1M25
   1 FM_USB_P0_EN_BOOT_BIOS_STRAP_N      A @BASEBOARD_FAB2_LIB.BASEBOARD_FAB2(SCH_1):FM_USB_P0_EN_BOOT_BIOS_STRAP_N
   2    GND      B @BASEBOARD_FAB2_LIB.BASEBOARD_FAB2(SCH_1):GND

CAPP_7343HLF-330UF,10V,20%,POSA  I113  C9B8
   1 P5V_USB      A @BASEBOARD_FAB2_LIB.BASEBOARD_FAB2(SCH_1):P5V_USB
   2    GND      B @BASEBOARD_FAB2_LIB.BASEBOARD_FAB2(SCH_1):GND

TTL1G08_SOTLF-NC7SZ08,IC,D1032B  I122  U6W10
   4 SPA_MID_DBG_RX   Y<0> @BASEBOARD_FAB2_LIB.BASEBOARD_FAB2(SCH_1):SPA_MID_DBG_RX
   1 SPA_MID_DBG1__RX   A<0> @BASEBOARD_FAB2_LIB.BASEBOARD_FAB2(SCH_1):SPA_MID_DBG1__RX
   2 SPA_MID_DBG2_RX   B<0> @BASEBOARD_FAB2_LIB.BASEBOARD_FAB2(SCH_1):SPA_MID_DBG2_RX

CAP_0402LF-0.1UF,16V,10%,X7R,AA  I124  C6W10
   1 P3V3_STBY      A @BASEBOARD_FAB2_LIB.BASEBOARD_FAB2(SCH_1):P3V3_STBY
   2    GND      B @BASEBOARD_FAB2_LIB.BASEBOARD_FAB2(SCH_1):GND


DRAWING: @BASEBOARD_FAB2_LIB.BASEBOARD_FAB2(SCH_1):PAGE177 

RES_0402-0.0,5%,1/16W,CHIP,G21A  I3  R1M13
   1 LED_PCH_SSATA_HDD_N      A @BASEBOARD_FAB2_LIB.BASEBOARD_FAB2(SCH_1):LED_PCH_SSATA_HDD_N
   2 LED_SAS_ACT_R_N      B @BASEBOARD_FAB2_LIB.BASEBOARD_FAB2(SCH_1):LED_SAS_ACT_R_N

RES_0402-0.0,5%,1/16W,CHIP,G21A  I6  R1M10
   1 LED_PCH_SATA_HDD_N      A @BASEBOARD_FAB2_LIB.BASEBOARD_FAB2(SCH_1):LED_PCH_SATA_HDD_N
   2 LED_SATA_ACT_R_N      B @BASEBOARD_FAB2_LIB.BASEBOARD_FAB2(SCH_1):LED_SATA_ACT_R_N

RES_0402-10.0K,1%,1/16W,CHIP,GA  I8  R1M12
   1   P3V3      A @BASEBOARD_FAB2_LIB.BASEBOARD_FAB2(SCH_1):P3V3
   2 LED_SAS_ACT_R_N      B @BASEBOARD_FAB2_LIB.BASEBOARD_FAB2(SCH_1):LED_SAS_ACT_R_N

RES_0402-10.0K,1%,1/16W,CHIP,GA  I9  R1M11
   1   P3V3      A @BASEBOARD_FAB2_LIB.BASEBOARD_FAB2(SCH_1):P3V3
   2 LED_SATA_ACT_R_N      B @BASEBOARD_FAB2_LIB.BASEBOARD_FAB2(SCH_1):LED_SATA_ACT_R_N

CAP_A_0402V-1.0UF,6.3V,10%,X6SA  I20  C1M3
   1   P3V3      A @BASEBOARD_FAB2_LIB.BASEBOARD_FAB2(SCH_1):P3V3
   2    GND      B @BASEBOARD_FAB2_LIB.BASEBOARD_FAB2(SCH_1):GND

LED_A1LF-GREEN,IC,C97278-010  I31  DS9A6
   2    GND      C @BASEBOARD_FAB2_LIB.BASEBOARD_FAB2(SCH_1):GND
   1 LED_P5V_STBY      A @BASEBOARD_FAB2_LIB.BASEBOARD_FAB2(SCH_1):LED_P5V_STBY

RES_0402-301.0,1%,1/16W,CHIP,GA  I33  R1L37
   1 P5V_STBY      A @BASEBOARD_FAB2_LIB.BASEBOARD_FAB2(SCH_1):P5V_STBY
   2 LED_P5V_STBY      B @BASEBOARD_FAB2_LIB.BASEBOARD_FAB2(SCH_1):LED_P5V_STBY

LED_1NCLF-GREEN,IC,C96565-011  I42  DS9A2
   1 FP_LED_HDD_ACTIVITY_AND_N      C @BASEBOARD_FAB2_LIB.BASEBOARD_FAB2(SCH_1):FP_LED_HDD_ACTIVITY_AND_N
   2 FP_LED_HDD_ACTIVITY_AND_R_N      A @BASEBOARD_FAB2_LIB.BASEBOARD_FAB2(SCH_1):FP_LED_HDD_ACTIVITY_AND_R_N

RES_0402-64.9,1.0%,1/16W,CHIP,A  I43  R1L21
   1   P3V3      A @BASEBOARD_FAB2_LIB.BASEBOARD_FAB2(SCH_1):P3V3
   2 FP_LED_HDD_ACTIVITY_AND_R_N      B @BASEBOARD_FAB2_LIB.BASEBOARD_FAB2(SCH_1):FP_LED_HDD_ACTIVITY_AND_R_N

TTL1G08_SOTLF-NC7SZ08,IC,D1032C  I70  U1M1
   4 FP_LED_HDD_ACTIVITY_AND_N   Y<0> @BASEBOARD_FAB2_LIB.BASEBOARD_FAB2(SCH_1):FP_LED_HDD_ACTIVITY_AND_N
   1 LED_SATA_ACT_R_N   A<0> @BASEBOARD_FAB2_LIB.BASEBOARD_FAB2(SCH_1):LED_SATA_ACT_R_N
   2 LED_SAS_ACT_R_N   B<0> @BASEBOARD_FAB2_LIB.BASEBOARD_FAB2(SCH_1):LED_SAS_ACT_R_N

LED_A1-RED,IC,D14725-005  I71  DS9F1
   2 FM_RED_LED_CATHODE      C @BASEBOARD_FAB2_LIB.BASEBOARD_FAB2(SCH_1):FM_RED_LED_CATHODE
   1 FM_RED_LED_ANODE      A @BASEBOARD_FAB2_LIB.BASEBOARD_FAB2(SCH_1):FM_RED_LED_ANODE

RES_0402-221,1.0%,1/16W,CHIP,GA  I72  R9F28
   1 P3V3_STBY      A @BASEBOARD_FAB2_LIB.BASEBOARD_FAB2(SCH_1):P3V3_STBY
   2 FM_RED_LED_ANODE      B @BASEBOARD_FAB2_LIB.BASEBOARD_FAB2(SCH_1):FM_RED_LED_ANODE

RES_0402-4.75K,1%,1/16W,CHIP,GA  I76  R9F30
   1 P3V3_STBY      A @BASEBOARD_FAB2_LIB.BASEBOARD_FAB2(SCH_1):P3V3_STBY
   2 FM_BMC_FAULT_LED_N      B @BASEBOARD_FAB2_LIB.BASEBOARD_FAB2(SCH_1):FM_BMC_FAULT_LED_N

FET_N_DUAL_SMLF-NTJD4001N,FET,A  I79  Q9F1
   5 FM_BMC_FAULT_LED GATE<0> @BASEBOARD_FAB2_LIB.BASEBOARD_FAB2(SCH_1):FM_BMC_FAULT_LED
   4    GND SOURCE<0> @BASEBOARD_FAB2_LIB.BASEBOARD_FAB2(SCH_1):GND
   3 FM_RED_LED_CATHODE DRAIN<0> @BASEBOARD_FAB2_LIB.BASEBOARD_FAB2(SCH_1):FM_RED_LED_CATHODE

FET_N_DUAL_SMLF-NTJD4001N,FET,A  I80  Q9F1
   2 FM_BMC_FAULT_LED_N GATE<0> @BASEBOARD_FAB2_LIB.BASEBOARD_FAB2(SCH_1):FM_BMC_FAULT_LED_N
   1    GND SOURCE<0> @BASEBOARD_FAB2_LIB.BASEBOARD_FAB2(SCH_1):GND
   6 FM_BMC_FAULT_LED DRAIN<0> @BASEBOARD_FAB2_LIB.BASEBOARD_FAB2(SCH_1):FM_BMC_FAULT_LED

RES_0402-4.75K,1%,1/16W,CHIP,GA  I82  R9F52
   1 P3V3_STBY      A @BASEBOARD_FAB2_LIB.BASEBOARD_FAB2(SCH_1):P3V3_STBY
   2 FM_BMC_FAULT_LED      B @BASEBOARD_FAB2_LIB.BASEBOARD_FAB2(SCH_1):FM_BMC_FAULT_LED


DRAWING: @BASEBOARD_FAB2_LIB.BASEBOARD_FAB2(SCH_1):PAGE178 

RES_0402-49.9,1%,1/16W,CHIP,G2A  I1  R8D20
   1 SGPIO_PCH_SATA_LOAD      A @BASEBOARD_FAB2_LIB.BASEBOARD_FAB2(SCH_1):SGPIO_PCH_SATA_LOAD
   2 SGPIO_PCH_SATA_LOAD_R      B @BASEBOARD_FAB2_LIB.BASEBOARD_FAB2(SCH_1):SGPIO_PCH_SATA_LOAD_R

RES_0402-2.0K,1%,1/16W,CHIP,G2A  I2  R2L12
   1 P3V3_STBY      A @BASEBOARD_FAB2_LIB.BASEBOARD_FAB2(SCH_1):P3V3_STBY
   2 SGPIO_PCH_SATA_LOAD_R      B @BASEBOARD_FAB2_LIB.BASEBOARD_FAB2(SCH_1):SGPIO_PCH_SATA_LOAD_R

RES_0402-49.9,1%,1/16W,CHIP,G2A  I8  R8D19
   1 SGPIO_PCH_SATA_DOUT0      A @BASEBOARD_FAB2_LIB.BASEBOARD_FAB2(SCH_1):SGPIO_PCH_SATA_DOUT0
   2 SGPIO_PCH_SATA_DOUT0_R      B @BASEBOARD_FAB2_LIB.BASEBOARD_FAB2(SCH_1):SGPIO_PCH_SATA_DOUT0_R

RES_0402-49.9,1%,1/16W,CHIP,G2A  I11  R2N31
   1 SGPIO_PCH_SATA_CLOCK      A @BASEBOARD_FAB2_LIB.BASEBOARD_FAB2(SCH_1):SGPIO_PCH_SATA_CLOCK
   2 SGPIO_PCH_SATA_CLOCK_R      B @BASEBOARD_FAB2_LIB.BASEBOARD_FAB2(SCH_1):SGPIO_PCH_SATA_CLOCK_R

RES_0402-2.0K,1%,1/16W,CHIP,G2A  I12  R2L15
   1 P3V3_STBY      A @BASEBOARD_FAB2_LIB.BASEBOARD_FAB2(SCH_1):P3V3_STBY
   2 SGPIO_PCH_SATA_DOUT0_R      B @BASEBOARD_FAB2_LIB.BASEBOARD_FAB2(SCH_1):SGPIO_PCH_SATA_DOUT0_R

RES_0402-2.0K,1%,1/16W,CHIP,G2A  I13  R2L11
   1 P3V3_STBY      A @BASEBOARD_FAB2_LIB.BASEBOARD_FAB2(SCH_1):P3V3_STBY
   2 SGPIO_PCH_SATA_CLOCK_R      B @BASEBOARD_FAB2_LIB.BASEBOARD_FAB2(SCH_1):SGPIO_PCH_SATA_CLOCK_R

RES_0402-2.0K,1%,1/16W,CHIP,G2A  I17  R2L6
   1 P3V3_STBY      A @BASEBOARD_FAB2_LIB.BASEBOARD_FAB2(SCH_1):P3V3_STBY
   2 SGPIO_PCH_SSATA_CLOCK_R      B @BASEBOARD_FAB2_LIB.BASEBOARD_FAB2(SCH_1):SGPIO_PCH_SSATA_CLOCK_R

RES_0402-2.0K,1%,1/16W,CHIP,G2A  I18  R2L4
   1 P3V3_STBY      A @BASEBOARD_FAB2_LIB.BASEBOARD_FAB2(SCH_1):P3V3_STBY
   2 SGPIO_PCH_SSATA_DOUT0_R      B @BASEBOARD_FAB2_LIB.BASEBOARD_FAB2(SCH_1):SGPIO_PCH_SSATA_DOUT0_R

RES_0402-2.0K,1%,1/16W,CHIP,G2A  I20  R2L5
   1 P3V3_STBY      A @BASEBOARD_FAB2_LIB.BASEBOARD_FAB2(SCH_1):P3V3_STBY
   2 SGPIO_PCH_SSATA_LOAD_R      B @BASEBOARD_FAB2_LIB.BASEBOARD_FAB2(SCH_1):SGPIO_PCH_SSATA_LOAD_R

RES_0402-49.9,1%,1/16W,CHIP,G2A  I21  R8B29
   1 SGPIO_PCH_SSATA_DOUT0      A @BASEBOARD_FAB2_LIB.BASEBOARD_FAB2(SCH_1):SGPIO_PCH_SSATA_DOUT0
   2 SGPIO_PCH_SSATA_DOUT0_R      B @BASEBOARD_FAB2_LIB.BASEBOARD_FAB2(SCH_1):SGPIO_PCH_SSATA_DOUT0_R

RES_0402-49.9,1%,1/16W,CHIP,G2A  I22  R2N19
   1 SGPIO_PCH_SSATA_LOAD      A @BASEBOARD_FAB2_LIB.BASEBOARD_FAB2(SCH_1):SGPIO_PCH_SSATA_LOAD
   2 SGPIO_PCH_SSATA_LOAD_R      B @BASEBOARD_FAB2_LIB.BASEBOARD_FAB2(SCH_1):SGPIO_PCH_SSATA_LOAD_R

RES_0402-49.9,1%,1/16W,CHIP,G2A  I23  R2N22
   1 SGPIO_PCH_SSATA_CLOCK      A @BASEBOARD_FAB2_LIB.BASEBOARD_FAB2(SCH_1):SGPIO_PCH_SSATA_CLOCK
   2 SGPIO_PCH_SSATA_CLOCK_R      B @BASEBOARD_FAB2_LIB.BASEBOARD_FAB2(SCH_1):SGPIO_PCH_SSATA_CLOCK_R


DRAWING: @BASEBOARD_FAB2_LIB.BASEBOARD_FAB2(SCH_1):PAGE181 

CONN76_H22707001_THMT1-CONN,H2A  I111  J1F1
  A2    GND  GNDA2 @BASEBOARD_FAB2_LIB.BASEBOARD_FAB2(SCH_1):GND
  A4 FAN_TACH3_R  GNDA4 @BASEBOARD_FAB2_LIB.BASEBOARD_FAB2(SCH_1):FAN_TACH3_R
  A6 IRQ_SML1_PMBUS_ALERT_R_N  GNDA6 @BASEBOARD_FAB2_LIB.BASEBOARD_FAB2(SCH_1):IRQ_SML1_PMBUS_ALERT_R_N
  A8    GND  GNDA8 @BASEBOARD_FAB2_LIB.BASEBOARD_FAB2(SCH_1):GND
  C1    GND  GNDC1 @BASEBOARD_FAB2_LIB.BASEBOARD_FAB2(SCH_1):GND
  C3    GND  GNDC3 @BASEBOARD_FAB2_LIB.BASEBOARD_FAB2(SCH_1):GND
  C5    GND  GNDC5 @BASEBOARD_FAB2_LIB.BASEBOARD_FAB2(SCH_1):GND
  C7    GND  GNDC7 @BASEBOARD_FAB2_LIB.BASEBOARD_FAB2(SCH_1):GND
  D2    GND  GNDD2 @BASEBOARD_FAB2_LIB.BASEBOARD_FAB2(SCH_1):GND
  D4 FAN_TACH0_R  GNDD4 @BASEBOARD_FAB2_LIB.BASEBOARD_FAB2(SCH_1):FAN_TACH0_R
  D6    GND  GNDD6 @BASEBOARD_FAB2_LIB.BASEBOARD_FAB2(SCH_1):GND
  D8    GND  GNDD8 @BASEBOARD_FAB2_LIB.BASEBOARD_FAB2(SCH_1):GND
  F1    GND  GNDF1 @BASEBOARD_FAB2_LIB.BASEBOARD_FAB2(SCH_1):GND
  F3    GND  GNDF3 @BASEBOARD_FAB2_LIB.BASEBOARD_FAB2(SCH_1):GND
  F5 FM_MB_SLOT_ID0  GNDF5 @BASEBOARD_FAB2_LIB.BASEBOARD_FAB2(SCH_1):FM_MB_SLOT_ID0
  F7    GND  GNDF7 @BASEBOARD_FAB2_LIB.BASEBOARD_FAB2(SCH_1):GND
  G2    GND  GNDG2 @BASEBOARD_FAB2_LIB.BASEBOARD_FAB2(SCH_1):GND
  G4    GND  GNDG4 @BASEBOARD_FAB2_LIB.BASEBOARD_FAB2(SCH_1):GND
  G6    GND  GNDG6 @BASEBOARD_FAB2_LIB.BASEBOARD_FAB2(SCH_1):GND
  G8    GND  GNDG8 @BASEBOARD_FAB2_LIB.BASEBOARD_FAB2(SCH_1):GND
  I1    GND  GNDI1 @BASEBOARD_FAB2_LIB.BASEBOARD_FAB2(SCH_1):GND
  I3 FM_ENABLE_FAN_POWER  GNDI3 @BASEBOARD_FAB2_LIB.BASEBOARD_FAB2(SCH_1):FM_ENABLE_FAN_POWER
  I5 RST_PCIE_MIDPLANE_N  GNDI5 @BASEBOARD_FAB2_LIB.BASEBOARD_FAB2(SCH_1):RST_PCIE_MIDPLANE_N
  I7    GND  GNDI7 @BASEBOARD_FAB2_LIB.BASEBOARD_FAB2(SCH_1):GND
  J2    GND  GNDJ2 @BASEBOARD_FAB2_LIB.BASEBOARD_FAB2(SCH_1):GND
  J4    GND  GNDJ4 @BASEBOARD_FAB2_LIB.BASEBOARD_FAB2(SCH_1):GND
  J6    GND  GNDJ6 @BASEBOARD_FAB2_LIB.BASEBOARD_FAB2(SCH_1):GND
  J8    GND  GNDJ8 @BASEBOARD_FAB2_LIB.BASEBOARD_FAB2(SCH_1):GND
  A1 P3E_CPU1_PE3_MP_RXN<0>   IOA1 @BASEBOARD_FAB2_LIB.BASEBOARD_FAB2(SCH_1):P3E_CPU1_PE3_MP_RXN(0)
  A3 P3E_CPU1_PE3_MP_RXP<6>   IOA3 @BASEBOARD_FAB2_LIB.BASEBOARD_FAB2(SCH_1):P3E_CPU1_PE3_MP_RXP(6)
  A5 NIC_MDI_MNG_TX_DP   IOA5 @BASEBOARD_FAB2_LIB.BASEBOARD_FAB2(SCH_1):NIC_MDI_MNG_TX_DP
  A7 P3E_CPU1_PE3_MP_C_TXN<3>   IOA7 @BASEBOARD_FAB2_LIB.BASEBOARD_FAB2(SCH_1):P3E_CPU1_PE3_MP_C_TXN(3)
  B1 P3E_CPU1_PE3_MP_RXP<0>   IOB1 @BASEBOARD_FAB2_LIB.BASEBOARD_FAB2(SCH_1):P3E_CPU1_PE3_MP_RXP(0)
  B2 P3E_CPU1_PE3_MP_RXN<3>   IOB2 @BASEBOARD_FAB2_LIB.BASEBOARD_FAB2(SCH_1):P3E_CPU1_PE3_MP_RXN(3)
  B3 P3E_CPU1_PE3_MP_RXN<6>   IOB3 @BASEBOARD_FAB2_LIB.BASEBOARD_FAB2(SCH_1):P3E_CPU1_PE3_MP_RXN(6)
  B4 FAN_TACH2_R   IOB4 @BASEBOARD_FAB2_LIB.BASEBOARD_FAB2(SCH_1):FAN_TACH2_R
  B5 NIC_MDI_MNG_TX_DN   IOB5 @BASEBOARD_FAB2_LIB.BASEBOARD_FAB2(SCH_1):NIC_MDI_MNG_TX_DN
  B6 SMB_BMC_PMBUS_STBY_LVC3_SDA   IOB6 @BASEBOARD_FAB2_LIB.BASEBOARD_FAB2(SCH_1):SMB_BMC_PMBUS_STBY_LVC3_SDA
  B7 P3E_CPU1_PE3_MP_C_TXP<3>   IOB7 @BASEBOARD_FAB2_LIB.BASEBOARD_FAB2(SCH_1):P3E_CPU1_PE3_MP_C_TXP(3)
  B8 P3E_CPU1_PE3_MP_C_TXN<0>   IOB8 @BASEBOARD_FAB2_LIB.BASEBOARD_FAB2(SCH_1):P3E_CPU1_PE3_MP_C_TXN(0)
  C2 P3E_CPU1_PE3_MP_RXP<3>   IOC2 @BASEBOARD_FAB2_LIB.BASEBOARD_FAB2(SCH_1):P3E_CPU1_PE3_MP_RXP(3)
  C4 FAN_TACH1_R   IOC4 @BASEBOARD_FAB2_LIB.BASEBOARD_FAB2(SCH_1):FAN_TACH1_R
  C6 SMB_BMC_PMBUS_STBY_LVC3_SCL   IOC6 @BASEBOARD_FAB2_LIB.BASEBOARD_FAB2(SCH_1):SMB_BMC_PMBUS_STBY_LVC3_SCL
  C8 P3E_CPU1_PE3_MP_C_TXP<0>   IOC8 @BASEBOARD_FAB2_LIB.BASEBOARD_FAB2(SCH_1):P3E_CPU1_PE3_MP_C_TXP(0)
  D1 P3E_CPU1_PE3_MP_RXN<1>   IOD1 @BASEBOARD_FAB2_LIB.BASEBOARD_FAB2(SCH_1):P3E_CPU1_PE3_MP_RXN(1)
  D3 P3E_CPU1_PE3_MP_RXN<7>   IOD3 @BASEBOARD_FAB2_LIB.BASEBOARD_FAB2(SCH_1):P3E_CPU1_PE3_MP_RXN(7)
  D5 NIC_MDI_MNG_RX_DP   IOD5 @BASEBOARD_FAB2_LIB.BASEBOARD_FAB2(SCH_1):NIC_MDI_MNG_RX_DP
  D7 P3E_CPU1_PE3_MP_C_TXN<4>   IOD7 @BASEBOARD_FAB2_LIB.BASEBOARD_FAB2(SCH_1):P3E_CPU1_PE3_MP_C_TXN(4)
  E1 P3E_CPU1_PE3_MP_RXP<1>   IOE1 @BASEBOARD_FAB2_LIB.BASEBOARD_FAB2(SCH_1):P3E_CPU1_PE3_MP_RXP(1)
  E2 P3E_CPU1_PE3_MP_RXN<4>   IOE2 @BASEBOARD_FAB2_LIB.BASEBOARD_FAB2(SCH_1):P3E_CPU1_PE3_MP_RXN(4)
  E3 P3E_CPU1_PE3_MP_RXP<7>   IOE3 @BASEBOARD_FAB2_LIB.BASEBOARD_FAB2(SCH_1):P3E_CPU1_PE3_MP_RXP(7)
  E4 FM_MATED_IN_N   IOE4 @BASEBOARD_FAB2_LIB.BASEBOARD_FAB2(SCH_1):FM_MATED_IN_N
  E5 NIC_MDI_MNG_RX_DN   IOE5 @BASEBOARD_FAB2_LIB.BASEBOARD_FAB2(SCH_1):NIC_MDI_MNG_RX_DN
  E6 P3E_CPU1_PE3_MP_C_TXN<6>   IOE6 @BASEBOARD_FAB2_LIB.BASEBOARD_FAB2(SCH_1):P3E_CPU1_PE3_MP_C_TXN(6)
  E7 P3E_CPU1_PE3_MP_C_TXP<4>   IOE7 @BASEBOARD_FAB2_LIB.BASEBOARD_FAB2(SCH_1):P3E_CPU1_PE3_MP_C_TXP(4)
  E8 P3E_CPU1_PE3_MP_C_TXN<1>   IOE8 @BASEBOARD_FAB2_LIB.BASEBOARD_FAB2(SCH_1):P3E_CPU1_PE3_MP_C_TXN(1)
  F2 P3E_CPU1_PE3_MP_RXP<4>   IOF2 @BASEBOARD_FAB2_LIB.BASEBOARD_FAB2(SCH_1):P3E_CPU1_PE3_MP_RXP(4)
  F4 FAN_PWM_OUT_SYS0_R1   IOF4 @BASEBOARD_FAB2_LIB.BASEBOARD_FAB2(SCH_1):FAN_PWM_OUT_SYS0_R1
  F6 P3E_CPU1_PE3_MP_C_TXP<6>   IOF6 @BASEBOARD_FAB2_LIB.BASEBOARD_FAB2(SCH_1):P3E_CPU1_PE3_MP_C_TXP(6)
  F8 P3E_CPU1_PE3_MP_C_TXP<1>   IOF8 @BASEBOARD_FAB2_LIB.BASEBOARD_FAB2(SCH_1):P3E_CPU1_PE3_MP_C_TXP(1)
  G1 P3E_CPU1_PE3_MP_RXP<2>   IOG1 @BASEBOARD_FAB2_LIB.BASEBOARD_FAB2(SCH_1):P3E_CPU1_PE3_MP_RXP(2)
  G3 SPA_MID_DBG_TX_R   IOG3 @BASEBOARD_FAB2_LIB.BASEBOARD_FAB2(SCH_1):SPA_MID_DBG_TX_R
  G5 FM_MB_SLOT_ID1   IOG5 @BASEBOARD_FAB2_LIB.BASEBOARD_FAB2(SCH_1):FM_MB_SLOT_ID1
  G7 P3E_CPU1_PE3_MP_C_TXP<5>   IOG7 @BASEBOARD_FAB2_LIB.BASEBOARD_FAB2(SCH_1):P3E_CPU1_PE3_MP_C_TXP(5)
  H1 P3E_CPU1_PE3_MP_RXN<2>   IOH1 @BASEBOARD_FAB2_LIB.BASEBOARD_FAB2(SCH_1):P3E_CPU1_PE3_MP_RXN(2)
  H2 P3E_CPU1_PE3_MP_RXP<5>   IOH2 @BASEBOARD_FAB2_LIB.BASEBOARD_FAB2(SCH_1):P3E_CPU1_PE3_MP_RXP(5)
  H3 SPA_MID_DBG_RX_R   IOH3 @BASEBOARD_FAB2_LIB.BASEBOARD_FAB2(SCH_1):SPA_MID_DBG_RX_R
  H4 CLK_100M_AIRMAX8_PE1_DP   IOH4 @BASEBOARD_FAB2_LIB.BASEBOARD_FAB2(SCH_1):CLK_100M_AIRMAX8_PE1_DP
  H5 FM_MB_SLOT_ID2   IOH5 @BASEBOARD_FAB2_LIB.BASEBOARD_FAB2(SCH_1):FM_MB_SLOT_ID2
  H6 P3E_CPU1_PE3_MP_C_TXP<7>   IOH6 @BASEBOARD_FAB2_LIB.BASEBOARD_FAB2(SCH_1):P3E_CPU1_PE3_MP_C_TXP(7)
  H7 P3E_CPU1_PE3_MP_C_TXN<5>   IOH7 @BASEBOARD_FAB2_LIB.BASEBOARD_FAB2(SCH_1):P3E_CPU1_PE3_MP_C_TXN(5)
  H8 P3E_CPU1_PE3_MP_C_TXN<2>   IOH8 @BASEBOARD_FAB2_LIB.BASEBOARD_FAB2(SCH_1):P3E_CPU1_PE3_MP_C_TXN(2)
  I2 P3E_CPU1_PE3_MP_RXN<5>   IOI2 @BASEBOARD_FAB2_LIB.BASEBOARD_FAB2(SCH_1):P3E_CPU1_PE3_MP_RXN(5)
  I4 CLK_100M_AIRMAX8_PE1_DN   IOI4 @BASEBOARD_FAB2_LIB.BASEBOARD_FAB2(SCH_1):CLK_100M_AIRMAX8_PE1_DN
  I6 P3E_CPU1_PE3_MP_C_TXN<7>   IOI6 @BASEBOARD_FAB2_LIB.BASEBOARD_FAB2(SCH_1):P3E_CPU1_PE3_MP_C_TXN(7)
  I8 P3E_CPU1_PE3_MP_C_TXP<2>   IOI8 @BASEBOARD_FAB2_LIB.BASEBOARD_FAB2(SCH_1):P3E_CPU1_PE3_MP_C_TXP(2)

CAP_0402-0.22UF,16V,10%,X7R,A3A  I160  C1F4
   1 P3E_CPU1_PE3_MP_C_TXN<6>      A @BASEBOARD_FAB2_LIB.BASEBOARD_FAB2(SCH_1):P3E_CPU1_PE3_MP_C_TXN(6)
   2 P3E_CPU1_PE3_MP_TXN<6>      B @BASEBOARD_FAB2_LIB.BASEBOARD_FAB2(SCH_1):P3E_CPU1_PE3_MP_TXN(6)

CAP_0402-0.22UF,16V,10%,X7R,A3A  I161  C1F5
   1 P3E_CPU1_PE3_MP_C_TXP<6>      A @BASEBOARD_FAB2_LIB.BASEBOARD_FAB2(SCH_1):P3E_CPU1_PE3_MP_C_TXP(6)
   2 P3E_CPU1_PE3_MP_TXP<6>      B @BASEBOARD_FAB2_LIB.BASEBOARD_FAB2(SCH_1):P3E_CPU1_PE3_MP_TXP(6)

CAP_0402-0.22UF,16V,10%,X7R,A3A  I162  C1F2
   1 P3E_CPU1_PE3_MP_C_TXP<7>      A @BASEBOARD_FAB2_LIB.BASEBOARD_FAB2(SCH_1):P3E_CPU1_PE3_MP_C_TXP(7)
   2 P3E_CPU1_PE3_MP_TXP<7>      B @BASEBOARD_FAB2_LIB.BASEBOARD_FAB2(SCH_1):P3E_CPU1_PE3_MP_TXP(7)

CAP_0402-0.22UF,16V,10%,X7R,A3A  I163  C1F13
   1 P3E_CPU1_PE3_MP_C_TXN<3>      A @BASEBOARD_FAB2_LIB.BASEBOARD_FAB2(SCH_1):P3E_CPU1_PE3_MP_C_TXN(3)
   2 P3E_CPU1_PE3_MP_TXN<3>      B @BASEBOARD_FAB2_LIB.BASEBOARD_FAB2(SCH_1):P3E_CPU1_PE3_MP_TXN(3)

CAP_0402-0.22UF,16V,10%,X7R,A3A  I164  C1F10
   1 P3E_CPU1_PE3_MP_C_TXN<4>      A @BASEBOARD_FAB2_LIB.BASEBOARD_FAB2(SCH_1):P3E_CPU1_PE3_MP_C_TXN(4)
   2 P3E_CPU1_PE3_MP_TXN<4>      B @BASEBOARD_FAB2_LIB.BASEBOARD_FAB2(SCH_1):P3E_CPU1_PE3_MP_TXN(4)

CAP_0402-0.22UF,16V,10%,X7R,A3A  I165  C1F6
   1 P3E_CPU1_PE3_MP_C_TXP<5>      A @BASEBOARD_FAB2_LIB.BASEBOARD_FAB2(SCH_1):P3E_CPU1_PE3_MP_C_TXP(5)
   2 P3E_CPU1_PE3_MP_TXP<5>      B @BASEBOARD_FAB2_LIB.BASEBOARD_FAB2(SCH_1):P3E_CPU1_PE3_MP_TXP(5)

CAP_0402-0.22UF,16V,10%,X7R,A3A  I166  C1F20
   1 P3E_CPU1_PE3_MP_C_TXN<0>      A @BASEBOARD_FAB2_LIB.BASEBOARD_FAB2(SCH_1):P3E_CPU1_PE3_MP_C_TXN(0)
   2 P3E_CPU1_PE3_MP_TXN<0>      B @BASEBOARD_FAB2_LIB.BASEBOARD_FAB2(SCH_1):P3E_CPU1_PE3_MP_TXN(0)

CAP_0402-0.22UF,16V,10%,X7R,A3A  I167  C1F3
   1 P3E_CPU1_PE3_MP_C_TXN<7>      A @BASEBOARD_FAB2_LIB.BASEBOARD_FAB2(SCH_1):P3E_CPU1_PE3_MP_C_TXN(7)
   2 P3E_CPU1_PE3_MP_TXN<7>      B @BASEBOARD_FAB2_LIB.BASEBOARD_FAB2(SCH_1):P3E_CPU1_PE3_MP_TXN(7)

CAP_0402-0.22UF,16V,10%,X7R,A3A  I168  C1F12
   1 P3E_CPU1_PE3_MP_C_TXP<3>      A @BASEBOARD_FAB2_LIB.BASEBOARD_FAB2(SCH_1):P3E_CPU1_PE3_MP_C_TXP(3)
   2 P3E_CPU1_PE3_MP_TXP<3>      B @BASEBOARD_FAB2_LIB.BASEBOARD_FAB2(SCH_1):P3E_CPU1_PE3_MP_TXP(3)

CAP_0402-0.22UF,16V,10%,X7R,A3A  I169  C1F11
   1 P3E_CPU1_PE3_MP_C_TXP<4>      A @BASEBOARD_FAB2_LIB.BASEBOARD_FAB2(SCH_1):P3E_CPU1_PE3_MP_C_TXP(4)
   2 P3E_CPU1_PE3_MP_TXP<4>      B @BASEBOARD_FAB2_LIB.BASEBOARD_FAB2(SCH_1):P3E_CPU1_PE3_MP_TXP(4)

CAP_0402-0.22UF,16V,10%,X7R,A3A  I170  C1F8
   1 P3E_CPU1_PE3_MP_C_TXN<5>      A @BASEBOARD_FAB2_LIB.BASEBOARD_FAB2(SCH_1):P3E_CPU1_PE3_MP_C_TXN(5)
   2 P3E_CPU1_PE3_MP_TXN<5>      B @BASEBOARD_FAB2_LIB.BASEBOARD_FAB2(SCH_1):P3E_CPU1_PE3_MP_TXN(5)

CAP_0402-0.22UF,16V,10%,X7R,A3A  I171  C1F18
   1 P3E_CPU1_PE3_MP_C_TXP<0>      A @BASEBOARD_FAB2_LIB.BASEBOARD_FAB2(SCH_1):P3E_CPU1_PE3_MP_C_TXP(0)
   2 P3E_CPU1_PE3_MP_TXP<0>      B @BASEBOARD_FAB2_LIB.BASEBOARD_FAB2(SCH_1):P3E_CPU1_PE3_MP_TXP(0)

CAP_0402-0.22UF,16V,10%,X7R,A3A  I172  C1F16
   1 P3E_CPU1_PE3_MP_C_TXN<1>      A @BASEBOARD_FAB2_LIB.BASEBOARD_FAB2(SCH_1):P3E_CPU1_PE3_MP_C_TXN(1)
   2 P3E_CPU1_PE3_MP_TXN<1>      B @BASEBOARD_FAB2_LIB.BASEBOARD_FAB2(SCH_1):P3E_CPU1_PE3_MP_TXN(1)

CAP_0402-0.22UF,16V,10%,X7R,A3A  I173  C1F17
   1 P3E_CPU1_PE3_MP_C_TXP<1>      A @BASEBOARD_FAB2_LIB.BASEBOARD_FAB2(SCH_1):P3E_CPU1_PE3_MP_C_TXP(1)
   2 P3E_CPU1_PE3_MP_TXP<1>      B @BASEBOARD_FAB2_LIB.BASEBOARD_FAB2(SCH_1):P3E_CPU1_PE3_MP_TXP(1)

CAP_0402-0.22UF,16V,10%,X7R,A3A  I174  C1F15
   1 P3E_CPU1_PE3_MP_C_TXN<2>      A @BASEBOARD_FAB2_LIB.BASEBOARD_FAB2(SCH_1):P3E_CPU1_PE3_MP_C_TXN(2)
   2 P3E_CPU1_PE3_MP_TXN<2>      B @BASEBOARD_FAB2_LIB.BASEBOARD_FAB2(SCH_1):P3E_CPU1_PE3_MP_TXN(2)

CAP_0402-0.22UF,16V,10%,X7R,A3A  I175  C1F14
   1 P3E_CPU1_PE3_MP_C_TXP<2>      A @BASEBOARD_FAB2_LIB.BASEBOARD_FAB2(SCH_1):P3E_CPU1_PE3_MP_C_TXP(2)
   2 P3E_CPU1_PE3_MP_TXP<2>      B @BASEBOARD_FAB2_LIB.BASEBOARD_FAB2(SCH_1):P3E_CPU1_PE3_MP_TXP(2)

RES_0402-4.75K,1%,1/16W,CHIP,GA  I177  R9T9
   1 P12V_PSU      A @BASEBOARD_FAB2_LIB.BASEBOARD_FAB2(SCH_1):P12V_PSU
   2 FM_MATED_IN_N      B @BASEBOARD_FAB2_LIB.BASEBOARD_FAB2(SCH_1):FM_MATED_IN_N

DIODE_SM-SDMK0340L,IC,H71799-0A  I178  CR1F4
   1 FM_MATED_IN_D1_N      C @BASEBOARD_FAB2_LIB.BASEBOARD_FAB2(SCH_1):FM_MATED_IN_D1_N
   2 FM_MATED_IN_N      A @BASEBOARD_FAB2_LIB.BASEBOARD_FAB2(SCH_1):FM_MATED_IN_N

DIODE_SM-SDMK0340L,IC,H71799-0A  I180  CR1F3
   1 FM_MATED_IN_D2_N      C @BASEBOARD_FAB2_LIB.BASEBOARD_FAB2(SCH_1):FM_MATED_IN_D2_N
   2 FM_MATED_IN_D1_N      A @BASEBOARD_FAB2_LIB.BASEBOARD_FAB2(SCH_1):FM_MATED_IN_D1_N

NPN_SM-MMBT3904,IC,C52245-001  I181  Q9T1
   1 FM_MATED_IN_D2_N      B @BASEBOARD_FAB2_LIB.BASEBOARD_FAB2(SCH_1):FM_MATED_IN_D2_N
   3 FM_P12V_HOTSWAP0_EN      C @BASEBOARD_FAB2_LIB.BASEBOARD_FAB2(SCH_1):FM_P12V_HOTSWAP0_EN
   2    GND      E @BASEBOARD_FAB2_LIB.BASEBOARD_FAB2(SCH_1):GND

RES_0402-15.0K,1%,1/16W,CHIP,GA  I183  R9T6
   1 P12V_PSU      A @BASEBOARD_FAB2_LIB.BASEBOARD_FAB2(SCH_1):P12V_PSU
   2 FM_P12V_HOTSWAP0_EN      B @BASEBOARD_FAB2_LIB.BASEBOARD_FAB2(SCH_1):FM_P12V_HOTSWAP0_EN

RES_0402-6.19K,1%,1/16W,CHIP,GA  I185  R9T3
   1 FM_P12V_HOTSWAP0_EN      A @BASEBOARD_FAB2_LIB.BASEBOARD_FAB2(SCH_1):FM_P12V_HOTSWAP0_EN
   2    GND      B @BASEBOARD_FAB2_LIB.BASEBOARD_FAB2(SCH_1):GND

CONN8_H62179001_PIP-CONN,H6217A  I189  J1F3
   1 P3V3_STBY    IO1 @BASEBOARD_FAB2_LIB.BASEBOARD_FAB2(SCH_1):P3V3_STBY
   2 FM_MP_PS_REDUNDANT_LOST_N    IO2 @BASEBOARD_FAB2_LIB.BASEBOARD_FAB2(SCH_1):FM_MP_PS_REDUNDANT_LOST_N
   3 FM_MP_PS_FAIL_N    IO3 @BASEBOARD_FAB2_LIB.BASEBOARD_FAB2(SCH_1):FM_MP_PS_FAIL_N
   4 FM_MATED_IN_N    IO4 @BASEBOARD_FAB2_LIB.BASEBOARD_FAB2(SCH_1):FM_MATED_IN_N
   5 IRQ_SML1_PMBUS_ALERT_R_N    IO5 @BASEBOARD_FAB2_LIB.BASEBOARD_FAB2(SCH_1):IRQ_SML1_PMBUS_ALERT_R_N
   6 SMB_BMC_PMBUS_STBY_LVC3_SDA    IO6 @BASEBOARD_FAB2_LIB.BASEBOARD_FAB2(SCH_1):SMB_BMC_PMBUS_STBY_LVC3_SDA
   7 SMB_BMC_PMBUS_STBY_LVC3_SCL    IO7 @BASEBOARD_FAB2_LIB.BASEBOARD_FAB2(SCH_1):SMB_BMC_PMBUS_STBY_LVC3_SCL
   8    GND    IO8 @BASEBOARD_FAB2_LIB.BASEBOARD_FAB2(SCH_1):GND

RES_0402-2.26K,1.0%,1/16W,CHIPA  I199  R7D5
   1 P3V3_STBY      A @BASEBOARD_FAB2_LIB.BASEBOARD_FAB2(SCH_1):P3V3_STBY
   2 FM_MB_SLOT_ID0      B @BASEBOARD_FAB2_LIB.BASEBOARD_FAB2(SCH_1):FM_MB_SLOT_ID0

RES_0402-2.26K,1.0%,1/16W,CHIPA  I200  R7D9
   1 P3V3_STBY      A @BASEBOARD_FAB2_LIB.BASEBOARD_FAB2(SCH_1):P3V3_STBY
   2 FM_MB_SLOT_ID1      B @BASEBOARD_FAB2_LIB.BASEBOARD_FAB2(SCH_1):FM_MB_SLOT_ID1

RES_0402-2.26K,1.0%,1/16W,CHIPA  I201  R3P61
   1 P3V3_STBY      A @BASEBOARD_FAB2_LIB.BASEBOARD_FAB2(SCH_1):P3V3_STBY
   2 FM_MB_SLOT_ID2      B @BASEBOARD_FAB2_LIB.BASEBOARD_FAB2(SCH_1):FM_MB_SLOT_ID2

RES_0402-33.2,1%,1/16W,CHIP,G2A  I218  R8E5
   1 FM_CTNR_PS_ON_R      A @BASEBOARD_FAB2_LIB.BASEBOARD_FAB2(SCH_1):FM_CTNR_PS_ON_R
   2 FM_CTNR_PS_ON      B @BASEBOARD_FAB2_LIB.BASEBOARD_FAB2(SCH_1):FM_CTNR_PS_ON

CAP_0402LF-470PF,50V,10%,EMPTYA  I224  C2R6
   1 FM_PS_EN      A @BASEBOARD_FAB2_LIB.BASEBOARD_FAB2(SCH_1):FM_PS_EN
   2    GND      B @BASEBOARD_FAB2_LIB.BASEBOARD_FAB2(SCH_1):GND

TTL08_QFN15-74LVC08A,IC,D90404B  I243  U8E1
   8 FM_CTNR_PS_ON_R   Y<0> @BASEBOARD_FAB2_LIB.BASEBOARD_FAB2(SCH_1):FM_CTNR_PS_ON_R
  10 PWRGD_P12V_HSC_DLY   B<0> @BASEBOARD_FAB2_LIB.BASEBOARD_FAB2(SCH_1):PWRGD_P12V_HSC_DLY
   9 FM_PS_EN   A<0> @BASEBOARD_FAB2_LIB.BASEBOARD_FAB2(SCH_1):FM_PS_EN

CAP_A_0402V-0.1UF,16V,10%,X7R,A  I253  C8E1
   1 P3V3_STBY      A @BASEBOARD_FAB2_LIB.BASEBOARD_FAB2(SCH_1):P3V3_STBY
   2    GND      B @BASEBOARD_FAB2_LIB.BASEBOARD_FAB2(SCH_1):GND

RES_0402-0.0,5%,1/16W,CHIP,G21A  I254  R9R9
   1 FAN_TACH3      A @BASEBOARD_FAB2_LIB.BASEBOARD_FAB2(SCH_1):FAN_TACH3
   2 FAN_TACH3_R      B @BASEBOARD_FAB2_LIB.BASEBOARD_FAB2(SCH_1):FAN_TACH3_R

RES_0402-0.0,5%,1/16W,CHIP,G21A  I255  R9R12
   1 FAN_TACH2      A @BASEBOARD_FAB2_LIB.BASEBOARD_FAB2(SCH_1):FAN_TACH2
   2 FAN_TACH2_R      B @BASEBOARD_FAB2_LIB.BASEBOARD_FAB2(SCH_1):FAN_TACH2_R

RES_0402-0.0,5%,1/16W,CHIP,G21A  I256  R9R10
   1 FAN_TACH1      A @BASEBOARD_FAB2_LIB.BASEBOARD_FAB2(SCH_1):FAN_TACH1
   2 FAN_TACH1_R      B @BASEBOARD_FAB2_LIB.BASEBOARD_FAB2(SCH_1):FAN_TACH1_R

RES_0402-0.0,5%,1/16W,CHIP,G21A  I261  R9T1
   1 FAN_PWM_OUT_SYS0_R      A @BASEBOARD_FAB2_LIB.BASEBOARD_FAB2(SCH_1):FAN_PWM_OUT_SYS0_R
   2 FAN_PWM_OUT_SYS0_R1      B @BASEBOARD_FAB2_LIB.BASEBOARD_FAB2(SCH_1):FAN_PWM_OUT_SYS0_R1

RES_0402-0.0,5%,1/16W,CHIP,G21A  I268  R1F8
   1 FAN_TACH0      A @BASEBOARD_FAB2_LIB.BASEBOARD_FAB2(SCH_1):FAN_TACH0
   2 FAN_TACH0_R      B @BASEBOARD_FAB2_LIB.BASEBOARD_FAB2(SCH_1):FAN_TACH0_R

RES_0402-0.0,5%,1/16W,CHIP,G21A  I278  R9T8
   1    GND      A @BASEBOARD_FAB2_LIB.BASEBOARD_FAB2(SCH_1):GND
   2 FM_MATED_IN_N      B @BASEBOARD_FAB2_LIB.BASEBOARD_FAB2(SCH_1):FM_MATED_IN_N

RES_0402-0.0,5%,1/16W,CHIP,G21A  I279  R9F67
   1 SP2_BMC_CM_UART_RX_R1      A @BASEBOARD_FAB2_LIB.BASEBOARD_FAB2(SCH_1):SP2_BMC_CM_UART_RX_R1
   2 SPA_MID_DBG_TX_R      B @BASEBOARD_FAB2_LIB.BASEBOARD_FAB2(SCH_1):SPA_MID_DBG_TX_R

RES_0402-0.0,5%,1/16W,EMPTY,G2A  I280  R9F70
   1 SPA_MID_DBG_TX      A @BASEBOARD_FAB2_LIB.BASEBOARD_FAB2(SCH_1):SPA_MID_DBG_TX
   2 SPA_MID_DBG_TX_R      B @BASEBOARD_FAB2_LIB.BASEBOARD_FAB2(SCH_1):SPA_MID_DBG_TX_R

RES_0402-0.0,5%,1/16W,CHIP,G21A  I281  R9F64
   1 SP2_BMC_CM_UART_TX_R1      A @BASEBOARD_FAB2_LIB.BASEBOARD_FAB2(SCH_1):SP2_BMC_CM_UART_TX_R1
   2 SPA_MID_DBG_RX_R      B @BASEBOARD_FAB2_LIB.BASEBOARD_FAB2(SCH_1):SPA_MID_DBG_RX_R

RES_0402-0.0,5%,1/16W,EMPTY,G2A  I282  R9F63
   1 SPA_MID_DBG_RX      A @BASEBOARD_FAB2_LIB.BASEBOARD_FAB2(SCH_1):SPA_MID_DBG_RX
   2 SPA_MID_DBG_RX_R      B @BASEBOARD_FAB2_LIB.BASEBOARD_FAB2(SCH_1):SPA_MID_DBG_RX_R


DRAWING: @BASEBOARD_FAB2_LIB.BASEBOARD_FAB2(SCH_1):PAGE182 

CAP_0402-0.22UF,16V,10%,X7R,A3A  I9  C9N18
   1 P3E_CPU1_PE3_MP_C_TXN<8>      A @BASEBOARD_FAB2_LIB.BASEBOARD_FAB2(SCH_1):P3E_CPU1_PE3_MP_C_TXN(8)
   2 P3E_CPU1_PE3_MP_TXN<8>      B @BASEBOARD_FAB2_LIB.BASEBOARD_FAB2(SCH_1):P3E_CPU1_PE3_MP_TXN(8)

CAP_0402-0.22UF,16V,10%,X7R,A3A  I12  C9N17
   1 P3E_CPU1_PE3_MP_C_TXP<8>      A @BASEBOARD_FAB2_LIB.BASEBOARD_FAB2(SCH_1):P3E_CPU1_PE3_MP_C_TXP(8)
   2 P3E_CPU1_PE3_MP_TXP<8>      B @BASEBOARD_FAB2_LIB.BASEBOARD_FAB2(SCH_1):P3E_CPU1_PE3_MP_TXP(8)

CAP_0402-0.22UF,16V,10%,X7R,A3A  I13  C9N15
   1 P3E_CPU1_PE3_MP_C_TXN<9>      A @BASEBOARD_FAB2_LIB.BASEBOARD_FAB2(SCH_1):P3E_CPU1_PE3_MP_C_TXN(9)
   2 P3E_CPU1_PE3_MP_TXN<9>      B @BASEBOARD_FAB2_LIB.BASEBOARD_FAB2(SCH_1):P3E_CPU1_PE3_MP_TXN(9)

CAP_0402-0.22UF,16V,10%,X7R,A3A  I14  C9N1
   1 P3E_CPU1_PE3_MP_C_TXP<10>      A @BASEBOARD_FAB2_LIB.BASEBOARD_FAB2(SCH_1):P3E_CPU1_PE3_MP_C_TXP(10)
   2 P3E_CPU1_PE3_MP_TXP<10>      B @BASEBOARD_FAB2_LIB.BASEBOARD_FAB2(SCH_1):P3E_CPU1_PE3_MP_TXP(10)

CAP_0402-0.22UF,16V,10%,X7R,A3A  I15  C9N2
   1 P3E_CPU1_PE3_MP_C_TXN<10>      A @BASEBOARD_FAB2_LIB.BASEBOARD_FAB2(SCH_1):P3E_CPU1_PE3_MP_C_TXN(10)
   2 P3E_CPU1_PE3_MP_TXN<10>      B @BASEBOARD_FAB2_LIB.BASEBOARD_FAB2(SCH_1):P3E_CPU1_PE3_MP_TXN(10)

CAP_0402-0.22UF,16V,10%,X7R,A3A  I16  C9N12
   1 P3E_CPU1_PE3_MP_C_TXP<9>      A @BASEBOARD_FAB2_LIB.BASEBOARD_FAB2(SCH_1):P3E_CPU1_PE3_MP_C_TXP(9)
   2 P3E_CPU1_PE3_MP_TXP<9>      B @BASEBOARD_FAB2_LIB.BASEBOARD_FAB2(SCH_1):P3E_CPU1_PE3_MP_TXP(9)

CONN76_H22707001_THMT1-CONN,H2A  I18  J1C1
  A2    GND  GNDA2 @BASEBOARD_FAB2_LIB.BASEBOARD_FAB2(SCH_1):GND
  A4    GND  GNDA4 @BASEBOARD_FAB2_LIB.BASEBOARD_FAB2(SCH_1):GND
  A6    GND  GNDA6 @BASEBOARD_FAB2_LIB.BASEBOARD_FAB2(SCH_1):GND
  A8    GND  GNDA8 @BASEBOARD_FAB2_LIB.BASEBOARD_FAB2(SCH_1):GND
  C1    GND  GNDC1 @BASEBOARD_FAB2_LIB.BASEBOARD_FAB2(SCH_1):GND
  C3    GND  GNDC3 @BASEBOARD_FAB2_LIB.BASEBOARD_FAB2(SCH_1):GND
  C5    GND  GNDC5 @BASEBOARD_FAB2_LIB.BASEBOARD_FAB2(SCH_1):GND
  C7    GND  GNDC7 @BASEBOARD_FAB2_LIB.BASEBOARD_FAB2(SCH_1):GND
  D2    GND  GNDD2 @BASEBOARD_FAB2_LIB.BASEBOARD_FAB2(SCH_1):GND
  D4    GND  GNDD4 @BASEBOARD_FAB2_LIB.BASEBOARD_FAB2(SCH_1):GND
  D6    GND  GNDD6 @BASEBOARD_FAB2_LIB.BASEBOARD_FAB2(SCH_1):GND
  D8    GND  GNDD8 @BASEBOARD_FAB2_LIB.BASEBOARD_FAB2(SCH_1):GND
  F1    GND  GNDF1 @BASEBOARD_FAB2_LIB.BASEBOARD_FAB2(SCH_1):GND
  F3    GND  GNDF3 @BASEBOARD_FAB2_LIB.BASEBOARD_FAB2(SCH_1):GND
  F5    GND  GNDF5 @BASEBOARD_FAB2_LIB.BASEBOARD_FAB2(SCH_1):GND
  F7    GND  GNDF7 @BASEBOARD_FAB2_LIB.BASEBOARD_FAB2(SCH_1):GND
  G2    GND  GNDG2 @BASEBOARD_FAB2_LIB.BASEBOARD_FAB2(SCH_1):GND
  G4    GND  GNDG4 @BASEBOARD_FAB2_LIB.BASEBOARD_FAB2(SCH_1):GND
  G6    GND  GNDG6 @BASEBOARD_FAB2_LIB.BASEBOARD_FAB2(SCH_1):GND
  G8    GND  GNDG8 @BASEBOARD_FAB2_LIB.BASEBOARD_FAB2(SCH_1):GND
  I1    GND  GNDI1 @BASEBOARD_FAB2_LIB.BASEBOARD_FAB2(SCH_1):GND
  I3    GND  GNDI3 @BASEBOARD_FAB2_LIB.BASEBOARD_FAB2(SCH_1):GND
  I5    GND  GNDI5 @BASEBOARD_FAB2_LIB.BASEBOARD_FAB2(SCH_1):GND
  I7    GND  GNDI7 @BASEBOARD_FAB2_LIB.BASEBOARD_FAB2(SCH_1):GND
  J2    GND  GNDJ2 @BASEBOARD_FAB2_LIB.BASEBOARD_FAB2(SCH_1):GND
  J4    GND  GNDJ4 @BASEBOARD_FAB2_LIB.BASEBOARD_FAB2(SCH_1):GND
  J6    GND  GNDJ6 @BASEBOARD_FAB2_LIB.BASEBOARD_FAB2(SCH_1):GND
  J8    GND  GNDJ8 @BASEBOARD_FAB2_LIB.BASEBOARD_FAB2(SCH_1):GND
  A1 P3E_CPU1_PE3_MP_RXN<8>   IOA1 @BASEBOARD_FAB2_LIB.BASEBOARD_FAB2(SCH_1):P3E_CPU1_PE3_MP_RXN(8)
  A3 P3E_CPU1_PE3_MP_RXP<14>   IOA3 @BASEBOARD_FAB2_LIB.BASEBOARD_FAB2(SCH_1):P3E_CPU1_PE3_MP_RXP(14)
  A5 TP_IOA5   IOA5 @BASEBOARD_FAB2_LIB.BASEBOARD_FAB2(SCH_1):TP_IOA5
  A7 P3E_CPU1_PE3_MP_C_TXN<11>   IOA7 @BASEBOARD_FAB2_LIB.BASEBOARD_FAB2(SCH_1):P3E_CPU1_PE3_MP_C_TXN(11)
  B1 P3E_CPU1_PE3_MP_RXP<8>   IOB1 @BASEBOARD_FAB2_LIB.BASEBOARD_FAB2(SCH_1):P3E_CPU1_PE3_MP_RXP(8)
  B2 P3E_CPU1_PE3_MP_RXN<11>   IOB2 @BASEBOARD_FAB2_LIB.BASEBOARD_FAB2(SCH_1):P3E_CPU1_PE3_MP_RXN(11)
  B3 P3E_CPU1_PE3_MP_RXN<14>   IOB3 @BASEBOARD_FAB2_LIB.BASEBOARD_FAB2(SCH_1):P3E_CPU1_PE3_MP_RXN(14)
  B4 TP_FM_WAKE_N   IOB4 @BASEBOARD_FAB2_LIB.BASEBOARD_FAB2(SCH_1):TP_FM_WAKE_N
  B5 IRQ_BOARD_BMC_ALERT_N   IOB5 @BASEBOARD_FAB2_LIB.BASEBOARD_FAB2(SCH_1):IRQ_BOARD_BMC_ALERT_N
  B6 SMB_PEHPCPU1_STBY_LVC3_SDA   IOB6 @BASEBOARD_FAB2_LIB.BASEBOARD_FAB2(SCH_1):SMB_PEHPCPU1_STBY_LVC3_SDA
  B7 P3E_CPU1_PE3_MP_C_TXP<11>   IOB7 @BASEBOARD_FAB2_LIB.BASEBOARD_FAB2(SCH_1):P3E_CPU1_PE3_MP_C_TXP(11)
  B8 P3E_CPU1_PE3_MP_C_TXN<8>   IOB8 @BASEBOARD_FAB2_LIB.BASEBOARD_FAB2(SCH_1):P3E_CPU1_PE3_MP_C_TXN(8)
  C2 P3E_CPU1_PE3_MP_RXP<11>   IOC2 @BASEBOARD_FAB2_LIB.BASEBOARD_FAB2(SCH_1):P3E_CPU1_PE3_MP_RXP(11)
  C4 FM_BB_BMC_MP_GPIO   IOC4 @BASEBOARD_FAB2_LIB.BASEBOARD_FAB2(SCH_1):FM_BB_BMC_MP_GPIO
  C6 SMB_PEHPCPU1_STBY_LVC3_SCL   IOC6 @BASEBOARD_FAB2_LIB.BASEBOARD_FAB2(SCH_1):SMB_PEHPCPU1_STBY_LVC3_SCL
  C8 P3E_CPU1_PE3_MP_C_TXP<8>   IOC8 @BASEBOARD_FAB2_LIB.BASEBOARD_FAB2(SCH_1):P3E_CPU1_PE3_MP_C_TXP(8)
  D1 P3E_CPU1_PE3_MP_RXN<9>   IOD1 @BASEBOARD_FAB2_LIB.BASEBOARD_FAB2(SCH_1):P3E_CPU1_PE3_MP_RXN(9)
  D3 P3E_CPU1_PE3_MP_RXN<15>   IOD3 @BASEBOARD_FAB2_LIB.BASEBOARD_FAB2(SCH_1):P3E_CPU1_PE3_MP_RXN(15)
  D5 SMB_LAN_STBY_LVC3_SDA   IOD5 @BASEBOARD_FAB2_LIB.BASEBOARD_FAB2(SCH_1):SMB_LAN_STBY_LVC3_SDA
  D7 P3E_CPU1_PE3_MP_C_TXN<12>   IOD7 @BASEBOARD_FAB2_LIB.BASEBOARD_FAB2(SCH_1):P3E_CPU1_PE3_MP_C_TXN(12)
  E1 P3E_CPU1_PE3_MP_RXP<9>   IOE1 @BASEBOARD_FAB2_LIB.BASEBOARD_FAB2(SCH_1):P3E_CPU1_PE3_MP_RXP(9)
  E2 P3E_CPU1_PE3_MP_RXN<12>   IOE2 @BASEBOARD_FAB2_LIB.BASEBOARD_FAB2(SCH_1):P3E_CPU1_PE3_MP_RXN(12)
  E3 P3E_CPU1_PE3_MP_RXP<15>   IOE3 @BASEBOARD_FAB2_LIB.BASEBOARD_FAB2(SCH_1):P3E_CPU1_PE3_MP_RXP(15)
  E4 TP_IOE4   IOE4 @BASEBOARD_FAB2_LIB.BASEBOARD_FAB2(SCH_1):TP_IOE4
  E5 SMB_LAN_STBY_LVC3_SCL   IOE5 @BASEBOARD_FAB2_LIB.BASEBOARD_FAB2(SCH_1):SMB_LAN_STBY_LVC3_SCL
  E6 P3E_CPU1_PE3_MP_C_TXN<14>   IOE6 @BASEBOARD_FAB2_LIB.BASEBOARD_FAB2(SCH_1):P3E_CPU1_PE3_MP_C_TXN(14)
  E7 P3E_CPU1_PE3_MP_C_TXP<12>   IOE7 @BASEBOARD_FAB2_LIB.BASEBOARD_FAB2(SCH_1):P3E_CPU1_PE3_MP_C_TXP(12)
  E8 P3E_CPU1_PE3_MP_C_TXN<9>   IOE8 @BASEBOARD_FAB2_LIB.BASEBOARD_FAB2(SCH_1):P3E_CPU1_PE3_MP_C_TXN(9)
  F2 P3E_CPU1_PE3_MP_RXP<12>   IOF2 @BASEBOARD_FAB2_LIB.BASEBOARD_FAB2(SCH_1):P3E_CPU1_PE3_MP_RXP(12)
  F4 TP_IOF4   IOF4 @BASEBOARD_FAB2_LIB.BASEBOARD_FAB2(SCH_1):TP_IOF4
  F6 P3E_CPU1_PE3_MP_C_TXP<14>   IOF6 @BASEBOARD_FAB2_LIB.BASEBOARD_FAB2(SCH_1):P3E_CPU1_PE3_MP_C_TXP(14)
  F8 P3E_CPU1_PE3_MP_C_TXP<9>   IOF8 @BASEBOARD_FAB2_LIB.BASEBOARD_FAB2(SCH_1):P3E_CPU1_PE3_MP_C_TXP(9)
  G1 P3E_CPU1_PE3_MP_RXP<10>   IOG1 @BASEBOARD_FAB2_LIB.BASEBOARD_FAB2(SCH_1):P3E_CPU1_PE3_MP_RXP(10)
  G3 TP_IOG3   IOG3 @BASEBOARD_FAB2_LIB.BASEBOARD_FAB2(SCH_1):TP_IOG3
  G5 FM_XRC_PRESENT_N   IOG5 @BASEBOARD_FAB2_LIB.BASEBOARD_FAB2(SCH_1):FM_XRC_PRESENT_N
  G7 P3E_CPU1_PE3_MP_C_TXN<13>   IOG7 @BASEBOARD_FAB2_LIB.BASEBOARD_FAB2(SCH_1):P3E_CPU1_PE3_MP_C_TXN(13)
  H1 P3E_CPU1_PE3_MP_RXN<10>   IOH1 @BASEBOARD_FAB2_LIB.BASEBOARD_FAB2(SCH_1):P3E_CPU1_PE3_MP_RXN(10)
  H2 P3E_CPU1_PE3_MP_RXP<13>   IOH2 @BASEBOARD_FAB2_LIB.BASEBOARD_FAB2(SCH_1):P3E_CPU1_PE3_MP_RXP(13)
  H3 TP_IOH3   IOH3 @BASEBOARD_FAB2_LIB.BASEBOARD_FAB2(SCH_1):TP_IOH3
  H4 TP_IOH4   IOH4 @BASEBOARD_FAB2_LIB.BASEBOARD_FAB2(SCH_1):TP_IOH4
  H5 FM_XRC_READY_N   IOH5 @BASEBOARD_FAB2_LIB.BASEBOARD_FAB2(SCH_1):FM_XRC_READY_N
  H6 P3E_CPU1_PE3_MP_C_TXN<15>   IOH6 @BASEBOARD_FAB2_LIB.BASEBOARD_FAB2(SCH_1):P3E_CPU1_PE3_MP_C_TXN(15)
  H7 P3E_CPU1_PE3_MP_C_TXP<13>   IOH7 @BASEBOARD_FAB2_LIB.BASEBOARD_FAB2(SCH_1):P3E_CPU1_PE3_MP_C_TXP(13)
  H8 P3E_CPU1_PE3_MP_C_TXP<10>   IOH8 @BASEBOARD_FAB2_LIB.BASEBOARD_FAB2(SCH_1):P3E_CPU1_PE3_MP_C_TXP(10)
  I2 P3E_CPU1_PE3_MP_RXN<13>   IOI2 @BASEBOARD_FAB2_LIB.BASEBOARD_FAB2(SCH_1):P3E_CPU1_PE3_MP_RXN(13)
  I4 TP_IOI4   IOI4 @BASEBOARD_FAB2_LIB.BASEBOARD_FAB2(SCH_1):TP_IOI4
  I6 P3E_CPU1_PE3_MP_C_TXP<15>   IOI6 @BASEBOARD_FAB2_LIB.BASEBOARD_FAB2(SCH_1):P3E_CPU1_PE3_MP_C_TXP(15)
  I8 P3E_CPU1_PE3_MP_C_TXN<10>   IOI8 @BASEBOARD_FAB2_LIB.BASEBOARD_FAB2(SCH_1):P3E_CPU1_PE3_MP_C_TXN(10)

CAP_0402-0.22UF,16V,10%,X7R,A3A  I49  C9N9
   1 P3E_CPU1_PE3_MP_C_TXN<15>      A @BASEBOARD_FAB2_LIB.BASEBOARD_FAB2(SCH_1):P3E_CPU1_PE3_MP_C_TXN(15)
   2 P3E_CPU1_PE3_MP_TXN<15>      B @BASEBOARD_FAB2_LIB.BASEBOARD_FAB2(SCH_1):P3E_CPU1_PE3_MP_TXN(15)

CAP_0402-0.22UF,16V,10%,X7R,A3A  I50  C9N8
   1 P3E_CPU1_PE3_MP_C_TXN<14>      A @BASEBOARD_FAB2_LIB.BASEBOARD_FAB2(SCH_1):P3E_CPU1_PE3_MP_C_TXN(14)
   2 P3E_CPU1_PE3_MP_TXN<14>      B @BASEBOARD_FAB2_LIB.BASEBOARD_FAB2(SCH_1):P3E_CPU1_PE3_MP_TXN(14)

CAP_0402-0.22UF,16V,10%,X7R,A3A  I51  C9N3
   1 P3E_CPU1_PE3_MP_C_TXN<11>      A @BASEBOARD_FAB2_LIB.BASEBOARD_FAB2(SCH_1):P3E_CPU1_PE3_MP_C_TXN(11)
   2 P3E_CPU1_PE3_MP_TXN<11>      B @BASEBOARD_FAB2_LIB.BASEBOARD_FAB2(SCH_1):P3E_CPU1_PE3_MP_TXN(11)

CAP_0402-0.22UF,16V,10%,X7R,A3A  I52  C9N16
   1 P3E_CPU1_PE3_MP_C_TXN<12>      A @BASEBOARD_FAB2_LIB.BASEBOARD_FAB2(SCH_1):P3E_CPU1_PE3_MP_C_TXN(12)
   2 P3E_CPU1_PE3_MP_TXN<12>      B @BASEBOARD_FAB2_LIB.BASEBOARD_FAB2(SCH_1):P3E_CPU1_PE3_MP_TXN(12)

CAP_0402-0.22UF,16V,10%,X7R,A3A  I53  C9N10
   1 P3E_CPU1_PE3_MP_C_TXP<14>      A @BASEBOARD_FAB2_LIB.BASEBOARD_FAB2(SCH_1):P3E_CPU1_PE3_MP_C_TXP(14)
   2 P3E_CPU1_PE3_MP_TXP<14>      B @BASEBOARD_FAB2_LIB.BASEBOARD_FAB2(SCH_1):P3E_CPU1_PE3_MP_TXP(14)

CAP_0402-0.22UF,16V,10%,X7R,A3A  I54  C9N7
   1 P3E_CPU1_PE3_MP_C_TXP<15>      A @BASEBOARD_FAB2_LIB.BASEBOARD_FAB2(SCH_1):P3E_CPU1_PE3_MP_C_TXP(15)
   2 P3E_CPU1_PE3_MP_TXP<15>      B @BASEBOARD_FAB2_LIB.BASEBOARD_FAB2(SCH_1):P3E_CPU1_PE3_MP_TXP(15)

CAP_0402-0.22UF,16V,10%,X7R,A3A  I55  C9N4
   1 P3E_CPU1_PE3_MP_C_TXP<11>      A @BASEBOARD_FAB2_LIB.BASEBOARD_FAB2(SCH_1):P3E_CPU1_PE3_MP_C_TXP(11)
   2 P3E_CPU1_PE3_MP_TXP<11>      B @BASEBOARD_FAB2_LIB.BASEBOARD_FAB2(SCH_1):P3E_CPU1_PE3_MP_TXP(11)

CAP_0402-0.22UF,16V,10%,X7R,A3A  I56  C9N14
   1 P3E_CPU1_PE3_MP_C_TXP<12>      A @BASEBOARD_FAB2_LIB.BASEBOARD_FAB2(SCH_1):P3E_CPU1_PE3_MP_C_TXP(12)
   2 P3E_CPU1_PE3_MP_TXP<12>      B @BASEBOARD_FAB2_LIB.BASEBOARD_FAB2(SCH_1):P3E_CPU1_PE3_MP_TXP(12)

CAP_0402-0.22UF,16V,10%,X7R,A3A  I81  C9N6
   1 P3E_CPU1_PE3_MP_C_TXN<13>      A @BASEBOARD_FAB2_LIB.BASEBOARD_FAB2(SCH_1):P3E_CPU1_PE3_MP_C_TXN(13)
   2 P3E_CPU1_PE3_MP_TXN<13>      B @BASEBOARD_FAB2_LIB.BASEBOARD_FAB2(SCH_1):P3E_CPU1_PE3_MP_TXN(13)

CAP_0402-0.22UF,16V,10%,X7R,A3A  I83  C9N5
   1 P3E_CPU1_PE3_MP_C_TXP<13>      A @BASEBOARD_FAB2_LIB.BASEBOARD_FAB2(SCH_1):P3E_CPU1_PE3_MP_C_TXP(13)
   2 P3E_CPU1_PE3_MP_TXP<13>      B @BASEBOARD_FAB2_LIB.BASEBOARD_FAB2(SCH_1):P3E_CPU1_PE3_MP_TXP(13)

RES_0402-0.0,5%,1/16W,EMPTY,G2A  I97  R1C11
   1 SMB_LAN_STBY_LVC3_SCL      A @BASEBOARD_FAB2_LIB.BASEBOARD_FAB2(SCH_1):SMB_LAN_STBY_LVC3_SCL
   2 FAN_TACH1_R      B @BASEBOARD_FAB2_LIB.BASEBOARD_FAB2(SCH_1):FAN_TACH1_R

RES_0402-0.0,5%,1/16W,EMPTY,G2A  I101  R1C10
   1 SMB_LAN_STBY_LVC3_SDA      A @BASEBOARD_FAB2_LIB.BASEBOARD_FAB2(SCH_1):SMB_LAN_STBY_LVC3_SDA
   2 FAN_TACH3_R      B @BASEBOARD_FAB2_LIB.BASEBOARD_FAB2(SCH_1):FAN_TACH3_R

RES_0402-0.0,5%,1/16W,EMPTY,G2A  I104  R1C9
   1 IRQ_BOARD_BMC_ALERT_N      A @BASEBOARD_FAB2_LIB.BASEBOARD_FAB2(SCH_1):IRQ_BOARD_BMC_ALERT_N
   2 FAN_TACH2_R      B @BASEBOARD_FAB2_LIB.BASEBOARD_FAB2(SCH_1):FAN_TACH2_R

RES_0402-0.0,5%,1/16W,EMPTY,G2A  I107  R1F9
   1 FM_BMC_READY_N      A @BASEBOARD_FAB2_LIB.BASEBOARD_FAB2(SCH_1):FM_BMC_READY_N
   2 FAN_PWM_OUT_SYS0_R1      B @BASEBOARD_FAB2_LIB.BASEBOARD_FAB2(SCH_1):FAN_PWM_OUT_SYS0_R1

RES_0402-0.0,5%,1/16W,EMPTY,G2A  I110  R1C31
   1 FM_XRC_READY_N      A @BASEBOARD_FAB2_LIB.BASEBOARD_FAB2(SCH_1):FM_XRC_READY_N
   2 FAN_TACH0_R      B @BASEBOARD_FAB2_LIB.BASEBOARD_FAB2(SCH_1):FAN_TACH0_R


DRAWING: @BASEBOARD_FAB2_LIB.BASEBOARD_FAB2(SCH_1):PAGE183 

PI7C9X1172_QFN-IC,H66899-001  I1  EU9F3
  30 FM_PI7C9X1172_A0 A0_CS_N @BASEBOARD_FAB2_LIB.BASEBOARD_FAB2(SCH_1):FM_PI7C9X1172_A0
  31 FM_PI7C9X1172_A1  A1_S1 @BASEBOARD_FAB2_LIB.BASEBOARD_FAB2(SCH_1):FM_PI7C9X1172_A1
  25    GND CTSA_N @BASEBOARD_FAB2_LIB.BASEBOARD_FAB2(SCH_1):GND
  16    GND CTSB_N @BASEBOARD_FAB2_LIB.BASEBOARD_FAB2(SCH_1):GND
  19 TP_PI7C9X1172_EN485_N EN485_N @BASEBOARD_FAB2_LIB.BASEBOARD_FAB2(SCH_1):TP_PI7C9X1172_EN485_N
  18 TP_PI7C9X1172_ENIR_N ENIR_N @BASEBOARD_FAB2_LIB.BASEBOARD_FAB2(SCH_1):TP_PI7C9X1172_ENIR_N
  12    GND    GND @BASEBOARD_FAB2_LIB.BASEBOARD_FAB2(SCH_1):GND
  13 TP_GPIO0_DSRB_N GPIO0_DSRB_N @BASEBOARD_FAB2_LIB.BASEBOARD_FAB2(SCH_1):TP_GPIO0_DSRB_N
  23 TP_GPIO1_DTRB_N GPIO1_DTRB_N @BASEBOARD_FAB2_LIB.BASEBOARD_FAB2(SCH_1):TP_GPIO1_DTRB_N
  11 TP_GPIO2_CDB_N GPIO2_CDB_N @BASEBOARD_FAB2_LIB.BASEBOARD_FAB2(SCH_1):TP_GPIO2_CDB_N
  14 TP_GPIO3_RIB_N GPIO3_RIB_N @BASEBOARD_FAB2_LIB.BASEBOARD_FAB2(SCH_1):TP_GPIO3_RIB_N
  26 TP_GPIO4_DSRA_N GPIO4_DSRA_N @BASEBOARD_FAB2_LIB.BASEBOARD_FAB2(SCH_1):TP_GPIO4_DSRA_N
  22 TP_GPIO5_DTRA_N GPIO5_DTRA_N @BASEBOARD_FAB2_LIB.BASEBOARD_FAB2(SCH_1):TP_GPIO5_DTRA_N
  27 TP_GPIO6_CDA_N GPIO6_CDA_N @BASEBOARD_FAB2_LIB.BASEBOARD_FAB2(SCH_1):TP_GPIO6_CDA_N
  28 TP_GPIO7_RIA_N GPIO7_RIA_N @BASEBOARD_FAB2_LIB.BASEBOARD_FAB2(SCH_1):TP_GPIO7_RIA_N
  32 PU_PI7C9X1172_I2C_SPI_N I2C_SPI_N @BASEBOARD_FAB2_LIB.BASEBOARD_FAB2(SCH_1):PU_PI7C9X1172_I2C_SPI_N
  20 FM_UART_ALERT_N  IRQ_N @BASEBOARD_FAB2_LIB.BASEBOARD_FAB2(SCH_1):FM_UART_ALERT_N
   8 NC_PI7C9X1172_8  NC<1> @BASEBOARD_FAB2_LIB.BASEBOARD_FAB2(SCH_1):NC_PI7C9X1172_8
   1 NC_PI7C9X1172_1  NC<0> @BASEBOARD_FAB2_LIB.BASEBOARD_FAB2(SCH_1):NC_PI7C9X1172_1
  24 PWRGD_DSW_PWROK RESET_N @BASEBOARD_FAB2_LIB.BASEBOARD_FAB2(SCH_1):PWRGD_DSW_PWROK
  21 TP_PI7C9X1172_RTSA_N RTSA_N @BASEBOARD_FAB2_LIB.BASEBOARD_FAB2(SCH_1):TP_PI7C9X1172_RTSA_N
  15 TP_PI7C9X1172_RTSB_N RTSB_N @BASEBOARD_FAB2_LIB.BASEBOARD_FAB2(SCH_1):TP_PI7C9X1172_RTSB_N
   5 SP1_HOST_BRIDGE_UART_RX    RXA @BASEBOARD_FAB2_LIB.BASEBOARD_FAB2(SCH_1):SP1_HOST_BRIDGE_UART_RX
   4 UART_BRIDGE_RXD5    RXB @BASEBOARD_FAB2_LIB.BASEBOARD_FAB2(SCH_1):UART_BRIDGE_RXD5
  17 SMB_SLOTX24_PCH_STBY_LVC3_SCL    SCL @BASEBOARD_FAB2_LIB.BASEBOARD_FAB2(SCH_1):SMB_SLOTX24_PCH_STBY_LVC3_SCL
   3 SMB_SLOTX24_PCH_STBY_LVC3_SDA    SDA @BASEBOARD_FAB2_LIB.BASEBOARD_FAB2(SCH_1):SMB_SLOTX24_PCH_STBY_LVC3_SDA
   2 TP_PI7C9X1172_SO     SO @BASEBOARD_FAB2_LIB.BASEBOARD_FAB2(SCH_1):TP_PI7C9X1172_SO
  33    GND  THPAD @BASEBOARD_FAB2_LIB.BASEBOARD_FAB2(SCH_1):GND
   6 SP1_HOST_BRIDGE_UART_TX    TXA @BASEBOARD_FAB2_LIB.BASEBOARD_FAB2(SCH_1):SP1_HOST_BRIDGE_UART_TX
   7 UART_BRIDGE_TXD5    TXB @BASEBOARD_FAB2_LIB.BASEBOARD_FAB2(SCH_1):UART_BRIDGE_TXD5
  29 P3V3_STBY    VDD @BASEBOARD_FAB2_LIB.BASEBOARD_FAB2(SCH_1):P3V3_STBY
   9 XTAL_24MHZ_IN_R  XTAL1 @BASEBOARD_FAB2_LIB.BASEBOARD_FAB2(SCH_1):XTAL_24MHZ_IN_R
  10 XTAL_24MHZ_OUT_R  XTAL2 @BASEBOARD_FAB2_LIB.BASEBOARD_FAB2(SCH_1):XTAL_24MHZ_OUT_R

RES_0402-4.75K,1%,1/16W,CHIP,GA  I4  R9F47
   1 P3V3_STBY      A @BASEBOARD_FAB2_LIB.BASEBOARD_FAB2(SCH_1):P3V3_STBY
   2 PU_PI7C9X1172_I2C_SPI_N      B @BASEBOARD_FAB2_LIB.BASEBOARD_FAB2(SCH_1):PU_PI7C9X1172_I2C_SPI_N

CAP_A_0402V-0.1UF,16V,10%,X7R,A  I7  C9F19
   1 P3V3_STBY      A @BASEBOARD_FAB2_LIB.BASEBOARD_FAB2(SCH_1):P3V3_STBY
   2    GND      B @BASEBOARD_FAB2_LIB.BASEBOARD_FAB2(SCH_1):GND

RES_0402-1.00K,1%,1/16W,CHIP,GA  I11  R9F50
   1 FM_PI7C9X1172_A1      A @BASEBOARD_FAB2_LIB.BASEBOARD_FAB2(SCH_1):FM_PI7C9X1172_A1
   2    GND      B @BASEBOARD_FAB2_LIB.BASEBOARD_FAB2(SCH_1):GND

RES_0402-1.00K,1%,1/16W,CHIP,GA  I12  R9F51
   1 FM_PI7C9X1172_A0      A @BASEBOARD_FAB2_LIB.BASEBOARD_FAB2(SCH_1):FM_PI7C9X1172_A0
   2    GND      B @BASEBOARD_FAB2_LIB.BASEBOARD_FAB2(SCH_1):GND

RES_0402-4.75K,1%,1/16W,EMPTY,A  I13  R9F48
   1 P3V3_STBY      A @BASEBOARD_FAB2_LIB.BASEBOARD_FAB2(SCH_1):P3V3_STBY
   2 FM_PI7C9X1172_A1      B @BASEBOARD_FAB2_LIB.BASEBOARD_FAB2(SCH_1):FM_PI7C9X1172_A1

RES_0402-4.75K,1%,1/16W,EMPTY,A  I14  R9F49
   1 P3V3_STBY      A @BASEBOARD_FAB2_LIB.BASEBOARD_FAB2(SCH_1):P3V3_STBY
   2 FM_PI7C9X1172_A0      B @BASEBOARD_FAB2_LIB.BASEBOARD_FAB2(SCH_1):FM_PI7C9X1172_A0

CRYSTAL_SM-24.000MHZ,IC,D95126A  I19  Y9F1
   1 XTAL_24MHZ_PI7C9X1172_IN      A @BASEBOARD_FAB2_LIB.BASEBOARD_FAB2(SCH_1):XTAL_24MHZ_PI7C9X1172_IN
   2 XTAL_24MHZ_PI7C9X1172_OUT      B @BASEBOARD_FAB2_LIB.BASEBOARD_FAB2(SCH_1):XTAL_24MHZ_PI7C9X1172_OUT

CAP_0402LF-12.0PF,50V,5%,COG,AA  I20  C9F20
   1 XTAL_24MHZ_PI7C9X1172_IN      A @BASEBOARD_FAB2_LIB.BASEBOARD_FAB2(SCH_1):XTAL_24MHZ_PI7C9X1172_IN
   2    GND      B @BASEBOARD_FAB2_LIB.BASEBOARD_FAB2(SCH_1):GND

CAP_0402LF-12.0PF,50V,5%,COG,AA  I21  C9F21
   1 XTAL_24MHZ_PI7C9X1172_OUT      A @BASEBOARD_FAB2_LIB.BASEBOARD_FAB2(SCH_1):XTAL_24MHZ_PI7C9X1172_OUT
   2    GND      B @BASEBOARD_FAB2_LIB.BASEBOARD_FAB2(SCH_1):GND

RES_0402-0.0,5%,1/16W,CHIP,G21A  I24  R9F58
   1 XTAL_24MHZ_PI7C9X1172_IN      A @BASEBOARD_FAB2_LIB.BASEBOARD_FAB2(SCH_1):XTAL_24MHZ_PI7C9X1172_IN
   2 XTAL_24MHZ_IN_R      B @BASEBOARD_FAB2_LIB.BASEBOARD_FAB2(SCH_1):XTAL_24MHZ_IN_R

RES_0402-0.0,5%,1/16W,CHIP,G21A  I25  R9F59
   1 XTAL_24MHZ_PI7C9X1172_OUT      A @BASEBOARD_FAB2_LIB.BASEBOARD_FAB2(SCH_1):XTAL_24MHZ_PI7C9X1172_OUT
   2 XTAL_24MHZ_OUT_R      B @BASEBOARD_FAB2_LIB.BASEBOARD_FAB2(SCH_1):XTAL_24MHZ_OUT_R

RES_0402-4.75K,1%,1/16W,CHIP,GA  I30  R9F55
   1 P3V3_STBY      A @BASEBOARD_FAB2_LIB.BASEBOARD_FAB2(SCH_1):P3V3_STBY
   2 FM_UART_ALERT_N      B @BASEBOARD_FAB2_LIB.BASEBOARD_FAB2(SCH_1):FM_UART_ALERT_N

RES_0402-0.0,5%,1/16W,CHIP,G21A  I48  R9F57
   1 UART_BRIDGE_TXD5      A @BASEBOARD_FAB2_LIB.BASEBOARD_FAB2(SCH_1):UART_BRIDGE_TXD5
   2 UART_BMC_TXD5      B @BASEBOARD_FAB2_LIB.BASEBOARD_FAB2(SCH_1):UART_BMC_TXD5

RES_0402-0.0,5%,1/16W,CHIP,G21A  I49  R9F56
   1 SP1_HOST_BRIDGE_UART_TX      A @BASEBOARD_FAB2_LIB.BASEBOARD_FAB2(SCH_1):SP1_HOST_BRIDGE_UART_TX
   2 SP1_BMC_HOST_UART_TX      B @BASEBOARD_FAB2_LIB.BASEBOARD_FAB2(SCH_1):SP1_BMC_HOST_UART_TX

RES_0402-0.0,5%,1/16W,CHIP,G21A  I52  R9F54
   1 SP1_BMC_HOST_UART_RX      A @BASEBOARD_FAB2_LIB.BASEBOARD_FAB2(SCH_1):SP1_BMC_HOST_UART_RX
   2 SP1_HOST_BRIDGE_UART_RX      B @BASEBOARD_FAB2_LIB.BASEBOARD_FAB2(SCH_1):SP1_HOST_BRIDGE_UART_RX

RES_0402-0.0,5%,1/16W,CHIP,G21A  I53  R9F53
   1 UART_BMC_RXD5      A @BASEBOARD_FAB2_LIB.BASEBOARD_FAB2(SCH_1):UART_BMC_RXD5
   2 UART_BRIDGE_RXD5      B @BASEBOARD_FAB2_LIB.BASEBOARD_FAB2(SCH_1):UART_BRIDGE_RXD5


DRAWING: @BASEBOARD_FAB2_LIB.BASEBOARD_FAB2(SCH_1):PAGE184 

SCONN11_H67026001_SM-CONN,H670A  I87  J8E1
   1 SPI_PCH_TPM_CLK_R    IO1 @BASEBOARD_FAB2_LIB.BASEBOARD_FAB2(SCH_1):SPI_PCH_TPM_CLK_R
   2 RST_PLTRST_BUF_N    IO2 @BASEBOARD_FAB2_LIB.BASEBOARD_FAB2(SCH_1):RST_PLTRST_BUF_N
   3 SPI_PCH_TPM_MOSI_R    IO3 @BASEBOARD_FAB2_LIB.BASEBOARD_FAB2(SCH_1):SPI_PCH_TPM_MOSI_R
   4 SPI_PCH_TPM_MISO_R    IO4 @BASEBOARD_FAB2_LIB.BASEBOARD_FAB2(SCH_1):SPI_PCH_TPM_MISO_R
   5 SPI_PCH_TPM_CS_R_N    IO5 @BASEBOARD_FAB2_LIB.BASEBOARD_FAB2(SCH_1):SPI_PCH_TPM_CS_R_N
   6 SMB_SENSOR_STBY_LVC3_SDA    IO6 @BASEBOARD_FAB2_LIB.BASEBOARD_FAB2(SCH_1):SMB_SENSOR_STBY_LVC3_SDA
   7 P3V3_STBY    IO7 @BASEBOARD_FAB2_LIB.BASEBOARD_FAB2(SCH_1):P3V3_STBY
   8 FM_TPM_PRES_RST_N    IO8 @BASEBOARD_FAB2_LIB.BASEBOARD_FAB2(SCH_1):FM_TPM_PRES_RST_N
   9 IRQ_SPI_TPM_N_R    IO9 @BASEBOARD_FAB2_LIB.BASEBOARD_FAB2(SCH_1):IRQ_SPI_TPM_N_R
  10 SMB_SENSOR_STBY_LVC3_SCL   IO10 @BASEBOARD_FAB2_LIB.BASEBOARD_FAB2(SCH_1):SMB_SENSOR_STBY_LVC3_SCL
  11    GND   IO11 @BASEBOARD_FAB2_LIB.BASEBOARD_FAB2(SCH_1):GND
 MP1    GND    MP1 @BASEBOARD_FAB2_LIB.BASEBOARD_FAB2(SCH_1):GND
 MP2    GND    MP2 @BASEBOARD_FAB2_LIB.BASEBOARD_FAB2(SCH_1):GND

RES_0402-33.2,1%,1/16W,CHIP,G2A  I88  R8E9
   1 SPI_PCH_CLK      A @BASEBOARD_FAB2_LIB.BASEBOARD_FAB2(SCH_1):SPI_PCH_CLK
   2 SPI_PCH_TPM_CLK_R      B @BASEBOARD_FAB2_LIB.BASEBOARD_FAB2(SCH_1):SPI_PCH_TPM_CLK_R

RES_0402-0.0,5%,1/16W,CHIP,G21A  I92  R8D35
   1 SPI_PCH_TPM_CS_N      A @BASEBOARD_FAB2_LIB.BASEBOARD_FAB2(SCH_1):SPI_PCH_TPM_CS_N
   2 SPI_PCH_TPM_CS_R_N      B @BASEBOARD_FAB2_LIB.BASEBOARD_FAB2(SCH_1):SPI_PCH_TPM_CS_R_N

RES_0402-33.2,1%,1/16W,CHIP,G2A  I93  R8E13
   1 SPI_PCH_MISO      A @BASEBOARD_FAB2_LIB.BASEBOARD_FAB2(SCH_1):SPI_PCH_MISO
   2 SPI_PCH_TPM_MISO_R      B @BASEBOARD_FAB2_LIB.BASEBOARD_FAB2(SCH_1):SPI_PCH_TPM_MISO_R

RES_0402-33.2,1%,1/16W,CHIP,G2A  I95  R8E10
   1 SPI_PCH_MOSI      A @BASEBOARD_FAB2_LIB.BASEBOARD_FAB2(SCH_1):SPI_PCH_MOSI
   2 SPI_PCH_TPM_MOSI_R      B @BASEBOARD_FAB2_LIB.BASEBOARD_FAB2(SCH_1):SPI_PCH_TPM_MOSI_R

RES_0402-0.0,5%,1/16W,CHIP,G21A  I99  R8E1
   1 IRQ_SPI_TPM_N_R      A @BASEBOARD_FAB2_LIB.BASEBOARD_FAB2(SCH_1):IRQ_SPI_TPM_N_R
   2 IRQ_PIRQA_SPI_TPM_N      B @BASEBOARD_FAB2_LIB.BASEBOARD_FAB2(SCH_1):IRQ_PIRQA_SPI_TPM_N

STANDOFF_TH1-SO,H72821-001  I104  RM8D1
   1    GND    IO1 @BASEBOARD_FAB2_LIB.BASEBOARD_FAB2(SCH_1):GND


DRAWING: @BASEBOARD_FAB2_LIB.BASEBOARD_FAB2(SCH_1):PAGE185 

SCONN75K_H17033002_SMT1-SCONN,A  I53  J8F1
   1    GND GND<0> @BASEBOARD_FAB2_LIB.BASEBOARD_FAB2(SCH_1):GND
   2   P3V3 3_3V<0> @BASEBOARD_FAB2_LIB.BASEBOARD_FAB2(SCH_1):P3V3
   3    GND GND<1> @BASEBOARD_FAB2_LIB.BASEBOARD_FAB2(SCH_1):GND
   4   P3V3 3_3V<1> @BASEBOARD_FAB2_LIB.BASEBOARD_FAB2(SCH_1):P3V3
   5 P3E_PCH_M2_RX_DN<3>  PERN3 @BASEBOARD_FAB2_LIB.BASEBOARD_FAB2(SCH_1):P3E_PCH_M2_RX_DN(3)
   6 NC_M2<0>  NC<0> @BASEBOARD_FAB2_LIB.BASEBOARD_FAB2(SCH_1):NC_M2(0)
   7 P3E_PCH_M2_RX_DP<3>  PERP3 @BASEBOARD_FAB2_LIB.BASEBOARD_FAB2(SCH_1):P3E_PCH_M2_RX_DP(3)
   8 NC_M2<1>  NC<1> @BASEBOARD_FAB2_LIB.BASEBOARD_FAB2(SCH_1):NC_M2(1)
   9    GND GND<2> @BASEBOARD_FAB2_LIB.BASEBOARD_FAB2(SCH_1):GND
  10 TP_LED_M2_ACT_N DAS_DSS_N @BASEBOARD_FAB2_LIB.BASEBOARD_FAB2(SCH_1):TP_LED_M2_ACT_N
  11 P3E_PCH_M2_TX_C_DN<3>  PETN3 @BASEBOARD_FAB2_LIB.BASEBOARD_FAB2(SCH_1):P3E_PCH_M2_TX_C_DN(3)
  12   P3V3 3_3V<2> @BASEBOARD_FAB2_LIB.BASEBOARD_FAB2(SCH_1):P3V3
  13 P3E_PCH_M2_TX_C_DP<3>  PETP3 @BASEBOARD_FAB2_LIB.BASEBOARD_FAB2(SCH_1):P3E_PCH_M2_TX_C_DP(3)
  14   P3V3 3_3V<3> @BASEBOARD_FAB2_LIB.BASEBOARD_FAB2(SCH_1):P3V3
  15    GND GND<3> @BASEBOARD_FAB2_LIB.BASEBOARD_FAB2(SCH_1):GND
  16   P3V3 3_3V<4> @BASEBOARD_FAB2_LIB.BASEBOARD_FAB2(SCH_1):P3V3
  17 P3E_PCH_M2_RX_DN<2>  PERN2 @BASEBOARD_FAB2_LIB.BASEBOARD_FAB2(SCH_1):P3E_PCH_M2_RX_DN(2)
  18   P3V3 3_3V<5> @BASEBOARD_FAB2_LIB.BASEBOARD_FAB2(SCH_1):P3V3
  19 P3E_PCH_M2_RX_DP<2>  PERP2 @BASEBOARD_FAB2_LIB.BASEBOARD_FAB2(SCH_1):P3E_PCH_M2_RX_DP(2)
  20 NC_M2<2>  NC<2> @BASEBOARD_FAB2_LIB.BASEBOARD_FAB2(SCH_1):NC_M2(2)
  21    GND GND<4> @BASEBOARD_FAB2_LIB.BASEBOARD_FAB2(SCH_1):GND
  22 NC_M2<3>  NC<3> @BASEBOARD_FAB2_LIB.BASEBOARD_FAB2(SCH_1):NC_M2(3)
  23 P3E_PCH_M2_TX_C_DN<2>  PETN2 @BASEBOARD_FAB2_LIB.BASEBOARD_FAB2(SCH_1):P3E_PCH_M2_TX_C_DN(2)
  24 NC_M2<4>  NC<4> @BASEBOARD_FAB2_LIB.BASEBOARD_FAB2(SCH_1):NC_M2(4)
  25 P3E_PCH_M2_TX_C_DP<2>  PETP2 @BASEBOARD_FAB2_LIB.BASEBOARD_FAB2(SCH_1):P3E_PCH_M2_TX_C_DP(2)
  26 NC_M2<5>  NC<5> @BASEBOARD_FAB2_LIB.BASEBOARD_FAB2(SCH_1):NC_M2(5)
  27    GND GND<5> @BASEBOARD_FAB2_LIB.BASEBOARD_FAB2(SCH_1):GND
  28 NC_M2<6>  NC<6> @BASEBOARD_FAB2_LIB.BASEBOARD_FAB2(SCH_1):NC_M2(6)
  29 P3E_PCH_M2_RX_DN<1>  PERN1 @BASEBOARD_FAB2_LIB.BASEBOARD_FAB2(SCH_1):P3E_PCH_M2_RX_DN(1)
  30 NC_M2<7>  NC<7> @BASEBOARD_FAB2_LIB.BASEBOARD_FAB2(SCH_1):NC_M2(7)
  31 P3E_PCH_M2_RX_DP<1>  PERP1 @BASEBOARD_FAB2_LIB.BASEBOARD_FAB2(SCH_1):P3E_PCH_M2_RX_DP(1)
  32 NC_M2<8>  NC<8> @BASEBOARD_FAB2_LIB.BASEBOARD_FAB2(SCH_1):NC_M2(8)
  33    GND GND<6> @BASEBOARD_FAB2_LIB.BASEBOARD_FAB2(SCH_1):GND
  34 NC_M2<9>  NC<9> @BASEBOARD_FAB2_LIB.BASEBOARD_FAB2(SCH_1):NC_M2(9)
  35 P3E_PCH_M2_TX_C_DN<1>  PETN1 @BASEBOARD_FAB2_LIB.BASEBOARD_FAB2(SCH_1):P3E_PCH_M2_TX_C_DN(1)
  36 NC_M2<10> NC<10> @BASEBOARD_FAB2_LIB.BASEBOARD_FAB2(SCH_1):NC_M2(10)
  37 P3E_PCH_M2_TX_C_DP<1>  PETP1 @BASEBOARD_FAB2_LIB.BASEBOARD_FAB2(SCH_1):P3E_PCH_M2_TX_C_DP(1)
  38 TP_M2_DEVSLP DEVSLP @BASEBOARD_FAB2_LIB.BASEBOARD_FAB2(SCH_1):TP_M2_DEVSLP
  39    GND GND<7> @BASEBOARD_FAB2_LIB.BASEBOARD_FAB2(SCH_1):GND
  40 NC_M2<11> NC<11> @BASEBOARD_FAB2_LIB.BASEBOARD_FAB2(SCH_1):NC_M2(11)
  41 P3E_PCH_M2_SATA6G_RX_R_DP PERN0_SATA_BP @BASEBOARD_FAB2_LIB.BASEBOARD_FAB2(SCH_1):P3E_PCH_M2_SATA6G_RX_R_DP
  42 NC_M2<12> NC<12> @BASEBOARD_FAB2_LIB.BASEBOARD_FAB2(SCH_1):NC_M2(12)
  43 P3E_PCH_M2_SATA6G_RX_R_DN PERP0_SATA_BN @BASEBOARD_FAB2_LIB.BASEBOARD_FAB2(SCH_1):P3E_PCH_M2_SATA6G_RX_R_DN
  44 NC_M2<13> NC<13> @BASEBOARD_FAB2_LIB.BASEBOARD_FAB2(SCH_1):NC_M2(13)
  45    GND GND<8> @BASEBOARD_FAB2_LIB.BASEBOARD_FAB2(SCH_1):GND
  46 NC_M2<14> NC<14> @BASEBOARD_FAB2_LIB.BASEBOARD_FAB2(SCH_1):NC_M2(14)
  47 P3E_PCH_M2_SATA6G_TX_R_DN PETN0_SATA_AN @BASEBOARD_FAB2_LIB.BASEBOARD_FAB2(SCH_1):P3E_PCH_M2_SATA6G_TX_R_DN
  48 NC_M2<15> NC<15> @BASEBOARD_FAB2_LIB.BASEBOARD_FAB2(SCH_1):NC_M2(15)
  49 P3E_PCH_M2_SATA6G_TX_R_DP PETP0_SATA_AP @BASEBOARD_FAB2_LIB.BASEBOARD_FAB2(SCH_1):P3E_PCH_M2_SATA6G_TX_R_DP
  50 RST_PCIE_M2_DEV_N PERST_N_NC @BASEBOARD_FAB2_LIB.BASEBOARD_FAB2(SCH_1):RST_PCIE_M2_DEV_N
  51    GND GND<9> @BASEBOARD_FAB2_LIB.BASEBOARD_FAB2(SCH_1):GND
  52 PU_M2_CLK_REQ_N CLKREQ_N_NC @BASEBOARD_FAB2_LIB.BASEBOARD_FAB2(SCH_1):PU_M2_CLK_REQ_N
  53 CLK_100M_M2_DN REFCLKN @BASEBOARD_FAB2_LIB.BASEBOARD_FAB2(SCH_1):CLK_100M_M2_DN
  54 FM_PE_M2_WAKE_N PEWAKE_N_NC @BASEBOARD_FAB2_LIB.BASEBOARD_FAB2(SCH_1):FM_PE_M2_WAKE_N
  55 CLK_100M_M2_DP REFCLKP @BASEBOARD_FAB2_LIB.BASEBOARD_FAB2(SCH_1):CLK_100M_M2_DP
  56 NC_M2<16> NC<16> @BASEBOARD_FAB2_LIB.BASEBOARD_FAB2(SCH_1):NC_M2(16)
  57    GND GND<10> @BASEBOARD_FAB2_LIB.BASEBOARD_FAB2(SCH_1):GND
  58 NC_M2<17> NC<17> @BASEBOARD_FAB2_LIB.BASEBOARD_FAB2(SCH_1):NC_M2(17)
  67 NC_M2<18> NC<18> @BASEBOARD_FAB2_LIB.BASEBOARD_FAB2(SCH_1):NC_M2(18)
  68 TP_M2_32M_SUSCLK SUSCLK @BASEBOARD_FAB2_LIB.BASEBOARD_FAB2(SCH_1):TP_M2_32M_SUSCLK
  69 FM_M2_SSD_PEDET  PEDET @BASEBOARD_FAB2_LIB.BASEBOARD_FAB2(SCH_1):FM_M2_SSD_PEDET
  70   P3V3 3_3V<6> @BASEBOARD_FAB2_LIB.BASEBOARD_FAB2(SCH_1):P3V3
  71    GND GND<11> @BASEBOARD_FAB2_LIB.BASEBOARD_FAB2(SCH_1):GND
  72   P3V3 3_3V<7> @BASEBOARD_FAB2_LIB.BASEBOARD_FAB2(SCH_1):P3V3
  73    GND GND<12> @BASEBOARD_FAB2_LIB.BASEBOARD_FAB2(SCH_1):GND
  74   P3V3 3_3V<8> @BASEBOARD_FAB2_LIB.BASEBOARD_FAB2(SCH_1):P3V3
  75    GND GND<13> @BASEBOARD_FAB2_LIB.BASEBOARD_FAB2(SCH_1):GND
 MP1    GND    MP1 @BASEBOARD_FAB2_LIB.BASEBOARD_FAB2(SCH_1):GND
 MP2    GND    MP2 @BASEBOARD_FAB2_LIB.BASEBOARD_FAB2(SCH_1):GND

CAP_0402-0.22UF,16V,10%,X7R,A3A  I62  C2T11
   1 P3E_PCH_M2_TX_C_DN<1>      A @BASEBOARD_FAB2_LIB.BASEBOARD_FAB2(SCH_1):P3E_PCH_M2_TX_C_DN(1)
   2 P3E_PCH_M2_TX_DN<1>      B @BASEBOARD_FAB2_LIB.BASEBOARD_FAB2(SCH_1):P3E_PCH_M2_TX_DN(1)

CAP_0402-0.22UF,16V,10%,X7R,A3A  I63  C2T10
   1 P3E_PCH_M2_TX_C_DP<1>      A @BASEBOARD_FAB2_LIB.BASEBOARD_FAB2(SCH_1):P3E_PCH_M2_TX_C_DP(1)
   2 P3E_PCH_M2_TX_DP<1>      B @BASEBOARD_FAB2_LIB.BASEBOARD_FAB2(SCH_1):P3E_PCH_M2_TX_DP(1)

CAP_0402-0.22UF,16V,10%,X7R,A3A  I64  C2T13
   1 P3E_PCH_M2_TX_C_DP<2>      A @BASEBOARD_FAB2_LIB.BASEBOARD_FAB2(SCH_1):P3E_PCH_M2_TX_C_DP(2)
   2 P3E_PCH_M2_TX_DP<2>      B @BASEBOARD_FAB2_LIB.BASEBOARD_FAB2(SCH_1):P3E_PCH_M2_TX_DP(2)

CAP_0402-0.22UF,16V,10%,X7R,A3A  I65  C2T14
   1 P3E_PCH_M2_TX_C_DN<2>      A @BASEBOARD_FAB2_LIB.BASEBOARD_FAB2(SCH_1):P3E_PCH_M2_TX_C_DN(2)
   2 P3E_PCH_M2_TX_DN<2>      B @BASEBOARD_FAB2_LIB.BASEBOARD_FAB2(SCH_1):P3E_PCH_M2_TX_DN(2)

CAP_0402-0.22UF,16V,10%,X7R,A3A  I66  C2T20
   1 P3E_PCH_M2_TX_C_DP<3>      A @BASEBOARD_FAB2_LIB.BASEBOARD_FAB2(SCH_1):P3E_PCH_M2_TX_C_DP(3)
   2 P3E_PCH_M2_TX_DP<3>      B @BASEBOARD_FAB2_LIB.BASEBOARD_FAB2(SCH_1):P3E_PCH_M2_TX_DP(3)

CAP_0402-0.22UF,16V,10%,X7R,A3A  I67  C2T23
   1 P3E_PCH_M2_TX_C_DN<3>      A @BASEBOARD_FAB2_LIB.BASEBOARD_FAB2(SCH_1):P3E_PCH_M2_TX_C_DN(3)
   2 P3E_PCH_M2_TX_DN<3>      B @BASEBOARD_FAB2_LIB.BASEBOARD_FAB2(SCH_1):P3E_PCH_M2_TX_DN(3)

CAP_A_0402V-0.01UF,25V,10%,EMPA  I90  C8F15
   1 SATA6G_S0_RX_DN      A @BASEBOARD_FAB2_LIB.BASEBOARD_FAB2(SCH_1):SATA6G_S0_RX_DN
   2 P3E_PCH_M2_SATA6G_RX_R_DN      B @BASEBOARD_FAB2_LIB.BASEBOARD_FAB2(SCH_1):P3E_PCH_M2_SATA6G_RX_R_DN

CAP_A_0402V-0.01UF,25V,10%,EMPA  I95  C8F6
   1 SATA6G_S0_TX_DP      A @BASEBOARD_FAB2_LIB.BASEBOARD_FAB2(SCH_1):SATA6G_S0_TX_DP
   2 P3E_PCH_M2_SATA6G_TX_R_DP      B @BASEBOARD_FAB2_LIB.BASEBOARD_FAB2(SCH_1):P3E_PCH_M2_SATA6G_TX_R_DP

CAP_0402-0.22UF,16V,10%,X7R,A3A  I96  C8F7
   1 P3E_PCH_TX_0_DP      A @BASEBOARD_FAB2_LIB.BASEBOARD_FAB2(SCH_1):P3E_PCH_TX_0_DP
   2 P3E_PCH_M2_SATA6G_TX_R_DP      B @BASEBOARD_FAB2_LIB.BASEBOARD_FAB2(SCH_1):P3E_PCH_M2_SATA6G_TX_R_DP

CAP_A_0402V-0.01UF,25V,10%,EMPA  I97  C8F11
   1 SATA6G_S0_TX_DN      A @BASEBOARD_FAB2_LIB.BASEBOARD_FAB2(SCH_1):SATA6G_S0_TX_DN
   2 P3E_PCH_M2_SATA6G_TX_R_DN      B @BASEBOARD_FAB2_LIB.BASEBOARD_FAB2(SCH_1):P3E_PCH_M2_SATA6G_TX_R_DN

CAP_0402-0.22UF,16V,10%,X7R,A3A  I98  C8F12
   1 P3E_PCH_TX_0_DN      A @BASEBOARD_FAB2_LIB.BASEBOARD_FAB2(SCH_1):P3E_PCH_TX_0_DN
   2 P3E_PCH_M2_SATA6G_TX_R_DN      B @BASEBOARD_FAB2_LIB.BASEBOARD_FAB2(SCH_1):P3E_PCH_M2_SATA6G_TX_R_DN

CAP_A_0402V-0.01UF,25V,10%,EMPA  I99  C8F13
   1 SATA6G_S0_RX_DP      A @BASEBOARD_FAB2_LIB.BASEBOARD_FAB2(SCH_1):SATA6G_S0_RX_DP
   2 P3E_PCH_M2_SATA6G_RX_R_DP      B @BASEBOARD_FAB2_LIB.BASEBOARD_FAB2(SCH_1):P3E_PCH_M2_SATA6G_RX_R_DP

RES_0402-0.0,5%,1/16W,CHIP,G21A  I105  R8F18
   1 P3E_PCH_RX_0_DP      A @BASEBOARD_FAB2_LIB.BASEBOARD_FAB2(SCH_1):P3E_PCH_RX_0_DP
   2 P3E_PCH_M2_SATA6G_RX_R_DP      B @BASEBOARD_FAB2_LIB.BASEBOARD_FAB2(SCH_1):P3E_PCH_M2_SATA6G_RX_R_DP

RES_0402-0.0,5%,1/16W,CHIP,G21A  I106  R8F21
   1 P3E_PCH_RX_0_DN      A @BASEBOARD_FAB2_LIB.BASEBOARD_FAB2(SCH_1):P3E_PCH_RX_0_DN
   2 P3E_PCH_M2_SATA6G_RX_R_DN      B @BASEBOARD_FAB2_LIB.BASEBOARD_FAB2(SCH_1):P3E_PCH_M2_SATA6G_RX_R_DN

TTL1G07_A_SOP-74LVC1G07,IC,C88B  I110  U2P1
   2 FM_M2_SSD_PEDET      A @BASEBOARD_FAB2_LIB.BASEBOARD_FAB2(SCH_1):FM_M2_SSD_PEDET
   4 FM_M2_DET_LVC3      Y @BASEBOARD_FAB2_LIB.BASEBOARD_FAB2(SCH_1):FM_M2_DET_LVC3

RES_0402-10.0K,1%,1/16W,CHIP,GA  I111  R2P15
   1   P3V3      A @BASEBOARD_FAB2_LIB.BASEBOARD_FAB2(SCH_1):P3V3
   2 FM_M2_SSD_PEDET      B @BASEBOARD_FAB2_LIB.BASEBOARD_FAB2(SCH_1):FM_M2_SSD_PEDET

RES_0402-10.0K,1%,1/16W,CHIP,GA  I113  R2P16
   1 P3V3_STBY      A @BASEBOARD_FAB2_LIB.BASEBOARD_FAB2(SCH_1):P3V3_STBY
   2 FM_M2_DET_LVC3      B @BASEBOARD_FAB2_LIB.BASEBOARD_FAB2(SCH_1):FM_M2_DET_LVC3

RES_0402-0.0,5%,1/16W,CHIP,G21A  I115  R2P14
   1 FM_M2_DET_LVC3      A @BASEBOARD_FAB2_LIB.BASEBOARD_FAB2(SCH_1):FM_M2_DET_LVC3
   2 FM_SSATA_PCIE_M2_SEL      B @BASEBOARD_FAB2_LIB.BASEBOARD_FAB2(SCH_1):FM_SSATA_PCIE_M2_SEL

CAP_A_0402V-0.1UF,16V,10%,X7R,A  I117  C2P9
   1 P3V3_STBY      A @BASEBOARD_FAB2_LIB.BASEBOARD_FAB2(SCH_1):P3V3_STBY
   2    GND      B @BASEBOARD_FAB2_LIB.BASEBOARD_FAB2(SCH_1):GND

CAP_A_0402V-0.1UF,16V,10%,X7R,A  I120  C2T29
   1   P3V3      A @BASEBOARD_FAB2_LIB.BASEBOARD_FAB2(SCH_1):P3V3
   2    GND      B @BASEBOARD_FAB2_LIB.BASEBOARD_FAB2(SCH_1):GND

CAP_A_0402V-0.1UF,16V,10%,X7R,A  I123  C2T26
   1   P3V3      A @BASEBOARD_FAB2_LIB.BASEBOARD_FAB2(SCH_1):P3V3
   2    GND      B @BASEBOARD_FAB2_LIB.BASEBOARD_FAB2(SCH_1):GND

CAP_A_0402V-0.1UF,16V,10%,X7R,A  I124  C2T21
   1   P3V3      A @BASEBOARD_FAB2_LIB.BASEBOARD_FAB2(SCH_1):P3V3
   2    GND      B @BASEBOARD_FAB2_LIB.BASEBOARD_FAB2(SCH_1):GND

CAP_A_0402V-0.1UF,16V,10%,X7R,A  I126  C2T16
   1   P3V3      A @BASEBOARD_FAB2_LIB.BASEBOARD_FAB2(SCH_1):P3V3
   2    GND      B @BASEBOARD_FAB2_LIB.BASEBOARD_FAB2(SCH_1):GND

CAP_A_0402V-0.1UF,16V,10%,X7R,A  I127  C2T15
   1   P3V3      A @BASEBOARD_FAB2_LIB.BASEBOARD_FAB2(SCH_1):P3V3
   2    GND      B @BASEBOARD_FAB2_LIB.BASEBOARD_FAB2(SCH_1):GND

CAP_A_0402V-0.1UF,16V,10%,X7R,A  I129  C2T24
   1   P3V3      A @BASEBOARD_FAB2_LIB.BASEBOARD_FAB2(SCH_1):P3V3
   2    GND      B @BASEBOARD_FAB2_LIB.BASEBOARD_FAB2(SCH_1):GND

CAP_A_0402V-0.1UF,16V,10%,X7R,A  I131  C2T2
   1   P3V3      A @BASEBOARD_FAB2_LIB.BASEBOARD_FAB2(SCH_1):P3V3
   2    GND      B @BASEBOARD_FAB2_LIB.BASEBOARD_FAB2(SCH_1):GND

CAP_A_0402V-0.1UF,16V,10%,X7R,A  I132  C2T4
   1   P3V3      A @BASEBOARD_FAB2_LIB.BASEBOARD_FAB2(SCH_1):P3V3
   2    GND      B @BASEBOARD_FAB2_LIB.BASEBOARD_FAB2(SCH_1):GND

CAP_A_0402V-0.1UF,16V,10%,X7R,A  I135  C2T5
   1   P3V3      A @BASEBOARD_FAB2_LIB.BASEBOARD_FAB2(SCH_1):P3V3
   2    GND      B @BASEBOARD_FAB2_LIB.BASEBOARD_FAB2(SCH_1):GND

RES_0402-10.0K,1%,1/16W,CHIP,GA  I136  R8F36
   1   P3V3      A @BASEBOARD_FAB2_LIB.BASEBOARD_FAB2(SCH_1):P3V3
   2 PU_M2_CLK_REQ_N      B @BASEBOARD_FAB2_LIB.BASEBOARD_FAB2(SCH_1):PU_M2_CLK_REQ_N


DRAWING: @BASEBOARD_FAB2_LIB.BASEBOARD_FAB2(SCH_1):PAGE186 

CAP_0805-10UF,16V,10%,X6S,C953A  I3  C1M27
   1 P12V_STBY      A @BASEBOARD_FAB2_LIB.BASEBOARD_FAB2(SCH_1):P12V_STBY
   2    GND      B @BASEBOARD_FAB2_LIB.BASEBOARD_FAB2(SCH_1):GND

CAP_0805-10UF,16V,10%,X6S,C953A  I6  C1M26
   1 P12V_STBY      A @BASEBOARD_FAB2_LIB.BASEBOARD_FAB2(SCH_1):P12V_STBY
   2    GND      B @BASEBOARD_FAB2_LIB.BASEBOARD_FAB2(SCH_1):GND

CAP_A_0402V-0.1UF,16V,10%,X7R,A  I7  C1M23
   1 P12V_STBY      A @BASEBOARD_FAB2_LIB.BASEBOARD_FAB2(SCH_1):P12V_STBY
   2    GND      B @BASEBOARD_FAB2_LIB.BASEBOARD_FAB2(SCH_1):GND

CAP_A_0402V-0.1UF,16V,10%,X7R,A  I8  C1M22
   1 P12V_STBY      A @BASEBOARD_FAB2_LIB.BASEBOARD_FAB2(SCH_1):P12V_STBY
   2    GND      B @BASEBOARD_FAB2_LIB.BASEBOARD_FAB2(SCH_1):GND

CAP_A_0402V-0.1UF,16V,10%,X7R,A  I10  C1M24
   1   P3V3      A @BASEBOARD_FAB2_LIB.BASEBOARD_FAB2(SCH_1):P3V3
   2    GND      B @BASEBOARD_FAB2_LIB.BASEBOARD_FAB2(SCH_1):GND

RES_0402-200.0,1%,1/16W,CHIP,GA  I220  R1M14
   1 RST_PCIE_CPU_DEV0_N      A @BASEBOARD_FAB2_LIB.BASEBOARD_FAB2(SCH_1):RST_PCIE_CPU_DEV0_N
   2 RST_PCIE_CPU_DEV0_R_N      B @BASEBOARD_FAB2_LIB.BASEBOARD_FAB2(SCH_1):RST_PCIE_CPU_DEV0_R_N

RES_0402-100.0,1%,1/16W,CHIP,GA  I222  R9B7
   1    GND      A @BASEBOARD_FAB2_LIB.BASEBOARD_FAB2(SCH_1):GND
   2 FM_MEZZA_PRSNT1_N      B @BASEBOARD_FAB2_LIB.BASEBOARD_FAB2(SCH_1):FM_MEZZA_PRSNT1_N

CAP_A_0402V-0.1UF,16V,10%,X7R,A  I270  C1M20
   1 P3V3_STBY      A @BASEBOARD_FAB2_LIB.BASEBOARD_FAB2(SCH_1):P3V3_STBY
   2    GND      B @BASEBOARD_FAB2_LIB.BASEBOARD_FAB2(SCH_1):GND

CAP_A_0402V-1.0UF,6.3V,10%,X6SA  I334  C1M21
   1   P3V3      A @BASEBOARD_FAB2_LIB.BASEBOARD_FAB2(SCH_1):P3V3
   2    GND      B @BASEBOARD_FAB2_LIB.BASEBOARD_FAB2(SCH_1):GND

CAP_A_0402V-1.0UF,6.3V,10%,X6SA  I335  C1M25
   1 P3V3_STBY      A @BASEBOARD_FAB2_LIB.BASEBOARD_FAB2(SCH_1):P3V3_STBY
   2    GND      B @BASEBOARD_FAB2_LIB.BASEBOARD_FAB2(SCH_1):GND

SCONN120_A28699018_SM-SCONN,A2A  I336  J9B3
   1 FM_MEZZA_PRSNT1_N    IO1 @BASEBOARD_FAB2_LIB.BASEBOARD_FAB2(SCH_1):FM_MEZZA_PRSNT1_N
  10    GND   IO10 @BASEBOARD_FAB2_LIB.BASEBOARD_FAB2(SCH_1):GND
 100    GND  IO100 @BASEBOARD_FAB2_LIB.BASEBOARD_FAB2(SCH_1):GND
 101 P3E_CPU0_PE3_OCP_RXN<10>  IO101 @BASEBOARD_FAB2_LIB.BASEBOARD_FAB2(SCH_1):P3E_CPU0_PE3_OCP_RXN(10)
 102    GND  IO102 @BASEBOARD_FAB2_LIB.BASEBOARD_FAB2(SCH_1):GND
 103    GND  IO103 @BASEBOARD_FAB2_LIB.BASEBOARD_FAB2(SCH_1):GND
 104 P3E_OCP_CPU0_PE3_C_TXP<9>  IO104 @BASEBOARD_FAB2_LIB.BASEBOARD_FAB2(SCH_1):P3E_OCP_CPU0_PE3_C_TXP(9)
 105    GND  IO105 @BASEBOARD_FAB2_LIB.BASEBOARD_FAB2(SCH_1):GND
 106 P3E_OCP_CPU0_PE3_C_TXN<9>  IO106 @BASEBOARD_FAB2_LIB.BASEBOARD_FAB2(SCH_1):P3E_OCP_CPU0_PE3_C_TXN(9)
 107 P3E_CPU0_PE3_OCP_RXP<9>  IO107 @BASEBOARD_FAB2_LIB.BASEBOARD_FAB2(SCH_1):P3E_CPU0_PE3_OCP_RXP(9)
 108    GND  IO108 @BASEBOARD_FAB2_LIB.BASEBOARD_FAB2(SCH_1):GND
 109 P3E_CPU0_PE3_OCP_RXN<9>  IO109 @BASEBOARD_FAB2_LIB.BASEBOARD_FAB2(SCH_1):P3E_CPU0_PE3_OCP_RXN(9)
  11    GND   IO11 @BASEBOARD_FAB2_LIB.BASEBOARD_FAB2(SCH_1):GND
 110    GND  IO110 @BASEBOARD_FAB2_LIB.BASEBOARD_FAB2(SCH_1):GND
 111    GND  IO111 @BASEBOARD_FAB2_LIB.BASEBOARD_FAB2(SCH_1):GND
 112 P3E_OCP_CPU0_PE3_C_TXP<8>  IO112 @BASEBOARD_FAB2_LIB.BASEBOARD_FAB2(SCH_1):P3E_OCP_CPU0_PE3_C_TXP(8)
 113    GND  IO113 @BASEBOARD_FAB2_LIB.BASEBOARD_FAB2(SCH_1):GND
 114 P3E_OCP_CPU0_PE3_C_TXN<8>  IO114 @BASEBOARD_FAB2_LIB.BASEBOARD_FAB2(SCH_1):P3E_OCP_CPU0_PE3_C_TXN(8)
 115 P3E_CPU0_PE3_OCP_RXP<8>  IO115 @BASEBOARD_FAB2_LIB.BASEBOARD_FAB2(SCH_1):P3E_CPU0_PE3_OCP_RXP(8)
 116    GND  IO116 @BASEBOARD_FAB2_LIB.BASEBOARD_FAB2(SCH_1):GND
 117 P3E_CPU0_PE3_OCP_RXN<8>  IO117 @BASEBOARD_FAB2_LIB.BASEBOARD_FAB2(SCH_1):P3E_CPU0_PE3_OCP_RXN(8)
 118    GND  IO118 @BASEBOARD_FAB2_LIB.BASEBOARD_FAB2(SCH_1):GND
 119    GND  IO119 @BASEBOARD_FAB2_LIB.BASEBOARD_FAB2(SCH_1):GND
  12 P3V3_STBY   IO12 @BASEBOARD_FAB2_LIB.BASEBOARD_FAB2(SCH_1):P3V3_STBY
 120 FM_OCP_MEZZA_PRES_N  IO120 @BASEBOARD_FAB2_LIB.BASEBOARD_FAB2(SCH_1):FM_OCP_MEZZA_PRES_N
  13 P3V3_STBY   IO13 @BASEBOARD_FAB2_LIB.BASEBOARD_FAB2(SCH_1):P3V3_STBY
  14    GND   IO14 @BASEBOARD_FAB2_LIB.BASEBOARD_FAB2(SCH_1):GND
  15    GND   IO15 @BASEBOARD_FAB2_LIB.BASEBOARD_FAB2(SCH_1):GND
  16    GND   IO16 @BASEBOARD_FAB2_LIB.BASEBOARD_FAB2(SCH_1):GND
  17    GND   IO17 @BASEBOARD_FAB2_LIB.BASEBOARD_FAB2(SCH_1):GND
  18   P3V3   IO18 @BASEBOARD_FAB2_LIB.BASEBOARD_FAB2(SCH_1):P3V3
  19   P3V3   IO19 @BASEBOARD_FAB2_LIB.BASEBOARD_FAB2(SCH_1):P3V3
   2 P12V_STBY    IO2 @BASEBOARD_FAB2_LIB.BASEBOARD_FAB2(SCH_1):P12V_STBY
  20   P3V3   IO20 @BASEBOARD_FAB2_LIB.BASEBOARD_FAB2(SCH_1):P3V3
  21   P3V3   IO21 @BASEBOARD_FAB2_LIB.BASEBOARD_FAB2(SCH_1):P3V3
  22   P3V3   IO22 @BASEBOARD_FAB2_LIB.BASEBOARD_FAB2(SCH_1):P3V3
  23   P3V3   IO23 @BASEBOARD_FAB2_LIB.BASEBOARD_FAB2(SCH_1):P3V3
  24   P3V3   IO24 @BASEBOARD_FAB2_LIB.BASEBOARD_FAB2(SCH_1):P3V3
  25   P3V3   IO25 @BASEBOARD_FAB2_LIB.BASEBOARD_FAB2(SCH_1):P3V3
  26    GND   IO26 @BASEBOARD_FAB2_LIB.BASEBOARD_FAB2(SCH_1):GND
  27 RMII_BMC_OCP_CRSDV_R   IO27 @BASEBOARD_FAB2_LIB.BASEBOARD_FAB2(SCH_1):RMII_BMC_OCP_CRSDV_R
  28 IRQ_MEZZ_LAN_ALERT_N   IO28 @BASEBOARD_FAB2_LIB.BASEBOARD_FAB2(SCH_1):IRQ_MEZZ_LAN_ALERT_N
  29 CLK_50M_CKMNG_OCP   IO29 @BASEBOARD_FAB2_LIB.BASEBOARD_FAB2(SCH_1):CLK_50M_CKMNG_OCP
   3 P5V_STBY    IO3 @BASEBOARD_FAB2_LIB.BASEBOARD_FAB2(SCH_1):P5V_STBY
  30 SMB_OCP_FRU_STBY_LVC3_SCL   IO30 @BASEBOARD_FAB2_LIB.BASEBOARD_FAB2(SCH_1):SMB_OCP_FRU_STBY_LVC3_SCL
  31 RMII_BMC_OCP_TXEN   IO31 @BASEBOARD_FAB2_LIB.BASEBOARD_FAB2(SCH_1):RMII_BMC_OCP_TXEN
  32 SMB_OCP_FRU_STBY_LVC3_SDA   IO32 @BASEBOARD_FAB2_LIB.BASEBOARD_FAB2(SCH_1):SMB_OCP_FRU_STBY_LVC3_SDA
  33 RST_PCIE_CPU_DEV0_R_N   IO33 @BASEBOARD_FAB2_LIB.BASEBOARD_FAB2(SCH_1):RST_PCIE_CPU_DEV0_R_N
  34 FM_PE_OCP_WAKE_N   IO34 @BASEBOARD_FAB2_LIB.BASEBOARD_FAB2(SCH_1):FM_PE_OCP_WAKE_N
  35 SMB_OCP_LAN_STBY_LVC3_SCL   IO35 @BASEBOARD_FAB2_LIB.BASEBOARD_FAB2(SCH_1):SMB_OCP_LAN_STBY_LVC3_SCL
  36 RMII_BMC_OCP_RXER_R   IO36 @BASEBOARD_FAB2_LIB.BASEBOARD_FAB2(SCH_1):RMII_BMC_OCP_RXER_R
  37 SMB_OCP_LAN_STBY_LVC3_SDA   IO37 @BASEBOARD_FAB2_LIB.BASEBOARD_FAB2(SCH_1):SMB_OCP_LAN_STBY_LVC3_SDA
  38    GND   IO38 @BASEBOARD_FAB2_LIB.BASEBOARD_FAB2(SCH_1):GND
  39    GND   IO39 @BASEBOARD_FAB2_LIB.BASEBOARD_FAB2(SCH_1):GND
   4 P12V_STBY    IO4 @BASEBOARD_FAB2_LIB.BASEBOARD_FAB2(SCH_1):P12V_STBY
  40 RMII_BMC_OCP_TXD0   IO40 @BASEBOARD_FAB2_LIB.BASEBOARD_FAB2(SCH_1):RMII_BMC_OCP_TXD0
  41    GND   IO41 @BASEBOARD_FAB2_LIB.BASEBOARD_FAB2(SCH_1):GND
  42 RMII_BMC_OCP_TXD1   IO42 @BASEBOARD_FAB2_LIB.BASEBOARD_FAB2(SCH_1):RMII_BMC_OCP_TXD1
  43 RMII_BMC_OCP_RXD0_R   IO43 @BASEBOARD_FAB2_LIB.BASEBOARD_FAB2(SCH_1):RMII_BMC_OCP_RXD0_R
  44    GND   IO44 @BASEBOARD_FAB2_LIB.BASEBOARD_FAB2(SCH_1):GND
  45 RMII_BMC_OCP_RXD1_R   IO45 @BASEBOARD_FAB2_LIB.BASEBOARD_FAB2(SCH_1):RMII_BMC_OCP_RXD1_R
  46    GND   IO46 @BASEBOARD_FAB2_LIB.BASEBOARD_FAB2(SCH_1):GND
  47    GND   IO47 @BASEBOARD_FAB2_LIB.BASEBOARD_FAB2(SCH_1):GND
  48 CLK_100M_MEZZ1_DP   IO48 @BASEBOARD_FAB2_LIB.BASEBOARD_FAB2(SCH_1):CLK_100M_MEZZ1_DP
  49    GND   IO49 @BASEBOARD_FAB2_LIB.BASEBOARD_FAB2(SCH_1):GND
   5 P5V_STBY    IO5 @BASEBOARD_FAB2_LIB.BASEBOARD_FAB2(SCH_1):P5V_STBY
  50 CLK_100M_MEZZ1_DN   IO50 @BASEBOARD_FAB2_LIB.BASEBOARD_FAB2(SCH_1):CLK_100M_MEZZ1_DN
  51 CLK_100M_MEZZ2_DP   IO51 @BASEBOARD_FAB2_LIB.BASEBOARD_FAB2(SCH_1):CLK_100M_MEZZ2_DP
  52    GND   IO52 @BASEBOARD_FAB2_LIB.BASEBOARD_FAB2(SCH_1):GND
  53 CLK_100M_MEZZ2_DN   IO53 @BASEBOARD_FAB2_LIB.BASEBOARD_FAB2(SCH_1):CLK_100M_MEZZ2_DN
  54    GND   IO54 @BASEBOARD_FAB2_LIB.BASEBOARD_FAB2(SCH_1):GND
  55    GND   IO55 @BASEBOARD_FAB2_LIB.BASEBOARD_FAB2(SCH_1):GND
  56 P3E_OCP_CPU0_PE3_C_TXP<15>   IO56 @BASEBOARD_FAB2_LIB.BASEBOARD_FAB2(SCH_1):P3E_OCP_CPU0_PE3_C_TXP(15)
  57    GND   IO57 @BASEBOARD_FAB2_LIB.BASEBOARD_FAB2(SCH_1):GND
  58 P3E_OCP_CPU0_PE3_C_TXN<15>   IO58 @BASEBOARD_FAB2_LIB.BASEBOARD_FAB2(SCH_1):P3E_OCP_CPU0_PE3_C_TXN(15)
  59 P3E_CPU0_PE3_OCP_RXP<15>   IO59 @BASEBOARD_FAB2_LIB.BASEBOARD_FAB2(SCH_1):P3E_CPU0_PE3_OCP_RXP(15)
   6 P12V_STBY    IO6 @BASEBOARD_FAB2_LIB.BASEBOARD_FAB2(SCH_1):P12V_STBY
  60    GND   IO60 @BASEBOARD_FAB2_LIB.BASEBOARD_FAB2(SCH_1):GND
  61 P3E_CPU0_PE3_OCP_RXN<15>   IO61 @BASEBOARD_FAB2_LIB.BASEBOARD_FAB2(SCH_1):P3E_CPU0_PE3_OCP_RXN(15)
  62    GND   IO62 @BASEBOARD_FAB2_LIB.BASEBOARD_FAB2(SCH_1):GND
  63    GND   IO63 @BASEBOARD_FAB2_LIB.BASEBOARD_FAB2(SCH_1):GND
  64 P3E_OCP_CPU0_PE3_C_TXP<14>   IO64 @BASEBOARD_FAB2_LIB.BASEBOARD_FAB2(SCH_1):P3E_OCP_CPU0_PE3_C_TXP(14)
  65    GND   IO65 @BASEBOARD_FAB2_LIB.BASEBOARD_FAB2(SCH_1):GND
  66 P3E_OCP_CPU0_PE3_C_TXN<14>   IO66 @BASEBOARD_FAB2_LIB.BASEBOARD_FAB2(SCH_1):P3E_OCP_CPU0_PE3_C_TXN(14)
  67 P3E_CPU0_PE3_OCP_RXP<14>   IO67 @BASEBOARD_FAB2_LIB.BASEBOARD_FAB2(SCH_1):P3E_CPU0_PE3_OCP_RXP(14)
  68    GND   IO68 @BASEBOARD_FAB2_LIB.BASEBOARD_FAB2(SCH_1):GND
  69 P3E_CPU0_PE3_OCP_RXN<14>   IO69 @BASEBOARD_FAB2_LIB.BASEBOARD_FAB2(SCH_1):P3E_CPU0_PE3_OCP_RXN(14)
   7 P5V_STBY    IO7 @BASEBOARD_FAB2_LIB.BASEBOARD_FAB2(SCH_1):P5V_STBY
  70    GND   IO70 @BASEBOARD_FAB2_LIB.BASEBOARD_FAB2(SCH_1):GND
  71    GND   IO71 @BASEBOARD_FAB2_LIB.BASEBOARD_FAB2(SCH_1):GND
  72 P3E_OCP_CPU0_PE3_C_TXP<13>   IO72 @BASEBOARD_FAB2_LIB.BASEBOARD_FAB2(SCH_1):P3E_OCP_CPU0_PE3_C_TXP(13)
  73    GND   IO73 @BASEBOARD_FAB2_LIB.BASEBOARD_FAB2(SCH_1):GND
  74 P3E_OCP_CPU0_PE3_C_TXN<13>   IO74 @BASEBOARD_FAB2_LIB.BASEBOARD_FAB2(SCH_1):P3E_OCP_CPU0_PE3_C_TXN(13)
  75 P3E_CPU0_PE3_OCP_RXP<13>   IO75 @BASEBOARD_FAB2_LIB.BASEBOARD_FAB2(SCH_1):P3E_CPU0_PE3_OCP_RXP(13)
  76    GND   IO76 @BASEBOARD_FAB2_LIB.BASEBOARD_FAB2(SCH_1):GND
  77 P3E_CPU0_PE3_OCP_RXN<13>   IO77 @BASEBOARD_FAB2_LIB.BASEBOARD_FAB2(SCH_1):P3E_CPU0_PE3_OCP_RXN(13)
  78    GND   IO78 @BASEBOARD_FAB2_LIB.BASEBOARD_FAB2(SCH_1):GND
  79    GND   IO79 @BASEBOARD_FAB2_LIB.BASEBOARD_FAB2(SCH_1):GND
   8    GND    IO8 @BASEBOARD_FAB2_LIB.BASEBOARD_FAB2(SCH_1):GND
  80 P3E_OCP_CPU0_PE3_C_TXP<12>   IO80 @BASEBOARD_FAB2_LIB.BASEBOARD_FAB2(SCH_1):P3E_OCP_CPU0_PE3_C_TXP(12)
  81    GND   IO81 @BASEBOARD_FAB2_LIB.BASEBOARD_FAB2(SCH_1):GND
  82 P3E_OCP_CPU0_PE3_C_TXN<12>   IO82 @BASEBOARD_FAB2_LIB.BASEBOARD_FAB2(SCH_1):P3E_OCP_CPU0_PE3_C_TXN(12)
  83 P3E_CPU0_PE3_OCP_RXP<12>   IO83 @BASEBOARD_FAB2_LIB.BASEBOARD_FAB2(SCH_1):P3E_CPU0_PE3_OCP_RXP(12)
  84    GND   IO84 @BASEBOARD_FAB2_LIB.BASEBOARD_FAB2(SCH_1):GND
  85 P3E_CPU0_PE3_OCP_RXN<12>   IO85 @BASEBOARD_FAB2_LIB.BASEBOARD_FAB2(SCH_1):P3E_CPU0_PE3_OCP_RXN(12)
  86    GND   IO86 @BASEBOARD_FAB2_LIB.BASEBOARD_FAB2(SCH_1):GND
  87    GND   IO87 @BASEBOARD_FAB2_LIB.BASEBOARD_FAB2(SCH_1):GND
  88 P3E_OCP_CPU0_PE3_C_TXP<11>   IO88 @BASEBOARD_FAB2_LIB.BASEBOARD_FAB2(SCH_1):P3E_OCP_CPU0_PE3_C_TXP(11)
  89    GND   IO89 @BASEBOARD_FAB2_LIB.BASEBOARD_FAB2(SCH_1):GND
   9    GND    IO9 @BASEBOARD_FAB2_LIB.BASEBOARD_FAB2(SCH_1):GND
  90 P3E_OCP_CPU0_PE3_C_TXN<11>   IO90 @BASEBOARD_FAB2_LIB.BASEBOARD_FAB2(SCH_1):P3E_OCP_CPU0_PE3_C_TXN(11)
  91 P3E_CPU0_PE3_OCP_RXP<11>   IO91 @BASEBOARD_FAB2_LIB.BASEBOARD_FAB2(SCH_1):P3E_CPU0_PE3_OCP_RXP(11)
  92    GND   IO92 @BASEBOARD_FAB2_LIB.BASEBOARD_FAB2(SCH_1):GND
  93 P3E_CPU0_PE3_OCP_RXN<11>   IO93 @BASEBOARD_FAB2_LIB.BASEBOARD_FAB2(SCH_1):P3E_CPU0_PE3_OCP_RXN(11)
  94    GND   IO94 @BASEBOARD_FAB2_LIB.BASEBOARD_FAB2(SCH_1):GND
  95    GND   IO95 @BASEBOARD_FAB2_LIB.BASEBOARD_FAB2(SCH_1):GND
  96 P3E_OCP_CPU0_PE3_C_TXP<10>   IO96 @BASEBOARD_FAB2_LIB.BASEBOARD_FAB2(SCH_1):P3E_OCP_CPU0_PE3_C_TXP(10)
  97    GND   IO97 @BASEBOARD_FAB2_LIB.BASEBOARD_FAB2(SCH_1):GND
  98 P3E_OCP_CPU0_PE3_C_TXN<10>   IO98 @BASEBOARD_FAB2_LIB.BASEBOARD_FAB2(SCH_1):P3E_OCP_CPU0_PE3_C_TXN(10)
  99 P3E_CPU0_PE3_OCP_RXP<10>   IO99 @BASEBOARD_FAB2_LIB.BASEBOARD_FAB2(SCH_1):P3E_CPU0_PE3_OCP_RXP(10)

RES_0402-0.0,5%,1/16W,CHIP,G21A  I337  R1M16
   1 RMII_BMC_OCP_RXD1      A @BASEBOARD_FAB2_LIB.BASEBOARD_FAB2(SCH_1):RMII_BMC_OCP_RXD1
   2 RMII_BMC_OCP_RXD1_R      B @BASEBOARD_FAB2_LIB.BASEBOARD_FAB2(SCH_1):RMII_BMC_OCP_RXD1_R

RES_0402-0.0,5%,1/16W,CHIP,G21A  I338  R1M17
   1 RMII_BMC_OCP_RXD0      A @BASEBOARD_FAB2_LIB.BASEBOARD_FAB2(SCH_1):RMII_BMC_OCP_RXD0
   2 RMII_BMC_OCP_RXD0_R      B @BASEBOARD_FAB2_LIB.BASEBOARD_FAB2(SCH_1):RMII_BMC_OCP_RXD0_R

RES_0402-0.0,5%,1/16W,CHIP,G21A  I339  R1M15
   1 RMII_BMC_OCP_CRSDV      A @BASEBOARD_FAB2_LIB.BASEBOARD_FAB2(SCH_1):RMII_BMC_OCP_CRSDV
   2 RMII_BMC_OCP_CRSDV_R      B @BASEBOARD_FAB2_LIB.BASEBOARD_FAB2(SCH_1):RMII_BMC_OCP_CRSDV_R

RES_0402-0.0,5%,1/16W,CHIP,G21A  I340  R1M18
   1 RMII_BMC_OCP_RXER_R      A @BASEBOARD_FAB2_LIB.BASEBOARD_FAB2(SCH_1):RMII_BMC_OCP_RXER_R
   2 RMII_BMC_OCP_RXER      B @BASEBOARD_FAB2_LIB.BASEBOARD_FAB2(SCH_1):RMII_BMC_OCP_RXER

CAP_A_0402V-0.1UF,16V,10%,X7R,A  I345  C9B10
   1 P5V_STBY      A @BASEBOARD_FAB2_LIB.BASEBOARD_FAB2(SCH_1):P5V_STBY
   2    GND      B @BASEBOARD_FAB2_LIB.BASEBOARD_FAB2(SCH_1):GND

CAP_A_0402V-1.0UF,6.3V,10%,X6SA  I347  C9B9
   1 P5V_STBY      A @BASEBOARD_FAB2_LIB.BASEBOARD_FAB2(SCH_1):P5V_STBY
   2    GND      B @BASEBOARD_FAB2_LIB.BASEBOARD_FAB2(SCH_1):GND


DRAWING: @BASEBOARD_FAB2_LIB.BASEBOARD_FAB2(SCH_1):PAGE187 

RES_0402-100.0,1%,1/16W,CHIP,GA  I18  R2R8
   1 FM_MEZZ_PRSNTB1_N      A @BASEBOARD_FAB2_LIB.BASEBOARD_FAB2(SCH_1):FM_MEZZ_PRSNTB1_N
   2    GND      B @BASEBOARD_FAB2_LIB.BASEBOARD_FAB2(SCH_1):GND

SCONN80_E67482007_SM-CONN,E674A  I119  J8E3
   1 FM_MEZZ_PRSNTB1_N    IO1 @BASEBOARD_FAB2_LIB.BASEBOARD_FAB2(SCH_1):FM_MEZZ_PRSNTB1_N
  10 P3E_OCP_CPU0_PE3_C_TXP<7>   IO10 @BASEBOARD_FAB2_LIB.BASEBOARD_FAB2(SCH_1):P3E_OCP_CPU0_PE3_C_TXP(7)
  11    GND   IO11 @BASEBOARD_FAB2_LIB.BASEBOARD_FAB2(SCH_1):GND
  12 P3E_OCP_CPU0_PE3_C_TXN<7>   IO12 @BASEBOARD_FAB2_LIB.BASEBOARD_FAB2(SCH_1):P3E_OCP_CPU0_PE3_C_TXN(7)
  13 P3E_CPU0_PE3_OCP_RXN<6>   IO13 @BASEBOARD_FAB2_LIB.BASEBOARD_FAB2(SCH_1):P3E_CPU0_PE3_OCP_RXN(6)
  14    GND   IO14 @BASEBOARD_FAB2_LIB.BASEBOARD_FAB2(SCH_1):GND
  15 P3E_CPU0_PE3_OCP_RXP<6>   IO15 @BASEBOARD_FAB2_LIB.BASEBOARD_FAB2(SCH_1):P3E_CPU0_PE3_OCP_RXP(6)
  16    GND   IO16 @BASEBOARD_FAB2_LIB.BASEBOARD_FAB2(SCH_1):GND
  17    GND   IO17 @BASEBOARD_FAB2_LIB.BASEBOARD_FAB2(SCH_1):GND
  18 P3E_OCP_CPU0_PE3_C_TXP<6>   IO18 @BASEBOARD_FAB2_LIB.BASEBOARD_FAB2(SCH_1):P3E_OCP_CPU0_PE3_C_TXP(6)
  19    GND   IO19 @BASEBOARD_FAB2_LIB.BASEBOARD_FAB2(SCH_1):GND
   2 P12V_STBY    IO2 @BASEBOARD_FAB2_LIB.BASEBOARD_FAB2(SCH_1):P12V_STBY
  20 P3E_OCP_CPU0_PE3_C_TXN<6>   IO20 @BASEBOARD_FAB2_LIB.BASEBOARD_FAB2(SCH_1):P3E_OCP_CPU0_PE3_C_TXN(6)
  21 P3E_CPU0_PE3_OCP_RXN<5>   IO21 @BASEBOARD_FAB2_LIB.BASEBOARD_FAB2(SCH_1):P3E_CPU0_PE3_OCP_RXN(5)
  22    GND   IO22 @BASEBOARD_FAB2_LIB.BASEBOARD_FAB2(SCH_1):GND
  23 P3E_CPU0_PE3_OCP_RXP<5>   IO23 @BASEBOARD_FAB2_LIB.BASEBOARD_FAB2(SCH_1):P3E_CPU0_PE3_OCP_RXP(5)
  24    GND   IO24 @BASEBOARD_FAB2_LIB.BASEBOARD_FAB2(SCH_1):GND
  25    GND   IO25 @BASEBOARD_FAB2_LIB.BASEBOARD_FAB2(SCH_1):GND
  26 P3E_OCP_CPU0_PE3_C_TXP<5>   IO26 @BASEBOARD_FAB2_LIB.BASEBOARD_FAB2(SCH_1):P3E_OCP_CPU0_PE3_C_TXP(5)
  27    GND   IO27 @BASEBOARD_FAB2_LIB.BASEBOARD_FAB2(SCH_1):GND
  28 P3E_OCP_CPU0_PE3_C_TXN<5>   IO28 @BASEBOARD_FAB2_LIB.BASEBOARD_FAB2(SCH_1):P3E_OCP_CPU0_PE3_C_TXN(5)
  29 P3E_CPU0_PE3_OCP_RXN<4>   IO29 @BASEBOARD_FAB2_LIB.BASEBOARD_FAB2(SCH_1):P3E_CPU0_PE3_OCP_RXN(4)
   3    GND    IO3 @BASEBOARD_FAB2_LIB.BASEBOARD_FAB2(SCH_1):GND
  30    GND   IO30 @BASEBOARD_FAB2_LIB.BASEBOARD_FAB2(SCH_1):GND
  31 P3E_CPU0_PE3_OCP_RXP<4>   IO31 @BASEBOARD_FAB2_LIB.BASEBOARD_FAB2(SCH_1):P3E_CPU0_PE3_OCP_RXP(4)
  32    GND   IO32 @BASEBOARD_FAB2_LIB.BASEBOARD_FAB2(SCH_1):GND
  33    GND   IO33 @BASEBOARD_FAB2_LIB.BASEBOARD_FAB2(SCH_1):GND
  34 P3E_OCP_CPU0_PE3_C_TXP<4>   IO34 @BASEBOARD_FAB2_LIB.BASEBOARD_FAB2(SCH_1):P3E_OCP_CPU0_PE3_C_TXP(4)
  35    GND   IO35 @BASEBOARD_FAB2_LIB.BASEBOARD_FAB2(SCH_1):GND
  36 P3E_OCP_CPU0_PE3_C_TXN<4>   IO36 @BASEBOARD_FAB2_LIB.BASEBOARD_FAB2(SCH_1):P3E_OCP_CPU0_PE3_C_TXN(4)
  37 P3E_CPU0_PE3_OCP_RXP<3>   IO37 @BASEBOARD_FAB2_LIB.BASEBOARD_FAB2(SCH_1):P3E_CPU0_PE3_OCP_RXP(3)
  38    GND   IO38 @BASEBOARD_FAB2_LIB.BASEBOARD_FAB2(SCH_1):GND
  39 P3E_CPU0_PE3_OCP_RXN<3>   IO39 @BASEBOARD_FAB2_LIB.BASEBOARD_FAB2(SCH_1):P3E_CPU0_PE3_OCP_RXN(3)
   4 P12V_STBY    IO4 @BASEBOARD_FAB2_LIB.BASEBOARD_FAB2(SCH_1):P12V_STBY
  40    GND   IO40 @BASEBOARD_FAB2_LIB.BASEBOARD_FAB2(SCH_1):GND
  41    GND   IO41 @BASEBOARD_FAB2_LIB.BASEBOARD_FAB2(SCH_1):GND
  42 P3E_OCP_CPU0_PE3_C_TXP<3>   IO42 @BASEBOARD_FAB2_LIB.BASEBOARD_FAB2(SCH_1):P3E_OCP_CPU0_PE3_C_TXP(3)
  43    GND   IO43 @BASEBOARD_FAB2_LIB.BASEBOARD_FAB2(SCH_1):GND
  44 P3E_OCP_CPU0_PE3_C_TXN<3>   IO44 @BASEBOARD_FAB2_LIB.BASEBOARD_FAB2(SCH_1):P3E_OCP_CPU0_PE3_C_TXN(3)
  45 P3E_CPU0_PE3_OCP_RXP<2>   IO45 @BASEBOARD_FAB2_LIB.BASEBOARD_FAB2(SCH_1):P3E_CPU0_PE3_OCP_RXP(2)
  46    GND   IO46 @BASEBOARD_FAB2_LIB.BASEBOARD_FAB2(SCH_1):GND
  47 P3E_CPU0_PE3_OCP_RXN<2>   IO47 @BASEBOARD_FAB2_LIB.BASEBOARD_FAB2(SCH_1):P3E_CPU0_PE3_OCP_RXN(2)
  48    GND   IO48 @BASEBOARD_FAB2_LIB.BASEBOARD_FAB2(SCH_1):GND
  49    GND   IO49 @BASEBOARD_FAB2_LIB.BASEBOARD_FAB2(SCH_1):GND
   5 P3E_CPU0_PE3_OCP_RXP<7>    IO5 @BASEBOARD_FAB2_LIB.BASEBOARD_FAB2(SCH_1):P3E_CPU0_PE3_OCP_RXP(7)
  50 P3E_OCP_CPU0_PE3_C_TXP<2>   IO50 @BASEBOARD_FAB2_LIB.BASEBOARD_FAB2(SCH_1):P3E_OCP_CPU0_PE3_C_TXP(2)
  51    GND   IO51 @BASEBOARD_FAB2_LIB.BASEBOARD_FAB2(SCH_1):GND
  52 P3E_OCP_CPU0_PE3_C_TXN<2>   IO52 @BASEBOARD_FAB2_LIB.BASEBOARD_FAB2(SCH_1):P3E_OCP_CPU0_PE3_C_TXN(2)
  53 P3E_CPU0_PE3_OCP_RXP<1>   IO53 @BASEBOARD_FAB2_LIB.BASEBOARD_FAB2(SCH_1):P3E_CPU0_PE3_OCP_RXP(1)
  54    GND   IO54 @BASEBOARD_FAB2_LIB.BASEBOARD_FAB2(SCH_1):GND
  55 P3E_CPU0_PE3_OCP_RXN<1>   IO55 @BASEBOARD_FAB2_LIB.BASEBOARD_FAB2(SCH_1):P3E_CPU0_PE3_OCP_RXN(1)
  56    GND   IO56 @BASEBOARD_FAB2_LIB.BASEBOARD_FAB2(SCH_1):GND
  57    GND   IO57 @BASEBOARD_FAB2_LIB.BASEBOARD_FAB2(SCH_1):GND
  58 P3E_OCP_CPU0_PE3_C_TXP<1>   IO58 @BASEBOARD_FAB2_LIB.BASEBOARD_FAB2(SCH_1):P3E_OCP_CPU0_PE3_C_TXP(1)
  59    GND   IO59 @BASEBOARD_FAB2_LIB.BASEBOARD_FAB2(SCH_1):GND
   6 TP_RSVD_B1    IO6 @BASEBOARD_FAB2_LIB.BASEBOARD_FAB2(SCH_1):TP_RSVD_B1
  60 P3E_OCP_CPU0_PE3_C_TXN<1>   IO60 @BASEBOARD_FAB2_LIB.BASEBOARD_FAB2(SCH_1):P3E_OCP_CPU0_PE3_C_TXN(1)
  61 P3E_CPU0_PE3_OCP_RXP<0>   IO61 @BASEBOARD_FAB2_LIB.BASEBOARD_FAB2(SCH_1):P3E_CPU0_PE3_OCP_RXP(0)
  62    GND   IO62 @BASEBOARD_FAB2_LIB.BASEBOARD_FAB2(SCH_1):GND
  63 P3E_CPU0_PE3_OCP_RXN<0>   IO63 @BASEBOARD_FAB2_LIB.BASEBOARD_FAB2(SCH_1):P3E_CPU0_PE3_OCP_RXN(0)
  64    GND   IO64 @BASEBOARD_FAB2_LIB.BASEBOARD_FAB2(SCH_1):GND
  65    GND   IO65 @BASEBOARD_FAB2_LIB.BASEBOARD_FAB2(SCH_1):GND
  66 P3E_OCP_CPU0_PE3_C_TXP<0>   IO66 @BASEBOARD_FAB2_LIB.BASEBOARD_FAB2(SCH_1):P3E_OCP_CPU0_PE3_C_TXP(0)
  67    GND   IO67 @BASEBOARD_FAB2_LIB.BASEBOARD_FAB2(SCH_1):GND
  68 P3E_OCP_CPU0_PE3_C_TXN<0>   IO68 @BASEBOARD_FAB2_LIB.BASEBOARD_FAB2(SCH_1):P3E_OCP_CPU0_PE3_C_TXN(0)
  69 CLK_100M_MEZZ3_DP   IO69 @BASEBOARD_FAB2_LIB.BASEBOARD_FAB2(SCH_1):CLK_100M_MEZZ3_DP
   7 P3E_CPU0_PE3_OCP_RXN<7>    IO7 @BASEBOARD_FAB2_LIB.BASEBOARD_FAB2(SCH_1):P3E_CPU0_PE3_OCP_RXN(7)
  70    GND   IO70 @BASEBOARD_FAB2_LIB.BASEBOARD_FAB2(SCH_1):GND
  71 CLK_100M_MEZZ3_DN   IO71 @BASEBOARD_FAB2_LIB.BASEBOARD_FAB2(SCH_1):CLK_100M_MEZZ3_DN
  72    GND   IO72 @BASEBOARD_FAB2_LIB.BASEBOARD_FAB2(SCH_1):GND
  73    GND   IO73 @BASEBOARD_FAB2_LIB.BASEBOARD_FAB2(SCH_1):GND
  74 CLK_100M_MEZZ4_DP   IO74 @BASEBOARD_FAB2_LIB.BASEBOARD_FAB2(SCH_1):CLK_100M_MEZZ4_DP
  75 RST_PCIE_CPU_DEV1_R_N   IO75 @BASEBOARD_FAB2_LIB.BASEBOARD_FAB2(SCH_1):RST_PCIE_CPU_DEV1_R_N
  76 CLK_100M_MEZZ4_DN   IO76 @BASEBOARD_FAB2_LIB.BASEBOARD_FAB2(SCH_1):CLK_100M_MEZZ4_DN
  77 RST_PCIE_CPU_DEV2_R_N   IO77 @BASEBOARD_FAB2_LIB.BASEBOARD_FAB2(SCH_1):RST_PCIE_CPU_DEV2_R_N
  78    GND   IO78 @BASEBOARD_FAB2_LIB.BASEBOARD_FAB2(SCH_1):GND
  79 RST_PCIE_CPU_DEV3_R_N   IO79 @BASEBOARD_FAB2_LIB.BASEBOARD_FAB2(SCH_1):RST_PCIE_CPU_DEV3_R_N
   8    GND    IO8 @BASEBOARD_FAB2_LIB.BASEBOARD_FAB2(SCH_1):GND
  80 FM_OCP_MEZZB_PRES_N   IO80 @BASEBOARD_FAB2_LIB.BASEBOARD_FAB2(SCH_1):FM_OCP_MEZZB_PRES_N
   9    GND    IO9 @BASEBOARD_FAB2_LIB.BASEBOARD_FAB2(SCH_1):GND

RES_0402-200.0,1%,1/16W,CHIP,GA  I145  R9E10
   1 RST_PCIE_CPU_DEV1_R_N      A @BASEBOARD_FAB2_LIB.BASEBOARD_FAB2(SCH_1):RST_PCIE_CPU_DEV1_R_N
   2 RST_PCIE_CPU_DEV1_N      B @BASEBOARD_FAB2_LIB.BASEBOARD_FAB2(SCH_1):RST_PCIE_CPU_DEV1_N

RES_0402-200.0,1%,1/16W,CHIP,GA  I150  R9E11
   1 RST_PCIE_CPU_DEV2_R_N      A @BASEBOARD_FAB2_LIB.BASEBOARD_FAB2(SCH_1):RST_PCIE_CPU_DEV2_R_N
   2 RST_PCIE_CPU_DEV2_N      B @BASEBOARD_FAB2_LIB.BASEBOARD_FAB2(SCH_1):RST_PCIE_CPU_DEV2_N

RES_0402-200.0,1%,1/16W,CHIP,GA  I153  R9E12
   1 RST_PCIE_CPU_DEV3_R_N      A @BASEBOARD_FAB2_LIB.BASEBOARD_FAB2(SCH_1):RST_PCIE_CPU_DEV3_R_N
   2 RST_PCIE_CPU_DEV3_N      B @BASEBOARD_FAB2_LIB.BASEBOARD_FAB2(SCH_1):RST_PCIE_CPU_DEV3_N


DRAWING: @BASEBOARD_FAB2_LIB.BASEBOARD_FAB2(SCH_1):PAGE188 

CAP_A_0402V-0.1UF,16V,10%,X7R,A  I2  C2R15
   1 P12V_STBY      A @BASEBOARD_FAB2_LIB.BASEBOARD_FAB2(SCH_1):P12V_STBY
   2    GND      B @BASEBOARD_FAB2_LIB.BASEBOARD_FAB2(SCH_1):GND

CAP_A_0402V-0.1UF,16V,10%,X7R,A  I3  C2R18
   1 P12V_STBY      A @BASEBOARD_FAB2_LIB.BASEBOARD_FAB2(SCH_1):P12V_STBY
   2    GND      B @BASEBOARD_FAB2_LIB.BASEBOARD_FAB2(SCH_1):GND

CAP_A_0402V-0.1UF,16V,10%,X7R,A  I21  C2P11
   1 P12V_STBY      A @BASEBOARD_FAB2_LIB.BASEBOARD_FAB2(SCH_1):P12V_STBY
   2    GND      B @BASEBOARD_FAB2_LIB.BASEBOARD_FAB2(SCH_1):GND

CAP_A_0402V-0.1UF,16V,10%,X7R,A  I23  C2P12
   1 P12V_STBY      A @BASEBOARD_FAB2_LIB.BASEBOARD_FAB2(SCH_1):P12V_STBY
   2    GND      B @BASEBOARD_FAB2_LIB.BASEBOARD_FAB2(SCH_1):GND

CAP_A_0402V-0.1UF,16V,10%,X7R,A  I25  C2R17
   1 P12V_STBY      A @BASEBOARD_FAB2_LIB.BASEBOARD_FAB2(SCH_1):P12V_STBY
   2    GND      B @BASEBOARD_FAB2_LIB.BASEBOARD_FAB2(SCH_1):GND

SCONN64_H87568002_A_SMT-CONN,HA  I27  J8E4
   1 SMB_OCP_FRU_STBY_LVC3_SCL    IO1 @BASEBOARD_FAB2_LIB.BASEBOARD_FAB2(SCH_1):SMB_OCP_FRU_STBY_LVC3_SCL
  10    GND   IO10 @BASEBOARD_FAB2_LIB.BASEBOARD_FAB2(SCH_1):GND
  11 KR_P3_OCP_TX_DP   IO11 @BASEBOARD_FAB2_LIB.BASEBOARD_FAB2(SCH_1):KR_P3_OCP_TX_DP
  12 KR_P3_OCP_TX_DN   IO12 @BASEBOARD_FAB2_LIB.BASEBOARD_FAB2(SCH_1):KR_P3_OCP_TX_DN
  13    GND   IO13 @BASEBOARD_FAB2_LIB.BASEBOARD_FAB2(SCH_1):GND
  14 LED_GBE_P2_0   IO14 @BASEBOARD_FAB2_LIB.BASEBOARD_FAB2(SCH_1):LED_GBE_P2_0
  15 LED_GBE_P2_1   IO15 @BASEBOARD_FAB2_LIB.BASEBOARD_FAB2(SCH_1):LED_GBE_P2_1
  16    GND   IO16 @BASEBOARD_FAB2_LIB.BASEBOARD_FAB2(SCH_1):GND
  17 KR_P2_OCP_RX_DP   IO17 @BASEBOARD_FAB2_LIB.BASEBOARD_FAB2(SCH_1):KR_P2_OCP_RX_DP
  18 KR_P2_OCP_RX_DN   IO18 @BASEBOARD_FAB2_LIB.BASEBOARD_FAB2(SCH_1):KR_P2_OCP_RX_DN
  19    GND   IO19 @BASEBOARD_FAB2_LIB.BASEBOARD_FAB2(SCH_1):GND
   2 SMB_OCP_FRU_STBY_LVC3_SDA    IO2 @BASEBOARD_FAB2_LIB.BASEBOARD_FAB2(SCH_1):SMB_OCP_FRU_STBY_LVC3_SDA
  20 SMB_PCH_MEZZ_LOM0_SCL   IO20 @BASEBOARD_FAB2_LIB.BASEBOARD_FAB2(SCH_1):SMB_PCH_MEZZ_LOM0_SCL
  21 SMB_PCH_MEZZ_LOM0_SDA   IO21 @BASEBOARD_FAB2_LIB.BASEBOARD_FAB2(SCH_1):SMB_PCH_MEZZ_LOM0_SDA
  22    GND   IO22 @BASEBOARD_FAB2_LIB.BASEBOARD_FAB2(SCH_1):GND
  23 KR_P3_OCP_RX_DP   IO23 @BASEBOARD_FAB2_LIB.BASEBOARD_FAB2(SCH_1):KR_P3_OCP_RX_DP
  24 KR_P3_OCP_RX_DN   IO24 @BASEBOARD_FAB2_LIB.BASEBOARD_FAB2(SCH_1):KR_P3_OCP_RX_DN
  25    GND   IO25 @BASEBOARD_FAB2_LIB.BASEBOARD_FAB2(SCH_1):GND
  26 SMB_PCH_MEZZ_LOM1_SCL   IO26 @BASEBOARD_FAB2_LIB.BASEBOARD_FAB2(SCH_1):SMB_PCH_MEZZ_LOM1_SCL
  27 SMB_PCH_MEZZ_LOM1_SDA   IO27 @BASEBOARD_FAB2_LIB.BASEBOARD_FAB2(SCH_1):SMB_PCH_MEZZ_LOM1_SDA
  28    GND   IO28 @BASEBOARD_FAB2_LIB.BASEBOARD_FAB2(SCH_1):GND
  29 SMB_PCH_MEZZ_LOM3_SCL   IO29 @BASEBOARD_FAB2_LIB.BASEBOARD_FAB2(SCH_1):SMB_PCH_MEZZ_LOM3_SCL
   3 TP_EXT_MDIO_I2C_SEL    IO3 @BASEBOARD_FAB2_LIB.BASEBOARD_FAB2(SCH_1):TP_EXT_MDIO_I2C_SEL
  30 SMB_PCH_MEZZ_LOM3_SDA   IO30 @BASEBOARD_FAB2_LIB.BASEBOARD_FAB2(SCH_1):SMB_PCH_MEZZ_LOM3_SDA
  31 FM_GBE2_LVC3_MOD_ABS   IO31 @BASEBOARD_FAB2_LIB.BASEBOARD_FAB2(SCH_1):FM_GBE2_LVC3_MOD_ABS
  32 FM_GBE3_LVC3_MOD_ABS   IO32 @BASEBOARD_FAB2_LIB.BASEBOARD_FAB2(SCH_1):FM_GBE3_LVC3_MOD_ABS
  33 P12V_STBY   IO33 @BASEBOARD_FAB2_LIB.BASEBOARD_FAB2(SCH_1):P12V_STBY
  34 P12V_STBY   IO34 @BASEBOARD_FAB2_LIB.BASEBOARD_FAB2(SCH_1):P12V_STBY
  35 P12V_STBY   IO35 @BASEBOARD_FAB2_LIB.BASEBOARD_FAB2(SCH_1):P12V_STBY
  36 TP_RSVD<0>   IO36 @BASEBOARD_FAB2_LIB.BASEBOARD_FAB2(SCH_1):TP_RSVD(0)
  37 FM_GBE0_LVC3_MOD_ABS   IO37 @BASEBOARD_FAB2_LIB.BASEBOARD_FAB2(SCH_1):FM_GBE0_LVC3_MOD_ABS
  38 FM_GBE1_LVC3_MOD_ABS   IO38 @BASEBOARD_FAB2_LIB.BASEBOARD_FAB2(SCH_1):FM_GBE1_LVC3_MOD_ABS
  39    GND   IO39 @BASEBOARD_FAB2_LIB.BASEBOARD_FAB2(SCH_1):GND
   4    GND    IO4 @BASEBOARD_FAB2_LIB.BASEBOARD_FAB2(SCH_1):GND
  40 KR_P0_OCP_TX_DP   IO40 @BASEBOARD_FAB2_LIB.BASEBOARD_FAB2(SCH_1):KR_P0_OCP_TX_DP
  41 KR_P0_OCP_TX_DN   IO41 @BASEBOARD_FAB2_LIB.BASEBOARD_FAB2(SCH_1):KR_P0_OCP_TX_DN
  42    GND   IO42 @BASEBOARD_FAB2_LIB.BASEBOARD_FAB2(SCH_1):GND
  43 LED_GBE_P0_0   IO43 @BASEBOARD_FAB2_LIB.BASEBOARD_FAB2(SCH_1):LED_GBE_P0_0
  44 LED_GBE_P0_1   IO44 @BASEBOARD_FAB2_LIB.BASEBOARD_FAB2(SCH_1):LED_GBE_P0_1
  45    GND   IO45 @BASEBOARD_FAB2_LIB.BASEBOARD_FAB2(SCH_1):GND
  46 KR_P1_OCP_TX_DP   IO46 @BASEBOARD_FAB2_LIB.BASEBOARD_FAB2(SCH_1):KR_P1_OCP_TX_DP
  47 KR_P1_OCP_TX_DN   IO47 @BASEBOARD_FAB2_LIB.BASEBOARD_FAB2(SCH_1):KR_P1_OCP_TX_DN
  48    GND   IO48 @BASEBOARD_FAB2_LIB.BASEBOARD_FAB2(SCH_1):GND
  49 TP_SHARED_KR_MDC_0   IO49 @BASEBOARD_FAB2_LIB.BASEBOARD_FAB2(SCH_1):TP_SHARED_KR_MDC_0
   5 KR_P2_OCP_TX_DP    IO5 @BASEBOARD_FAB2_LIB.BASEBOARD_FAB2(SCH_1):KR_P2_OCP_TX_DP
  50 TP_SHARED_KR_MDIO_0   IO50 @BASEBOARD_FAB2_LIB.BASEBOARD_FAB2(SCH_1):TP_SHARED_KR_MDIO_0
  51    GND   IO51 @BASEBOARD_FAB2_LIB.BASEBOARD_FAB2(SCH_1):GND
  52 KR_P0_OCP_RX_DP   IO52 @BASEBOARD_FAB2_LIB.BASEBOARD_FAB2(SCH_1):KR_P0_OCP_RX_DP
  53 KR_P0_OCP_RX_DN   IO53 @BASEBOARD_FAB2_LIB.BASEBOARD_FAB2(SCH_1):KR_P0_OCP_RX_DN
  54    GND   IO54 @BASEBOARD_FAB2_LIB.BASEBOARD_FAB2(SCH_1):GND
  55 LED_GBE_P3_0   IO55 @BASEBOARD_FAB2_LIB.BASEBOARD_FAB2(SCH_1):LED_GBE_P3_0
  56 LED_GBE_P3_1   IO56 @BASEBOARD_FAB2_LIB.BASEBOARD_FAB2(SCH_1):LED_GBE_P3_1
  57    GND   IO57 @BASEBOARD_FAB2_LIB.BASEBOARD_FAB2(SCH_1):GND
  58 KR_P1_OCP_RX_DP   IO58 @BASEBOARD_FAB2_LIB.BASEBOARD_FAB2(SCH_1):KR_P1_OCP_RX_DP
  59 KR_P1_OCP_RX_DN   IO59 @BASEBOARD_FAB2_LIB.BASEBOARD_FAB2(SCH_1):KR_P1_OCP_RX_DN
   6 KR_P2_OCP_TX_DN    IO6 @BASEBOARD_FAB2_LIB.BASEBOARD_FAB2(SCH_1):KR_P2_OCP_TX_DN
  60    GND   IO60 @BASEBOARD_FAB2_LIB.BASEBOARD_FAB2(SCH_1):GND
  61 SMB_PCH_MEZZ_LOM2_SCL   IO61 @BASEBOARD_FAB2_LIB.BASEBOARD_FAB2(SCH_1):SMB_PCH_MEZZ_LOM2_SCL
  62 SMB_PCH_MEZZ_LOM2_SDA   IO62 @BASEBOARD_FAB2_LIB.BASEBOARD_FAB2(SCH_1):SMB_PCH_MEZZ_LOM2_SDA
  63    GND   IO63 @BASEBOARD_FAB2_LIB.BASEBOARD_FAB2(SCH_1):GND
  64 FM_OCP_MEZZC_PRES_N   IO64 @BASEBOARD_FAB2_LIB.BASEBOARD_FAB2(SCH_1):FM_OCP_MEZZC_PRES_N
   7    GND    IO7 @BASEBOARD_FAB2_LIB.BASEBOARD_FAB2(SCH_1):GND
   8 LED_GBE_P1_0    IO8 @BASEBOARD_FAB2_LIB.BASEBOARD_FAB2(SCH_1):LED_GBE_P1_0
   9 LED_GBE_P1_1    IO9 @BASEBOARD_FAB2_LIB.BASEBOARD_FAB2(SCH_1):LED_GBE_P1_1

CAP_A_0402V-0.1UF,16V,10%,X7R,A  I40  C2R16
   1 P12V_STBY      A @BASEBOARD_FAB2_LIB.BASEBOARD_FAB2(SCH_1):P12V_STBY
   2    GND      B @BASEBOARD_FAB2_LIB.BASEBOARD_FAB2(SCH_1):GND

CAP_1206LF-22UF,16V,10%,X6S,D3A  I41  C2P10
   1 P12V_STBY      A @BASEBOARD_FAB2_LIB.BASEBOARD_FAB2(SCH_1):P12V_STBY
   2    GND      B @BASEBOARD_FAB2_LIB.BASEBOARD_FAB2(SCH_1):GND

CAP_A_0402V-0.1UF,16V,10%,X7R,A  I53  C2P16
   1 P12V_STBY      A @BASEBOARD_FAB2_LIB.BASEBOARD_FAB2(SCH_1):P12V_STBY
   2    GND      B @BASEBOARD_FAB2_LIB.BASEBOARD_FAB2(SCH_1):GND

CAP_A_0402V-0.1UF,16V,10%,X7R,A  I55  C2P15
   1 P12V_STBY      A @BASEBOARD_FAB2_LIB.BASEBOARD_FAB2(SCH_1):P12V_STBY
   2    GND      B @BASEBOARD_FAB2_LIB.BASEBOARD_FAB2(SCH_1):GND

CAP_A_0402V-0.1UF,16V,10%,X7R,A  I56  C2P14
   1 P12V_STBY      A @BASEBOARD_FAB2_LIB.BASEBOARD_FAB2(SCH_1):P12V_STBY
   2    GND      B @BASEBOARD_FAB2_LIB.BASEBOARD_FAB2(SCH_1):GND

CAP_A_0402V-0.1UF,16V,10%,X7R,A  I57  C2P13
   1 P12V_STBY      A @BASEBOARD_FAB2_LIB.BASEBOARD_FAB2(SCH_1):P12V_STBY
   2    GND      B @BASEBOARD_FAB2_LIB.BASEBOARD_FAB2(SCH_1):GND

CAP_A_0402V-0.1UF,16V,10%,X7R,A  I64  C8C8
   1 KR_P3_OCP_RX_DP      A @BASEBOARD_FAB2_LIB.BASEBOARD_FAB2(SCH_1):KR_P3_OCP_RX_DP
   2 KR_P3_OCP_RX_C_DP      B @BASEBOARD_FAB2_LIB.BASEBOARD_FAB2(SCH_1):KR_P3_OCP_RX_C_DP

CAP_A_0402V-0.1UF,16V,10%,X7R,A  I68  C8C9
   1 KR_P3_OCP_RX_DN      A @BASEBOARD_FAB2_LIB.BASEBOARD_FAB2(SCH_1):KR_P3_OCP_RX_DN
   2 KR_P3_OCP_RX_C_DN      B @BASEBOARD_FAB2_LIB.BASEBOARD_FAB2(SCH_1):KR_P3_OCP_RX_C_DN

CAP_A_0402V-0.1UF,16V,10%,X7R,A  I72  C8C11
   1 KR_P2_OCP_RX_DP      A @BASEBOARD_FAB2_LIB.BASEBOARD_FAB2(SCH_1):KR_P2_OCP_RX_DP
   2 KR_P2_OCP_RX_C_DP      B @BASEBOARD_FAB2_LIB.BASEBOARD_FAB2(SCH_1):KR_P2_OCP_RX_C_DP

CAP_A_0402V-0.1UF,16V,10%,X7R,A  I73  C8C10
   1 KR_P2_OCP_RX_DN      A @BASEBOARD_FAB2_LIB.BASEBOARD_FAB2(SCH_1):KR_P2_OCP_RX_DN
   2 KR_P2_OCP_RX_C_DN      B @BASEBOARD_FAB2_LIB.BASEBOARD_FAB2(SCH_1):KR_P2_OCP_RX_C_DN

CAP_A_0402V-0.1UF,16V,10%,X7R,A  I80  C8C12
   1 KR_P1_OCP_RX_DP      A @BASEBOARD_FAB2_LIB.BASEBOARD_FAB2(SCH_1):KR_P1_OCP_RX_DP
   2 KR_P1_OCP_RX_C_DP      B @BASEBOARD_FAB2_LIB.BASEBOARD_FAB2(SCH_1):KR_P1_OCP_RX_C_DP

CAP_A_0402V-0.1UF,16V,10%,X7R,A  I81  C8C13
   1 KR_P1_OCP_RX_DN      A @BASEBOARD_FAB2_LIB.BASEBOARD_FAB2(SCH_1):KR_P1_OCP_RX_DN
   2 KR_P1_OCP_RX_C_DN      B @BASEBOARD_FAB2_LIB.BASEBOARD_FAB2(SCH_1):KR_P1_OCP_RX_C_DN

CAP_A_0402V-0.1UF,16V,10%,X7R,A  I82  C8C15
   1 KR_P0_OCP_RX_DP      A @BASEBOARD_FAB2_LIB.BASEBOARD_FAB2(SCH_1):KR_P0_OCP_RX_DP
   2 KR_P0_OCP_RX_C_DP      B @BASEBOARD_FAB2_LIB.BASEBOARD_FAB2(SCH_1):KR_P0_OCP_RX_C_DP

CAP_A_0402V-0.1UF,16V,10%,X7R,A  I86  C8C14
   1 KR_P0_OCP_RX_DN      A @BASEBOARD_FAB2_LIB.BASEBOARD_FAB2(SCH_1):KR_P0_OCP_RX_DN
   2 KR_P0_OCP_RX_C_DN      B @BASEBOARD_FAB2_LIB.BASEBOARD_FAB2(SCH_1):KR_P0_OCP_RX_C_DN

RES_0402-2.21K,1%,1/16W,CHIP,GA  I88  R1R18
   1 P3V3_STBY      A @BASEBOARD_FAB2_LIB.BASEBOARD_FAB2(SCH_1):P3V3_STBY
   2 SMB_PCH_MEZZ_LOM0_SCL      B @BASEBOARD_FAB2_LIB.BASEBOARD_FAB2(SCH_1):SMB_PCH_MEZZ_LOM0_SCL

RES_0402-2.21K,1%,1/16W,CHIP,GA  I89  R1R19
   1 P3V3_STBY      A @BASEBOARD_FAB2_LIB.BASEBOARD_FAB2(SCH_1):P3V3_STBY
   2 SMB_PCH_MEZZ_LOM0_SDA      B @BASEBOARD_FAB2_LIB.BASEBOARD_FAB2(SCH_1):SMB_PCH_MEZZ_LOM0_SDA

RES_0402-2.21K,1%,1/16W,CHIP,GA  I90  R1R21
   1 P3V3_STBY      A @BASEBOARD_FAB2_LIB.BASEBOARD_FAB2(SCH_1):P3V3_STBY
   2 SMB_PCH_MEZZ_LOM1_SDA      B @BASEBOARD_FAB2_LIB.BASEBOARD_FAB2(SCH_1):SMB_PCH_MEZZ_LOM1_SDA

RES_0402-2.21K,1%,1/16W,CHIP,GA  I91  R1R20
   1 P3V3_STBY      A @BASEBOARD_FAB2_LIB.BASEBOARD_FAB2(SCH_1):P3V3_STBY
   2 SMB_PCH_MEZZ_LOM1_SCL      B @BASEBOARD_FAB2_LIB.BASEBOARD_FAB2(SCH_1):SMB_PCH_MEZZ_LOM1_SCL

RES_0402-2.21K,1%,1/16W,CHIP,GA  I92  R1R22
   1 P3V3_STBY      A @BASEBOARD_FAB2_LIB.BASEBOARD_FAB2(SCH_1):P3V3_STBY
   2 SMB_PCH_MEZZ_LOM3_SDA      B @BASEBOARD_FAB2_LIB.BASEBOARD_FAB2(SCH_1):SMB_PCH_MEZZ_LOM3_SDA

RES_0402-2.21K,1%,1/16W,CHIP,GA  I93  R1R16
   1 P3V3_STBY      A @BASEBOARD_FAB2_LIB.BASEBOARD_FAB2(SCH_1):P3V3_STBY
   2 SMB_PCH_MEZZ_LOM2_SCL      B @BASEBOARD_FAB2_LIB.BASEBOARD_FAB2(SCH_1):SMB_PCH_MEZZ_LOM2_SCL

RES_0402-2.21K,1%,1/16W,CHIP,GA  I94  R1R17
   1 P3V3_STBY      A @BASEBOARD_FAB2_LIB.BASEBOARD_FAB2(SCH_1):P3V3_STBY
   2 SMB_PCH_MEZZ_LOM2_SDA      B @BASEBOARD_FAB2_LIB.BASEBOARD_FAB2(SCH_1):SMB_PCH_MEZZ_LOM2_SDA

RES_0402-2.21K,1%,1/16W,CHIP,GA  I95  R1R23
   1 P3V3_STBY      A @BASEBOARD_FAB2_LIB.BASEBOARD_FAB2(SCH_1):P3V3_STBY
   2 SMB_PCH_MEZZ_LOM3_SCL      B @BASEBOARD_FAB2_LIB.BASEBOARD_FAB2(SCH_1):SMB_PCH_MEZZ_LOM3_SCL


DRAWING: @BASEBOARD_FAB2_LIB.BASEBOARD_FAB2(SCH_1):PAGE189 

RES_0402-0.0,5%,1/16W,CHIP,G21A  I7  R8G10
   1 JTAG_BMC_TRST_N      A @BASEBOARD_FAB2_LIB.BASEBOARD_FAB2(SCH_1):JTAG_BMC_TRST_N
   2 JTAG_TRST_N      B @BASEBOARD_FAB2_LIB.BASEBOARD_FAB2(SCH_1):JTAG_TRST_N

RES_0402-0.0,5%,1/16W,EMPTY,G2A  I8  R7G19
   1 JTAG_PCH_GBE_TDI      A @BASEBOARD_FAB2_LIB.BASEBOARD_FAB2(SCH_1):JTAG_PCH_GBE_TDI
   2 JTAG_TDI      B @BASEBOARD_FAB2_LIB.BASEBOARD_FAB2(SCH_1):JTAG_TDI

RES_0402-0.0,5%,1/16W,EMPTY,G2A  I9  R8G9
   1 JTAG_PCH_GBE_TRST_N      A @BASEBOARD_FAB2_LIB.BASEBOARD_FAB2(SCH_1):JTAG_PCH_GBE_TRST_N
   2 JTAG_TRST_N      B @BASEBOARD_FAB2_LIB.BASEBOARD_FAB2(SCH_1):JTAG_TRST_N

RES_0402-0.0,5%,1/16W,EMPTY,G2A  I13  R7G18
   1 JTAG_PCH_PLD_TDI      A @BASEBOARD_FAB2_LIB.BASEBOARD_FAB2(SCH_1):JTAG_PCH_PLD_TDI
   2 JTAG_TDI      B @BASEBOARD_FAB2_LIB.BASEBOARD_FAB2(SCH_1):JTAG_TDI

RES_0402-0.0,5%,1/16W,CHIP,G21A  I17  R8G8
   1 JTAG_BMC_TDI      A @BASEBOARD_FAB2_LIB.BASEBOARD_FAB2(SCH_1):JTAG_BMC_TDI
   2 JTAG_TDI      B @BASEBOARD_FAB2_LIB.BASEBOARD_FAB2(SCH_1):JTAG_TDI

RES_0402-0.0,5%,1/16W,CHIP,G21A  I18  R8G7
   1 JTAG_PLD_TDI      A @BASEBOARD_FAB2_LIB.BASEBOARD_FAB2(SCH_1):JTAG_PLD_TDI
   2 JTAG_TDI      B @BASEBOARD_FAB2_LIB.BASEBOARD_FAB2(SCH_1):JTAG_TDI

RES_0402-0.0,5%,1/16W,EMPTY,G2A  I19  R8G11
   1 JTAG_PCH_PLD_TMS      A @BASEBOARD_FAB2_LIB.BASEBOARD_FAB2(SCH_1):JTAG_PCH_PLD_TMS
   2 JTAG_TMS      B @BASEBOARD_FAB2_LIB.BASEBOARD_FAB2(SCH_1):JTAG_TMS

RES_0402-0.0,5%,1/16W,CHIP,G21A  I20  R8G14
   1 JTAG_BMC_TMS      A @BASEBOARD_FAB2_LIB.BASEBOARD_FAB2(SCH_1):JTAG_BMC_TMS
   2 JTAG_TMS      B @BASEBOARD_FAB2_LIB.BASEBOARD_FAB2(SCH_1):JTAG_TMS

RES_0402-0.0,5%,1/16W,EMPTY,G2A  I21  R8G12
   1 JTAG_PCH_GBE_TMS      A @BASEBOARD_FAB2_LIB.BASEBOARD_FAB2(SCH_1):JTAG_PCH_GBE_TMS
   2 JTAG_TMS      B @BASEBOARD_FAB2_LIB.BASEBOARD_FAB2(SCH_1):JTAG_TMS

RES_0402-0.0,5%,1/16W,EMPTY,G2A  I22  R8G16
   1 JTAG_PCH_PLD_TCK      A @BASEBOARD_FAB2_LIB.BASEBOARD_FAB2(SCH_1):JTAG_PCH_PLD_TCK
   2 JTAG_TCK      B @BASEBOARD_FAB2_LIB.BASEBOARD_FAB2(SCH_1):JTAG_TCK

RES_0402-0.0,5%,1/16W,CHIP,G21A  I23  R8G13
   1 JTAG_PLD_TMS      A @BASEBOARD_FAB2_LIB.BASEBOARD_FAB2(SCH_1):JTAG_PLD_TMS
   2 JTAG_TMS      B @BASEBOARD_FAB2_LIB.BASEBOARD_FAB2(SCH_1):JTAG_TMS

RES_0402-0.0,5%,1/16W,EMPTY,G2A  I24  R8G15
   1 JTAG_PCH_GBE_CLK      A @BASEBOARD_FAB2_LIB.BASEBOARD_FAB2(SCH_1):JTAG_PCH_GBE_CLK
   2 JTAG_TCK      B @BASEBOARD_FAB2_LIB.BASEBOARD_FAB2(SCH_1):JTAG_TCK

RES_0402-0.0,5%,1/16W,CHIP,G21A  I25  R8G17
   1 JTAG_BMC_TCK      A @BASEBOARD_FAB2_LIB.BASEBOARD_FAB2(SCH_1):JTAG_BMC_TCK
   2 JTAG_TCK      B @BASEBOARD_FAB2_LIB.BASEBOARD_FAB2(SCH_1):JTAG_TCK

RES_0402-0.0,5%,1/16W,CHIP,G21A  I26  R8G18
   1 JTAG_PLD_TCK      A @BASEBOARD_FAB2_LIB.BASEBOARD_FAB2(SCH_1):JTAG_PLD_TCK
   2 JTAG_TCK      B @BASEBOARD_FAB2_LIB.BASEBOARD_FAB2(SCH_1):JTAG_TCK

RES_0402-0.0,5%,1/16W,EMPTY,G2A  I27  R7G16
   1 JTAG_PCH_GBE_TDO      A @BASEBOARD_FAB2_LIB.BASEBOARD_FAB2(SCH_1):JTAG_PCH_GBE_TDO
   2 JTAG_TDO      B @BASEBOARD_FAB2_LIB.BASEBOARD_FAB2(SCH_1):JTAG_TDO

RES_0402-0.0,5%,1/16W,EMPTY,G2A  I36  R7G15
   1 JTAG_PCH_PLD_TDO      A @BASEBOARD_FAB2_LIB.BASEBOARD_FAB2(SCH_1):JTAG_PCH_PLD_TDO
   2 JTAG_TDO      B @BASEBOARD_FAB2_LIB.BASEBOARD_FAB2(SCH_1):JTAG_TDO

RES_0402-0.0,5%,1/16W,CHIP,G21A  I37  R7G17
   1 JTAG_BMC_TDO      A @BASEBOARD_FAB2_LIB.BASEBOARD_FAB2(SCH_1):JTAG_BMC_TDO
   2 JTAG_TDO      B @BASEBOARD_FAB2_LIB.BASEBOARD_FAB2(SCH_1):JTAG_TDO

RES_0402-0.0,5%,1/16W,CHIP,G21A  I38  R7G14
   1 JTAG_PLD_TDO      A @BASEBOARD_FAB2_LIB.BASEBOARD_FAB2(SCH_1):JTAG_PLD_TDO
   2 JTAG_TDO      B @BASEBOARD_FAB2_LIB.BASEBOARD_FAB2(SCH_1):JTAG_TDO

RES_0402-1.00K,1%,1/16W,CHIP,GA  I44  R3R15
   1 P3V3_STBY      A @BASEBOARD_FAB2_LIB.BASEBOARD_FAB2(SCH_1):P3V3_STBY
   2 FM_JTAG_PLD_EN_DEBUG      B @BASEBOARD_FAB2_LIB.BASEBOARD_FAB2(SCH_1):FM_JTAG_PLD_EN_DEBUG

RES_0402-10.0K,1%,1/16W,EMPTY,A  I45  R3R11
   1 FM_JTAG_PLD_EN_DEBUG      A @BASEBOARD_FAB2_LIB.BASEBOARD_FAB2(SCH_1):FM_JTAG_PLD_EN_DEBUG
   2    GND      B @BASEBOARD_FAB2_LIB.BASEBOARD_FAB2(SCH_1):GND

CONN8_C77962004_PIP-CONN,C7796A  I47  J7G2
   1 P3V3_STBY_PLD_D    IO1 @BASEBOARD_FAB2_LIB.BASEBOARD_FAB2(SCH_1):P3V3_STBY_PLD_D
   2 JTAG_TDO_R    IO2 @BASEBOARD_FAB2_LIB.BASEBOARD_FAB2(SCH_1):JTAG_TDO_R
   3 JTAG_TDI_R    IO3 @BASEBOARD_FAB2_LIB.BASEBOARD_FAB2(SCH_1):JTAG_TDI_R
   4 JTAG_TRST_N    IO4 @BASEBOARD_FAB2_LIB.BASEBOARD_FAB2(SCH_1):JTAG_TRST_N
   5 PWRGD_P3V3_STBY    IO5 @BASEBOARD_FAB2_LIB.BASEBOARD_FAB2(SCH_1):PWRGD_P3V3_STBY
   6 JTAG_TMS_R    IO6 @BASEBOARD_FAB2_LIB.BASEBOARD_FAB2(SCH_1):JTAG_TMS_R
   7    GND    IO7 @BASEBOARD_FAB2_LIB.BASEBOARD_FAB2(SCH_1):GND
   8 JTAG_TCK_R    IO8 @BASEBOARD_FAB2_LIB.BASEBOARD_FAB2(SCH_1):JTAG_TCK_R

DIODE_SMLF-1N5819HW,IC,D55839-A  I49  CR3U1
   1 P3V3_STBY_PLD_D      C @BASEBOARD_FAB2_LIB.BASEBOARD_FAB2(SCH_1):P3V3_STBY_PLD_D
   2 P3V3_STBY      A @BASEBOARD_FAB2_LIB.BASEBOARD_FAB2(SCH_1):P3V3_STBY

RES_0402-10.0K,1%,1/16W,CHIP,GA  I50  R8G20
   1 P3V3_STBY      A @BASEBOARD_FAB2_LIB.BASEBOARD_FAB2(SCH_1):P3V3_STBY
   2 JTAG_TMS_R      B @BASEBOARD_FAB2_LIB.BASEBOARD_FAB2(SCH_1):JTAG_TMS_R

RES_0402-10.0K,1%,1/16W,CHIP,GA  I51  R7G23
   1 P3V3_STBY      A @BASEBOARD_FAB2_LIB.BASEBOARD_FAB2(SCH_1):P3V3_STBY
   2 JTAG_TDI_R      B @BASEBOARD_FAB2_LIB.BASEBOARD_FAB2(SCH_1):JTAG_TDI_R

RES_0402-10.0K,1%,1/16W,CHIP,GA  I53  R7G22
   1 P3V3_STBY      A @BASEBOARD_FAB2_LIB.BASEBOARD_FAB2(SCH_1):P3V3_STBY
   2 JTAG_TDO_R      B @BASEBOARD_FAB2_LIB.BASEBOARD_FAB2(SCH_1):JTAG_TDO_R

RES_0402-4.75K,1%,1/16W,CHIP,GA  I56  R8G23
   1 JTAG_TCK_R      A @BASEBOARD_FAB2_LIB.BASEBOARD_FAB2(SCH_1):JTAG_TCK_R
   2    GND      B @BASEBOARD_FAB2_LIB.BASEBOARD_FAB2(SCH_1):GND

RES_0402-0.0,5%,1/16W,CHIP,G21A  I63  R7G21
   1 JTAG_TDO      A @BASEBOARD_FAB2_LIB.BASEBOARD_FAB2(SCH_1):JTAG_TDO
   2 JTAG_TDO_R      B @BASEBOARD_FAB2_LIB.BASEBOARD_FAB2(SCH_1):JTAG_TDO_R

RES_0402-0.0,5%,1/16W,CHIP,G21A  I64  R8G19
   1 JTAG_TDI      A @BASEBOARD_FAB2_LIB.BASEBOARD_FAB2(SCH_1):JTAG_TDI
   2 JTAG_TDI_R      B @BASEBOARD_FAB2_LIB.BASEBOARD_FAB2(SCH_1):JTAG_TDI_R

RES_0402-0.0,5%,1/16W,CHIP,G21A  I65  R8G21
   1 JTAG_TMS      A @BASEBOARD_FAB2_LIB.BASEBOARD_FAB2(SCH_1):JTAG_TMS
   2 JTAG_TMS_R      B @BASEBOARD_FAB2_LIB.BASEBOARD_FAB2(SCH_1):JTAG_TMS_R

RES_0402-0.0,5%,1/16W,CHIP,G21A  I66  R8G22
   1 JTAG_TCK      A @BASEBOARD_FAB2_LIB.BASEBOARD_FAB2(SCH_1):JTAG_TCK
   2 JTAG_TCK_R      B @BASEBOARD_FAB2_LIB.BASEBOARD_FAB2(SCH_1):JTAG_TCK_R


DRAWING: @BASEBOARD_FAB2_LIB.BASEBOARD_FAB2(SCH_1):PAGE190 

RES_0402-0.0,5%,1/16W,CHIP,G21A  I116  R3P34
   1 RST_CPU0_LVC3_R1_N      A @BASEBOARD_FAB2_LIB.BASEBOARD_FAB2(SCH_1):RST_CPU0_LVC3_R1_N
   2 RST_CPU0_LVC3_N      B @BASEBOARD_FAB2_LIB.BASEBOARD_FAB2(SCH_1):RST_CPU0_LVC3_N

RES_0402-0.0,5%,1/16W,CHIP,G21A  I117  R3P35
   1 RST_CPU1_LVC3_R1_N      A @BASEBOARD_FAB2_LIB.BASEBOARD_FAB2(SCH_1):RST_CPU1_LVC3_R1_N
   2 RST_CPU1_LVC3_N      B @BASEBOARD_FAB2_LIB.BASEBOARD_FAB2(SCH_1):RST_CPU1_LVC3_N

LCMXO2_A_256BGA-IC,H63395-001  I179  U8D7
  P4 FM_CPU1_RC_EN   PB3A @BASEBOARD_FAB2_LIB.BASEBOARD_FAB2(SCH_1):FM_CPU1_RC_EN
  T4 PWRGD_PVSA_CPU1   PB3B @BASEBOARD_FAB2_LIB.BASEBOARD_FAB2(SCH_1):PWRGD_PVSA_CPU1
  T2 FM_ADR_MODE_SEL   PB3C @BASEBOARD_FAB2_LIB.BASEBOARD_FAB2(SCH_1):FM_ADR_MODE_SEL
  R3 FM_CPU0_RC_EN   PB3D @BASEBOARD_FAB2_LIB.BASEBOARD_FAB2(SCH_1):FM_CPU0_RC_EN
  R5 TP_CPLD1_PB5A_CSSPIN PB5A_CSSPIN @BASEBOARD_FAB2_LIB.BASEBOARD_FAB2(SCH_1):TP_CPLD1_PB5A_CSSPIN
  P5 PWRGD_PVCCMCP_CPU0   PB5B @BASEBOARD_FAB2_LIB.BASEBOARD_FAB2(SCH_1):PWRGD_PVCCMCP_CPU0
  T5 PWRGD_PVCCIOMCP_CPU1   PB6A @BASEBOARD_FAB2_LIB.BASEBOARD_FAB2(SCH_1):PWRGD_PVCCIOMCP_CPU1
  R6 RST_PCIE_M2_DEV_N   PB6B @BASEBOARD_FAB2_LIB.BASEBOARD_FAB2(SCH_1):RST_PCIE_M2_DEV_N
  T3 FM_DIS_ADR_DLY   PB6C @BASEBOARD_FAB2_LIB.BASEBOARD_FAB2(SCH_1):FM_DIS_ADR_DLY
  R4 FM_BMC_CPLD_MP_RST_N   PB6D @BASEBOARD_FAB2_LIB.BASEBOARD_FAB2(SCH_1):FM_BMC_CPLD_MP_RST_N
  P6 TP_CPLD1_PB8A_MCLK_CCLK PB8A_MCLK_CCLK @BASEBOARD_FAB2_LIB.BASEBOARD_FAB2(SCH_1):TP_CPLD1_PB8A_MCLK_CCLK
  T6 TP_CPLD1_PB8B_SO_SPISO PB8B_SO_SPISO @BASEBOARD_FAB2_LIB.BASEBOARD_FAB2(SCH_1):TP_CPLD1_PB8B_SO_SPISO
  N6 PWRGD_PVCCIOMCP_CPU0   PB8C @BASEBOARD_FAB2_LIB.BASEBOARD_FAB2(SCH_1):PWRGD_PVCCIOMCP_CPU0
  L7 TP_CPLD1_PB8D   PB8D @BASEBOARD_FAB2_LIB.BASEBOARD_FAB2(SCH_1):TP_CPLD1_PB8D
  R7 PWRGD_PVTT_CPU1   PB9A @BASEBOARD_FAB2_LIB.BASEBOARD_FAB2(SCH_1):PWRGD_PVTT_CPU1
  P7 FM_PVCCIOMCP_CPU1_EN   PB9B @BASEBOARD_FAB2_LIB.BASEBOARD_FAB2(SCH_1):FM_PVCCIOMCP_CPU1_EN
  M7 FM_PVCCIO_CPU0_EN   PB9C @BASEBOARD_FAB2_LIB.BASEBOARD_FAB2(SCH_1):FM_PVCCIO_CPU0_EN
  N7 PWRGD_PVPP_ABC   PB9D @BASEBOARD_FAB2_LIB.BASEBOARD_FAB2(SCH_1):PWRGD_PVPP_ABC
  T7 FM_PVCCIO_CPU1_EN PB11A_PCLKT2_0 @BASEBOARD_FAB2_LIB.BASEBOARD_FAB2(SCH_1):FM_PVCCIO_CPU1_EN
  R8 TP_CPLD1_PB11B_PCLKC2_0 PB11B_PCLKC2_0 @BASEBOARD_FAB2_LIB.BASEBOARD_FAB2(SCH_1):TP_CPLD1_PB11B_PCLKC2_0
  M6 PWRGD_PVPP_DEF  PB11C @BASEBOARD_FAB2_LIB.BASEBOARD_FAB2(SCH_1):PWRGD_PVPP_DEF
  L8 PWRGD_PVCCIO_CPU0  PB11D @BASEBOARD_FAB2_LIB.BASEBOARD_FAB2(SCH_1):PWRGD_PVCCIO_CPU0
  P8 PWRGD_PVNN_P1V05_PCH  PB12A @BASEBOARD_FAB2_LIB.BASEBOARD_FAB2(SCH_1):PWRGD_PVNN_P1V05_PCH
  T8 FM_CPLD_DBG_PWR_EN_N  PB12B @BASEBOARD_FAB2_LIB.BASEBOARD_FAB2(SCH_1):FM_CPLD_DBG_PWR_EN_N
  N8 FM_156M_CPU1_BRD_OSC_EN  PB12C @BASEBOARD_FAB2_LIB.BASEBOARD_FAB2(SCH_1):FM_156M_CPU1_BRD_OSC_EN
  L9 FM_IE_DISABLE_N  PB12D @BASEBOARD_FAB2_LIB.BASEBOARD_FAB2(SCH_1):FM_IE_DISABLE_N
  T9 TP_CPLD1_PB16A_PCLKT2_1 PB16A_PCLKT2_1 @BASEBOARD_FAB2_LIB.BASEBOARD_FAB2(SCH_1):TP_CPLD1_PB16A_PCLKT2_1
  P9 TP_CPLD1_PB16B_PCLKC2_1 PB16B_PCLKC2_1 @BASEBOARD_FAB2_LIB.BASEBOARD_FAB2(SCH_1):TP_CPLD1_PB16B_PCLKC2_1
  M8 FM_PVCCMCP_CPU1_EN  PB16C @BASEBOARD_FAB2_LIB.BASEBOARD_FAB2(SCH_1):FM_PVCCMCP_CPU1_EN
  N9 FM_CPLD_BMC_PWRDN_N  PB16D @BASEBOARD_FAB2_LIB.BASEBOARD_FAB2(SCH_1):FM_CPLD_BMC_PWRDN_N
  R9 FM_UARTSW_LSB_N  PB18A @BASEBOARD_FAB2_LIB.BASEBOARD_FAB2(SCH_1):FM_UARTSW_LSB_N
 T10 FM_156M_CPU0_BRD_OSC_EN  PB18B @BASEBOARD_FAB2_LIB.BASEBOARD_FAB2(SCH_1):FM_156M_CPU0_BRD_OSC_EN
  M9 FM_CPLD_UART_CH_LOCK_N  PB18C @BASEBOARD_FAB2_LIB.BASEBOARD_FAB2(SCH_1):FM_CPLD_UART_CH_LOCK_N
 L10 FM_SOL_UART_CH_SEL  PB18D @BASEBOARD_FAB2_LIB.BASEBOARD_FAB2(SCH_1):FM_SOL_UART_CH_SEL
 P10 RST_CD_CPU1_POR_N  PB19A @BASEBOARD_FAB2_LIB.BASEBOARD_FAB2(SCH_1):RST_CD_CPU1_POR_N
 R10 RST_CPU0_LVC3_R1_N  PB19B @BASEBOARD_FAB2_LIB.BASEBOARD_FAB2(SCH_1):RST_CPU0_LVC3_R1_N
 N10 RST_CPU1_LVC3_R1_N  PB19C @BASEBOARD_FAB2_LIB.BASEBOARD_FAB2(SCH_1):RST_CPU1_LVC3_R1_N
 M11 XDP_PWRGD_RST_N  PB19D @BASEBOARD_FAB2_LIB.BASEBOARD_FAB2(SCH_1):XDP_PWRGD_RST_N
 T11 FM_CPU1_PKGID2  PB21A @BASEBOARD_FAB2_LIB.BASEBOARD_FAB2(SCH_1):FM_CPU1_PKGID2
 P11 FM_UARTSW_MSB_N  PB21B @BASEBOARD_FAB2_LIB.BASEBOARD_FAB2(SCH_1):FM_UARTSW_MSB_N
 M10 PWRGD_CPU1_LVC3  PB21C @BASEBOARD_FAB2_LIB.BASEBOARD_FAB2(SCH_1):PWRGD_CPU1_LVC3
 N11 XDP_SYSPWROK  PB21D @BASEBOARD_FAB2_LIB.BASEBOARD_FAB2(SCH_1):XDP_SYSPWROK
 R11 FM_DB1200ZL_BCLKS_EN_N  PB22A @BASEBOARD_FAB2_LIB.BASEBOARD_FAB2(SCH_1):FM_DB1200ZL_BCLKS_EN_N
 T12 FM_CPU1_SKTOCC_LVT3_N  PB22B @BASEBOARD_FAB2_LIB.BASEBOARD_FAB2(SCH_1):FM_CPU1_SKTOCC_LVT3_N
 R13 FM_CPU0_VRM_OSC_EN  PB22C @BASEBOARD_FAB2_LIB.BASEBOARD_FAB2(SCH_1):FM_CPU0_VRM_OSC_EN
 T14 FM_CPU0_SKTOCC_LVT3_N  PB22D @BASEBOARD_FAB2_LIB.BASEBOARD_FAB2(SCH_1):FM_CPU0_SKTOCC_LVT3_N
 P12 FM_CPU1_PKGID1  PB24A @BASEBOARD_FAB2_LIB.BASEBOARD_FAB2(SCH_1):FM_CPU1_PKGID1
 T13 FM_CPU_MSMI_LVT3_N  PB24B @BASEBOARD_FAB2_LIB.BASEBOARD_FAB2(SCH_1):FM_CPU_MSMI_LVT3_N
 R12 FM_CPU1_PKGID0 PB25A_SN @BASEBOARD_FAB2_LIB.BASEBOARD_FAB2(SCH_1):FM_CPU1_PKGID0
 P13 TP_CPLD1_PB25B_SI_SISPI PB25B_SI_SISPI @BASEBOARD_FAB2_LIB.BASEBOARD_FAB2(SCH_1):TP_CPLD1_PB25B_SI_SISPI
 T15 PWRGD_DRAMPWRGD  PB25C @BASEBOARD_FAB2_LIB.BASEBOARD_FAB2(SCH_1):PWRGD_DRAMPWRGD
 R14 FM_CPU_CATERR_LVT3_N  PB25D @BASEBOARD_FAB2_LIB.BASEBOARD_FAB2(SCH_1):FM_CPU_CATERR_LVT3_N
  D3 TP_CPLD1_PL1A_L_GPLLT_FB PL1A_L_GPLLT_FB @BASEBOARD_FAB2_LIB.BASEBOARD_FAB2(SCH_1):TP_CPLD1_PL1A_L_GPLLT_FB
  D1 TP_CPLD1_PL1B_L_GPLLC_FB PL1B_L_GPLLC_FB @BASEBOARD_FAB2_LIB.BASEBOARD_FAB2(SCH_1):TP_CPLD1_PL1B_L_GPLLC_FB
  B1 RST_PCIE_PCH_PERST_N   PL1C @BASEBOARD_FAB2_LIB.BASEBOARD_FAB2(SCH_1):RST_PCIE_PCH_PERST_N
  C2 FM_PCH_PLD_DATA   PL1D @BASEBOARD_FAB2_LIB.BASEBOARD_FAB2(SCH_1):FM_PCH_PLD_DATA
  E2 FM_CPU_CATERR_DLY_LVT3_N PL2A_L_GPLLT_IN @BASEBOARD_FAB2_LIB.BASEBOARD_FAB2(SCH_1):FM_CPU_CATERR_DLY_LVT3_N
  E3 TP_CPLD1_PL2B_L_GPLLC_IN PL2B_L_GPLLC_IN @BASEBOARD_FAB2_LIB.BASEBOARD_FAB2(SCH_1):TP_CPLD1_PL2B_L_GPLLC_IN
  C1 RST_PCIE_CPU_DEV1_N   PL2C @BASEBOARD_FAB2_LIB.BASEBOARD_FAB2(SCH_1):RST_PCIE_CPU_DEV1_N
  D2 FM_MEM_EVENT_FUNC   PL2D @BASEBOARD_FAB2_LIB.BASEBOARD_FAB2(SCH_1):FM_MEM_EVENT_FUNC
  E1 CLK_32K_SUSCLK_PLD PL3A_PCLKT5_0 @BASEBOARD_FAB2_LIB.BASEBOARD_FAB2(SCH_1):CLK_32K_SUSCLK_PLD
  F2 FM_CPU0_PKGID0 PL3B_PCLKC5_0 @BASEBOARD_FAB2_LIB.BASEBOARD_FAB2(SCH_1):FM_CPU0_PKGID0
  F4 PU_RST_PERST_BIT0   PL3C @BASEBOARD_FAB2_LIB.BASEBOARD_FAB2(SCH_1):PU_RST_PERST_BIT0
  G6 FM_PWR_BTN_N   PL3D @BASEBOARD_FAB2_LIB.BASEBOARD_FAB2(SCH_1):FM_PWR_BTN_N
  F3 FM_CPU0_PROC_ID1   PL4A @BASEBOARD_FAB2_LIB.BASEBOARD_FAB2(SCH_1):FM_CPU0_PROC_ID1
  F1 FM_CPU0_PROC_ID0   PL4B @BASEBOARD_FAB2_LIB.BASEBOARD_FAB2(SCH_1):FM_CPU0_PROC_ID0
  G5 FM_DEBUG_RST_BTN_N   PL4C @BASEBOARD_FAB2_LIB.BASEBOARD_FAB2(SCH_1):FM_DEBUG_RST_BTN_N
  G4 RST_RSMRST_R_N   PL4D @BASEBOARD_FAB2_LIB.BASEBOARD_FAB2(SCH_1):RST_RSMRST_R_N
  G2 FM_CPU0_PKGID2   PL5A @BASEBOARD_FAB2_LIB.BASEBOARD_FAB2(SCH_1):FM_CPU0_PKGID2
  G3 FM_CPU0_PKGID1   PL5B @BASEBOARD_FAB2_LIB.BASEBOARD_FAB2(SCH_1):FM_CPU0_PKGID1
  F5 FM_CPU0_FIVR_FAULT_LVT3_N   PL5C @BASEBOARD_FAB2_LIB.BASEBOARD_FAB2(SCH_1):FM_CPU0_FIVR_FAULT_LVT3_N
  H6 PWRGD_P3V3   PL5D @BASEBOARD_FAB2_LIB.BASEBOARD_FAB2(SCH_1):PWRGD_P3V3
  G1 FM_SLPS3_N   PL6A @BASEBOARD_FAB2_LIB.BASEBOARD_FAB2(SCH_1):FM_SLPS3_N
  H2 FM_PVCCMCP_CPU0_EN   PL6B @BASEBOARD_FAB2_LIB.BASEBOARD_FAB2(SCH_1):FM_PVCCMCP_CPU0_EN
  H4 FM_MP_PS_FAIL_N   PL6C @BASEBOARD_FAB2_LIB.BASEBOARD_FAB2(SCH_1):FM_MP_PS_FAIL_N
  J6 PWRGD_P5V   PL6D @BASEBOARD_FAB2_LIB.BASEBOARD_FAB2(SCH_1):PWRGD_P5V
  H3 RST_PCIE_CPU_DEV2_N   PL7A @BASEBOARD_FAB2_LIB.BASEBOARD_FAB2(SCH_1):RST_PCIE_CPU_DEV2_N
  H1 RST_PCIE_CPU_DEV3_N   PL7B @BASEBOARD_FAB2_LIB.BASEBOARD_FAB2(SCH_1):RST_PCIE_CPU_DEV3_N
  J1 SGPIO_BMC_CLK PL7C_PCLKT4_0 @BASEBOARD_FAB2_LIB.BASEBOARD_FAB2(SCH_1):SGPIO_BMC_CLK
  J3 TP_CPLD1_PL7D_PCLKT4_0 PL7D_PCLKC4_0 @BASEBOARD_FAB2_LIB.BASEBOARD_FAB2(SCH_1):TP_CPLD1_PL7D_PCLKT4_0
  J2 SGPIO_BMC_DOUT   PL9A @BASEBOARD_FAB2_LIB.BASEBOARD_FAB2(SCH_1):SGPIO_BMC_DOUT
  K1 FM_PVCCIOMCP_CPU0_EN   PL9B @BASEBOARD_FAB2_LIB.BASEBOARD_FAB2(SCH_1):FM_PVCCIOMCP_CPU0_EN
  H5 SMB_SLOTX24_PCH_STBY_LVC3_SCL   PL9C @BASEBOARD_FAB2_LIB.BASEBOARD_FAB2(SCH_1):SMB_SLOTX24_PCH_STBY_LVC3_SCL
  J4 SMB_SLOTX24_PCH_STBY_LVC3_SDA   PL9D @BASEBOARD_FAB2_LIB.BASEBOARD_FAB2(SCH_1):SMB_SLOTX24_PCH_STBY_LVC3_SDA
  K3 SP1_BMC_HOST_UART_RX  PL10A @BASEBOARD_FAB2_LIB.BASEBOARD_FAB2(SCH_1):SP1_BMC_HOST_UART_RX
  K2 SP1_BMC_HOST_UART_TX  PL10B @BASEBOARD_FAB2_LIB.BASEBOARD_FAB2(SCH_1):SP1_BMC_HOST_UART_TX
  J5 UART_BMC_RXD5  PL10C @BASEBOARD_FAB2_LIB.BASEBOARD_FAB2(SCH_1):UART_BMC_RXD5
  K6 UART_BMC_TXD5  PL10D @BASEBOARD_FAB2_LIB.BASEBOARD_FAB2(SCH_1):UART_BMC_TXD5
  L1 PWRGD_PVSA_CPU0  PL11A @BASEBOARD_FAB2_LIB.BASEBOARD_FAB2(SCH_1):PWRGD_PVSA_CPU0
  L3 TP_CPLD1_PL11A  PL11B @BASEBOARD_FAB2_LIB.BASEBOARD_FAB2(SCH_1):TP_CPLD1_PL11A
  K4 SGPIO_BMC_LD_N  PL11C @BASEBOARD_FAB2_LIB.BASEBOARD_FAB2(SCH_1):SGPIO_BMC_LD_N
  L5 PWRGD_CPU0_LVC3  PL11D @BASEBOARD_FAB2_LIB.BASEBOARD_FAB2(SCH_1):PWRGD_CPU0_LVC3
  L2 CLK_25M_CPLD PL12A_PCLKT3_0 @BASEBOARD_FAB2_LIB.BASEBOARD_FAB2(SCH_1):CLK_25M_CPLD
  M1 RST_RSMRST_DLY PL12B_PCLKC3_0 @BASEBOARD_FAB2_LIB.BASEBOARD_FAB2(SCH_1):RST_RSMRST_DLY
  K5 PWRGD_PVCCIN_CPU0  PL12C @BASEBOARD_FAB2_LIB.BASEBOARD_FAB2(SCH_1):PWRGD_PVCCIN_CPU0
  L4 PWRGD_PVCCMCP_CPU1  PL12D @BASEBOARD_FAB2_LIB.BASEBOARD_FAB2(SCH_1):PWRGD_PVCCMCP_CPU1
  M3 RST_PCIE_RISER1_PERST_N  PL13A @BASEBOARD_FAB2_LIB.BASEBOARD_FAB2(SCH_1):RST_PCIE_RISER1_PERST_N
  N1 PWRGD_PVCCIN_CPU1  PL13B @BASEBOARD_FAB2_LIB.BASEBOARD_FAB2(SCH_1):PWRGD_PVCCIN_CPU1
  N2 PWRGD_PVPP_KLM  PL13C @BASEBOARD_FAB2_LIB.BASEBOARD_FAB2(SCH_1):PWRGD_PVPP_KLM
  P1 FM_GLOBAL_RST_WARN_N  PL13D @BASEBOARD_FAB2_LIB.BASEBOARD_FAB2(SCH_1):FM_GLOBAL_RST_WARN_N
  M2 PWRGD_PVPP_GHJ  PL14A @BASEBOARD_FAB2_LIB.BASEBOARD_FAB2(SCH_1):PWRGD_PVPP_GHJ
  N3 RST_CD_CPU0_POR_N  PL14B @BASEBOARD_FAB2_LIB.BASEBOARD_FAB2(SCH_1):RST_CD_CPU0_POR_N
  R1 FM_BMC_CPLD_GPO  PL14C @BASEBOARD_FAB2_LIB.BASEBOARD_FAB2(SCH_1):FM_BMC_CPLD_GPO
  P2 FM_UART_ALERT_N  PL14D @BASEBOARD_FAB2_LIB.BASEBOARD_FAB2(SCH_1):FM_UART_ALERT_N

RES_0402-33.2,1%,1/16W,CHIP,G2A  I338  R2R2
   1 RST_RSMRST_R_N      A @BASEBOARD_FAB2_LIB.BASEBOARD_FAB2(SCH_1):RST_RSMRST_R_N
   2 RST_RSMRST_N      B @BASEBOARD_FAB2_LIB.BASEBOARD_FAB2(SCH_1):RST_RSMRST_N


DRAWING: @BASEBOARD_FAB2_LIB.BASEBOARD_FAB2(SCH_1):PAGE191 

LCMXO2_A_256BGA-IC,H63395-001  I59  U8D7
 D14 PWRGD_SYS_PWROK   PR1A @BASEBOARD_FAB2_LIB.BASEBOARD_FAB2(SCH_1):PWRGD_SYS_PWROK
 E15 RST_PLTRST_N   PR1B @BASEBOARD_FAB2_LIB.BASEBOARD_FAB2(SCH_1):RST_PLTRST_N
 C15 FM_DB1200_PWRGD   PR1C @BASEBOARD_FAB2_LIB.BASEBOARD_FAB2(SCH_1):FM_DB1200_PWRGD
 B16 FM_ADR_COMPLETE_DLY   PR1D @BASEBOARD_FAB2_LIB.BASEBOARD_FAB2(SCH_1):FM_ADR_COMPLETE_DLY
 D16 PWRGD_P1V8MCP_CPU1   PR2A @BASEBOARD_FAB2_LIB.BASEBOARD_FAB2(SCH_1):PWRGD_P1V8MCP_CPU1
 E14 FM_CPLD_ADR_TRIGGER_N   PR2B @BASEBOARD_FAB2_LIB.BASEBOARD_FAB2(SCH_1):FM_CPLD_ADR_TRIGGER_N
 C16 PWRGD_PCH_PWROK   PR2C @BASEBOARD_FAB2_LIB.BASEBOARD_FAB2(SCH_1):PWRGD_PCH_PWROK
 D15 PWRGD_P1V8MCP_CPU0   PR2D @BASEBOARD_FAB2_LIB.BASEBOARD_FAB2(SCH_1):PWRGD_P1V8MCP_CPU0
 E16 FM_P1V8MCP_CPU0_EN   PR3A @BASEBOARD_FAB2_LIB.BASEBOARD_FAB2(SCH_1):FM_P1V8MCP_CPU0_EN
 F15 FM_CPU0_MCP_CLK_EN_N   PR3B @BASEBOARD_FAB2_LIB.BASEBOARD_FAB2(SCH_1):FM_CPU0_MCP_CLK_EN_N
 F13 PWRGD_CPUPWRGD   PR3C @BASEBOARD_FAB2_LIB.BASEBOARD_FAB2(SCH_1):PWRGD_CPUPWRGD
 G12 FM_CPU0_THERMTRIP_LATCH_LVT3_N   PR3D @BASEBOARD_FAB2_LIB.BASEBOARD_FAB2(SCH_1):FM_CPU0_THERMTRIP_LATCH_LVT3_N
 F14 RST_BMC_SYSRST_BTN_OUT_B_N   PR4A @BASEBOARD_FAB2_LIB.BASEBOARD_FAB2(SCH_1):RST_BMC_SYSRST_BTN_OUT_B_N
 F16 FM_CPU1_MCP_CLK_EN_N   PR4B @BASEBOARD_FAB2_LIB.BASEBOARD_FAB2(SCH_1):FM_CPU1_MCP_CLK_EN_N
 F12 FM_P1V8MCP_CPU1_EN   PR4C @BASEBOARD_FAB2_LIB.BASEBOARD_FAB2(SCH_1):FM_P1V8MCP_CPU1_EN
 G13 FM_CPU1_FIVR_FAULT_LVT3   PR4D @BASEBOARD_FAB2_LIB.BASEBOARD_FAB2(SCH_1):FM_CPU1_FIVR_FAULT_LVT3
 G15 FM_UV_ADR_TRIGGER_N   PR5A @BASEBOARD_FAB2_LIB.BASEBOARD_FAB2(SCH_1):FM_UV_ADR_TRIGGER_N
 G14 FM_CPU1_THERMTRIP_LVT3_N   PR5B @BASEBOARD_FAB2_LIB.BASEBOARD_FAB2(SCH_1):FM_CPU1_THERMTRIP_LVT3_N
 G11 FM_WBG_PRSNT_N   PR5C @BASEBOARD_FAB2_LIB.BASEBOARD_FAB2(SCH_1):FM_WBG_PRSNT_N
 H12 FM_UV_ADR_TRIGGER_EN   PR5D @BASEBOARD_FAB2_LIB.BASEBOARD_FAB2(SCH_1):FM_UV_ADR_TRIGGER_EN
 G16 FM_FAST_PROCHOT_THROTTLE_IN_N   PR6A @BASEBOARD_FAB2_LIB.BASEBOARD_FAB2(SCH_1):FM_FAST_PROCHOT_THROTTLE_IN_N
 H15 FM_PVDDQ_KLM_EN   PR6B @BASEBOARD_FAB2_LIB.BASEBOARD_FAB2(SCH_1):FM_PVDDQ_KLM_EN
 H13 FM_PVDDQ_GHJ_EN   PR6C @BASEBOARD_FAB2_LIB.BASEBOARD_FAB2(SCH_1):FM_PVDDQ_GHJ_EN
 J12 FM_FAST_PROCHOT_THROTTLE_DLY_N   PR6D @BASEBOARD_FAB2_LIB.BASEBOARD_FAB2(SCH_1):FM_FAST_PROCHOT_THROTTLE_DLY_N
 H14 TP_CPLD1_PR7A_PCLKT1_0 PR7A_PCLKT1_0 @BASEBOARD_FAB2_LIB.BASEBOARD_FAB2(SCH_1):TP_CPLD1_PR7A_PCLKT1_0
 H16 TP_CPLD1_PR7B_PCLKC1_0 PR7B_PCLKC1_0 @BASEBOARD_FAB2_LIB.BASEBOARD_FAB2(SCH_1):TP_CPLD1_PR7B_PCLKC1_0
 J16 TP_CPLD1_PR7C   PR7C @BASEBOARD_FAB2_LIB.BASEBOARD_FAB2(SCH_1):TP_CPLD1_PR7C
 J14 TP_CPLD1_PR7D   PR7D @BASEBOARD_FAB2_LIB.BASEBOARD_FAB2(SCH_1):TP_CPLD1_PR7D
 J15 TP_CPLD1_PR9A   PR9A @BASEBOARD_FAB2_LIB.BASEBOARD_FAB2(SCH_1):TP_CPLD1_PR9A
 K16 PU_FAB2_MARKER_CPLD   PR9B @BASEBOARD_FAB2_LIB.BASEBOARD_FAB2(SCH_1):PU_FAB2_MARKER_CPLD
 H11 TP_CPLD1_PR9C   PR9C @BASEBOARD_FAB2_LIB.BASEBOARD_FAB2(SCH_1):TP_CPLD1_PR9C
 J13 TP_CPLD1_PR9D   PR9D @BASEBOARD_FAB2_LIB.BASEBOARD_FAB2(SCH_1):TP_CPLD1_PR9D
 K14 FM_PVDDQ_ABC_EN  PR10A @BASEBOARD_FAB2_LIB.BASEBOARD_FAB2(SCH_1):FM_PVDDQ_ABC_EN
 K15 FM_PVDDQ_DEF_EN  PR10B @BASEBOARD_FAB2_LIB.BASEBOARD_FAB2(SCH_1):FM_PVDDQ_DEF_EN
 J11 TP_CPLD1_PR10C  PR10C @BASEBOARD_FAB2_LIB.BASEBOARD_FAB2(SCH_1):TP_CPLD1_PR10C
 L12 PWRGD_P3V3_STBY  PR10D @BASEBOARD_FAB2_LIB.BASEBOARD_FAB2(SCH_1):PWRGD_P3V3_STBY
 L16 PWRGD_PVCCIO_CPU1  PR11A @BASEBOARD_FAB2_LIB.BASEBOARD_FAB2(SCH_1):PWRGD_PVCCIO_CPU1
 L14 TP_CPLD1_PR11B  PR11B @BASEBOARD_FAB2_LIB.BASEBOARD_FAB2(SCH_1):TP_CPLD1_PR11B
 K13 FM_MEM_THERM_EVENT_LVT3_N  PR11C @BASEBOARD_FAB2_LIB.BASEBOARD_FAB2(SCH_1):FM_MEM_THERM_EVENT_LVT3_N
 K12 FM_MEM_THERM_EVENT_PCH_N  PR11D @BASEBOARD_FAB2_LIB.BASEBOARD_FAB2(SCH_1):FM_MEM_THERM_EVENT_PCH_N
 L15 FM_THERMTRIP_DLY  PR12A @BASEBOARD_FAB2_LIB.BASEBOARD_FAB2(SCH_1):FM_THERMTRIP_DLY
 M16 FM_CPU0_FIVR_FAULT_LVT3  PR12B @BASEBOARD_FAB2_LIB.BASEBOARD_FAB2(SCH_1):FM_CPU0_FIVR_FAULT_LVT3
 K11 RST_PLTRST_BUF_N  PR12C @BASEBOARD_FAB2_LIB.BASEBOARD_FAB2(SCH_1):RST_PLTRST_BUF_N
 L13 TP_CPLD1_PR12D  PR12D @BASEBOARD_FAB2_LIB.BASEBOARD_FAB2(SCH_1):TP_CPLD1_PR12D
 M14 FM_CPU1_PROC_ID1  PR13A @BASEBOARD_FAB2_LIB.BASEBOARD_FAB2(SCH_1):FM_CPU1_PROC_ID1
 M15 FM_CPU1_PROC_ID0  PR13B @BASEBOARD_FAB2_LIB.BASEBOARD_FAB2(SCH_1):FM_CPU1_PROC_ID0
 N15 FM_CPU0_THERMTRIP_LVT3_N  PR13C @BASEBOARD_FAB2_LIB.BASEBOARD_FAB2(SCH_1):FM_CPU0_THERMTRIP_LVT3_N
 P16 FM_PVPP_CPU1_EN  PR13D @BASEBOARD_FAB2_LIB.BASEBOARD_FAB2(SCH_1):FM_PVPP_CPU1_EN
 N16 FM_PVCCIN_PVCCSA_CPU1_EN_LVC1  PR14A @BASEBOARD_FAB2_LIB.BASEBOARD_FAB2(SCH_1):FM_PVCCIN_PVCCSA_CPU1_EN_LVC1
 N14 FM_CPU1_VRM_OSC_EN  PR14B @BASEBOARD_FAB2_LIB.BASEBOARD_FAB2(SCH_1):FM_CPU1_VRM_OSC_EN
 P15 FM_PVPP_CPU0_EN  PR14C @BASEBOARD_FAB2_LIB.BASEBOARD_FAB2(SCH_1):FM_PVPP_CPU0_EN
 R16 FM_P12V_MAIN_SW_EN  PR14D @BASEBOARD_FAB2_LIB.BASEBOARD_FAB2(SCH_1):FM_P12V_MAIN_SW_EN
  C4 FM_ADR_SMI_GPIO_R_N   PT9A @BASEBOARD_FAB2_LIB.BASEBOARD_FAB2(SCH_1):FM_ADR_SMI_GPIO_R_N
  B5 PWRGD_P12V_MAIN   PT9B @BASEBOARD_FAB2_LIB.BASEBOARD_FAB2(SCH_1):PWRGD_P12V_MAIN
  B3 FM_CTNR_PS_ON   PT9C @BASEBOARD_FAB2_LIB.BASEBOARD_FAB2(SCH_1):FM_CTNR_PS_ON
  A4 FM_P3V3_CPLD_EN  PT10A @BASEBOARD_FAB2_LIB.BASEBOARD_FAB2(SCH_1):FM_P3V3_CPLD_EN
  C5 FM_CPU1_THERMTRIP_LATCH_LVT3_N  PT10B @BASEBOARD_FAB2_LIB.BASEBOARD_FAB2(SCH_1):FM_CPU1_THERMTRIP_LATCH_LVT3_N
  A5 TP_CPLD1_PT11A  PT11A @BASEBOARD_FAB2_LIB.BASEBOARD_FAB2(SCH_1):TP_CPLD1_PT11A
  B6 TP_CPLD1_PT11B  PT11B @BASEBOARD_FAB2_LIB.BASEBOARD_FAB2(SCH_1):TP_CPLD1_PT11B
  A3 FM_PCH_PRSNT_N  PT11C @BASEBOARD_FAB2_LIB.BASEBOARD_FAB2(SCH_1):FM_PCH_PRSNT_N
  B4 PWRGD_PVTT_CPU0  PT11D @BASEBOARD_FAB2_LIB.BASEBOARD_FAB2(SCH_1):PWRGD_PVTT_CPU0
  D6 RST_PCIE_CPU_DEV0_N  PT12A @BASEBOARD_FAB2_LIB.BASEBOARD_FAB2(SCH_1):RST_PCIE_CPU_DEV0_N
  E7 PWRGD_P1V26_BMC_STBY  PT12B @BASEBOARD_FAB2_LIB.BASEBOARD_FAB2(SCH_1):PWRGD_P1V26_BMC_STBY
  C6 JTAG_PLD_TDO PT12C_TDO @BASEBOARD_FAB2_LIB.BASEBOARD_FAB2(SCH_1):JTAG_PLD_TDO
  A6 JTAG_PLD_TDI PT12D_TDI @BASEBOARD_FAB2_LIB.BASEBOARD_FAB2(SCH_1):JTAG_PLD_TDI
  B7 TP_CPLD1_PT13A  PT13A @BASEBOARD_FAB2_LIB.BASEBOARD_FAB2(SCH_1):TP_CPLD1_PT13A
  C7 FM_BMC_ONCTL_N  PT13B @BASEBOARD_FAB2_LIB.BASEBOARD_FAB2(SCH_1):FM_BMC_ONCTL_N
  E6 FM_CPU1_FIVR_FAULT_LVT3_N  PT13C @BASEBOARD_FAB2_LIB.BASEBOARD_FAB2(SCH_1):FM_CPU1_FIVR_FAULT_LVT3_N
  D7 FM_FORCE_ADR_N  PT13D @BASEBOARD_FAB2_LIB.BASEBOARD_FAB2(SCH_1):FM_FORCE_ADR_N
  F7 FM_PLD_DEBUG_MODE_N  PT16A @BASEBOARD_FAB2_LIB.BASEBOARD_FAB2(SCH_1):FM_PLD_DEBUG_MODE_N
  E8 TP_CPLD1_PT16B  PT16B @BASEBOARD_FAB2_LIB.BASEBOARD_FAB2(SCH_1):TP_CPLD1_PT16B
  A7 JTAG_PLD_TCK PT16C_TCK @BASEBOARD_FAB2_LIB.BASEBOARD_FAB2(SCH_1):JTAG_PLD_TCK
  B8 JTAG_PLD_TMS PT16D_TMS @BASEBOARD_FAB2_LIB.BASEBOARD_FAB2(SCH_1):JTAG_PLD_TMS
  C8 FM_ADR_COMPLETE PT17A_PCLKT0_1 @BASEBOARD_FAB2_LIB.BASEBOARD_FAB2(SCH_1):FM_ADR_COMPLETE
  A8 TP_CPLD1_PT17B_PCLKC0_1 PT17B_PCLKC0_1 @BASEBOARD_FAB2_LIB.BASEBOARD_FAB2(SCH_1):TP_CPLD1_PT17B_PCLKC0_1
  D8 TP_CPLD1_PT17C  PT17C @BASEBOARD_FAB2_LIB.BASEBOARD_FAB2(SCH_1):TP_CPLD1_PT17C
  E9 FM_SLP_SUS_N  PT17D @BASEBOARD_FAB2_LIB.BASEBOARD_FAB2(SCH_1):FM_SLP_SUS_N
  F8 SGPIO_BMC_DIN_R  PT18A @BASEBOARD_FAB2_LIB.BASEBOARD_FAB2(SCH_1):SGPIO_BMC_DIN_R
  D9 RST_PCIE_MIDPLANE_N  PT18B @BASEBOARD_FAB2_LIB.BASEBOARD_FAB2(SCH_1):RST_PCIE_MIDPLANE_N
  A9 SMB_SENSOR_STBY_LVC3_SCL PT18C_SCL_PCLKT0_0 @BASEBOARD_FAB2_LIB.BASEBOARD_FAB2(SCH_1):SMB_SENSOR_STBY_LVC3_SCL
  C9 SMB_SENSOR_STBY_LVC3_SDA PT18D_SDA_PCLKC0_0 @BASEBOARD_FAB2_LIB.BASEBOARD_FAB2(SCH_1):SMB_SENSOR_STBY_LVC3_SDA
  B9 PU_RST_PERST_BIT1  PT19A @BASEBOARD_FAB2_LIB.BASEBOARD_FAB2(SCH_1):PU_RST_PERST_BIT1
 A10 FM_PVCCIN_PVCCSA_CPU0_EN_LVC1  PT19B @BASEBOARD_FAB2_LIB.BASEBOARD_FAB2(SCH_1):FM_PVCCIN_PVCCSA_CPU0_EN_LVC1
  F9 FM_PS_EN  PT19C @BASEBOARD_FAB2_LIB.BASEBOARD_FAB2(SCH_1):FM_PS_EN
 E11 TP_CPLD1_PT19D  PT19D @BASEBOARD_FAB2_LIB.BASEBOARD_FAB2(SCH_1):TP_CPLD1_PT19D
 D10 TP_CPLD1_PT20A  PT20A @BASEBOARD_FAB2_LIB.BASEBOARD_FAB2(SCH_1):TP_CPLD1_PT20A
 E10 TP_CPLD1_PT20B  PT20B @BASEBOARD_FAB2_LIB.BASEBOARD_FAB2(SCH_1):TP_CPLD1_PT20B
 C10 FM_JTAG_PLD_EN_DEBUG PT20C_JTAGENB @BASEBOARD_FAB2_LIB.BASEBOARD_FAB2(SCH_1):FM_JTAG_PLD_EN_DEBUG
 B10 TP_CPLD1_PT20D_PROGRAMN PT20D_PROGRAMN @BASEBOARD_FAB2_LIB.BASEBOARD_FAB2(SCH_1):TP_CPLD1_PT20D_PROGRAMN
 A11 FM_CPU0_OR_CPU1_MCP_PRES  PT21A @BASEBOARD_FAB2_LIB.BASEBOARD_FAB2(SCH_1):FM_CPU0_OR_CPU1_MCP_PRES
 C11 FM_CPU0_CD_PRES  PT21B @BASEBOARD_FAB2_LIB.BASEBOARD_FAB2(SCH_1):FM_CPU0_CD_PRES
 F10 FM_CPU1_CD_PRES  PT21C @BASEBOARD_FAB2_LIB.BASEBOARD_FAB2(SCH_1):FM_CPU1_CD_PRES
 D11 FM_CPU0_AND_CPU1_MCP_PRES  PT21D @BASEBOARD_FAB2_LIB.BASEBOARD_FAB2(SCH_1):FM_CPU0_AND_CPU1_MCP_PRES
 B11 PWRGD_DSW_PWROK  PT22A @BASEBOARD_FAB2_LIB.BASEBOARD_FAB2(SCH_1):PWRGD_DSW_PWROK
 A12 PU_THERMTRIP_FORCE_N  PT22B @BASEBOARD_FAB2_LIB.BASEBOARD_FAB2(SCH_1):PU_THERMTRIP_FORCE_N
 B13 TP_CPLD1_PT22C  PT22C @BASEBOARD_FAB2_LIB.BASEBOARD_FAB2(SCH_1):TP_CPLD1_PT22C
 A14 TP_CPLD1_PT22D  PT22D @BASEBOARD_FAB2_LIB.BASEBOARD_FAB2(SCH_1):TP_CPLD1_PT22D
 C12 FM_SLPS4_N  PT23A @BASEBOARD_FAB2_LIB.BASEBOARD_FAB2(SCH_1):FM_SLPS4_N
 B12 FM_PCH_PWRBTN_N  PT23B @BASEBOARD_FAB2_LIB.BASEBOARD_FAB2(SCH_1):FM_PCH_PWRBTN_N
 B14 FM_SINT_PRSNT_N  PT24A @BASEBOARD_FAB2_LIB.BASEBOARD_FAB2(SCH_1):FM_SINT_PRSNT_N
 A15 TP_CPLD1_PT24B  PT24B @BASEBOARD_FAB2_LIB.BASEBOARD_FAB2(SCH_1):TP_CPLD1_PT24B
 A13 TP_CPLD1_PT24C_INITN PT24C_INITN @BASEBOARD_FAB2_LIB.BASEBOARD_FAB2(SCH_1):TP_CPLD1_PT24C_INITN
 C13 TP_CPLD1_PT24D_DONE PT24D_DONE @BASEBOARD_FAB2_LIB.BASEBOARD_FAB2(SCH_1):TP_CPLD1_PT24D_DONE

RES_0402-51,5.0%,1/16W,CHIP,G2A  I166  R2R6
   1 SGPIO_BMC_DIN_R      A @BASEBOARD_FAB2_LIB.BASEBOARD_FAB2(SCH_1):SGPIO_BMC_DIN_R
   2 SGPIO_BMC_DIN      B @BASEBOARD_FAB2_LIB.BASEBOARD_FAB2(SCH_1):SGPIO_BMC_DIN

RES_0402-4.75K,1%,1/16W,CHIP,GA  I172  R2R7
   1 P3V3_STBY      A @BASEBOARD_FAB2_LIB.BASEBOARD_FAB2(SCH_1):P3V3_STBY
   2 FM_FORCE_ADR_N      B @BASEBOARD_FAB2_LIB.BASEBOARD_FAB2(SCH_1):FM_FORCE_ADR_N

RES_0402-0.0,5%,1/16W,CHIP,G21A  I184  R2R4
   1 FM_ADR_SMI_GPIO_R_N      A @BASEBOARD_FAB2_LIB.BASEBOARD_FAB2(SCH_1):FM_ADR_SMI_GPIO_R_N
   2 FM_ADR_SMI_GPIO_N      B @BASEBOARD_FAB2_LIB.BASEBOARD_FAB2(SCH_1):FM_ADR_SMI_GPIO_N

RES_0402-4.75K,1%,1/16W,CHIP,GA  I193  R7D42
   1 P3V3_STBY      A @BASEBOARD_FAB2_LIB.BASEBOARD_FAB2(SCH_1):P3V3_STBY
   2 PU_FAB2_MARKER_CPLD      B @BASEBOARD_FAB2_LIB.BASEBOARD_FAB2(SCH_1):PU_FAB2_MARKER_CPLD


DRAWING: @BASEBOARD_FAB2_LIB.BASEBOARD_FAB2(SCH_1):PAGE192 

CAP_A_0402V-0.01UF,25V,10%,X7RA  I1  C2P8
   1 P3V3_STBY      A @BASEBOARD_FAB2_LIB.BASEBOARD_FAB2(SCH_1):P3V3_STBY
   2    GND      B @BASEBOARD_FAB2_LIB.BASEBOARD_FAB2(SCH_1):GND

CAP_A_0402V-0.1UF,16V,10%,X7R,A  I3  C2P5
   1 P3V3_STBY      A @BASEBOARD_FAB2_LIB.BASEBOARD_FAB2(SCH_1):P3V3_STBY
   2    GND      B @BASEBOARD_FAB2_LIB.BASEBOARD_FAB2(SCH_1):GND

CAP_A_0402V-0.1UF,16V,10%,X7R,A  I4  C3R1
   1 P3V3_STBY      A @BASEBOARD_FAB2_LIB.BASEBOARD_FAB2(SCH_1):P3V3_STBY
   2    GND      B @BASEBOARD_FAB2_LIB.BASEBOARD_FAB2(SCH_1):GND

CAP_A_0402V-0.1UF,16V,10%,X7R,A  I6  C3P43
   1 P3V3_STBY      A @BASEBOARD_FAB2_LIB.BASEBOARD_FAB2(SCH_1):P3V3_STBY
   2    GND      B @BASEBOARD_FAB2_LIB.BASEBOARD_FAB2(SCH_1):GND

CAP_A_0402V-0.1UF,16V,10%,X7R,A  I7  C3R3
   1 P3V3_STBY      A @BASEBOARD_FAB2_LIB.BASEBOARD_FAB2(SCH_1):P3V3_STBY
   2    GND      B @BASEBOARD_FAB2_LIB.BASEBOARD_FAB2(SCH_1):GND

CAP_A_0402V-0.1UF,16V,10%,X7R,A  I8  C2R1
   1 P3V3_STBY      A @BASEBOARD_FAB2_LIB.BASEBOARD_FAB2(SCH_1):P3V3_STBY
   2    GND      B @BASEBOARD_FAB2_LIB.BASEBOARD_FAB2(SCH_1):GND

CAP_A_0402V-0.1UF,16V,10%,X7R,A  I9  C2P2
   1 P3V3_STBY      A @BASEBOARD_FAB2_LIB.BASEBOARD_FAB2(SCH_1):P3V3_STBY
   2    GND      B @BASEBOARD_FAB2_LIB.BASEBOARD_FAB2(SCH_1):GND

CAP_A_0402V-0.1UF,16V,10%,X7R,A  I10  C3R2
   1 P3V3_STBY      A @BASEBOARD_FAB2_LIB.BASEBOARD_FAB2(SCH_1):P3V3_STBY
   2    GND      B @BASEBOARD_FAB2_LIB.BASEBOARD_FAB2(SCH_1):GND

CAP_A_0402V-0.1UF,16V,10%,X7R,A  I11  C3P51
   1 P3V3_STBY      A @BASEBOARD_FAB2_LIB.BASEBOARD_FAB2(SCH_1):P3V3_STBY
   2    GND      B @BASEBOARD_FAB2_LIB.BASEBOARD_FAB2(SCH_1):GND

CAP_A_0402V-0.1UF,16V,10%,X7R,A  I12  C3P47
   1 P3V3_STBY      A @BASEBOARD_FAB2_LIB.BASEBOARD_FAB2(SCH_1):P3V3_STBY
   2    GND      B @BASEBOARD_FAB2_LIB.BASEBOARD_FAB2(SCH_1):GND

LCMXO2_A_256BGA-IC,H63395-001  I14  U8D7
  B2    GND GND<0> @BASEBOARD_FAB2_LIB.BASEBOARD_FAB2(SCH_1):GND
 B15    GND GND<1> @BASEBOARD_FAB2_LIB.BASEBOARD_FAB2(SCH_1):GND
  C3    GND GND<2> @BASEBOARD_FAB2_LIB.BASEBOARD_FAB2(SCH_1):GND
 C14    GND GND<3> @BASEBOARD_FAB2_LIB.BASEBOARD_FAB2(SCH_1):GND
  D4    GND GND<4> @BASEBOARD_FAB2_LIB.BASEBOARD_FAB2(SCH_1):GND
 D13    GND GND<5> @BASEBOARD_FAB2_LIB.BASEBOARD_FAB2(SCH_1):GND
  E5    GND GND<6> @BASEBOARD_FAB2_LIB.BASEBOARD_FAB2(SCH_1):GND
 E12    GND GND<7> @BASEBOARD_FAB2_LIB.BASEBOARD_FAB2(SCH_1):GND
  F6    GND GND<8> @BASEBOARD_FAB2_LIB.BASEBOARD_FAB2(SCH_1):GND
 F11    GND GND<9> @BASEBOARD_FAB2_LIB.BASEBOARD_FAB2(SCH_1):GND
  H8    GND GND<10> @BASEBOARD_FAB2_LIB.BASEBOARD_FAB2(SCH_1):GND
  H9    GND GND<11> @BASEBOARD_FAB2_LIB.BASEBOARD_FAB2(SCH_1):GND
  J8    GND GND<12> @BASEBOARD_FAB2_LIB.BASEBOARD_FAB2(SCH_1):GND
  J9    GND GND<13> @BASEBOARD_FAB2_LIB.BASEBOARD_FAB2(SCH_1):GND
  L6    GND GND<14> @BASEBOARD_FAB2_LIB.BASEBOARD_FAB2(SCH_1):GND
 L11    GND GND<15> @BASEBOARD_FAB2_LIB.BASEBOARD_FAB2(SCH_1):GND
  M5    GND GND<16> @BASEBOARD_FAB2_LIB.BASEBOARD_FAB2(SCH_1):GND
 M12    GND GND<17> @BASEBOARD_FAB2_LIB.BASEBOARD_FAB2(SCH_1):GND
  N4    GND GND<18> @BASEBOARD_FAB2_LIB.BASEBOARD_FAB2(SCH_1):GND
 N13    GND GND<19> @BASEBOARD_FAB2_LIB.BASEBOARD_FAB2(SCH_1):GND
  P3    GND GND<20> @BASEBOARD_FAB2_LIB.BASEBOARD_FAB2(SCH_1):GND
 P14    GND GND<21> @BASEBOARD_FAB2_LIB.BASEBOARD_FAB2(SCH_1):GND
  R2    GND GND<22> @BASEBOARD_FAB2_LIB.BASEBOARD_FAB2(SCH_1):GND
 R15    GND GND<23> @BASEBOARD_FAB2_LIB.BASEBOARD_FAB2(SCH_1):GND
  A1 P3V3_STBY VCC<0> @BASEBOARD_FAB2_LIB.BASEBOARD_FAB2(SCH_1):P3V3_STBY
 A16 P3V3_STBY VCC<1> @BASEBOARD_FAB2_LIB.BASEBOARD_FAB2(SCH_1):P3V3_STBY
  T1 P3V3_STBY VCC<2> @BASEBOARD_FAB2_LIB.BASEBOARD_FAB2(SCH_1):P3V3_STBY
 T16 P3V3_STBY VCC<3> @BASEBOARD_FAB2_LIB.BASEBOARD_FAB2(SCH_1):P3V3_STBY
  G7 P3V3_STBY VCC<4> @BASEBOARD_FAB2_LIB.BASEBOARD_FAB2(SCH_1):P3V3_STBY
 G10 P3V3_STBY VCC<5> @BASEBOARD_FAB2_LIB.BASEBOARD_FAB2(SCH_1):P3V3_STBY
  K7 P3V3_STBY VCC<6> @BASEBOARD_FAB2_LIB.BASEBOARD_FAB2(SCH_1):P3V3_STBY
 K10 P3V3_STBY VCC<7> @BASEBOARD_FAB2_LIB.BASEBOARD_FAB2(SCH_1):P3V3_STBY
  G8 P3V3_STBY VCCIO0<0> @BASEBOARD_FAB2_LIB.BASEBOARD_FAB2(SCH_1):P3V3_STBY
 D12 P3V3_STBY VCCIO0<1> @BASEBOARD_FAB2_LIB.BASEBOARD_FAB2(SCH_1):P3V3_STBY
  G9 P3V3_STBY VCCIO0<2> @BASEBOARD_FAB2_LIB.BASEBOARD_FAB2(SCH_1):P3V3_STBY
 E13 P3V3_STBY VCCIO1<0> @BASEBOARD_FAB2_LIB.BASEBOARD_FAB2(SCH_1):P3V3_STBY
 H10 P3V3_STBY VCCIO1<1> @BASEBOARD_FAB2_LIB.BASEBOARD_FAB2(SCH_1):P3V3_STBY
 J10 P3V3_STBY VCCIO1<2> @BASEBOARD_FAB2_LIB.BASEBOARD_FAB2(SCH_1):P3V3_STBY
 M13 P3V3_STBY VCCIO1<3> @BASEBOARD_FAB2_LIB.BASEBOARD_FAB2(SCH_1):P3V3_STBY
  K9 P3V3_STBY VCCIO2<0> @BASEBOARD_FAB2_LIB.BASEBOARD_FAB2(SCH_1):P3V3_STBY
 N12 P3V3_STBY VCCIO2<1> @BASEBOARD_FAB2_LIB.BASEBOARD_FAB2(SCH_1):P3V3_STBY
  K8 P3V3_STBY VCCIO2<2> @BASEBOARD_FAB2_LIB.BASEBOARD_FAB2(SCH_1):P3V3_STBY
  N5 P3V3_STBY VCCIO2<3> @BASEBOARD_FAB2_LIB.BASEBOARD_FAB2(SCH_1):P3V3_STBY
  J7 P3V3_STBY VCCIO4<0> @BASEBOARD_FAB2_LIB.BASEBOARD_FAB2(SCH_1):P3V3_STBY
  H7 P3V3_STBY VCCIO4<1> @BASEBOARD_FAB2_LIB.BASEBOARD_FAB2(SCH_1):P3V3_STBY
  E4 P3V3_STBY VCCIO5<0> @BASEBOARD_FAB2_LIB.BASEBOARD_FAB2(SCH_1):P3V3_STBY
  D5 P3V3_STBY VCCIO0<3> @BASEBOARD_FAB2_LIB.BASEBOARD_FAB2(SCH_1):P3V3_STBY
  A2 NC_CPLD1  NC<0> @BASEBOARD_FAB2_LIB.BASEBOARD_FAB2(SCH_1):NC_CPLD1
  M4 P3V3_STBY VCCIO3<0> @BASEBOARD_FAB2_LIB.BASEBOARD_FAB2(SCH_1):P3V3_STBY

CAP_A_0402V-0.1UF,16V,10%,X7R,A  I15  C2R5
   1 P3V3_STBY      A @BASEBOARD_FAB2_LIB.BASEBOARD_FAB2(SCH_1):P3V3_STBY
   2    GND      B @BASEBOARD_FAB2_LIB.BASEBOARD_FAB2(SCH_1):GND

CAP_A_0402V-0.1UF,16V,10%,X7R,A  I16  C2P4
   1 P3V3_STBY      A @BASEBOARD_FAB2_LIB.BASEBOARD_FAB2(SCH_1):P3V3_STBY
   2    GND      B @BASEBOARD_FAB2_LIB.BASEBOARD_FAB2(SCH_1):GND

CAP_A_0402V-0.1UF,16V,10%,X7R,A  I17  C3P52
   1 P3V3_STBY      A @BASEBOARD_FAB2_LIB.BASEBOARD_FAB2(SCH_1):P3V3_STBY
   2    GND      B @BASEBOARD_FAB2_LIB.BASEBOARD_FAB2(SCH_1):GND

CAP_A_0402V-0.1UF,16V,10%,X7R,A  I18  C2P6
   1 P3V3_STBY      A @BASEBOARD_FAB2_LIB.BASEBOARD_FAB2(SCH_1):P3V3_STBY
   2    GND      B @BASEBOARD_FAB2_LIB.BASEBOARD_FAB2(SCH_1):GND

CAP_A_0402V-0.1UF,16V,10%,X7R,A  I19  C2R3
   1 P3V3_STBY      A @BASEBOARD_FAB2_LIB.BASEBOARD_FAB2(SCH_1):P3V3_STBY
   2    GND      B @BASEBOARD_FAB2_LIB.BASEBOARD_FAB2(SCH_1):GND

CAP_A_0402V-0.1UF,16V,10%,X7R,A  I20  C2P7
   1 P3V3_STBY      A @BASEBOARD_FAB2_LIB.BASEBOARD_FAB2(SCH_1):P3V3_STBY
   2    GND      B @BASEBOARD_FAB2_LIB.BASEBOARD_FAB2(SCH_1):GND

CAP_A_0402V-0.1UF,16V,10%,X7R,A  I21  C2R4
   1 P3V3_STBY      A @BASEBOARD_FAB2_LIB.BASEBOARD_FAB2(SCH_1):P3V3_STBY
   2    GND      B @BASEBOARD_FAB2_LIB.BASEBOARD_FAB2(SCH_1):GND

CAP_A_0402V-0.1UF,16V,10%,X7R,A  I22  C2P3
   1 P3V3_STBY      A @BASEBOARD_FAB2_LIB.BASEBOARD_FAB2(SCH_1):P3V3_STBY
   2    GND      B @BASEBOARD_FAB2_LIB.BASEBOARD_FAB2(SCH_1):GND

CAP_A_0402V-0.1UF,16V,10%,X7R,A  I23  C3P44
   1 P3V3_STBY      A @BASEBOARD_FAB2_LIB.BASEBOARD_FAB2(SCH_1):P3V3_STBY
   2    GND      B @BASEBOARD_FAB2_LIB.BASEBOARD_FAB2(SCH_1):GND

CAP_A_0402V-0.1UF,16V,10%,X7R,A  I25  C3P48
   1 P3V3_STBY      A @BASEBOARD_FAB2_LIB.BASEBOARD_FAB2(SCH_1):P3V3_STBY
   2    GND      B @BASEBOARD_FAB2_LIB.BASEBOARD_FAB2(SCH_1):GND

CAP_A_0402V-0.1UF,16V,10%,X7R,A  I28  C2R2
   1 P3V3_STBY      A @BASEBOARD_FAB2_LIB.BASEBOARD_FAB2(SCH_1):P3V3_STBY
   2    GND      B @BASEBOARD_FAB2_LIB.BASEBOARD_FAB2(SCH_1):GND

RES_0402-10.0K,1%,1/16W,CHIP,GA  I33  R7E6
   1 P3V3_STBY      A @BASEBOARD_FAB2_LIB.BASEBOARD_FAB2(SCH_1):P3V3_STBY
   2 PU_RST_PERST_BIT1      B @BASEBOARD_FAB2_LIB.BASEBOARD_FAB2(SCH_1):PU_RST_PERST_BIT1

RES_0402-10.0K,1%,1/16W,CHIP,GA  I34  R2R1
   1 P3V3_STBY      A @BASEBOARD_FAB2_LIB.BASEBOARD_FAB2(SCH_1):P3V3_STBY
   2 PU_RST_PERST_BIT0      B @BASEBOARD_FAB2_LIB.BASEBOARD_FAB2(SCH_1):PU_RST_PERST_BIT0

RES_0402-10.0K,1%,1/16W,CHIP,GA  I38  R7E5
   1 P3V3_STBY      A @BASEBOARD_FAB2_LIB.BASEBOARD_FAB2(SCH_1):P3V3_STBY
   2 PU_THERMTRIP_FORCE_N      B @BASEBOARD_FAB2_LIB.BASEBOARD_FAB2(SCH_1):PU_THERMTRIP_FORCE_N

RES_0402-10.0K,1%,1/16W,CHIP,GA  I41  R2R3
   1 P3V3_STBY      A @BASEBOARD_FAB2_LIB.BASEBOARD_FAB2(SCH_1):P3V3_STBY
   2 FM_PLD_DEBUG_MODE_N      B @BASEBOARD_FAB2_LIB.BASEBOARD_FAB2(SCH_1):FM_PLD_DEBUG_MODE_N

RES_0402-4.75K,1%,1/16W,CHIP,GA  I48  R3R16
   1 PVPP_ABC      A @BASEBOARD_FAB2_LIB.BASEBOARD_FAB2(SCH_1):PVPP_ABC
   2 RST_CD_CPU0_POR_N      B @BASEBOARD_FAB2_LIB.BASEBOARD_FAB2(SCH_1):RST_CD_CPU0_POR_N

RES_0402-4.75K,1%,1/16W,CHIP,GA  I49  R6M9
   1 PVPP_KLM      A @BASEBOARD_FAB2_LIB.BASEBOARD_FAB2(SCH_1):PVPP_KLM
   2 RST_CD_CPU1_POR_N      B @BASEBOARD_FAB2_LIB.BASEBOARD_FAB2(SCH_1):RST_CD_CPU1_POR_N

RES_0402-4.75K,1%,1/16W,CHIP,GA  I55  R7E18
   1 P3V3_STBY      A @BASEBOARD_FAB2_LIB.BASEBOARD_FAB2(SCH_1):P3V3_STBY
   2 RST_RSMRST_N      B @BASEBOARD_FAB2_LIB.BASEBOARD_FAB2(SCH_1):RST_RSMRST_N

RES_0402-1.00K,1%,1/16W,EMPTY,A  I57  R7E19
   1 P3V3_STBY      A @BASEBOARD_FAB2_LIB.BASEBOARD_FAB2(SCH_1):P3V3_STBY
   2 FM_MEM_EVENT_FUNC      B @BASEBOARD_FAB2_LIB.BASEBOARD_FAB2(SCH_1):FM_MEM_EVENT_FUNC

RES_0402-1.00K,1%,1/16W,CHIP,GA  I59  R7E20
   1 FM_MEM_EVENT_FUNC      A @BASEBOARD_FAB2_LIB.BASEBOARD_FAB2(SCH_1):FM_MEM_EVENT_FUNC
   2    GND      B @BASEBOARD_FAB2_LIB.BASEBOARD_FAB2(SCH_1):GND


DRAWING: @BASEBOARD_FAB2_LIB.BASEBOARD_FAB2(SCH_1):PAGE193 

CAPP_3018-470UF,2.5V,20%,ALUM,A  I29  C4C1
   1 PVCCIOMCP_CPU1      A @BASEBOARD_FAB2_LIB.BASEBOARD_FAB2(SCH_1):PVCCIOMCP_CPU1
   2    GND      B @BASEBOARD_FAB2_LIB.BASEBOARD_FAB2(SCH_1):GND

CAP_A_0402V-1.0UF,6.3V,10%,X6SA  I31  C3C2
   1 PVCCIOMCP_CPU1      A @BASEBOARD_FAB2_LIB.BASEBOARD_FAB2(SCH_1):PVCCIOMCP_CPU1
   2    GND      B @BASEBOARD_FAB2_LIB.BASEBOARD_FAB2(SCH_1):GND

CAP_A_0402V-1.0UF,6.3V,10%,X6SA  I38  C3C1
   1 PVCCIOMCP_CPU1      A @BASEBOARD_FAB2_LIB.BASEBOARD_FAB2(SCH_1):PVCCIOMCP_CPU1
   2    GND      B @BASEBOARD_FAB2_LIB.BASEBOARD_FAB2(SCH_1):GND

SCONN120_H61426002_SM-CONN,H61A  I45  J4E1
  A1 PVCCMCP_CPU1   IOA1 @BASEBOARD_FAB2_LIB.BASEBOARD_FAB2(SCH_1):PVCCMCP_CPU1
 A10 PVCCMCP_CPU1  IOA10 @BASEBOARD_FAB2_LIB.BASEBOARD_FAB2(SCH_1):PVCCMCP_CPU1
 A11 PVCCMCP_CPU1  IOA11 @BASEBOARD_FAB2_LIB.BASEBOARD_FAB2(SCH_1):PVCCMCP_CPU1
 A12 PVCCMCP_CPU1  IOA12 @BASEBOARD_FAB2_LIB.BASEBOARD_FAB2(SCH_1):PVCCMCP_CPU1
 A13 PVCCMCP_CPU1  IOA13 @BASEBOARD_FAB2_LIB.BASEBOARD_FAB2(SCH_1):PVCCMCP_CPU1
 A14 PVCCMCP_CPU1  IOA14 @BASEBOARD_FAB2_LIB.BASEBOARD_FAB2(SCH_1):PVCCMCP_CPU1
 A15 PVCCMCP_CPU1  IOA15 @BASEBOARD_FAB2_LIB.BASEBOARD_FAB2(SCH_1):PVCCMCP_CPU1
 A16 PVCCMCP_CPU1  IOA16 @BASEBOARD_FAB2_LIB.BASEBOARD_FAB2(SCH_1):PVCCMCP_CPU1
 A17 PVCCMCP_CPU1  IOA17 @BASEBOARD_FAB2_LIB.BASEBOARD_FAB2(SCH_1):PVCCMCP_CPU1
 A18 PVCCMCP_CPU1  IOA18 @BASEBOARD_FAB2_LIB.BASEBOARD_FAB2(SCH_1):PVCCMCP_CPU1
 A19    GND  IOA19 @BASEBOARD_FAB2_LIB.BASEBOARD_FAB2(SCH_1):GND
  A2 PVCCMCP_CPU1   IOA2 @BASEBOARD_FAB2_LIB.BASEBOARD_FAB2(SCH_1):PVCCMCP_CPU1
 A20    GND  IOA20 @BASEBOARD_FAB2_LIB.BASEBOARD_FAB2(SCH_1):GND
  A3 PVCCMCP_CPU1   IOA3 @BASEBOARD_FAB2_LIB.BASEBOARD_FAB2(SCH_1):PVCCMCP_CPU1
  A4 VSENSE_PVCCMCP_CPU1_SKT_VSEN   IOA4 @BASEBOARD_FAB2_LIB.BASEBOARD_FAB2(SCH_1):VSENSE_PVCCMCP_CPU1_SKT_VSEN
  A5 PVCCMCP_CPU1   IOA5 @BASEBOARD_FAB2_LIB.BASEBOARD_FAB2(SCH_1):PVCCMCP_CPU1
  A6 PVCCMCP_CPU1   IOA6 @BASEBOARD_FAB2_LIB.BASEBOARD_FAB2(SCH_1):PVCCMCP_CPU1
  A7 PVCCMCP_CPU1   IOA7 @BASEBOARD_FAB2_LIB.BASEBOARD_FAB2(SCH_1):PVCCMCP_CPU1
  A8 PVCCMCP_CPU1   IOA8 @BASEBOARD_FAB2_LIB.BASEBOARD_FAB2(SCH_1):PVCCMCP_CPU1
  A9 PVCCMCP_CPU1   IOA9 @BASEBOARD_FAB2_LIB.BASEBOARD_FAB2(SCH_1):PVCCMCP_CPU1
  B1 PVCCMCP_CPU1   IOB1 @BASEBOARD_FAB2_LIB.BASEBOARD_FAB2(SCH_1):PVCCMCP_CPU1
 B10 PVCCMCP_CPU1  IOB10 @BASEBOARD_FAB2_LIB.BASEBOARD_FAB2(SCH_1):PVCCMCP_CPU1
 B11 PVCCMCP_CPU1  IOB11 @BASEBOARD_FAB2_LIB.BASEBOARD_FAB2(SCH_1):PVCCMCP_CPU1
 B12 PVCCMCP_CPU1  IOB12 @BASEBOARD_FAB2_LIB.BASEBOARD_FAB2(SCH_1):PVCCMCP_CPU1
 B13 PVCCMCP_CPU1  IOB13 @BASEBOARD_FAB2_LIB.BASEBOARD_FAB2(SCH_1):PVCCMCP_CPU1
 B14 PVCCMCP_CPU1  IOB14 @BASEBOARD_FAB2_LIB.BASEBOARD_FAB2(SCH_1):PVCCMCP_CPU1
 B15 PVCCMCP_CPU1  IOB15 @BASEBOARD_FAB2_LIB.BASEBOARD_FAB2(SCH_1):PVCCMCP_CPU1
 B16 PVCCMCP_CPU1  IOB16 @BASEBOARD_FAB2_LIB.BASEBOARD_FAB2(SCH_1):PVCCMCP_CPU1
 B17 PVCCMCP_CPU1  IOB17 @BASEBOARD_FAB2_LIB.BASEBOARD_FAB2(SCH_1):PVCCMCP_CPU1
 B18 PVCCMCP_CPU1  IOB18 @BASEBOARD_FAB2_LIB.BASEBOARD_FAB2(SCH_1):PVCCMCP_CPU1
 B19    GND  IOB19 @BASEBOARD_FAB2_LIB.BASEBOARD_FAB2(SCH_1):GND
  B2 PVCCMCP_CPU1   IOB2 @BASEBOARD_FAB2_LIB.BASEBOARD_FAB2(SCH_1):PVCCMCP_CPU1
 B20    GND  IOB20 @BASEBOARD_FAB2_LIB.BASEBOARD_FAB2(SCH_1):GND
  B3 PVCCMCP_CPU1   IOB3 @BASEBOARD_FAB2_LIB.BASEBOARD_FAB2(SCH_1):PVCCMCP_CPU1
  B4 VSENSE_PVCCMCP_CPU1_SKT_VRTN   IOB4 @BASEBOARD_FAB2_LIB.BASEBOARD_FAB2(SCH_1):VSENSE_PVCCMCP_CPU1_SKT_VRTN
  B5 PVCCMCP_CPU1   IOB5 @BASEBOARD_FAB2_LIB.BASEBOARD_FAB2(SCH_1):PVCCMCP_CPU1
  B6 PVCCMCP_CPU1   IOB6 @BASEBOARD_FAB2_LIB.BASEBOARD_FAB2(SCH_1):PVCCMCP_CPU1
  B7 PVCCMCP_CPU1   IOB7 @BASEBOARD_FAB2_LIB.BASEBOARD_FAB2(SCH_1):PVCCMCP_CPU1
  B8 PVCCMCP_CPU1   IOB8 @BASEBOARD_FAB2_LIB.BASEBOARD_FAB2(SCH_1):PVCCMCP_CPU1
  B9 PVCCMCP_CPU1   IOB9 @BASEBOARD_FAB2_LIB.BASEBOARD_FAB2(SCH_1):PVCCMCP_CPU1
  C1 PVCCMCP_CPU1   IOC1 @BASEBOARD_FAB2_LIB.BASEBOARD_FAB2(SCH_1):PVCCMCP_CPU1
 C10 PVCCMCP_CPU1  IOC10 @BASEBOARD_FAB2_LIB.BASEBOARD_FAB2(SCH_1):PVCCMCP_CPU1
 C11 PVCCMCP_CPU1  IOC11 @BASEBOARD_FAB2_LIB.BASEBOARD_FAB2(SCH_1):PVCCMCP_CPU1
 C12 PVCCMCP_CPU1  IOC12 @BASEBOARD_FAB2_LIB.BASEBOARD_FAB2(SCH_1):PVCCMCP_CPU1
 C13 PVCCMCP_CPU1  IOC13 @BASEBOARD_FAB2_LIB.BASEBOARD_FAB2(SCH_1):PVCCMCP_CPU1
 C14 PVCCMCP_CPU1  IOC14 @BASEBOARD_FAB2_LIB.BASEBOARD_FAB2(SCH_1):PVCCMCP_CPU1
 C15 PVCCMCP_CPU1  IOC15 @BASEBOARD_FAB2_LIB.BASEBOARD_FAB2(SCH_1):PVCCMCP_CPU1
 C16 PVCCMCP_CPU1  IOC16 @BASEBOARD_FAB2_LIB.BASEBOARD_FAB2(SCH_1):PVCCMCP_CPU1
 C17 PVCCMCP_CPU1  IOC17 @BASEBOARD_FAB2_LIB.BASEBOARD_FAB2(SCH_1):PVCCMCP_CPU1
 C18 PVCCMCP_CPU1  IOC18 @BASEBOARD_FAB2_LIB.BASEBOARD_FAB2(SCH_1):PVCCMCP_CPU1
 C19    GND  IOC19 @BASEBOARD_FAB2_LIB.BASEBOARD_FAB2(SCH_1):GND
  C2 PVCCMCP_CPU1   IOC2 @BASEBOARD_FAB2_LIB.BASEBOARD_FAB2(SCH_1):PVCCMCP_CPU1
 C20    GND  IOC20 @BASEBOARD_FAB2_LIB.BASEBOARD_FAB2(SCH_1):GND
  C3 PVCCMCP_CPU1   IOC3 @BASEBOARD_FAB2_LIB.BASEBOARD_FAB2(SCH_1):PVCCMCP_CPU1
  C4 PVCCMCP_CPU1   IOC4 @BASEBOARD_FAB2_LIB.BASEBOARD_FAB2(SCH_1):PVCCMCP_CPU1
  C5 PVCCMCP_CPU1   IOC5 @BASEBOARD_FAB2_LIB.BASEBOARD_FAB2(SCH_1):PVCCMCP_CPU1
  C6 PVCCMCP_CPU1   IOC6 @BASEBOARD_FAB2_LIB.BASEBOARD_FAB2(SCH_1):PVCCMCP_CPU1
  C7 PVCCMCP_CPU1   IOC7 @BASEBOARD_FAB2_LIB.BASEBOARD_FAB2(SCH_1):PVCCMCP_CPU1
  C8 PVCCMCP_CPU1   IOC8 @BASEBOARD_FAB2_LIB.BASEBOARD_FAB2(SCH_1):PVCCMCP_CPU1
  C9 PVCCMCP_CPU1   IOC9 @BASEBOARD_FAB2_LIB.BASEBOARD_FAB2(SCH_1):PVCCMCP_CPU1
  D1 VSENSE_P1V8MCP_CPU1_SKT_VSEN   IOD1 @BASEBOARD_FAB2_LIB.BASEBOARD_FAB2(SCH_1):VSENSE_P1V8MCP_CPU1_SKT_VSEN
 D10    GND  IOD10 @BASEBOARD_FAB2_LIB.BASEBOARD_FAB2(SCH_1):GND
 D11    GND  IOD11 @BASEBOARD_FAB2_LIB.BASEBOARD_FAB2(SCH_1):GND
 D12    GND  IOD12 @BASEBOARD_FAB2_LIB.BASEBOARD_FAB2(SCH_1):GND
 D13    GND  IOD13 @BASEBOARD_FAB2_LIB.BASEBOARD_FAB2(SCH_1):GND
 D14    GND  IOD14 @BASEBOARD_FAB2_LIB.BASEBOARD_FAB2(SCH_1):GND
 D15    GND  IOD15 @BASEBOARD_FAB2_LIB.BASEBOARD_FAB2(SCH_1):GND
 D16    GND  IOD16 @BASEBOARD_FAB2_LIB.BASEBOARD_FAB2(SCH_1):GND
 D17    GND  IOD17 @BASEBOARD_FAB2_LIB.BASEBOARD_FAB2(SCH_1):GND
 D18    GND  IOD18 @BASEBOARD_FAB2_LIB.BASEBOARD_FAB2(SCH_1):GND
 D19    GND  IOD19 @BASEBOARD_FAB2_LIB.BASEBOARD_FAB2(SCH_1):GND
  D2 VSENSE_P1V8MCP_CPU1_SKT_VRTN   IOD2 @BASEBOARD_FAB2_LIB.BASEBOARD_FAB2(SCH_1):VSENSE_P1V8MCP_CPU1_SKT_VRTN
 D20    GND  IOD20 @BASEBOARD_FAB2_LIB.BASEBOARD_FAB2(SCH_1):GND
  D3    GND   IOD3 @BASEBOARD_FAB2_LIB.BASEBOARD_FAB2(SCH_1):GND
  D4    GND   IOD4 @BASEBOARD_FAB2_LIB.BASEBOARD_FAB2(SCH_1):GND
  D5    GND   IOD5 @BASEBOARD_FAB2_LIB.BASEBOARD_FAB2(SCH_1):GND
  D6    GND   IOD6 @BASEBOARD_FAB2_LIB.BASEBOARD_FAB2(SCH_1):GND
  D7    GND   IOD7 @BASEBOARD_FAB2_LIB.BASEBOARD_FAB2(SCH_1):GND
  D8    GND   IOD8 @BASEBOARD_FAB2_LIB.BASEBOARD_FAB2(SCH_1):GND
  D9    GND   IOD9 @BASEBOARD_FAB2_LIB.BASEBOARD_FAB2(SCH_1):GND
  E1 P1V8_MCP_CPU1   IOE1 @BASEBOARD_FAB2_LIB.BASEBOARD_FAB2(SCH_1):P1V8_MCP_CPU1
 E10    GND  IOE10 @BASEBOARD_FAB2_LIB.BASEBOARD_FAB2(SCH_1):GND
 E11    GND  IOE11 @BASEBOARD_FAB2_LIB.BASEBOARD_FAB2(SCH_1):GND
 E12    GND  IOE12 @BASEBOARD_FAB2_LIB.BASEBOARD_FAB2(SCH_1):GND
 E13    GND  IOE13 @BASEBOARD_FAB2_LIB.BASEBOARD_FAB2(SCH_1):GND
 E14    GND  IOE14 @BASEBOARD_FAB2_LIB.BASEBOARD_FAB2(SCH_1):GND
 E15    GND  IOE15 @BASEBOARD_FAB2_LIB.BASEBOARD_FAB2(SCH_1):GND
 E16    GND  IOE16 @BASEBOARD_FAB2_LIB.BASEBOARD_FAB2(SCH_1):GND
 E17    GND  IOE17 @BASEBOARD_FAB2_LIB.BASEBOARD_FAB2(SCH_1):GND
 E18    GND  IOE18 @BASEBOARD_FAB2_LIB.BASEBOARD_FAB2(SCH_1):GND
 E19    GND  IOE19 @BASEBOARD_FAB2_LIB.BASEBOARD_FAB2(SCH_1):GND
  E2 P1V8_MCP_CPU1   IOE2 @BASEBOARD_FAB2_LIB.BASEBOARD_FAB2(SCH_1):P1V8_MCP_CPU1
 E20    GND  IOE20 @BASEBOARD_FAB2_LIB.BASEBOARD_FAB2(SCH_1):GND
  E3    GND   IOE3 @BASEBOARD_FAB2_LIB.BASEBOARD_FAB2(SCH_1):GND
  E4    GND   IOE4 @BASEBOARD_FAB2_LIB.BASEBOARD_FAB2(SCH_1):GND
  E5 CLK_322M_156M_CPU1_OSC_VRM_DP   IOE5 @BASEBOARD_FAB2_LIB.BASEBOARD_FAB2(SCH_1):CLK_322M_156M_CPU1_OSC_VRM_DP
  E6    GND   IOE6 @BASEBOARD_FAB2_LIB.BASEBOARD_FAB2(SCH_1):GND
  E7    GND   IOE7 @BASEBOARD_FAB2_LIB.BASEBOARD_FAB2(SCH_1):GND
  E8    GND   IOE8 @BASEBOARD_FAB2_LIB.BASEBOARD_FAB2(SCH_1):GND
  E9    GND   IOE9 @BASEBOARD_FAB2_LIB.BASEBOARD_FAB2(SCH_1):GND
  F1 P1V8_MCP_CPU1   IOF1 @BASEBOARD_FAB2_LIB.BASEBOARD_FAB2(SCH_1):P1V8_MCP_CPU1
 F10    GND  IOF10 @BASEBOARD_FAB2_LIB.BASEBOARD_FAB2(SCH_1):GND
 F11    GND  IOF11 @BASEBOARD_FAB2_LIB.BASEBOARD_FAB2(SCH_1):GND
 F12    GND  IOF12 @BASEBOARD_FAB2_LIB.BASEBOARD_FAB2(SCH_1):GND
 F13    GND  IOF13 @BASEBOARD_FAB2_LIB.BASEBOARD_FAB2(SCH_1):GND
 F14    GND  IOF14 @BASEBOARD_FAB2_LIB.BASEBOARD_FAB2(SCH_1):GND
 F15    GND  IOF15 @BASEBOARD_FAB2_LIB.BASEBOARD_FAB2(SCH_1):GND
 F16    GND  IOF16 @BASEBOARD_FAB2_LIB.BASEBOARD_FAB2(SCH_1):GND
 F17    GND  IOF17 @BASEBOARD_FAB2_LIB.BASEBOARD_FAB2(SCH_1):GND
 F18    GND  IOF18 @BASEBOARD_FAB2_LIB.BASEBOARD_FAB2(SCH_1):GND
 F19    GND  IOF19 @BASEBOARD_FAB2_LIB.BASEBOARD_FAB2(SCH_1):GND
  F2 P1V8_MCP_CPU1   IOF2 @BASEBOARD_FAB2_LIB.BASEBOARD_FAB2(SCH_1):P1V8_MCP_CPU1
 F20    GND  IOF20 @BASEBOARD_FAB2_LIB.BASEBOARD_FAB2(SCH_1):GND
  F3    GND   IOF3 @BASEBOARD_FAB2_LIB.BASEBOARD_FAB2(SCH_1):GND
  F4    GND   IOF4 @BASEBOARD_FAB2_LIB.BASEBOARD_FAB2(SCH_1):GND
  F5 CLK_322M_156M_CPU1_OSC_VRM_DN   IOF5 @BASEBOARD_FAB2_LIB.BASEBOARD_FAB2(SCH_1):CLK_322M_156M_CPU1_OSC_VRM_DN
  F6    GND   IOF6 @BASEBOARD_FAB2_LIB.BASEBOARD_FAB2(SCH_1):GND
  F7    GND   IOF7 @BASEBOARD_FAB2_LIB.BASEBOARD_FAB2(SCH_1):GND
  F8    GND   IOF8 @BASEBOARD_FAB2_LIB.BASEBOARD_FAB2(SCH_1):GND
  F9    GND   IOF9 @BASEBOARD_FAB2_LIB.BASEBOARD_FAB2(SCH_1):GND

SCONN120_H61426002_SM-CONN,H61A  I46  J4B2
  A1 P12V_STBY   IOA1 @BASEBOARD_FAB2_LIB.BASEBOARD_FAB2(SCH_1):P12V_STBY
 A10    GND  IOA10 @BASEBOARD_FAB2_LIB.BASEBOARD_FAB2(SCH_1):GND
 A11 P3V3_STBY  IOA11 @BASEBOARD_FAB2_LIB.BASEBOARD_FAB2(SCH_1):P3V3_STBY
 A12    GND  IOA12 @BASEBOARD_FAB2_LIB.BASEBOARD_FAB2(SCH_1):GND
 A13 P5V_STBY  IOA13 @BASEBOARD_FAB2_LIB.BASEBOARD_FAB2(SCH_1):P5V_STBY
 A14    GND  IOA14 @BASEBOARD_FAB2_LIB.BASEBOARD_FAB2(SCH_1):GND
 A15 FM_P1V8MCP_CPU1_EN  IOA15 @BASEBOARD_FAB2_LIB.BASEBOARD_FAB2(SCH_1):FM_P1V8MCP_CPU1_EN
 A16 FM_PVCCIOMCP_CPU1_EN  IOA16 @BASEBOARD_FAB2_LIB.BASEBOARD_FAB2(SCH_1):FM_PVCCIOMCP_CPU1_EN
 A17    GND  IOA17 @BASEBOARD_FAB2_LIB.BASEBOARD_FAB2(SCH_1):GND
 A18 SMB_VR_STBY_LVC3_SCL  IOA18 @BASEBOARD_FAB2_LIB.BASEBOARD_FAB2(SCH_1):SMB_VR_STBY_LVC3_SCL
 A19 SVID_ALERT0_CPU1_R_N  IOA19 @BASEBOARD_FAB2_LIB.BASEBOARD_FAB2(SCH_1):SVID_ALERT0_CPU1_R_N
  A2 P12V_STBY   IOA2 @BASEBOARD_FAB2_LIB.BASEBOARD_FAB2(SCH_1):P12V_STBY
 A20 SVID_CLK0_CPU1_R  IOA20 @BASEBOARD_FAB2_LIB.BASEBOARD_FAB2(SCH_1):SVID_CLK0_CPU1_R
  A3 P12V_STBY   IOA3 @BASEBOARD_FAB2_LIB.BASEBOARD_FAB2(SCH_1):P12V_STBY
  A4 P12V_STBY   IOA4 @BASEBOARD_FAB2_LIB.BASEBOARD_FAB2(SCH_1):P12V_STBY
  A5 P12V_STBY   IOA5 @BASEBOARD_FAB2_LIB.BASEBOARD_FAB2(SCH_1):P12V_STBY
  A6 P12V_STBY   IOA6 @BASEBOARD_FAB2_LIB.BASEBOARD_FAB2(SCH_1):P12V_STBY
  A7 P12V_STBY   IOA7 @BASEBOARD_FAB2_LIB.BASEBOARD_FAB2(SCH_1):P12V_STBY
  A8 P12V_STBY   IOA8 @BASEBOARD_FAB2_LIB.BASEBOARD_FAB2(SCH_1):P12V_STBY
  A9    GND   IOA9 @BASEBOARD_FAB2_LIB.BASEBOARD_FAB2(SCH_1):GND
  B1 P12V_STBY   IOB1 @BASEBOARD_FAB2_LIB.BASEBOARD_FAB2(SCH_1):P12V_STBY
 B10    GND  IOB10 @BASEBOARD_FAB2_LIB.BASEBOARD_FAB2(SCH_1):GND
 B11 P3V3_STBY  IOB11 @BASEBOARD_FAB2_LIB.BASEBOARD_FAB2(SCH_1):P3V3_STBY
 B12    GND  IOB12 @BASEBOARD_FAB2_LIB.BASEBOARD_FAB2(SCH_1):GND
 B13 P5V_STBY  IOB13 @BASEBOARD_FAB2_LIB.BASEBOARD_FAB2(SCH_1):P5V_STBY
 B14    GND  IOB14 @BASEBOARD_FAB2_LIB.BASEBOARD_FAB2(SCH_1):GND
 B15 PWRGD_P1V8MCP_CPU1  IOB15 @BASEBOARD_FAB2_LIB.BASEBOARD_FAB2(SCH_1):PWRGD_P1V8MCP_CPU1
 B16 PWRGD_PVCCIOMCP_CPU1  IOB16 @BASEBOARD_FAB2_LIB.BASEBOARD_FAB2(SCH_1):PWRGD_PVCCIOMCP_CPU1
 B17    GND  IOB17 @BASEBOARD_FAB2_LIB.BASEBOARD_FAB2(SCH_1):GND
 B18 SMB_VR_STBY_LVC3_SDA  IOB18 @BASEBOARD_FAB2_LIB.BASEBOARD_FAB2(SCH_1):SMB_VR_STBY_LVC3_SDA
 B19 SVID_ALERT1_CPU1_R_N  IOB19 @BASEBOARD_FAB2_LIB.BASEBOARD_FAB2(SCH_1):SVID_ALERT1_CPU1_R_N
  B2 P12V_STBY   IOB2 @BASEBOARD_FAB2_LIB.BASEBOARD_FAB2(SCH_1):P12V_STBY
 B20 SVID_DIO0_CPU1_R  IOB20 @BASEBOARD_FAB2_LIB.BASEBOARD_FAB2(SCH_1):SVID_DIO0_CPU1_R
  B3 P12V_STBY   IOB3 @BASEBOARD_FAB2_LIB.BASEBOARD_FAB2(SCH_1):P12V_STBY
  B4 P12V_STBY   IOB4 @BASEBOARD_FAB2_LIB.BASEBOARD_FAB2(SCH_1):P12V_STBY
  B5 P12V_STBY   IOB5 @BASEBOARD_FAB2_LIB.BASEBOARD_FAB2(SCH_1):P12V_STBY
  B6 P12V_STBY   IOB6 @BASEBOARD_FAB2_LIB.BASEBOARD_FAB2(SCH_1):P12V_STBY
  B7 P12V_STBY   IOB7 @BASEBOARD_FAB2_LIB.BASEBOARD_FAB2(SCH_1):P12V_STBY
  B8 P12V_STBY   IOB8 @BASEBOARD_FAB2_LIB.BASEBOARD_FAB2(SCH_1):P12V_STBY
  B9    GND   IOB9 @BASEBOARD_FAB2_LIB.BASEBOARD_FAB2(SCH_1):GND
  C1    GND   IOC1 @BASEBOARD_FAB2_LIB.BASEBOARD_FAB2(SCH_1):GND
 C10    GND  IOC10 @BASEBOARD_FAB2_LIB.BASEBOARD_FAB2(SCH_1):GND
 C11 P3V3_STBY  IOC11 @BASEBOARD_FAB2_LIB.BASEBOARD_FAB2(SCH_1):P3V3_STBY
 C12    GND  IOC12 @BASEBOARD_FAB2_LIB.BASEBOARD_FAB2(SCH_1):GND
 C13 P5V_STBY  IOC13 @BASEBOARD_FAB2_LIB.BASEBOARD_FAB2(SCH_1):P5V_STBY
 C14    GND  IOC14 @BASEBOARD_FAB2_LIB.BASEBOARD_FAB2(SCH_1):GND
 C15    GND  IOC15 @BASEBOARD_FAB2_LIB.BASEBOARD_FAB2(SCH_1):GND
 C16    GND  IOC16 @BASEBOARD_FAB2_LIB.BASEBOARD_FAB2(SCH_1):GND
 C17 PVCCIOMCP_CPU1  IOC17 @BASEBOARD_FAB2_LIB.BASEBOARD_FAB2(SCH_1):PVCCIOMCP_CPU1
 C18 PVCCIOMCP_CPU1  IOC18 @BASEBOARD_FAB2_LIB.BASEBOARD_FAB2(SCH_1):PVCCIOMCP_CPU1
 C19 PVCCIOMCP_CPU1  IOC19 @BASEBOARD_FAB2_LIB.BASEBOARD_FAB2(SCH_1):PVCCIOMCP_CPU1
  C2    GND   IOC2 @BASEBOARD_FAB2_LIB.BASEBOARD_FAB2(SCH_1):GND
 C20 FM_PVCCMCP_CPU1_EN  IOC20 @BASEBOARD_FAB2_LIB.BASEBOARD_FAB2(SCH_1):FM_PVCCMCP_CPU1_EN
  C3    GND   IOC3 @BASEBOARD_FAB2_LIB.BASEBOARD_FAB2(SCH_1):GND
  C4    GND   IOC4 @BASEBOARD_FAB2_LIB.BASEBOARD_FAB2(SCH_1):GND
  C5    GND   IOC5 @BASEBOARD_FAB2_LIB.BASEBOARD_FAB2(SCH_1):GND
  C6    GND   IOC6 @BASEBOARD_FAB2_LIB.BASEBOARD_FAB2(SCH_1):GND
  C7    GND   IOC7 @BASEBOARD_FAB2_LIB.BASEBOARD_FAB2(SCH_1):GND
  C8    GND   IOC8 @BASEBOARD_FAB2_LIB.BASEBOARD_FAB2(SCH_1):GND
  C9    GND   IOC9 @BASEBOARD_FAB2_LIB.BASEBOARD_FAB2(SCH_1):GND
  D1   P3V3   IOD1 @BASEBOARD_FAB2_LIB.BASEBOARD_FAB2(SCH_1):P3V3
 D10    GND  IOD10 @BASEBOARD_FAB2_LIB.BASEBOARD_FAB2(SCH_1):GND
 D11    GND  IOD11 @BASEBOARD_FAB2_LIB.BASEBOARD_FAB2(SCH_1):GND
 D12    GND  IOD12 @BASEBOARD_FAB2_LIB.BASEBOARD_FAB2(SCH_1):GND
 D13    GND  IOD13 @BASEBOARD_FAB2_LIB.BASEBOARD_FAB2(SCH_1):GND
 D14    GND  IOD14 @BASEBOARD_FAB2_LIB.BASEBOARD_FAB2(SCH_1):GND
 D15 PVCCIOMCP_CPU1  IOD15 @BASEBOARD_FAB2_LIB.BASEBOARD_FAB2(SCH_1):PVCCIOMCP_CPU1
 D16 PVCCIOMCP_CPU1  IOD16 @BASEBOARD_FAB2_LIB.BASEBOARD_FAB2(SCH_1):PVCCIOMCP_CPU1
 D17 PVCCIOMCP_CPU1  IOD17 @BASEBOARD_FAB2_LIB.BASEBOARD_FAB2(SCH_1):PVCCIOMCP_CPU1
 D18 PVCCIOMCP_CPU1  IOD18 @BASEBOARD_FAB2_LIB.BASEBOARD_FAB2(SCH_1):PVCCIOMCP_CPU1
 D19 PVCCIOMCP_CPU1  IOD19 @BASEBOARD_FAB2_LIB.BASEBOARD_FAB2(SCH_1):PVCCIOMCP_CPU1
  D2    GND   IOD2 @BASEBOARD_FAB2_LIB.BASEBOARD_FAB2(SCH_1):GND
 D20 PWRGD_PVCCMCP_CPU1  IOD20 @BASEBOARD_FAB2_LIB.BASEBOARD_FAB2(SCH_1):PWRGD_PVCCMCP_CPU1
  D3    GND   IOD3 @BASEBOARD_FAB2_LIB.BASEBOARD_FAB2(SCH_1):GND
  D4    GND   IOD4 @BASEBOARD_FAB2_LIB.BASEBOARD_FAB2(SCH_1):GND
  D5    GND   IOD5 @BASEBOARD_FAB2_LIB.BASEBOARD_FAB2(SCH_1):GND
  D6    GND   IOD6 @BASEBOARD_FAB2_LIB.BASEBOARD_FAB2(SCH_1):GND
  D7    GND   IOD7 @BASEBOARD_FAB2_LIB.BASEBOARD_FAB2(SCH_1):GND
  D8    GND   IOD8 @BASEBOARD_FAB2_LIB.BASEBOARD_FAB2(SCH_1):GND
  D9    GND   IOD9 @BASEBOARD_FAB2_LIB.BASEBOARD_FAB2(SCH_1):GND
  E1 FM_CPU1_VRM_322M_156M_OSC_EN   IOE1 @BASEBOARD_FAB2_LIB.BASEBOARD_FAB2(SCH_1):FM_CPU1_VRM_322M_156M_OSC_EN
 E10 VR_PVCCIOMCP_CPU1_XADDR1  IOE10 @BASEBOARD_FAB2_LIB.BASEBOARD_FAB2(SCH_1):VR_PVCCIOMCP_CPU1_XADDR1
 E11    GND  IOE11 @BASEBOARD_FAB2_LIB.BASEBOARD_FAB2(SCH_1):GND
 E12    GND  IOE12 @BASEBOARD_FAB2_LIB.BASEBOARD_FAB2(SCH_1):GND
 E13    GND  IOE13 @BASEBOARD_FAB2_LIB.BASEBOARD_FAB2(SCH_1):GND
 E14    GND  IOE14 @BASEBOARD_FAB2_LIB.BASEBOARD_FAB2(SCH_1):GND
 E15 PVCCIOMCP_CPU1  IOE15 @BASEBOARD_FAB2_LIB.BASEBOARD_FAB2(SCH_1):PVCCIOMCP_CPU1
 E16 PVCCIOMCP_CPU1  IOE16 @BASEBOARD_FAB2_LIB.BASEBOARD_FAB2(SCH_1):PVCCIOMCP_CPU1
 E17 PVCCIOMCP_CPU1  IOE17 @BASEBOARD_FAB2_LIB.BASEBOARD_FAB2(SCH_1):PVCCIOMCP_CPU1
 E18 PVCCIOMCP_CPU1  IOE18 @BASEBOARD_FAB2_LIB.BASEBOARD_FAB2(SCH_1):PVCCIOMCP_CPU1
 E19 PVCCIOMCP_CPU1  IOE19 @BASEBOARD_FAB2_LIB.BASEBOARD_FAB2(SCH_1):PVCCIOMCP_CPU1
  E2    GND   IOE2 @BASEBOARD_FAB2_LIB.BASEBOARD_FAB2(SCH_1):GND
 E20 SVID_CLK1_CPU1_R  IOE20 @BASEBOARD_FAB2_LIB.BASEBOARD_FAB2(SCH_1):SVID_CLK1_CPU1_R
  E3    GND   IOE3 @BASEBOARD_FAB2_LIB.BASEBOARD_FAB2(SCH_1):GND
  E4    GND   IOE4 @BASEBOARD_FAB2_LIB.BASEBOARD_FAB2(SCH_1):GND
  E5    GND   IOE5 @BASEBOARD_FAB2_LIB.BASEBOARD_FAB2(SCH_1):GND
  E6    GND   IOE6 @BASEBOARD_FAB2_LIB.BASEBOARD_FAB2(SCH_1):GND
  E7    GND   IOE7 @BASEBOARD_FAB2_LIB.BASEBOARD_FAB2(SCH_1):GND
  E8 VSENSE_PVCCIOMCP_CPU1_SKT_VSEN   IOE8 @BASEBOARD_FAB2_LIB.BASEBOARD_FAB2(SCH_1):VSENSE_PVCCIOMCP_CPU1_SKT_VSEN
  E9    GND   IOE9 @BASEBOARD_FAB2_LIB.BASEBOARD_FAB2(SCH_1):GND
  F1 PVCCIO_CPU1   IOF1 @BASEBOARD_FAB2_LIB.BASEBOARD_FAB2(SCH_1):PVCCIO_CPU1
 F10 VR_PVCCMCP_CPU1_XADDR2  IOF10 @BASEBOARD_FAB2_LIB.BASEBOARD_FAB2(SCH_1):VR_PVCCMCP_CPU1_XADDR2
 F11    GND  IOF11 @BASEBOARD_FAB2_LIB.BASEBOARD_FAB2(SCH_1):GND
 F12    GND  IOF12 @BASEBOARD_FAB2_LIB.BASEBOARD_FAB2(SCH_1):GND
 F13    GND  IOF13 @BASEBOARD_FAB2_LIB.BASEBOARD_FAB2(SCH_1):GND
 F14    GND  IOF14 @BASEBOARD_FAB2_LIB.BASEBOARD_FAB2(SCH_1):GND
 F15 PVCCIOMCP_CPU1  IOF15 @BASEBOARD_FAB2_LIB.BASEBOARD_FAB2(SCH_1):PVCCIOMCP_CPU1
 F16 PVCCIOMCP_CPU1  IOF16 @BASEBOARD_FAB2_LIB.BASEBOARD_FAB2(SCH_1):PVCCIOMCP_CPU1
 F17 PVCCIOMCP_CPU1  IOF17 @BASEBOARD_FAB2_LIB.BASEBOARD_FAB2(SCH_1):PVCCIOMCP_CPU1
 F18 PVCCIOMCP_CPU1  IOF18 @BASEBOARD_FAB2_LIB.BASEBOARD_FAB2(SCH_1):PVCCIOMCP_CPU1
 F19 PVCCIOMCP_CPU1  IOF19 @BASEBOARD_FAB2_LIB.BASEBOARD_FAB2(SCH_1):PVCCIOMCP_CPU1
  F2    GND   IOF2 @BASEBOARD_FAB2_LIB.BASEBOARD_FAB2(SCH_1):GND
 F20 SVID_DIO1_CPU1_R  IOF20 @BASEBOARD_FAB2_LIB.BASEBOARD_FAB2(SCH_1):SVID_DIO1_CPU1_R
  F3    GND   IOF3 @BASEBOARD_FAB2_LIB.BASEBOARD_FAB2(SCH_1):GND
  F4    GND   IOF4 @BASEBOARD_FAB2_LIB.BASEBOARD_FAB2(SCH_1):GND
  F5    GND   IOF5 @BASEBOARD_FAB2_LIB.BASEBOARD_FAB2(SCH_1):GND
  F6    GND   IOF6 @BASEBOARD_FAB2_LIB.BASEBOARD_FAB2(SCH_1):GND
  F7    GND   IOF7 @BASEBOARD_FAB2_LIB.BASEBOARD_FAB2(SCH_1):GND
  F8 VSENSE_PVCCIOMCP_CPU1_SKT_VRTN   IOF8 @BASEBOARD_FAB2_LIB.BASEBOARD_FAB2(SCH_1):VSENSE_PVCCIOMCP_CPU1_SKT_VRTN
  F9    GND   IOF9 @BASEBOARD_FAB2_LIB.BASEBOARD_FAB2(SCH_1):GND

CAPP_3018-470UF,2.5V,20%,ALUM,A  I61  C4E24
   1 PVCCMCP_CPU1      A @BASEBOARD_FAB2_LIB.BASEBOARD_FAB2(SCH_1):PVCCMCP_CPU1
   2    GND      B @BASEBOARD_FAB2_LIB.BASEBOARD_FAB2(SCH_1):GND

CAPP_3018-470UF,2.5V,20%,ALUM,A  I62  C6R16
   1 PVCCMCP_CPU1      A @BASEBOARD_FAB2_LIB.BASEBOARD_FAB2(SCH_1):PVCCMCP_CPU1
   2    GND      B @BASEBOARD_FAB2_LIB.BASEBOARD_FAB2(SCH_1):GND

CAP_A_0402V-1.0UF,6.3V,10%,X6SA  I68  C4F1
   1 P1V8_MCP_CPU1      A @BASEBOARD_FAB2_LIB.BASEBOARD_FAB2(SCH_1):P1V8_MCP_CPU1
   2    GND      B @BASEBOARD_FAB2_LIB.BASEBOARD_FAB2(SCH_1):GND

CAP_A_0402V-1.0UF,6.3V,10%,X6SA  I70  C4F3
   1 P1V8_MCP_CPU1      A @BASEBOARD_FAB2_LIB.BASEBOARD_FAB2(SCH_1):P1V8_MCP_CPU1
   2    GND      B @BASEBOARD_FAB2_LIB.BASEBOARD_FAB2(SCH_1):GND

CAP_A_0603V-47UF,4V,20%,X5R,60A  I140  C3F1
   1 P1V8_MCP_CPU1      A @BASEBOARD_FAB2_LIB.BASEBOARD_FAB2(SCH_1):P1V8_MCP_CPU1
   2    GND      B @BASEBOARD_FAB2_LIB.BASEBOARD_FAB2(SCH_1):GND

CAP_A_0603V-47UF,4V,20%,X5R,60A  I141  C4F2
   1 P1V8_MCP_CPU1      A @BASEBOARD_FAB2_LIB.BASEBOARD_FAB2(SCH_1):P1V8_MCP_CPU1
   2    GND      B @BASEBOARD_FAB2_LIB.BASEBOARD_FAB2(SCH_1):GND

RES_0402-8.06K,1%,1/16W,CHIP,GA  I169  R4C12
   1 VR_PVCCIOMCP_CPU1_XADDR1      A @BASEBOARD_FAB2_LIB.BASEBOARD_FAB2(SCH_1):VR_PVCCIOMCP_CPU1_XADDR1
   2    GND      B @BASEBOARD_FAB2_LIB.BASEBOARD_FAB2(SCH_1):GND

RES_0402-3.16K,1%,1/16W,CHIP,GA  I170  R4C11
   1 VR_PVCCMCP_CPU1_XADDR2      A @BASEBOARD_FAB2_LIB.BASEBOARD_FAB2(SCH_1):VR_PVCCMCP_CPU1_XADDR2
   2    GND      B @BASEBOARD_FAB2_LIB.BASEBOARD_FAB2(SCH_1):GND


DRAWING: @BASEBOARD_FAB2_LIB.BASEBOARD_FAB2(SCH_1):PAGE194 

CAP_A_0402V-1.0UF,6.3V,10%,X6SA  I9  C4T2
   1 P1V8_MCP_CPU0      A @BASEBOARD_FAB2_LIB.BASEBOARD_FAB2(SCH_1):P1V8_MCP_CPU0
   2    GND      B @BASEBOARD_FAB2_LIB.BASEBOARD_FAB2(SCH_1):GND

CAP_A_0402V-1.0UF,6.3V,10%,X6SA  I16  C4T1
   1 P1V8_MCP_CPU0      A @BASEBOARD_FAB2_LIB.BASEBOARD_FAB2(SCH_1):P1V8_MCP_CPU0
   2    GND      B @BASEBOARD_FAB2_LIB.BASEBOARD_FAB2(SCH_1):GND

CAPP_3018-470UF,2.5V,20%,ALUM,A  I29  C4R1
   1 PVCCMCP_CPU0      A @BASEBOARD_FAB2_LIB.BASEBOARD_FAB2(SCH_1):PVCCMCP_CPU0
   2    GND      B @BASEBOARD_FAB2_LIB.BASEBOARD_FAB2(SCH_1):GND

CAPP_3018-470UF,2.5V,20%,ALUM,A  I31  C3R4
   1 PVCCMCP_CPU0      A @BASEBOARD_FAB2_LIB.BASEBOARD_FAB2(SCH_1):PVCCMCP_CPU0
   2    GND      B @BASEBOARD_FAB2_LIB.BASEBOARD_FAB2(SCH_1):GND

SCONN120_H61426002_SM-CONN,H61A  I55  J6E1
  A1 PVCCMCP_CPU0   IOA1 @BASEBOARD_FAB2_LIB.BASEBOARD_FAB2(SCH_1):PVCCMCP_CPU0
 A10 PVCCMCP_CPU0  IOA10 @BASEBOARD_FAB2_LIB.BASEBOARD_FAB2(SCH_1):PVCCMCP_CPU0
 A11 PVCCMCP_CPU0  IOA11 @BASEBOARD_FAB2_LIB.BASEBOARD_FAB2(SCH_1):PVCCMCP_CPU0
 A12 PVCCMCP_CPU0  IOA12 @BASEBOARD_FAB2_LIB.BASEBOARD_FAB2(SCH_1):PVCCMCP_CPU0
 A13 PVCCMCP_CPU0  IOA13 @BASEBOARD_FAB2_LIB.BASEBOARD_FAB2(SCH_1):PVCCMCP_CPU0
 A14 PVCCMCP_CPU0  IOA14 @BASEBOARD_FAB2_LIB.BASEBOARD_FAB2(SCH_1):PVCCMCP_CPU0
 A15 PVCCMCP_CPU0  IOA15 @BASEBOARD_FAB2_LIB.BASEBOARD_FAB2(SCH_1):PVCCMCP_CPU0
 A16 PVCCMCP_CPU0  IOA16 @BASEBOARD_FAB2_LIB.BASEBOARD_FAB2(SCH_1):PVCCMCP_CPU0
 A17 PVCCMCP_CPU0  IOA17 @BASEBOARD_FAB2_LIB.BASEBOARD_FAB2(SCH_1):PVCCMCP_CPU0
 A18 PVCCMCP_CPU0  IOA18 @BASEBOARD_FAB2_LIB.BASEBOARD_FAB2(SCH_1):PVCCMCP_CPU0
 A19    GND  IOA19 @BASEBOARD_FAB2_LIB.BASEBOARD_FAB2(SCH_1):GND
  A2 PVCCMCP_CPU0   IOA2 @BASEBOARD_FAB2_LIB.BASEBOARD_FAB2(SCH_1):PVCCMCP_CPU0
 A20    GND  IOA20 @BASEBOARD_FAB2_LIB.BASEBOARD_FAB2(SCH_1):GND
  A3 PVCCMCP_CPU0   IOA3 @BASEBOARD_FAB2_LIB.BASEBOARD_FAB2(SCH_1):PVCCMCP_CPU0
  A4 VSENSE_PVCCMCP_CPU0_SKT_VSEN   IOA4 @BASEBOARD_FAB2_LIB.BASEBOARD_FAB2(SCH_1):VSENSE_PVCCMCP_CPU0_SKT_VSEN
  A5 PVCCMCP_CPU0   IOA5 @BASEBOARD_FAB2_LIB.BASEBOARD_FAB2(SCH_1):PVCCMCP_CPU0
  A6 PVCCMCP_CPU0   IOA6 @BASEBOARD_FAB2_LIB.BASEBOARD_FAB2(SCH_1):PVCCMCP_CPU0
  A7 PVCCMCP_CPU0   IOA7 @BASEBOARD_FAB2_LIB.BASEBOARD_FAB2(SCH_1):PVCCMCP_CPU0
  A8 PVCCMCP_CPU0   IOA8 @BASEBOARD_FAB2_LIB.BASEBOARD_FAB2(SCH_1):PVCCMCP_CPU0
  A9 PVCCMCP_CPU0   IOA9 @BASEBOARD_FAB2_LIB.BASEBOARD_FAB2(SCH_1):PVCCMCP_CPU0
  B1 PVCCMCP_CPU0   IOB1 @BASEBOARD_FAB2_LIB.BASEBOARD_FAB2(SCH_1):PVCCMCP_CPU0
 B10 PVCCMCP_CPU0  IOB10 @BASEBOARD_FAB2_LIB.BASEBOARD_FAB2(SCH_1):PVCCMCP_CPU0
 B11 PVCCMCP_CPU0  IOB11 @BASEBOARD_FAB2_LIB.BASEBOARD_FAB2(SCH_1):PVCCMCP_CPU0
 B12 PVCCMCP_CPU0  IOB12 @BASEBOARD_FAB2_LIB.BASEBOARD_FAB2(SCH_1):PVCCMCP_CPU0
 B13 PVCCMCP_CPU0  IOB13 @BASEBOARD_FAB2_LIB.BASEBOARD_FAB2(SCH_1):PVCCMCP_CPU0
 B14 PVCCMCP_CPU0  IOB14 @BASEBOARD_FAB2_LIB.BASEBOARD_FAB2(SCH_1):PVCCMCP_CPU0
 B15 PVCCMCP_CPU0  IOB15 @BASEBOARD_FAB2_LIB.BASEBOARD_FAB2(SCH_1):PVCCMCP_CPU0
 B16 PVCCMCP_CPU0  IOB16 @BASEBOARD_FAB2_LIB.BASEBOARD_FAB2(SCH_1):PVCCMCP_CPU0
 B17 PVCCMCP_CPU0  IOB17 @BASEBOARD_FAB2_LIB.BASEBOARD_FAB2(SCH_1):PVCCMCP_CPU0
 B18 PVCCMCP_CPU0  IOB18 @BASEBOARD_FAB2_LIB.BASEBOARD_FAB2(SCH_1):PVCCMCP_CPU0
 B19    GND  IOB19 @BASEBOARD_FAB2_LIB.BASEBOARD_FAB2(SCH_1):GND
  B2 PVCCMCP_CPU0   IOB2 @BASEBOARD_FAB2_LIB.BASEBOARD_FAB2(SCH_1):PVCCMCP_CPU0
 B20    GND  IOB20 @BASEBOARD_FAB2_LIB.BASEBOARD_FAB2(SCH_1):GND
  B3 PVCCMCP_CPU0   IOB3 @BASEBOARD_FAB2_LIB.BASEBOARD_FAB2(SCH_1):PVCCMCP_CPU0
  B4 VSENSE_PVCCMCP_CPU0_SKT_VRTN   IOB4 @BASEBOARD_FAB2_LIB.BASEBOARD_FAB2(SCH_1):VSENSE_PVCCMCP_CPU0_SKT_VRTN
  B5 PVCCMCP_CPU0   IOB5 @BASEBOARD_FAB2_LIB.BASEBOARD_FAB2(SCH_1):PVCCMCP_CPU0
  B6 PVCCMCP_CPU0   IOB6 @BASEBOARD_FAB2_LIB.BASEBOARD_FAB2(SCH_1):PVCCMCP_CPU0
  B7 PVCCMCP_CPU0   IOB7 @BASEBOARD_FAB2_LIB.BASEBOARD_FAB2(SCH_1):PVCCMCP_CPU0
  B8 PVCCMCP_CPU0   IOB8 @BASEBOARD_FAB2_LIB.BASEBOARD_FAB2(SCH_1):PVCCMCP_CPU0
  B9 PVCCMCP_CPU0   IOB9 @BASEBOARD_FAB2_LIB.BASEBOARD_FAB2(SCH_1):PVCCMCP_CPU0
  C1 PVCCMCP_CPU0   IOC1 @BASEBOARD_FAB2_LIB.BASEBOARD_FAB2(SCH_1):PVCCMCP_CPU0
 C10 PVCCMCP_CPU0  IOC10 @BASEBOARD_FAB2_LIB.BASEBOARD_FAB2(SCH_1):PVCCMCP_CPU0
 C11 PVCCMCP_CPU0  IOC11 @BASEBOARD_FAB2_LIB.BASEBOARD_FAB2(SCH_1):PVCCMCP_CPU0
 C12 PVCCMCP_CPU0  IOC12 @BASEBOARD_FAB2_LIB.BASEBOARD_FAB2(SCH_1):PVCCMCP_CPU0
 C13 PVCCMCP_CPU0  IOC13 @BASEBOARD_FAB2_LIB.BASEBOARD_FAB2(SCH_1):PVCCMCP_CPU0
 C14 PVCCMCP_CPU0  IOC14 @BASEBOARD_FAB2_LIB.BASEBOARD_FAB2(SCH_1):PVCCMCP_CPU0
 C15 PVCCMCP_CPU0  IOC15 @BASEBOARD_FAB2_LIB.BASEBOARD_FAB2(SCH_1):PVCCMCP_CPU0
 C16 PVCCMCP_CPU0  IOC16 @BASEBOARD_FAB2_LIB.BASEBOARD_FAB2(SCH_1):PVCCMCP_CPU0
 C17 PVCCMCP_CPU0  IOC17 @BASEBOARD_FAB2_LIB.BASEBOARD_FAB2(SCH_1):PVCCMCP_CPU0
 C18 PVCCMCP_CPU0  IOC18 @BASEBOARD_FAB2_LIB.BASEBOARD_FAB2(SCH_1):PVCCMCP_CPU0
 C19    GND  IOC19 @BASEBOARD_FAB2_LIB.BASEBOARD_FAB2(SCH_1):GND
  C2 PVCCMCP_CPU0   IOC2 @BASEBOARD_FAB2_LIB.BASEBOARD_FAB2(SCH_1):PVCCMCP_CPU0
 C20    GND  IOC20 @BASEBOARD_FAB2_LIB.BASEBOARD_FAB2(SCH_1):GND
  C3 PVCCMCP_CPU0   IOC3 @BASEBOARD_FAB2_LIB.BASEBOARD_FAB2(SCH_1):PVCCMCP_CPU0
  C4 PVCCMCP_CPU0   IOC4 @BASEBOARD_FAB2_LIB.BASEBOARD_FAB2(SCH_1):PVCCMCP_CPU0
  C5 PVCCMCP_CPU0   IOC5 @BASEBOARD_FAB2_LIB.BASEBOARD_FAB2(SCH_1):PVCCMCP_CPU0
  C6 PVCCMCP_CPU0   IOC6 @BASEBOARD_FAB2_LIB.BASEBOARD_FAB2(SCH_1):PVCCMCP_CPU0
  C7 PVCCMCP_CPU0   IOC7 @BASEBOARD_FAB2_LIB.BASEBOARD_FAB2(SCH_1):PVCCMCP_CPU0
  C8 PVCCMCP_CPU0   IOC8 @BASEBOARD_FAB2_LIB.BASEBOARD_FAB2(SCH_1):PVCCMCP_CPU0
  C9 PVCCMCP_CPU0   IOC9 @BASEBOARD_FAB2_LIB.BASEBOARD_FAB2(SCH_1):PVCCMCP_CPU0
  D1 VSENSE_P1V8MCP_CPU0_SKT_VSEN   IOD1 @BASEBOARD_FAB2_LIB.BASEBOARD_FAB2(SCH_1):VSENSE_P1V8MCP_CPU0_SKT_VSEN
 D10    GND  IOD10 @BASEBOARD_FAB2_LIB.BASEBOARD_FAB2(SCH_1):GND
 D11    GND  IOD11 @BASEBOARD_FAB2_LIB.BASEBOARD_FAB2(SCH_1):GND
 D12    GND  IOD12 @BASEBOARD_FAB2_LIB.BASEBOARD_FAB2(SCH_1):GND
 D13    GND  IOD13 @BASEBOARD_FAB2_LIB.BASEBOARD_FAB2(SCH_1):GND
 D14    GND  IOD14 @BASEBOARD_FAB2_LIB.BASEBOARD_FAB2(SCH_1):GND
 D15    GND  IOD15 @BASEBOARD_FAB2_LIB.BASEBOARD_FAB2(SCH_1):GND
 D16    GND  IOD16 @BASEBOARD_FAB2_LIB.BASEBOARD_FAB2(SCH_1):GND
 D17    GND  IOD17 @BASEBOARD_FAB2_LIB.BASEBOARD_FAB2(SCH_1):GND
 D18    GND  IOD18 @BASEBOARD_FAB2_LIB.BASEBOARD_FAB2(SCH_1):GND
 D19    GND  IOD19 @BASEBOARD_FAB2_LIB.BASEBOARD_FAB2(SCH_1):GND
  D2 VSENSE_P1V8MCP_CPU0_SKT_VRTN   IOD2 @BASEBOARD_FAB2_LIB.BASEBOARD_FAB2(SCH_1):VSENSE_P1V8MCP_CPU0_SKT_VRTN
 D20    GND  IOD20 @BASEBOARD_FAB2_LIB.BASEBOARD_FAB2(SCH_1):GND
  D3    GND   IOD3 @BASEBOARD_FAB2_LIB.BASEBOARD_FAB2(SCH_1):GND
  D4    GND   IOD4 @BASEBOARD_FAB2_LIB.BASEBOARD_FAB2(SCH_1):GND
  D5    GND   IOD5 @BASEBOARD_FAB2_LIB.BASEBOARD_FAB2(SCH_1):GND
  D6    GND   IOD6 @BASEBOARD_FAB2_LIB.BASEBOARD_FAB2(SCH_1):GND
  D7    GND   IOD7 @BASEBOARD_FAB2_LIB.BASEBOARD_FAB2(SCH_1):GND
  D8    GND   IOD8 @BASEBOARD_FAB2_LIB.BASEBOARD_FAB2(SCH_1):GND
  D9    GND   IOD9 @BASEBOARD_FAB2_LIB.BASEBOARD_FAB2(SCH_1):GND
  E1 P1V8_MCP_CPU0   IOE1 @BASEBOARD_FAB2_LIB.BASEBOARD_FAB2(SCH_1):P1V8_MCP_CPU0
 E10    GND  IOE10 @BASEBOARD_FAB2_LIB.BASEBOARD_FAB2(SCH_1):GND
 E11    GND  IOE11 @BASEBOARD_FAB2_LIB.BASEBOARD_FAB2(SCH_1):GND
 E12    GND  IOE12 @BASEBOARD_FAB2_LIB.BASEBOARD_FAB2(SCH_1):GND
 E13    GND  IOE13 @BASEBOARD_FAB2_LIB.BASEBOARD_FAB2(SCH_1):GND
 E14    GND  IOE14 @BASEBOARD_FAB2_LIB.BASEBOARD_FAB2(SCH_1):GND
 E15    GND  IOE15 @BASEBOARD_FAB2_LIB.BASEBOARD_FAB2(SCH_1):GND
 E16    GND  IOE16 @BASEBOARD_FAB2_LIB.BASEBOARD_FAB2(SCH_1):GND
 E17    GND  IOE17 @BASEBOARD_FAB2_LIB.BASEBOARD_FAB2(SCH_1):GND
 E18    GND  IOE18 @BASEBOARD_FAB2_LIB.BASEBOARD_FAB2(SCH_1):GND
 E19    GND  IOE19 @BASEBOARD_FAB2_LIB.BASEBOARD_FAB2(SCH_1):GND
  E2 P1V8_MCP_CPU0   IOE2 @BASEBOARD_FAB2_LIB.BASEBOARD_FAB2(SCH_1):P1V8_MCP_CPU0
 E20    GND  IOE20 @BASEBOARD_FAB2_LIB.BASEBOARD_FAB2(SCH_1):GND
  E3    GND   IOE3 @BASEBOARD_FAB2_LIB.BASEBOARD_FAB2(SCH_1):GND
  E4    GND   IOE4 @BASEBOARD_FAB2_LIB.BASEBOARD_FAB2(SCH_1):GND
  E5 CLK_322M_156M_CPU0_OSC_VRM_DP   IOE5 @BASEBOARD_FAB2_LIB.BASEBOARD_FAB2(SCH_1):CLK_322M_156M_CPU0_OSC_VRM_DP
  E6    GND   IOE6 @BASEBOARD_FAB2_LIB.BASEBOARD_FAB2(SCH_1):GND
  E7    GND   IOE7 @BASEBOARD_FAB2_LIB.BASEBOARD_FAB2(SCH_1):GND
  E8    GND   IOE8 @BASEBOARD_FAB2_LIB.BASEBOARD_FAB2(SCH_1):GND
  E9    GND   IOE9 @BASEBOARD_FAB2_LIB.BASEBOARD_FAB2(SCH_1):GND
  F1 P1V8_MCP_CPU0   IOF1 @BASEBOARD_FAB2_LIB.BASEBOARD_FAB2(SCH_1):P1V8_MCP_CPU0
 F10    GND  IOF10 @BASEBOARD_FAB2_LIB.BASEBOARD_FAB2(SCH_1):GND
 F11    GND  IOF11 @BASEBOARD_FAB2_LIB.BASEBOARD_FAB2(SCH_1):GND
 F12    GND  IOF12 @BASEBOARD_FAB2_LIB.BASEBOARD_FAB2(SCH_1):GND
 F13    GND  IOF13 @BASEBOARD_FAB2_LIB.BASEBOARD_FAB2(SCH_1):GND
 F14    GND  IOF14 @BASEBOARD_FAB2_LIB.BASEBOARD_FAB2(SCH_1):GND
 F15    GND  IOF15 @BASEBOARD_FAB2_LIB.BASEBOARD_FAB2(SCH_1):GND
 F16    GND  IOF16 @BASEBOARD_FAB2_LIB.BASEBOARD_FAB2(SCH_1):GND
 F17    GND  IOF17 @BASEBOARD_FAB2_LIB.BASEBOARD_FAB2(SCH_1):GND
 F18    GND  IOF18 @BASEBOARD_FAB2_LIB.BASEBOARD_FAB2(SCH_1):GND
 F19    GND  IOF19 @BASEBOARD_FAB2_LIB.BASEBOARD_FAB2(SCH_1):GND
  F2 P1V8_MCP_CPU0   IOF2 @BASEBOARD_FAB2_LIB.BASEBOARD_FAB2(SCH_1):P1V8_MCP_CPU0
 F20    GND  IOF20 @BASEBOARD_FAB2_LIB.BASEBOARD_FAB2(SCH_1):GND
  F3    GND   IOF3 @BASEBOARD_FAB2_LIB.BASEBOARD_FAB2(SCH_1):GND
  F4    GND   IOF4 @BASEBOARD_FAB2_LIB.BASEBOARD_FAB2(SCH_1):GND
  F5 CLK_322M_156M_CPU0_OSC_VRM_DN   IOF5 @BASEBOARD_FAB2_LIB.BASEBOARD_FAB2(SCH_1):CLK_322M_156M_CPU0_OSC_VRM_DN
  F6    GND   IOF6 @BASEBOARD_FAB2_LIB.BASEBOARD_FAB2(SCH_1):GND
  F7    GND   IOF7 @BASEBOARD_FAB2_LIB.BASEBOARD_FAB2(SCH_1):GND
  F8    GND   IOF8 @BASEBOARD_FAB2_LIB.BASEBOARD_FAB2(SCH_1):GND
  F9    GND   IOF9 @BASEBOARD_FAB2_LIB.BASEBOARD_FAB2(SCH_1):GND

SCONN120_H61426002_SM-CONN,H61A  I56  J6B1
  A1 P12V_STBY   IOA1 @BASEBOARD_FAB2_LIB.BASEBOARD_FAB2(SCH_1):P12V_STBY
 A10    GND  IOA10 @BASEBOARD_FAB2_LIB.BASEBOARD_FAB2(SCH_1):GND
 A11 P3V3_STBY  IOA11 @BASEBOARD_FAB2_LIB.BASEBOARD_FAB2(SCH_1):P3V3_STBY
 A12    GND  IOA12 @BASEBOARD_FAB2_LIB.BASEBOARD_FAB2(SCH_1):GND
 A13 P5V_STBY  IOA13 @BASEBOARD_FAB2_LIB.BASEBOARD_FAB2(SCH_1):P5V_STBY
 A14    GND  IOA14 @BASEBOARD_FAB2_LIB.BASEBOARD_FAB2(SCH_1):GND
 A15 FM_P1V8MCP_CPU0_EN  IOA15 @BASEBOARD_FAB2_LIB.BASEBOARD_FAB2(SCH_1):FM_P1V8MCP_CPU0_EN
 A16 FM_PVCCIOMCP_CPU0_EN  IOA16 @BASEBOARD_FAB2_LIB.BASEBOARD_FAB2(SCH_1):FM_PVCCIOMCP_CPU0_EN
 A17    GND  IOA17 @BASEBOARD_FAB2_LIB.BASEBOARD_FAB2(SCH_1):GND
 A18 SMB_VR_STBY_LVC3_SCL  IOA18 @BASEBOARD_FAB2_LIB.BASEBOARD_FAB2(SCH_1):SMB_VR_STBY_LVC3_SCL
 A19 SVID_ALERT0_CPU0_R_N  IOA19 @BASEBOARD_FAB2_LIB.BASEBOARD_FAB2(SCH_1):SVID_ALERT0_CPU0_R_N
  A2 P12V_STBY   IOA2 @BASEBOARD_FAB2_LIB.BASEBOARD_FAB2(SCH_1):P12V_STBY
 A20 SVID_CLK0_CPU0_R  IOA20 @BASEBOARD_FAB2_LIB.BASEBOARD_FAB2(SCH_1):SVID_CLK0_CPU0_R
  A3 P12V_STBY   IOA3 @BASEBOARD_FAB2_LIB.BASEBOARD_FAB2(SCH_1):P12V_STBY
  A4 P12V_STBY   IOA4 @BASEBOARD_FAB2_LIB.BASEBOARD_FAB2(SCH_1):P12V_STBY
  A5 P12V_STBY   IOA5 @BASEBOARD_FAB2_LIB.BASEBOARD_FAB2(SCH_1):P12V_STBY
  A6 P12V_STBY   IOA6 @BASEBOARD_FAB2_LIB.BASEBOARD_FAB2(SCH_1):P12V_STBY
  A7 P12V_STBY   IOA7 @BASEBOARD_FAB2_LIB.BASEBOARD_FAB2(SCH_1):P12V_STBY
  A8 P12V_STBY   IOA8 @BASEBOARD_FAB2_LIB.BASEBOARD_FAB2(SCH_1):P12V_STBY
  A9    GND   IOA9 @BASEBOARD_FAB2_LIB.BASEBOARD_FAB2(SCH_1):GND
  B1 P12V_STBY   IOB1 @BASEBOARD_FAB2_LIB.BASEBOARD_FAB2(SCH_1):P12V_STBY
 B10    GND  IOB10 @BASEBOARD_FAB2_LIB.BASEBOARD_FAB2(SCH_1):GND
 B11 P3V3_STBY  IOB11 @BASEBOARD_FAB2_LIB.BASEBOARD_FAB2(SCH_1):P3V3_STBY
 B12    GND  IOB12 @BASEBOARD_FAB2_LIB.BASEBOARD_FAB2(SCH_1):GND
 B13 P5V_STBY  IOB13 @BASEBOARD_FAB2_LIB.BASEBOARD_FAB2(SCH_1):P5V_STBY
 B14    GND  IOB14 @BASEBOARD_FAB2_LIB.BASEBOARD_FAB2(SCH_1):GND
 B15 PWRGD_P1V8MCP_CPU0  IOB15 @BASEBOARD_FAB2_LIB.BASEBOARD_FAB2(SCH_1):PWRGD_P1V8MCP_CPU0
 B16 PWRGD_PVCCIOMCP_CPU0  IOB16 @BASEBOARD_FAB2_LIB.BASEBOARD_FAB2(SCH_1):PWRGD_PVCCIOMCP_CPU0
 B17    GND  IOB17 @BASEBOARD_FAB2_LIB.BASEBOARD_FAB2(SCH_1):GND
 B18 SMB_VR_STBY_LVC3_SDA  IOB18 @BASEBOARD_FAB2_LIB.BASEBOARD_FAB2(SCH_1):SMB_VR_STBY_LVC3_SDA
 B19 SVID_ALERT1_CPU0_R_N  IOB19 @BASEBOARD_FAB2_LIB.BASEBOARD_FAB2(SCH_1):SVID_ALERT1_CPU0_R_N
  B2 P12V_STBY   IOB2 @BASEBOARD_FAB2_LIB.BASEBOARD_FAB2(SCH_1):P12V_STBY
 B20 SVID_DIO0_CPU0_R  IOB20 @BASEBOARD_FAB2_LIB.BASEBOARD_FAB2(SCH_1):SVID_DIO0_CPU0_R
  B3 P12V_STBY   IOB3 @BASEBOARD_FAB2_LIB.BASEBOARD_FAB2(SCH_1):P12V_STBY
  B4 P12V_STBY   IOB4 @BASEBOARD_FAB2_LIB.BASEBOARD_FAB2(SCH_1):P12V_STBY
  B5 P12V_STBY   IOB5 @BASEBOARD_FAB2_LIB.BASEBOARD_FAB2(SCH_1):P12V_STBY
  B6 P12V_STBY   IOB6 @BASEBOARD_FAB2_LIB.BASEBOARD_FAB2(SCH_1):P12V_STBY
  B7 P12V_STBY   IOB7 @BASEBOARD_FAB2_LIB.BASEBOARD_FAB2(SCH_1):P12V_STBY
  B8 P12V_STBY   IOB8 @BASEBOARD_FAB2_LIB.BASEBOARD_FAB2(SCH_1):P12V_STBY
  B9    GND   IOB9 @BASEBOARD_FAB2_LIB.BASEBOARD_FAB2(SCH_1):GND
  C1    GND   IOC1 @BASEBOARD_FAB2_LIB.BASEBOARD_FAB2(SCH_1):GND
 C10    GND  IOC10 @BASEBOARD_FAB2_LIB.BASEBOARD_FAB2(SCH_1):GND
 C11 P3V3_STBY  IOC11 @BASEBOARD_FAB2_LIB.BASEBOARD_FAB2(SCH_1):P3V3_STBY
 C12    GND  IOC12 @BASEBOARD_FAB2_LIB.BASEBOARD_FAB2(SCH_1):GND
 C13 P5V_STBY  IOC13 @BASEBOARD_FAB2_LIB.BASEBOARD_FAB2(SCH_1):P5V_STBY
 C14    GND  IOC14 @BASEBOARD_FAB2_LIB.BASEBOARD_FAB2(SCH_1):GND
 C15    GND  IOC15 @BASEBOARD_FAB2_LIB.BASEBOARD_FAB2(SCH_1):GND
 C16    GND  IOC16 @BASEBOARD_FAB2_LIB.BASEBOARD_FAB2(SCH_1):GND
 C17 PVCCIOMCP_CPU0  IOC17 @BASEBOARD_FAB2_LIB.BASEBOARD_FAB2(SCH_1):PVCCIOMCP_CPU0
 C18 PVCCIOMCP_CPU0  IOC18 @BASEBOARD_FAB2_LIB.BASEBOARD_FAB2(SCH_1):PVCCIOMCP_CPU0
 C19 PVCCIOMCP_CPU0  IOC19 @BASEBOARD_FAB2_LIB.BASEBOARD_FAB2(SCH_1):PVCCIOMCP_CPU0
  C2    GND   IOC2 @BASEBOARD_FAB2_LIB.BASEBOARD_FAB2(SCH_1):GND
 C20 FM_PVCCMCP_CPU0_EN  IOC20 @BASEBOARD_FAB2_LIB.BASEBOARD_FAB2(SCH_1):FM_PVCCMCP_CPU0_EN
  C3    GND   IOC3 @BASEBOARD_FAB2_LIB.BASEBOARD_FAB2(SCH_1):GND
  C4    GND   IOC4 @BASEBOARD_FAB2_LIB.BASEBOARD_FAB2(SCH_1):GND
  C5    GND   IOC5 @BASEBOARD_FAB2_LIB.BASEBOARD_FAB2(SCH_1):GND
  C6    GND   IOC6 @BASEBOARD_FAB2_LIB.BASEBOARD_FAB2(SCH_1):GND
  C7    GND   IOC7 @BASEBOARD_FAB2_LIB.BASEBOARD_FAB2(SCH_1):GND
  C8    GND   IOC8 @BASEBOARD_FAB2_LIB.BASEBOARD_FAB2(SCH_1):GND
  C9    GND   IOC9 @BASEBOARD_FAB2_LIB.BASEBOARD_FAB2(SCH_1):GND
  D1   P3V3   IOD1 @BASEBOARD_FAB2_LIB.BASEBOARD_FAB2(SCH_1):P3V3
 D10    GND  IOD10 @BASEBOARD_FAB2_LIB.BASEBOARD_FAB2(SCH_1):GND
 D11    GND  IOD11 @BASEBOARD_FAB2_LIB.BASEBOARD_FAB2(SCH_1):GND
 D12    GND  IOD12 @BASEBOARD_FAB2_LIB.BASEBOARD_FAB2(SCH_1):GND
 D13    GND  IOD13 @BASEBOARD_FAB2_LIB.BASEBOARD_FAB2(SCH_1):GND
 D14    GND  IOD14 @BASEBOARD_FAB2_LIB.BASEBOARD_FAB2(SCH_1):GND
 D15 PVCCIOMCP_CPU0  IOD15 @BASEBOARD_FAB2_LIB.BASEBOARD_FAB2(SCH_1):PVCCIOMCP_CPU0
 D16 PVCCIOMCP_CPU0  IOD16 @BASEBOARD_FAB2_LIB.BASEBOARD_FAB2(SCH_1):PVCCIOMCP_CPU0
 D17 PVCCIOMCP_CPU0  IOD17 @BASEBOARD_FAB2_LIB.BASEBOARD_FAB2(SCH_1):PVCCIOMCP_CPU0
 D18 PVCCIOMCP_CPU0  IOD18 @BASEBOARD_FAB2_LIB.BASEBOARD_FAB2(SCH_1):PVCCIOMCP_CPU0
 D19 PVCCIOMCP_CPU0  IOD19 @BASEBOARD_FAB2_LIB.BASEBOARD_FAB2(SCH_1):PVCCIOMCP_CPU0
  D2    GND   IOD2 @BASEBOARD_FAB2_LIB.BASEBOARD_FAB2(SCH_1):GND
 D20 PWRGD_PVCCMCP_CPU0  IOD20 @BASEBOARD_FAB2_LIB.BASEBOARD_FAB2(SCH_1):PWRGD_PVCCMCP_CPU0
  D3    GND   IOD3 @BASEBOARD_FAB2_LIB.BASEBOARD_FAB2(SCH_1):GND
  D4    GND   IOD4 @BASEBOARD_FAB2_LIB.BASEBOARD_FAB2(SCH_1):GND
  D5    GND   IOD5 @BASEBOARD_FAB2_LIB.BASEBOARD_FAB2(SCH_1):GND
  D6    GND   IOD6 @BASEBOARD_FAB2_LIB.BASEBOARD_FAB2(SCH_1):GND
  D7    GND   IOD7 @BASEBOARD_FAB2_LIB.BASEBOARD_FAB2(SCH_1):GND
  D8    GND   IOD8 @BASEBOARD_FAB2_LIB.BASEBOARD_FAB2(SCH_1):GND
  D9    GND   IOD9 @BASEBOARD_FAB2_LIB.BASEBOARD_FAB2(SCH_1):GND
  E1 FM_CPU0_VRM_322M_156M_OSC_EN   IOE1 @BASEBOARD_FAB2_LIB.BASEBOARD_FAB2(SCH_1):FM_CPU0_VRM_322M_156M_OSC_EN
 E10 VR_PVCCIOMCP_CPU0_XADDR1  IOE10 @BASEBOARD_FAB2_LIB.BASEBOARD_FAB2(SCH_1):VR_PVCCIOMCP_CPU0_XADDR1
 E11    GND  IOE11 @BASEBOARD_FAB2_LIB.BASEBOARD_FAB2(SCH_1):GND
 E12    GND  IOE12 @BASEBOARD_FAB2_LIB.BASEBOARD_FAB2(SCH_1):GND
 E13    GND  IOE13 @BASEBOARD_FAB2_LIB.BASEBOARD_FAB2(SCH_1):GND
 E14    GND  IOE14 @BASEBOARD_FAB2_LIB.BASEBOARD_FAB2(SCH_1):GND
 E15 PVCCIOMCP_CPU0  IOE15 @BASEBOARD_FAB2_LIB.BASEBOARD_FAB2(SCH_1):PVCCIOMCP_CPU0
 E16 PVCCIOMCP_CPU0  IOE16 @BASEBOARD_FAB2_LIB.BASEBOARD_FAB2(SCH_1):PVCCIOMCP_CPU0
 E17 PVCCIOMCP_CPU0  IOE17 @BASEBOARD_FAB2_LIB.BASEBOARD_FAB2(SCH_1):PVCCIOMCP_CPU0
 E18 PVCCIOMCP_CPU0  IOE18 @BASEBOARD_FAB2_LIB.BASEBOARD_FAB2(SCH_1):PVCCIOMCP_CPU0
 E19 PVCCIOMCP_CPU0  IOE19 @BASEBOARD_FAB2_LIB.BASEBOARD_FAB2(SCH_1):PVCCIOMCP_CPU0
  E2    GND   IOE2 @BASEBOARD_FAB2_LIB.BASEBOARD_FAB2(SCH_1):GND
 E20 SVID_CLK1_CPU0_R  IOE20 @BASEBOARD_FAB2_LIB.BASEBOARD_FAB2(SCH_1):SVID_CLK1_CPU0_R
  E3    GND   IOE3 @BASEBOARD_FAB2_LIB.BASEBOARD_FAB2(SCH_1):GND
  E4    GND   IOE4 @BASEBOARD_FAB2_LIB.BASEBOARD_FAB2(SCH_1):GND
  E5    GND   IOE5 @BASEBOARD_FAB2_LIB.BASEBOARD_FAB2(SCH_1):GND
  E6    GND   IOE6 @BASEBOARD_FAB2_LIB.BASEBOARD_FAB2(SCH_1):GND
  E7    GND   IOE7 @BASEBOARD_FAB2_LIB.BASEBOARD_FAB2(SCH_1):GND
  E8 VSENSE_PVCCIOMCP_CPU0_SKT_VSEN   IOE8 @BASEBOARD_FAB2_LIB.BASEBOARD_FAB2(SCH_1):VSENSE_PVCCIOMCP_CPU0_SKT_VSEN
  E9    GND   IOE9 @BASEBOARD_FAB2_LIB.BASEBOARD_FAB2(SCH_1):GND
  F1 PVCCIO_CPU0   IOF1 @BASEBOARD_FAB2_LIB.BASEBOARD_FAB2(SCH_1):PVCCIO_CPU0
 F10 VR_PVCCMCP_CPU0_XADDR2  IOF10 @BASEBOARD_FAB2_LIB.BASEBOARD_FAB2(SCH_1):VR_PVCCMCP_CPU0_XADDR2
 F11    GND  IOF11 @BASEBOARD_FAB2_LIB.BASEBOARD_FAB2(SCH_1):GND
 F12    GND  IOF12 @BASEBOARD_FAB2_LIB.BASEBOARD_FAB2(SCH_1):GND
 F13    GND  IOF13 @BASEBOARD_FAB2_LIB.BASEBOARD_FAB2(SCH_1):GND
 F14    GND  IOF14 @BASEBOARD_FAB2_LIB.BASEBOARD_FAB2(SCH_1):GND
 F15 PVCCIOMCP_CPU0  IOF15 @BASEBOARD_FAB2_LIB.BASEBOARD_FAB2(SCH_1):PVCCIOMCP_CPU0
 F16 PVCCIOMCP_CPU0  IOF16 @BASEBOARD_FAB2_LIB.BASEBOARD_FAB2(SCH_1):PVCCIOMCP_CPU0
 F17 PVCCIOMCP_CPU0  IOF17 @BASEBOARD_FAB2_LIB.BASEBOARD_FAB2(SCH_1):PVCCIOMCP_CPU0
 F18 PVCCIOMCP_CPU0  IOF18 @BASEBOARD_FAB2_LIB.BASEBOARD_FAB2(SCH_1):PVCCIOMCP_CPU0
 F19 PVCCIOMCP_CPU0  IOF19 @BASEBOARD_FAB2_LIB.BASEBOARD_FAB2(SCH_1):PVCCIOMCP_CPU0
  F2    GND   IOF2 @BASEBOARD_FAB2_LIB.BASEBOARD_FAB2(SCH_1):GND
 F20 SVID_DIO1_CPU0_R  IOF20 @BASEBOARD_FAB2_LIB.BASEBOARD_FAB2(SCH_1):SVID_DIO1_CPU0_R
  F3    GND   IOF3 @BASEBOARD_FAB2_LIB.BASEBOARD_FAB2(SCH_1):GND
  F4    GND   IOF4 @BASEBOARD_FAB2_LIB.BASEBOARD_FAB2(SCH_1):GND
  F5    GND   IOF5 @BASEBOARD_FAB2_LIB.BASEBOARD_FAB2(SCH_1):GND
  F6    GND   IOF6 @BASEBOARD_FAB2_LIB.BASEBOARD_FAB2(SCH_1):GND
  F7    GND   IOF7 @BASEBOARD_FAB2_LIB.BASEBOARD_FAB2(SCH_1):GND
  F8 VSENSE_PVCCIOMCP_CPU0_SKT_VRTN   IOF8 @BASEBOARD_FAB2_LIB.BASEBOARD_FAB2(SCH_1):VSENSE_PVCCIOMCP_CPU0_SKT_VRTN
  F9    GND   IOF9 @BASEBOARD_FAB2_LIB.BASEBOARD_FAB2(SCH_1):GND

CAP_A_0402V-1.0UF,6.3V,10%,X6SA  I86  C3N40
   1 PVCCIOMCP_CPU0      A @BASEBOARD_FAB2_LIB.BASEBOARD_FAB2(SCH_1):PVCCIOMCP_CPU0
   2    GND      B @BASEBOARD_FAB2_LIB.BASEBOARD_FAB2(SCH_1):GND

CAP_A_0402V-1.0UF,6.3V,10%,X6SA  I99  C3M46
   1 PVCCIOMCP_CPU0      A @BASEBOARD_FAB2_LIB.BASEBOARD_FAB2(SCH_1):PVCCIOMCP_CPU0
   2    GND      B @BASEBOARD_FAB2_LIB.BASEBOARD_FAB2(SCH_1):GND

CAPP_3018-470UF,2.5V,20%,ALUM,A  I101  C3N14
   1 PVCCIOMCP_CPU0      A @BASEBOARD_FAB2_LIB.BASEBOARD_FAB2(SCH_1):PVCCIOMCP_CPU0
   2    GND      B @BASEBOARD_FAB2_LIB.BASEBOARD_FAB2(SCH_1):GND

CAP_A_0603V-47UF,4V,20%,X5R,60A  I149  C3T1
   1 P1V8_MCP_CPU0      A @BASEBOARD_FAB2_LIB.BASEBOARD_FAB2(SCH_1):P1V8_MCP_CPU0
   2    GND      B @BASEBOARD_FAB2_LIB.BASEBOARD_FAB2(SCH_1):GND

CAP_A_0603V-47UF,4V,20%,X5R,60A  I150  C3T2
   1 P1V8_MCP_CPU0      A @BASEBOARD_FAB2_LIB.BASEBOARD_FAB2(SCH_1):P1V8_MCP_CPU0
   2    GND      B @BASEBOARD_FAB2_LIB.BASEBOARD_FAB2(SCH_1):GND

RES_0402-4.02K,1%,1/16W,CHIP,GA  I155  R7C24
   1 VR_PVCCMCP_CPU0_XADDR2      A @BASEBOARD_FAB2_LIB.BASEBOARD_FAB2(SCH_1):VR_PVCCMCP_CPU0_XADDR2
   2    GND      B @BASEBOARD_FAB2_LIB.BASEBOARD_FAB2(SCH_1):GND

RES_0402-16K,1.0%,1/16W,CHIP,GA  I156  R3N29
   1 VR_PVCCIOMCP_CPU0_XADDR1      A @BASEBOARD_FAB2_LIB.BASEBOARD_FAB2(SCH_1):VR_PVCCIOMCP_CPU0_XADDR1
   2    GND      B @BASEBOARD_FAB2_LIB.BASEBOARD_FAB2(SCH_1):GND


DRAWING: @BASEBOARD_FAB2_LIB.BASEBOARD_FAB2(SCH_1):PAGE195 

CONN3_G98259001_PIP-CONN,G9825A  I26  RM1E1
   1    GND    IO1 @BASEBOARD_FAB2_LIB.BASEBOARD_FAB2(SCH_1):GND
   2    GND    IO2 @BASEBOARD_FAB2_LIB.BASEBOARD_FAB2(SCH_1):GND
   3    GND    IO3 @BASEBOARD_FAB2_LIB.BASEBOARD_FAB2(SCH_1):GND

CONN12_G98257001_THMT-CONN,G98A  I29  J1E1
  A1 P12V_PSU     A1 @BASEBOARD_FAB2_LIB.BASEBOARD_FAB2(SCH_1):P12V_PSU
  A2 P12V_PSU     A2 @BASEBOARD_FAB2_LIB.BASEBOARD_FAB2(SCH_1):P12V_PSU
  A3 P12V_PSU     A3 @BASEBOARD_FAB2_LIB.BASEBOARD_FAB2(SCH_1):P12V_PSU
  B1 P12V_PSU     B1 @BASEBOARD_FAB2_LIB.BASEBOARD_FAB2(SCH_1):P12V_PSU
  B2 P12V_PSU     B2 @BASEBOARD_FAB2_LIB.BASEBOARD_FAB2(SCH_1):P12V_PSU
  B3 P12V_PSU     B3 @BASEBOARD_FAB2_LIB.BASEBOARD_FAB2(SCH_1):P12V_PSU
  C1    GND     C1 @BASEBOARD_FAB2_LIB.BASEBOARD_FAB2(SCH_1):GND
  C2    GND     C2 @BASEBOARD_FAB2_LIB.BASEBOARD_FAB2(SCH_1):GND
  C3    GND     C3 @BASEBOARD_FAB2_LIB.BASEBOARD_FAB2(SCH_1):GND
  D1    GND     D1 @BASEBOARD_FAB2_LIB.BASEBOARD_FAB2(SCH_1):GND
  D2    GND     D2 @BASEBOARD_FAB2_LIB.BASEBOARD_FAB2(SCH_1):GND
  D3    GND     D3 @BASEBOARD_FAB2_LIB.BASEBOARD_FAB2(SCH_1):GND

CAP_0805-10UF,16V,10%,X6S,C953A  I31  C9R5
   1 P12V_PSU      A @BASEBOARD_FAB2_LIB.BASEBOARD_FAB2(SCH_1):P12V_PSU
   2    GND      B @BASEBOARD_FAB2_LIB.BASEBOARD_FAB2(SCH_1):GND

CAP_0805-10UF,16V,10%,X6S,C953A  I32  C1E12
   1 P12V_PSU      A @BASEBOARD_FAB2_LIB.BASEBOARD_FAB2(SCH_1):P12V_PSU
   2    GND      B @BASEBOARD_FAB2_LIB.BASEBOARD_FAB2(SCH_1):GND

CAP_0805-10UF,16V,10%,X6S,C953A  I35  C1E15
   1 P12V_PSU      A @BASEBOARD_FAB2_LIB.BASEBOARD_FAB2(SCH_1):P12V_PSU
   2    GND      B @BASEBOARD_FAB2_LIB.BASEBOARD_FAB2(SCH_1):GND

CAP_A_0402V-0.1UF,16V,10%,X7R,A  I36  C9R12
   1 P12V_PSU      A @BASEBOARD_FAB2_LIB.BASEBOARD_FAB2(SCH_1):P12V_PSU
   2    GND      B @BASEBOARD_FAB2_LIB.BASEBOARD_FAB2(SCH_1):GND

CAP_A_0402V-0.1UF,16V,10%,X7R,A  I37  C9R6
   1 P12V_PSU      A @BASEBOARD_FAB2_LIB.BASEBOARD_FAB2(SCH_1):P12V_PSU
   2    GND      B @BASEBOARD_FAB2_LIB.BASEBOARD_FAB2(SCH_1):GND

CAP_A_0402V-0.1UF,16V,10%,X7R,A  I38  C1E17
   1 P12V_PSU      A @BASEBOARD_FAB2_LIB.BASEBOARD_FAB2(SCH_1):P12V_PSU
   2    GND      B @BASEBOARD_FAB2_LIB.BASEBOARD_FAB2(SCH_1):GND

CAP_A_0402V-0.1UF,16V,10%,X7R,A  I39  C1E16
   1 P12V_PSU      A @BASEBOARD_FAB2_LIB.BASEBOARD_FAB2(SCH_1):P12V_PSU
   2    GND      B @BASEBOARD_FAB2_LIB.BASEBOARD_FAB2(SCH_1):GND

MTG_KEYHOLE_TH-EMPTY,NA  I49  TH4G1
   1    GND      1 @BASEBOARD_FAB2_LIB.BASEBOARD_FAB2(SCH_1):GND

MTG_KEYHOLE_TH-EMPTY,NA  I52  TH9G1
   1    GND      1 @BASEBOARD_FAB2_LIB.BASEBOARD_FAB2(SCH_1):GND

MTG_KEYHOLE_TH-EMPTY,NA  I54  TH9A1
   1    GND      1 @BASEBOARD_FAB2_LIB.BASEBOARD_FAB2(SCH_1):GND

MTG_KEYHOLE_TH-EMPTY,NA  I56  TH1A1
   1    GND      1 @BASEBOARD_FAB2_LIB.BASEBOARD_FAB2(SCH_1):GND

MTG_KEYHOLE_TH-EMPTY,NA  I62  TH4A1
   1    GND      1 @BASEBOARD_FAB2_LIB.BASEBOARD_FAB2(SCH_1):GND

MTG_KEYHOLE_TH-EMPTY,NA  I65  TH7A1
   1    GND      1 @BASEBOARD_FAB2_LIB.BASEBOARD_FAB2(SCH_1):GND

MTG_KEYHOLE_TH-EMPTY,NA  I67  TH7G1
   1    GND      1 @BASEBOARD_FAB2_LIB.BASEBOARD_FAB2(SCH_1):GND

CAPTIVE_SCREW_TH-HDW,H57868-001  I76  RM1G1
CONN12_G98257001_THMT-CONN,G98A  I78  J1D1
  A1 P12V_PSU     A1 @BASEBOARD_FAB2_LIB.BASEBOARD_FAB2(SCH_1):P12V_PSU
  A2 P12V_PSU     A2 @BASEBOARD_FAB2_LIB.BASEBOARD_FAB2(SCH_1):P12V_PSU
  A3 P12V_PSU     A3 @BASEBOARD_FAB2_LIB.BASEBOARD_FAB2(SCH_1):P12V_PSU
  B1 P12V_PSU     B1 @BASEBOARD_FAB2_LIB.BASEBOARD_FAB2(SCH_1):P12V_PSU
  B2 P12V_PSU     B2 @BASEBOARD_FAB2_LIB.BASEBOARD_FAB2(SCH_1):P12V_PSU
  B3 P12V_PSU     B3 @BASEBOARD_FAB2_LIB.BASEBOARD_FAB2(SCH_1):P12V_PSU
  C1    GND     C1 @BASEBOARD_FAB2_LIB.BASEBOARD_FAB2(SCH_1):GND
  C2    GND     C2 @BASEBOARD_FAB2_LIB.BASEBOARD_FAB2(SCH_1):GND
  C3    GND     C3 @BASEBOARD_FAB2_LIB.BASEBOARD_FAB2(SCH_1):GND
  D1    GND     D1 @BASEBOARD_FAB2_LIB.BASEBOARD_FAB2(SCH_1):GND
  D2    GND     D2 @BASEBOARD_FAB2_LIB.BASEBOARD_FAB2(SCH_1):GND
  D3    GND     D3 @BASEBOARD_FAB2_LIB.BASEBOARD_FAB2(SCH_1):GND

CAPP_4040LF-470UF,16V,20%,ALUMA  I82  C4F6
   1 P12V_STBY      A @BASEBOARD_FAB2_LIB.BASEBOARD_FAB2(SCH_1):P12V_STBY
   2    GND      B @BASEBOARD_FAB2_LIB.BASEBOARD_FAB2(SCH_1):GND

CAPP_4040LF-470UF,16V,20%,ALUMA  I83  C4B13
   1 P12V_STBY      A @BASEBOARD_FAB2_LIB.BASEBOARD_FAB2(SCH_1):P12V_STBY
   2    GND      B @BASEBOARD_FAB2_LIB.BASEBOARD_FAB2(SCH_1):GND

CAPP_4040LF-470UF,16V,20%,ALUMA  I84  C1B14
   1 P12V_STBY      A @BASEBOARD_FAB2_LIB.BASEBOARD_FAB2(SCH_1):P12V_STBY
   2    GND      B @BASEBOARD_FAB2_LIB.BASEBOARD_FAB2(SCH_1):GND

CAPP_4040LF-470UF,16V,20%,ALUMA  I85  C1F7
   1 P12V_STBY      A @BASEBOARD_FAB2_LIB.BASEBOARD_FAB2(SCH_1):P12V_STBY
   2    GND      B @BASEBOARD_FAB2_LIB.BASEBOARD_FAB2(SCH_1):GND

CAPP_3018-68UF,16V,20%,TANT,72A  I96  C4F5
   1 P12V_STBY      A @BASEBOARD_FAB2_LIB.BASEBOARD_FAB2(SCH_1):P12V_STBY
   2    GND      B @BASEBOARD_FAB2_LIB.BASEBOARD_FAB2(SCH_1):GND

CAPP_3018-68UF,16V,20%,TANT,72A  I97  C4B14
   1 P12V_STBY      A @BASEBOARD_FAB2_LIB.BASEBOARD_FAB2(SCH_1):P12V_STBY
   2    GND      B @BASEBOARD_FAB2_LIB.BASEBOARD_FAB2(SCH_1):GND

CAPP_3018-68UF,16V,20%,TANT,72A  I98  C3T6
   1 P12V_STBY      A @BASEBOARD_FAB2_LIB.BASEBOARD_FAB2(SCH_1):P12V_STBY
   2    GND      B @BASEBOARD_FAB2_LIB.BASEBOARD_FAB2(SCH_1):GND

CAPP_3018-68UF,16V,20%,TANT,72A  I99  C9M3
   1 P12V_STBY      A @BASEBOARD_FAB2_LIB.BASEBOARD_FAB2(SCH_1):P12V_STBY
   2    GND      B @BASEBOARD_FAB2_LIB.BASEBOARD_FAB2(SCH_1):GND

CAPP_3018-68UF,16V,20%,TANT,72A  I100  C3B6
   1 P12V_STBY      A @BASEBOARD_FAB2_LIB.BASEBOARD_FAB2(SCH_1):P12V_STBY
   2    GND      B @BASEBOARD_FAB2_LIB.BASEBOARD_FAB2(SCH_1):GND

CAPP_3018-68UF,16V,20%,TANT,72A  I101  C1R23
   1 P12V_STBY      A @BASEBOARD_FAB2_LIB.BASEBOARD_FAB2(SCH_1):P12V_STBY
   2    GND      B @BASEBOARD_FAB2_LIB.BASEBOARD_FAB2(SCH_1):GND

CAPP_3018-68UF,16V,20%,TANT,72A  I102  C4M6
   1 P12V_STBY      A @BASEBOARD_FAB2_LIB.BASEBOARD_FAB2(SCH_1):P12V_STBY
   2    GND      B @BASEBOARD_FAB2_LIB.BASEBOARD_FAB2(SCH_1):GND

CAPP_3018-68UF,16V,20%,TANT,72A  I103  C1M5
   1 P12V_STBY      A @BASEBOARD_FAB2_LIB.BASEBOARD_FAB2(SCH_1):P12V_STBY
   2    GND      B @BASEBOARD_FAB2_LIB.BASEBOARD_FAB2(SCH_1):GND

CAPP_3018-68UF,16V,20%,TANT,72A  I104  C3T13
   1 P12V_STBY      A @BASEBOARD_FAB2_LIB.BASEBOARD_FAB2(SCH_1):P12V_STBY
   2    GND      B @BASEBOARD_FAB2_LIB.BASEBOARD_FAB2(SCH_1):GND

CAPP_3018-68UF,16V,20%,TANT,72A  I105  C4M7
   1 P12V_STBY      A @BASEBOARD_FAB2_LIB.BASEBOARD_FAB2(SCH_1):P12V_STBY
   2    GND      B @BASEBOARD_FAB2_LIB.BASEBOARD_FAB2(SCH_1):GND

CAPP_3018-68UF,16V,20%,TANT,72A  I106  C3T15
   1 P12V_STBY      A @BASEBOARD_FAB2_LIB.BASEBOARD_FAB2(SCH_1):P12V_STBY
   2    GND      B @BASEBOARD_FAB2_LIB.BASEBOARD_FAB2(SCH_1):GND

CAPP_3018-68UF,16V,20%,TANT,72A  I108  C7M6
   1 P12V_STBY      A @BASEBOARD_FAB2_LIB.BASEBOARD_FAB2(SCH_1):P12V_STBY
   2    GND      B @BASEBOARD_FAB2_LIB.BASEBOARD_FAB2(SCH_1):GND

CAPP_3018-68UF,16V,20%,TANT,72A  I109  C6N5
   1 P12V_STBY      A @BASEBOARD_FAB2_LIB.BASEBOARD_FAB2(SCH_1):P12V_STBY
   2    GND      B @BASEBOARD_FAB2_LIB.BASEBOARD_FAB2(SCH_1):GND

CAPP_3018-68UF,16V,20%,TANT,72A  I111  C9T3
   1 P12V_STBY      A @BASEBOARD_FAB2_LIB.BASEBOARD_FAB2(SCH_1):P12V_STBY
   2    GND      B @BASEBOARD_FAB2_LIB.BASEBOARD_FAB2(SCH_1):GND

CAPP_3018-68UF,16V,20%,TANT,72A  I112  C4F4
   1 P12V_STBY      A @BASEBOARD_FAB2_LIB.BASEBOARD_FAB2(SCH_1):P12V_STBY
   2    GND      B @BASEBOARD_FAB2_LIB.BASEBOARD_FAB2(SCH_1):GND

CAPP_3018-68UF,16V,20%,TANT,72A  I113  C3T3
   1 P12V_STBY      A @BASEBOARD_FAB2_LIB.BASEBOARD_FAB2(SCH_1):P12V_STBY
   2    GND      B @BASEBOARD_FAB2_LIB.BASEBOARD_FAB2(SCH_1):GND


DRAWING: @BASEBOARD_FAB2_LIB.BASEBOARD_FAB2(SCH_1):PAGE196 

RES_0402-1.00K,1%,1/16W,CHIP,GA  I46  R2U43
   1 P3V_BAT_SOURCE      A @BASEBOARD_FAB2_LIB.BASEBOARD_FAB2(SCH_1):P3V_BAT_SOURCE
   2 A_P3V_BAT_R      B @BASEBOARD_FAB2_LIB.BASEBOARD_FAB2(SCH_1):A_P3V_BAT_R

BATTERY_PLCLF-202168-001  I47  BT8G1
VERT_BATT_3PIN_PIP-3PVERT,C686A  I51  XBT8G1
   3    GND      N @BASEBOARD_FAB2_LIB.BASEBOARD_FAB2(SCH_1):GND
   1 P3V_BAT_SOURCE     P1 @BASEBOARD_FAB2_LIB.BASEBOARD_FAB2(SCH_1):P3V_BAT_SOURCE
   2 P3V_BAT_SOURCE     P2 @BASEBOARD_FAB2_LIB.BASEBOARD_FAB2(SCH_1):P3V_BAT_SOURCE

DIODE2A_DUAL_SMLF-BAS70-05,DIOA  I53  CR2U1
   3 P3V3_RTC_STBY      C @BASEBOARD_FAB2_LIB.BASEBOARD_FAB2(SCH_1):P3V3_RTC_STBY
   1 P3V3_STBY     A1 @BASEBOARD_FAB2_LIB.BASEBOARD_FAB2(SCH_1):P3V3_STBY
   2 A_P3V_BAT_R     A2 @BASEBOARD_FAB2_LIB.BASEBOARD_FAB2(SCH_1):A_P3V_BAT_R

RES_0402-4.75K,1%,1/16W,CHIP,GA  I59  R3P44
   1 P3V3_STBY      A @BASEBOARD_FAB2_LIB.BASEBOARD_FAB2(SCH_1):P3V3_STBY
   2 PWRGD_DSW_PWROK      B @BASEBOARD_FAB2_LIB.BASEBOARD_FAB2(SCH_1):PWRGD_DSW_PWROK

CAP_0402-0.047UF,25V,10%,X7R,AA  I60  C3P45
   1 A_ADM1085_CEXT      A @BASEBOARD_FAB2_LIB.BASEBOARD_FAB2(SCH_1):A_ADM1085_CEXT
   2    GND      B @BASEBOARD_FAB2_LIB.BASEBOARD_FAB2(SCH_1):GND

RES_0402-100.0,1%,1/16W,CHIP,GA  I65  R2P20
   1 PWRGD_P5V_R      A @BASEBOARD_FAB2_LIB.BASEBOARD_FAB2(SCH_1):PWRGD_P5V_R
   2 PWRGD_P5V      B @BASEBOARD_FAB2_LIB.BASEBOARD_FAB2(SCH_1):PWRGD_P5V

RES_0402-49.9,1%,1/16W,CHIP,G2A  I68  R1L16
   1 PWRGD_P3V3_R1      A @BASEBOARD_FAB2_LIB.BASEBOARD_FAB2(SCH_1):PWRGD_P3V3_R1
   2 PWRGD_P3V3      B @BASEBOARD_FAB2_LIB.BASEBOARD_FAB2(SCH_1):PWRGD_P3V3

ADM1085_SMT-IC,H46130-001  I70  U7D3
   5 A_ADM1085_CEXT   CEXT @BASEBOARD_FAB2_LIB.BASEBOARD_FAB2(SCH_1):A_ADM1085_CEXT
   1 PWRGD_P3V3_STBY   ENIN @BASEBOARD_FAB2_LIB.BASEBOARD_FAB2(SCH_1):PWRGD_P3V3_STBY
   4 PWRGD_DSW_PWROK  ENOUT @BASEBOARD_FAB2_LIB.BASEBOARD_FAB2(SCH_1):PWRGD_DSW_PWROK
   2    GND    GND @BASEBOARD_FAB2_LIB.BASEBOARD_FAB2(SCH_1):GND
   6 P3V3_STBY    VCC @BASEBOARD_FAB2_LIB.BASEBOARD_FAB2(SCH_1):P3V3_STBY
   3 VSENSE_P12V_ADM1085    VIN @BASEBOARD_FAB2_LIB.BASEBOARD_FAB2(SCH_1):VSENSE_P12V_ADM1085

RES_0402-10.0K,1%,1/16W,EMPTY,A  I71  R3P50
   1 P3V3_STBY      A @BASEBOARD_FAB2_LIB.BASEBOARD_FAB2(SCH_1):P3V3_STBY
   2 PWRGD_P3V3_STBY      B @BASEBOARD_FAB2_LIB.BASEBOARD_FAB2(SCH_1):PWRGD_P3V3_STBY

CAP_A_0402V-0.1UF,16V,10%,X7R,A  I72  C3P46
   1 P3V3_STBY      A @BASEBOARD_FAB2_LIB.BASEBOARD_FAB2(SCH_1):P3V3_STBY
   2    GND      B @BASEBOARD_FAB2_LIB.BASEBOARD_FAB2(SCH_1):GND

RES_0402-90.9K,1%,1/16W,CHIP,GA  I74  R3P48
   1 P12V_STBY      A @BASEBOARD_FAB2_LIB.BASEBOARD_FAB2(SCH_1):P12V_STBY
   2 VSENSE_P12V_ADM1085      B @BASEBOARD_FAB2_LIB.BASEBOARD_FAB2(SCH_1):VSENSE_P12V_ADM1085

RES_0402-6.34K,1%,1/16W,CHIP,GA  I75  R3P51
   1 VSENSE_P12V_ADM1085      A @BASEBOARD_FAB2_LIB.BASEBOARD_FAB2(SCH_1):VSENSE_P12V_ADM1085
   2    GND      B @BASEBOARD_FAB2_LIB.BASEBOARD_FAB2(SCH_1):GND

ADM809_SMLF-IC,D23047-001-GND=A  I80  U1L3
   3   P3V3    VCC @BASEBOARD_FAB2_LIB.BASEBOARD_FAB2(SCH_1):P3V3
   2 PWRGD_P3V3_R1 RESET_N @BASEBOARD_FAB2_LIB.BASEBOARD_FAB2(SCH_1):PWRGD_P3V3_R1

CAP_A_0402V-0.1UF,16V,10%,X7R,A  I81  C1L16
   1   P3V3      A @BASEBOARD_FAB2_LIB.BASEBOARD_FAB2(SCH_1):P3V3
   2    GND      B @BASEBOARD_FAB2_LIB.BASEBOARD_FAB2(SCH_1):GND

ADM809_SMLF-IC,D23047-001-GND=A  I89  U8E2
   3 PWRGD_P12V_HSC    VCC @BASEBOARD_FAB2_LIB.BASEBOARD_FAB2(SCH_1):PWRGD_P12V_HSC
   2 PWRGD_P12V_HSC_DLY_R RESET_N @BASEBOARD_FAB2_LIB.BASEBOARD_FAB2(SCH_1):PWRGD_P12V_HSC_DLY_R

RES_0402-22.1,1.0%,1/16W,CHIP,A  I90  R8E7
   1 PWRGD_P12V_HSC_DLY_R      A @BASEBOARD_FAB2_LIB.BASEBOARD_FAB2(SCH_1):PWRGD_P12V_HSC_DLY_R
   2 PWRGD_P12V_HSC_DLY      B @BASEBOARD_FAB2_LIB.BASEBOARD_FAB2(SCH_1):PWRGD_P12V_HSC_DLY

CAP_A_0402V-0.1UF,16V,10%,X7R,A  I94  C8E3
   1 PWRGD_P12V_HSC      A @BASEBOARD_FAB2_LIB.BASEBOARD_FAB2(SCH_1):PWRGD_P12V_HSC
   2    GND      B @BASEBOARD_FAB2_LIB.BASEBOARD_FAB2(SCH_1):GND

CAP_A_0402V-1.0UF,6.3V,10%,X6SA  I102  C2U26
   1 P3V3_RTC_STBY      A @BASEBOARD_FAB2_LIB.BASEBOARD_FAB2(SCH_1):P3V3_RTC_STBY
   2    GND      B @BASEBOARD_FAB2_LIB.BASEBOARD_FAB2(SCH_1):GND

DIODE_SMLF-BAT54WS,IC,C73510-0A  I103  CR7E1
   1 PWRGD_P3V3_STBY      C @BASEBOARD_FAB2_LIB.BASEBOARD_FAB2(SCH_1):PWRGD_P3V3_STBY
   2 PWRGD_DSW_PWROK      A @BASEBOARD_FAB2_LIB.BASEBOARD_FAB2(SCH_1):PWRGD_DSW_PWROK

TPS3700_SM-IC,H69492-001  I104  U8D8
   5    GND    GND @BASEBOARD_FAB2_LIB.BASEBOARD_FAB2(SCH_1):GND
   4 A_PG_P12V_MAIN   INAP @BASEBOARD_FAB2_LIB.BASEBOARD_FAB2(SCH_1):A_PG_P12V_MAIN
   3 A_PG_P5V   INBN @BASEBOARD_FAB2_LIB.BASEBOARD_FAB2(SCH_1):A_PG_P5V
   6 PWRGD_P12V_MAIN_R   OUTA @BASEBOARD_FAB2_LIB.BASEBOARD_FAB2(SCH_1):PWRGD_P12V_MAIN_R
   1 PWRGD_P5V_N   OUTB @BASEBOARD_FAB2_LIB.BASEBOARD_FAB2(SCH_1):PWRGD_P5V_N
   2 P3V3_STBY    VDD @BASEBOARD_FAB2_LIB.BASEBOARD_FAB2(SCH_1):P3V3_STBY

CAP_A_0402V-0.1UF,16V,10%,X7R,A  I105  C8D4
   1 P3V3_STBY      A @BASEBOARD_FAB2_LIB.BASEBOARD_FAB2(SCH_1):P3V3_STBY
   2    GND      B @BASEBOARD_FAB2_LIB.BASEBOARD_FAB2(SCH_1):GND

RES_0402-100.0,1%,1/16W,CHIP,GA  I106  R8D42
   1 PWRGD_P12V_MAIN_R      A @BASEBOARD_FAB2_LIB.BASEBOARD_FAB2(SCH_1):PWRGD_P12V_MAIN_R
   2 PWRGD_P12V_MAIN      B @BASEBOARD_FAB2_LIB.BASEBOARD_FAB2(SCH_1):PWRGD_P12V_MAIN

RES_0402-100.0K,1%,1/16W,CHIP,A  I112  R8D38
   1   P12V      A @BASEBOARD_FAB2_LIB.BASEBOARD_FAB2(SCH_1):P12V
   2 A_PG_P12V_MAIN      B @BASEBOARD_FAB2_LIB.BASEBOARD_FAB2(SCH_1):A_PG_P12V_MAIN

RES_0402-3.74K,1%,1/16W,CHIP,GA  I113  R8D40
   1 A_PG_P12V_MAIN      A @BASEBOARD_FAB2_LIB.BASEBOARD_FAB2(SCH_1):A_PG_P12V_MAIN
   2    GND      B @BASEBOARD_FAB2_LIB.BASEBOARD_FAB2(SCH_1):GND

RES_0402-49.9K,1%,1/16W,CHIP,GA  I114  R8D39
   1    P5V      A @BASEBOARD_FAB2_LIB.BASEBOARD_FAB2(SCH_1):P5V
   2 A_PG_P5V      B @BASEBOARD_FAB2_LIB.BASEBOARD_FAB2(SCH_1):A_PG_P5V

RES_0402-4.75K,1%,1/16W,CHIP,GA  I115  R8D37
   1 A_PG_P5V      A @BASEBOARD_FAB2_LIB.BASEBOARD_FAB2(SCH_1):A_PG_P5V
   2    GND      B @BASEBOARD_FAB2_LIB.BASEBOARD_FAB2(SCH_1):GND

RES_0402-10.0K,1%,1/16W,CHIP,GA  I120  R8D41
   1 P3V3_STBY      A @BASEBOARD_FAB2_LIB.BASEBOARD_FAB2(SCH_1):P3V3_STBY
   2 PWRGD_P12V_MAIN_R      B @BASEBOARD_FAB2_LIB.BASEBOARD_FAB2(SCH_1):PWRGD_P12V_MAIN_R

RES_0402-10.0K,1%,1/16W,CHIP,GA  I121  R2P18
   1 P3V3_STBY      A @BASEBOARD_FAB2_LIB.BASEBOARD_FAB2(SCH_1):P3V3_STBY
   2 PWRGD_P5V_N      B @BASEBOARD_FAB2_LIB.BASEBOARD_FAB2(SCH_1):PWRGD_P5V_N

RES_0402-10.0K,1%,1/16W,CHIP,GA  I122  R2P21
   1 P3V3_STBY      A @BASEBOARD_FAB2_LIB.BASEBOARD_FAB2(SCH_1):P3V3_STBY
   2 PWRGD_P5V_R      B @BASEBOARD_FAB2_LIB.BASEBOARD_FAB2(SCH_1):PWRGD_P5V_R

FET_N_SOT23-2N7002,FET,C79254-A  I124  Q2P2
   1 PWRGD_P5V_N   GATE @BASEBOARD_FAB2_LIB.BASEBOARD_FAB2(SCH_1):PWRGD_P5V_N
   2    GND    SRC @BASEBOARD_FAB2_LIB.BASEBOARD_FAB2(SCH_1):GND
   3 PWRGD_P5V_R    DRN @BASEBOARD_FAB2_LIB.BASEBOARD_FAB2(SCH_1):PWRGD_P5V_R

DIODE_SMLF-BAT54WS,IC,C73510-0A  I128  CR8E1
   1 PWRGD_P12V_HSC      C @BASEBOARD_FAB2_LIB.BASEBOARD_FAB2(SCH_1):PWRGD_P12V_HSC
   2 PWRGD_P12V_HSC_DLY      A @BASEBOARD_FAB2_LIB.BASEBOARD_FAB2(SCH_1):PWRGD_P12V_HSC_DLY


DRAWING: @BASEBOARD_FAB2_LIB.BASEBOARD_FAB2(SCH_1):PAGE197 

CAP_0805-10UF,16V,10%,X7R,G106A  I52  C6U18
   1 P12V_NVDIMM_ABC      A @BASEBOARD_FAB2_LIB.BASEBOARD_FAB2(SCH_1):P12V_NVDIMM_ABC
   2    GND      B @BASEBOARD_FAB2_LIB.BASEBOARD_FAB2(SCH_1):GND

CAP_0805-10UF,16V,10%,X7R,G106A  I54  C6T2
   1 P12V_NVDIMM_ABC      A @BASEBOARD_FAB2_LIB.BASEBOARD_FAB2(SCH_1):P12V_NVDIMM_ABC
   2    GND      B @BASEBOARD_FAB2_LIB.BASEBOARD_FAB2(SCH_1):GND

CAP_0805-10UF,16V,10%,X7R,G106A  I59  C4B11
   1 P12V_NVDIMM_DEF      A @BASEBOARD_FAB2_LIB.BASEBOARD_FAB2(SCH_1):P12V_NVDIMM_DEF
   2    GND      B @BASEBOARD_FAB2_LIB.BASEBOARD_FAB2(SCH_1):GND

CAP_0805-10UF,16V,10%,X7R,G106A  I62  C4A4
   1 P12V_NVDIMM_DEF      A @BASEBOARD_FAB2_LIB.BASEBOARD_FAB2(SCH_1):P12V_NVDIMM_DEF
   2    GND      B @BASEBOARD_FAB2_LIB.BASEBOARD_FAB2(SCH_1):GND

CAP_0805-10UF,16V,10%,X7R,G106A  I65  C6U10
   1 P12V_NVDIMM_ABC      A @BASEBOARD_FAB2_LIB.BASEBOARD_FAB2(SCH_1):P12V_NVDIMM_ABC
   2    GND      B @BASEBOARD_FAB2_LIB.BASEBOARD_FAB2(SCH_1):GND

CAP_0805-10UF,16V,10%,X7R,G106A  I67  C4A17
   1 P12V_NVDIMM_DEF      A @BASEBOARD_FAB2_LIB.BASEBOARD_FAB2(SCH_1):P12V_NVDIMM_DEF
   2    GND      B @BASEBOARD_FAB2_LIB.BASEBOARD_FAB2(SCH_1):GND

CAP_0805-10UF,16V,10%,X7R,G106A  I70  C9T8
   1 P12V_NVDIMM_GHJ      A @BASEBOARD_FAB2_LIB.BASEBOARD_FAB2(SCH_1):P12V_NVDIMM_GHJ
   2    GND      B @BASEBOARD_FAB2_LIB.BASEBOARD_FAB2(SCH_1):GND

CAP_0805-10UF,16V,10%,X7R,G106A  I73  C9U11
   1 P12V_NVDIMM_GHJ      A @BASEBOARD_FAB2_LIB.BASEBOARD_FAB2(SCH_1):P12V_NVDIMM_GHJ
   2    GND      B @BASEBOARD_FAB2_LIB.BASEBOARD_FAB2(SCH_1):GND

CAP_0805-10UF,16V,10%,X7R,G106A  I76  C9U8
   1 P12V_NVDIMM_GHJ      A @BASEBOARD_FAB2_LIB.BASEBOARD_FAB2(SCH_1):P12V_NVDIMM_GHJ
   2    GND      B @BASEBOARD_FAB2_LIB.BASEBOARD_FAB2(SCH_1):GND

CAP_0805-10UF,16V,10%,X7R,G106A  I79  C1A4
   1 P12V_NVDIMM_KLM      A @BASEBOARD_FAB2_LIB.BASEBOARD_FAB2(SCH_1):P12V_NVDIMM_KLM
   2    GND      B @BASEBOARD_FAB2_LIB.BASEBOARD_FAB2(SCH_1):GND

CAP_0805-10UF,16V,10%,X7R,G106A  I82  C1B7
   1 P12V_NVDIMM_KLM      A @BASEBOARD_FAB2_LIB.BASEBOARD_FAB2(SCH_1):P12V_NVDIMM_KLM
   2    GND      B @BASEBOARD_FAB2_LIB.BASEBOARD_FAB2(SCH_1):GND

CAP_0805-10UF,16V,10%,X7R,G106A  I85  C1A16
   1 P12V_NVDIMM_KLM      A @BASEBOARD_FAB2_LIB.BASEBOARD_FAB2(SCH_1):P12V_NVDIMM_KLM
   2    GND      B @BASEBOARD_FAB2_LIB.BASEBOARD_FAB2(SCH_1):GND

MAX9634_SOT-IC,H35789-001  I97  U4F1
   1    GND GND<1> @BASEBOARD_FAB2_LIB.BASEBOARD_FAB2(SCH_1):GND
   2    GND GND<0> @BASEBOARD_FAB2_LIB.BASEBOARD_FAB2(SCH_1):GND
   3 VR_PVDDQ_ABC_AIINSEN_R    OUT @BASEBOARD_FAB2_LIB.BASEBOARD_FAB2(SCH_1):VR_PVDDQ_ABC_AIINSEN_R
   4 P12V_NVDIMM_ABC    RSN @BASEBOARD_FAB2_LIB.BASEBOARD_FAB2(SCH_1):P12V_NVDIMM_ABC
   5 P12V_STBY    RSP @BASEBOARD_FAB2_LIB.BASEBOARD_FAB2(SCH_1):P12V_STBY

RES_1206-0.002,1%,1W,CHIP,G521A  I99  R4F2
   1 P12V_NVDIMM_ABC      A @BASEBOARD_FAB2_LIB.BASEBOARD_FAB2(SCH_1):P12V_NVDIMM_ABC
   2 P12V_STBY      B @BASEBOARD_FAB2_LIB.BASEBOARD_FAB2(SCH_1):P12V_STBY

RES_0402-0.0,5%,1/16W,CHIP,G21A  I110  R4F1
   1 VR_PVDDQ_ABC_AIINSEN_R      A @BASEBOARD_FAB2_LIB.BASEBOARD_FAB2(SCH_1):VR_PVDDQ_ABC_AIINSEN_R
   2 VR_PVDDQ_ABC_AIINSEN      B @BASEBOARD_FAB2_LIB.BASEBOARD_FAB2(SCH_1):VR_PVDDQ_ABC_AIINSEN

RES_0402-0.0,5%,1/16W,CHIP,G21A  I113  R4B11
   1 VR_PVDDQ_DEF_AIINSEN_R      A @BASEBOARD_FAB2_LIB.BASEBOARD_FAB2(SCH_1):VR_PVDDQ_DEF_AIINSEN_R
   2 VR_PVDDQ_DEF_AIINSEN      B @BASEBOARD_FAB2_LIB.BASEBOARD_FAB2(SCH_1):VR_PVDDQ_DEF_AIINSEN

MAX9634_SOT-IC,H35789-001  I120  U4B1
   1    GND GND<1> @BASEBOARD_FAB2_LIB.BASEBOARD_FAB2(SCH_1):GND
   2    GND GND<0> @BASEBOARD_FAB2_LIB.BASEBOARD_FAB2(SCH_1):GND
   3 VR_PVDDQ_DEF_AIINSEN_R    OUT @BASEBOARD_FAB2_LIB.BASEBOARD_FAB2(SCH_1):VR_PVDDQ_DEF_AIINSEN_R
   4 P12V_NVDIMM_DEF    RSN @BASEBOARD_FAB2_LIB.BASEBOARD_FAB2(SCH_1):P12V_NVDIMM_DEF
   5 P12V_STBY    RSP @BASEBOARD_FAB2_LIB.BASEBOARD_FAB2(SCH_1):P12V_STBY

RES_1206-0.002,1%,1W,CHIP,G521A  I121  R4B12
   1 P12V_NVDIMM_DEF      A @BASEBOARD_FAB2_LIB.BASEBOARD_FAB2(SCH_1):P12V_NVDIMM_DEF
   2 P12V_STBY      B @BASEBOARD_FAB2_LIB.BASEBOARD_FAB2(SCH_1):P12V_STBY

RES_0402-0.0,5%,1/16W,CHIP,G21A  I126  R9T4
   1 VR_PVDDQ_GHJ_AIINSEN_R      A @BASEBOARD_FAB2_LIB.BASEBOARD_FAB2(SCH_1):VR_PVDDQ_GHJ_AIINSEN_R
   2 VR_PVDDQ_GHJ_AIINSEN      B @BASEBOARD_FAB2_LIB.BASEBOARD_FAB2(SCH_1):VR_PVDDQ_GHJ_AIINSEN

RES_1206-0.002,1%,1W,CHIP,G521A  I131  R1F3
   1 P12V_NVDIMM_GHJ      A @BASEBOARD_FAB2_LIB.BASEBOARD_FAB2(SCH_1):P12V_NVDIMM_GHJ
   2 P12V_STBY      B @BASEBOARD_FAB2_LIB.BASEBOARD_FAB2(SCH_1):P12V_STBY

MAX9634_SOT-IC,H35789-001  I133  U1F1
   1    GND GND<1> @BASEBOARD_FAB2_LIB.BASEBOARD_FAB2(SCH_1):GND
   2    GND GND<0> @BASEBOARD_FAB2_LIB.BASEBOARD_FAB2(SCH_1):GND
   3 VR_PVDDQ_GHJ_AIINSEN_R    OUT @BASEBOARD_FAB2_LIB.BASEBOARD_FAB2(SCH_1):VR_PVDDQ_GHJ_AIINSEN_R
   4 P12V_NVDIMM_GHJ    RSN @BASEBOARD_FAB2_LIB.BASEBOARD_FAB2(SCH_1):P12V_NVDIMM_GHJ
   5 P12V_STBY    RSP @BASEBOARD_FAB2_LIB.BASEBOARD_FAB2(SCH_1):P12V_STBY

RES_0402-0.0,5%,1/16W,CHIP,G21A  I137  R1B14
   1 VR_PVDDQ_KLM_AIINSEN_R      A @BASEBOARD_FAB2_LIB.BASEBOARD_FAB2(SCH_1):VR_PVDDQ_KLM_AIINSEN_R
   2 VR_PVDDQ_KLM_AIINSEN      B @BASEBOARD_FAB2_LIB.BASEBOARD_FAB2(SCH_1):VR_PVDDQ_KLM_AIINSEN

RES_1206-0.002,1%,1W,CHIP,G521A  I142  R9M4
   1 P12V_NVDIMM_KLM      A @BASEBOARD_FAB2_LIB.BASEBOARD_FAB2(SCH_1):P12V_NVDIMM_KLM
   2 P12V_STBY      B @BASEBOARD_FAB2_LIB.BASEBOARD_FAB2(SCH_1):P12V_STBY

MAX9634_SOT-IC,H35789-001  I144  U1B1
   1    GND GND<1> @BASEBOARD_FAB2_LIB.BASEBOARD_FAB2(SCH_1):GND
   2    GND GND<0> @BASEBOARD_FAB2_LIB.BASEBOARD_FAB2(SCH_1):GND
   3 VR_PVDDQ_KLM_AIINSEN_R    OUT @BASEBOARD_FAB2_LIB.BASEBOARD_FAB2(SCH_1):VR_PVDDQ_KLM_AIINSEN_R
   4 P12V_NVDIMM_KLM    RSN @BASEBOARD_FAB2_LIB.BASEBOARD_FAB2(SCH_1):P12V_NVDIMM_KLM
   5 P12V_STBY    RSP @BASEBOARD_FAB2_LIB.BASEBOARD_FAB2(SCH_1):P12V_STBY


DRAWING: @BASEBOARD_FAB2_LIB.BASEBOARD_FAB2(SCH_1):PAGE198 

SLG55021_SM-IC,G56246-001  I1  EU2T1
   4    GND    GND @BASEBOARD_FAB2_LIB.BASEBOARD_FAB2(SCH_1):GND
   9    GND  THPAD @BASEBOARD_FAB2_LIB.BASEBOARD_FAB2(SCH_1):GND
   1 P5V_STBY    VCC @BASEBOARD_FAB2_LIB.BASEBOARD_FAB2(SCH_1):P5V_STBY
   2 FM_P3V3_CPLD_EN     ON @BASEBOARD_FAB2_LIB.BASEBOARD_FAB2(SCH_1):FM_P3V3_CPLD_EN
   3 P5V_STBY SHDN_N @BASEBOARD_FAB2_LIB.BASEBOARD_FAB2(SCH_1):P5V_STBY
   5 P3V3_STBY      D @BASEBOARD_FAB2_LIB.BASEBOARD_FAB2(SCH_1):P3V3_STBY
   6   P3V3      S @BASEBOARD_FAB2_LIB.BASEBOARD_FAB2(SCH_1):P3V3
   7 P3V3_SWITCH_G      G @BASEBOARD_FAB2_LIB.BASEBOARD_FAB2(SCH_1):P3V3_SWITCH_G
   8 TP_SLG55021_P3V3_8     PG @BASEBOARD_FAB2_LIB.BASEBOARD_FAB2(SCH_1):TP_SLG55021_P3V3_8

SLG55021_SM-IC,G56246-001  I13  EU8B1
   4    GND    GND @BASEBOARD_FAB2_LIB.BASEBOARD_FAB2(SCH_1):GND
   9    GND  THPAD @BASEBOARD_FAB2_LIB.BASEBOARD_FAB2(SCH_1):GND
   1 P5V_STBY    VCC @BASEBOARD_FAB2_LIB.BASEBOARD_FAB2(SCH_1):P5V_STBY
   2 FM_CTNR_PS_ON     ON @BASEBOARD_FAB2_LIB.BASEBOARD_FAB2(SCH_1):FM_CTNR_PS_ON
   3 P5V_STBY SHDN_N @BASEBOARD_FAB2_LIB.BASEBOARD_FAB2(SCH_1):P5V_STBY
   5 P5V_STBY      D @BASEBOARD_FAB2_LIB.BASEBOARD_FAB2(SCH_1):P5V_STBY
   6    P5V      S @BASEBOARD_FAB2_LIB.BASEBOARD_FAB2(SCH_1):P5V
   7 P5V_SWITCH_G      G @BASEBOARD_FAB2_LIB.BASEBOARD_FAB2(SCH_1):P5V_SWITCH_G
   8 TP_SLG55021_P5V_8     PG @BASEBOARD_FAB2_LIB.BASEBOARD_FAB2(SCH_1):TP_SLG55021_P5V_8

SLG55021_SM-IC,G56246-001  I19  EU7E1
   4    GND    GND @BASEBOARD_FAB2_LIB.BASEBOARD_FAB2(SCH_1):GND
   9    GND  THPAD @BASEBOARD_FAB2_LIB.BASEBOARD_FAB2(SCH_1):GND
   1 P5V_STBY    VCC @BASEBOARD_FAB2_LIB.BASEBOARD_FAB2(SCH_1):P5V_STBY
   2 FM_P12V_MAIN_SW_EN     ON @BASEBOARD_FAB2_LIB.BASEBOARD_FAB2(SCH_1):FM_P12V_MAIN_SW_EN
   3 P5V_STBY SHDN_N @BASEBOARD_FAB2_LIB.BASEBOARD_FAB2(SCH_1):P5V_STBY
   5 P12V_STBY      D @BASEBOARD_FAB2_LIB.BASEBOARD_FAB2(SCH_1):P12V_STBY
   6   P12V      S @BASEBOARD_FAB2_LIB.BASEBOARD_FAB2(SCH_1):P12V
   7 P12V_SWITCH_G      G @BASEBOARD_FAB2_LIB.BASEBOARD_FAB2(SCH_1):P12V_SWITCH_G
   8 TP_SLG55021_P12V_MAIN_8     PG @BASEBOARD_FAB2_LIB.BASEBOARD_FAB2(SCH_1):TP_SLG55021_P12V_MAIN_8

CAP_A_0402V-0.1UF,16V,10%,X7R,A  I24  C8F17
   1 P5V_STBY      A @BASEBOARD_FAB2_LIB.BASEBOARD_FAB2(SCH_1):P5V_STBY
   2    GND      B @BASEBOARD_FAB2_LIB.BASEBOARD_FAB2(SCH_1):GND

CAP_A_0402V-0.1UF,16V,10%,X7R,A  I26  C8B8
   1 P5V_STBY      A @BASEBOARD_FAB2_LIB.BASEBOARD_FAB2(SCH_1):P5V_STBY
   2    GND      B @BASEBOARD_FAB2_LIB.BASEBOARD_FAB2(SCH_1):GND

CAP_A_0402V-0.1UF,16V,10%,X7R,A  I28  C8E19
   1 P5V_STBY      A @BASEBOARD_FAB2_LIB.BASEBOARD_FAB2(SCH_1):P5V_STBY
   2    GND      B @BASEBOARD_FAB2_LIB.BASEBOARD_FAB2(SCH_1):GND

CAP_A_0402V-0.1UF,16V,10%,X7R,A  I37  C8B5
   1 P5V_STBY      A @BASEBOARD_FAB2_LIB.BASEBOARD_FAB2(SCH_1):P5V_STBY
   2    GND      B @BASEBOARD_FAB2_LIB.BASEBOARD_FAB2(SCH_1):GND

CAP_0805-10UF,16V,10%,X6S,C953A  I38  C8B12
   1 P5V_STBY      A @BASEBOARD_FAB2_LIB.BASEBOARD_FAB2(SCH_1):P5V_STBY
   2    GND      B @BASEBOARD_FAB2_LIB.BASEBOARD_FAB2(SCH_1):GND

CAP_0805-10UF,16V,10%,X6S,C953A  I40  C8B6
   1    P5V      A @BASEBOARD_FAB2_LIB.BASEBOARD_FAB2(SCH_1):P5V
   2    GND      B @BASEBOARD_FAB2_LIB.BASEBOARD_FAB2(SCH_1):GND

CAP_A_0402V-0.1UF,16V,10%,X7R,A  I41  C8B7
   1    P5V      A @BASEBOARD_FAB2_LIB.BASEBOARD_FAB2(SCH_1):P5V
   2    GND      B @BASEBOARD_FAB2_LIB.BASEBOARD_FAB2(SCH_1):GND

CAP_A_0402V-0.1UF,16V,10%,X7R,A  I43  C2T36
   1 P3V3_STBY      A @BASEBOARD_FAB2_LIB.BASEBOARD_FAB2(SCH_1):P3V3_STBY
   2    GND      B @BASEBOARD_FAB2_LIB.BASEBOARD_FAB2(SCH_1):GND

CAP_0805-10UF,16V,10%,X6S,C953A  I44  C2U1
   1 P3V3_STBY      A @BASEBOARD_FAB2_LIB.BASEBOARD_FAB2(SCH_1):P3V3_STBY
   2    GND      B @BASEBOARD_FAB2_LIB.BASEBOARD_FAB2(SCH_1):GND

CAP_A_0402V-0.1UF,16V,10%,X7R,A  I46  C2U19
   1   P3V3      A @BASEBOARD_FAB2_LIB.BASEBOARD_FAB2(SCH_1):P3V3
   2    GND      B @BASEBOARD_FAB2_LIB.BASEBOARD_FAB2(SCH_1):GND

CAP_0805-10UF,16V,10%,X6S,C953A  I47  C2U2
   1   P3V3      A @BASEBOARD_FAB2_LIB.BASEBOARD_FAB2(SCH_1):P3V3
   2    GND      B @BASEBOARD_FAB2_LIB.BASEBOARD_FAB2(SCH_1):GND

CAP_A_0402V-0.1UF,16V,10%,X7R,A  I49  C7E9
   1   P12V      A @BASEBOARD_FAB2_LIB.BASEBOARD_FAB2(SCH_1):P12V
   2    GND      B @BASEBOARD_FAB2_LIB.BASEBOARD_FAB2(SCH_1):GND

CAP_0805-10UF,16V,10%,X6S,C953A  I50  C7E8
   1   P12V      A @BASEBOARD_FAB2_LIB.BASEBOARD_FAB2(SCH_1):P12V
   2    GND      B @BASEBOARD_FAB2_LIB.BASEBOARD_FAB2(SCH_1):GND

CAP_A_0402V-0.1UF,16V,10%,X7R,A  I52  C7E5
   1 P12V_STBY      A @BASEBOARD_FAB2_LIB.BASEBOARD_FAB2(SCH_1):P12V_STBY
   2    GND      B @BASEBOARD_FAB2_LIB.BASEBOARD_FAB2(SCH_1):GND

CAP_0805-10UF,16V,10%,X6S,C953A  I53  C7E6
   1 P12V_STBY      A @BASEBOARD_FAB2_LIB.BASEBOARD_FAB2(SCH_1):P12V_STBY
   2    GND      B @BASEBOARD_FAB2_LIB.BASEBOARD_FAB2(SCH_1):GND

CAP_0805-10UF,16V,10%,X6S,C953A  I61  C1B18
   1 P12V_FAN      A @BASEBOARD_FAB2_LIB.BASEBOARD_FAB2(SCH_1):P12V_FAN
   2    GND      B @BASEBOARD_FAB2_LIB.BASEBOARD_FAB2(SCH_1):GND

CAP_A_0402V-0.1UF,16V,10%,X7R,A  I64  C1B19
   1 P12V_FAN      A @BASEBOARD_FAB2_LIB.BASEBOARD_FAB2(SCH_1):P12V_FAN
   2    GND      B @BASEBOARD_FAB2_LIB.BASEBOARD_FAB2(SCH_1):GND

CAP_A_0402V-0.1UF,16V,10%,X7R,A  I67  C9M6
   1 P5V_STBY      A @BASEBOARD_FAB2_LIB.BASEBOARD_FAB2(SCH_1):P5V_STBY
   2    GND      B @BASEBOARD_FAB2_LIB.BASEBOARD_FAB2(SCH_1):GND

SLG55021_SM-IC,G56246-001  I69  EU9M1
   4    GND    GND @BASEBOARD_FAB2_LIB.BASEBOARD_FAB2(SCH_1):GND
   9    GND  THPAD @BASEBOARD_FAB2_LIB.BASEBOARD_FAB2(SCH_1):GND
   1 P5V_STBY    VCC @BASEBOARD_FAB2_LIB.BASEBOARD_FAB2(SCH_1):P5V_STBY
   2 FM_ENABLE_FAN_POWER     ON @BASEBOARD_FAB2_LIB.BASEBOARD_FAB2(SCH_1):FM_ENABLE_FAN_POWER
   3 P5V_STBY SHDN_N @BASEBOARD_FAB2_LIB.BASEBOARD_FAB2(SCH_1):P5V_STBY
   5 P12V_STBY      D @BASEBOARD_FAB2_LIB.BASEBOARD_FAB2(SCH_1):P12V_STBY
   6 P12V_FAN      S @BASEBOARD_FAB2_LIB.BASEBOARD_FAB2(SCH_1):P12V_FAN
   7 P12V_FAN_SWITCH_G      G @BASEBOARD_FAB2_LIB.BASEBOARD_FAB2(SCH_1):P12V_FAN_SWITCH_G
   8 TP_SLG55021_P12V_FAN_8     PG @BASEBOARD_FAB2_LIB.BASEBOARD_FAB2(SCH_1):TP_SLG55021_P12V_FAN_8

CAP_0805-10UF,16V,10%,X6S,C953A  I74  C9M10
   1 P12V_STBY      A @BASEBOARD_FAB2_LIB.BASEBOARD_FAB2(SCH_1):P12V_STBY
   2    GND      B @BASEBOARD_FAB2_LIB.BASEBOARD_FAB2(SCH_1):GND

CAP_A_0402V-0.1UF,16V,10%,X7R,A  I76  C9M9
   1 P12V_STBY      A @BASEBOARD_FAB2_LIB.BASEBOARD_FAB2(SCH_1):P12V_STBY
   2    GND      B @BASEBOARD_FAB2_LIB.BASEBOARD_FAB2(SCH_1):GND

RES_0402-4.75K,1%,1/16W,EMPTY,A  I78  R8E12
   1 P3V3_STBY      A @BASEBOARD_FAB2_LIB.BASEBOARD_FAB2(SCH_1):P3V3_STBY
   2 FM_CTNR_PS_ON      B @BASEBOARD_FAB2_LIB.BASEBOARD_FAB2(SCH_1):FM_CTNR_PS_ON

RES_0402-100.0K,1%,1/16W,CHIP,A  I83  R8B4
   1 FM_CTNR_PS_ON      A @BASEBOARD_FAB2_LIB.BASEBOARD_FAB2(SCH_1):FM_CTNR_PS_ON
   2    GND      B @BASEBOARD_FAB2_LIB.BASEBOARD_FAB2(SCH_1):GND

MOSFET_N_LCC3-BSZ019N03LS,NFETA  I85  Q8G1
   4 P3V3_SWITCH_G   GATE @BASEBOARD_FAB2_LIB.BASEBOARD_FAB2(SCH_1):P3V3_SWITCH_G
   1   P3V3    SRC @BASEBOARD_FAB2_LIB.BASEBOARD_FAB2(SCH_1):P3V3
   5 P3V3_STBY    DRN @BASEBOARD_FAB2_LIB.BASEBOARD_FAB2(SCH_1):P3V3_STBY

MOSFET_N_LCC3-BSZ019N03LS,NFETA  I86  Q1B1
   4 P12V_FAN_SWITCH_G   GATE @BASEBOARD_FAB2_LIB.BASEBOARD_FAB2(SCH_1):P12V_FAN_SWITCH_G
   1 P12V_FAN    SRC @BASEBOARD_FAB2_LIB.BASEBOARD_FAB2(SCH_1):P12V_FAN
   5 P12V_STBY    DRN @BASEBOARD_FAB2_LIB.BASEBOARD_FAB2(SCH_1):P12V_STBY

MOSFET_N_LCC3-BSZ019N03LS,NFETA  I87  Q8B1
   4 P5V_SWITCH_G   GATE @BASEBOARD_FAB2_LIB.BASEBOARD_FAB2(SCH_1):P5V_SWITCH_G
   1    P5V    SRC @BASEBOARD_FAB2_LIB.BASEBOARD_FAB2(SCH_1):P5V
   5 P5V_STBY    DRN @BASEBOARD_FAB2_LIB.BASEBOARD_FAB2(SCH_1):P5V_STBY

MOSFET_N_LCC3-BSZ019N03LS,NFETA  I88  Q7E7
   4 P12V_SWITCH_G   GATE @BASEBOARD_FAB2_LIB.BASEBOARD_FAB2(SCH_1):P12V_SWITCH_G
   1   P12V    SRC @BASEBOARD_FAB2_LIB.BASEBOARD_FAB2(SCH_1):P12V
   5 P12V_STBY    DRN @BASEBOARD_FAB2_LIB.BASEBOARD_FAB2(SCH_1):P12V_STBY


DRAWING: @BASEBOARD_FAB2_LIB.BASEBOARD_FAB2(SCH_1):PAGE199 

RES_0603-10.0,1%,1/10W,CHIP,G2A  I2  R9P30
   1 P12V_PSU      A @BASEBOARD_FAB2_LIB.BASEBOARD_FAB2(SCH_1):P12V_PSU
   2 P12V_HSC_VCC      B @BASEBOARD_FAB2_LIB.BASEBOARD_FAB2(SCH_1):P12V_HSC_VCC

CAP_0402-1.0UF,16V,10%,X6S,D97A  I3  C1D25
   1 P12V_HSC_VCC      A @BASEBOARD_FAB2_LIB.BASEBOARD_FAB2(SCH_1):P12V_HSC_VCC
   2 AGND_HSC      B @BASEBOARD_FAB2_LIB.BASEBOARD_FAB2(SCH_1):AGND_HSC

RES_0402-100.0K,1%,1/16W,CHIP,A  I6  R9P28
   1 P12V_PSU      A @BASEBOARD_FAB2_LIB.BASEBOARD_FAB2(SCH_1):P12V_PSU
   2 A_HSC_OV      B @BASEBOARD_FAB2_LIB.BASEBOARD_FAB2(SCH_1):A_HSC_OV

CAP_A_0402V-0.1UF,16V,10%,X7R,A  I7  C1D27
   1 A_HSC_OV      A @BASEBOARD_FAB2_LIB.BASEBOARD_FAB2(SCH_1):A_HSC_OV
   2 AGND_HSC      B @BASEBOARD_FAB2_LIB.BASEBOARD_FAB2(SCH_1):AGND_HSC

RES_0402-7.5K,1%,1/16W,CHIP,G2A  I9  R1D43
   1 A_HSC_OV      A @BASEBOARD_FAB2_LIB.BASEBOARD_FAB2(SCH_1):A_HSC_OV
   2 AGND_HSC      B @BASEBOARD_FAB2_LIB.BASEBOARD_FAB2(SCH_1):AGND_HSC

ADM1278_SM-IC,G99251-001  I10  EU1D2
   7 FM_P12V_HSC_ADR1   ADR1 @BASEBOARD_FAB2_LIB.BASEBOARD_FAB2(SCH_1):FM_P12V_HSC_ADR1
   8 FM_P12V_HSC_ADR2   ADR2 @BASEBOARD_FAB2_LIB.BASEBOARD_FAB2(SCH_1):FM_P12V_HSC_ADR2
  19 A_HSC_CSOUT  CSOUT @BASEBOARD_FAB2_LIB.BASEBOARD_FAB2(SCH_1):A_HSC_CSOUT
  12 FM_P12V_HOTSWAP0_EN ENABLE @BASEBOARD_FAB2_LIB.BASEBOARD_FAB2(SCH_1):FM_P12V_HOTSWAP0_EN
  33 AGND_HSC     EP @BASEBOARD_FAB2_LIB.BASEBOARD_FAB2(SCH_1):AGND_HSC
   6 IRQ_HSC_FAULT_R_N FAULT_N @BASEBOARD_FAB2_LIB.BASEBOARD_FAB2(SCH_1):IRQ_HSC_FAULT_R_N
  24 A_HSC_GATE   GATE @BASEBOARD_FAB2_LIB.BASEBOARD_FAB2(SCH_1):A_HSC_GATE
  22 AGND_HSC    GND @BASEBOARD_FAB2_LIB.BASEBOARD_FAB2(SCH_1):AGND_HSC
  13 IRQ_SML1_PMBUS_ALERT_R_N GPO1_ALERT1_N_CONV @BASEBOARD_FAB2_LIB.BASEBOARD_FAB2(SCH_1):IRQ_SML1_PMBUS_ALERT_R_N
  14 TP_HSC_ALERT2_N GPO2_ALERT2_N @BASEBOARD_FAB2_LIB.BASEBOARD_FAB2(SCH_1):TP_HSC_ALERT2_N
  27 A_HSC_HSN    HSN @BASEBOARD_FAB2_LIB.BASEBOARD_FAB2(SCH_1):A_HSC_HSN
  28 A_HSC_HSP    HSP @BASEBOARD_FAB2_LIB.BASEBOARD_FAB2(SCH_1):A_HSC_HSP
   3 A_HSC_ISET   ISET @BASEBOARD_FAB2_LIB.BASEBOARD_FAB2(SCH_1):A_HSC_ISET
   4 A_HSC_ISTART ISTART @BASEBOARD_FAB2_LIB.BASEBOARD_FAB2(SCH_1):A_HSC_ISTART
  10 TP_HSC_MCLK   MCLK @BASEBOARD_FAB2_LIB.BASEBOARD_FAB2(SCH_1):TP_HSC_MCLK
  11 TP_HSC_MDAT   MDAT @BASEBOARD_FAB2_LIB.BASEBOARD_FAB2(SCH_1):TP_HSC_MDAT
  26 A_HSC_MON    MON @BASEBOARD_FAB2_LIB.BASEBOARD_FAB2(SCH_1):A_HSC_MON
  29 A_HSC_MOP    MOP @BASEBOARD_FAB2_LIB.BASEBOARD_FAB2(SCH_1):A_HSC_MOP
  32 A_HSC_OV     OV @BASEBOARD_FAB2_LIB.BASEBOARD_FAB2(SCH_1):A_HSC_OV
  23    GND   PGND @BASEBOARD_FAB2_LIB.BASEBOARD_FAB2(SCH_1):GND
   1 A_HSC_PSET   PSET @BASEBOARD_FAB2_LIB.BASEBOARD_FAB2(SCH_1):A_HSC_PSET
  21 A_HSC_PWGIN  PWGIN @BASEBOARD_FAB2_LIB.BASEBOARD_FAB2(SCH_1):A_HSC_PWGIN
  18 PWRGD_P12V_R  PWRGD @BASEBOARD_FAB2_LIB.BASEBOARD_FAB2(SCH_1):PWRGD_P12V_R
  17 PD_HSC_RETRY_N RETRY_N @BASEBOARD_FAB2_LIB.BASEBOARD_FAB2(SCH_1):PD_HSC_RETRY_N
  16 SMB_3V3SB_HSC_SCL_R    SCL @BASEBOARD_FAB2_LIB.BASEBOARD_FAB2(SCH_1):SMB_3V3SB_HSC_SCL_R
  15 SMB_3V3SB_HSC_SDA_R    SDA @BASEBOARD_FAB2_LIB.BASEBOARD_FAB2(SCH_1):SMB_3V3SB_HSC_SDA_R
   9 TP_HSC_SPISSN SPISS_N @BASEBOARD_FAB2_LIB.BASEBOARD_FAB2(SCH_1):TP_HSC_SPISSN
  25 A_HSC_TEMP   TEMP @BASEBOARD_FAB2_LIB.BASEBOARD_FAB2(SCH_1):A_HSC_TEMP
   5 A_HSC_TIMER  TIMER @BASEBOARD_FAB2_LIB.BASEBOARD_FAB2(SCH_1):A_HSC_TIMER
  31 A_HSC_UV     UV @BASEBOARD_FAB2_LIB.BASEBOARD_FAB2(SCH_1):A_HSC_UV
   2 A_HSC_VCAP   VCAP @BASEBOARD_FAB2_LIB.BASEBOARD_FAB2(SCH_1):A_HSC_VCAP
  30 P12V_HSC_VCC    VCC @BASEBOARD_FAB2_LIB.BASEBOARD_FAB2(SCH_1):P12V_HSC_VCC
  20 A_HSC_VOUT   VOUT @BASEBOARD_FAB2_LIB.BASEBOARD_FAB2(SCH_1):A_HSC_VOUT

RES_0402-100.0K,1%,1/16W,CHIP,A  I12  R9P29
   1 P12V_PSU      A @BASEBOARD_FAB2_LIB.BASEBOARD_FAB2(SCH_1):P12V_PSU
   2 A_HSC_UV      B @BASEBOARD_FAB2_LIB.BASEBOARD_FAB2(SCH_1):A_HSC_UV

RES_0402-11K,1%,1/16W,CHIP,G21A  I13  R1D42
   1 A_HSC_UV      A @BASEBOARD_FAB2_LIB.BASEBOARD_FAB2(SCH_1):A_HSC_UV
   2 AGND_HSC      B @BASEBOARD_FAB2_LIB.BASEBOARD_FAB2(SCH_1):AGND_HSC

RES_0402-100.0K,1%,1/16W,CHIP,A  I15  R1D37
   1 A_HSC_VCAP      A @BASEBOARD_FAB2_LIB.BASEBOARD_FAB2(SCH_1):A_HSC_VCAP
   2 A_HSC_ISET      B @BASEBOARD_FAB2_LIB.BASEBOARD_FAB2(SCH_1):A_HSC_ISET

RES_0402-100.0K,1%,1/16W,CHIP,A  I16  R1D39
   1 A_HSC_VCAP      A @BASEBOARD_FAB2_LIB.BASEBOARD_FAB2(SCH_1):A_HSC_VCAP
   2 A_HSC_PSET      B @BASEBOARD_FAB2_LIB.BASEBOARD_FAB2(SCH_1):A_HSC_PSET

RES_0402-100.0K,1%,1/16W,CHIP,A  I17  R1D32
   1 A_HSC_VCAP      A @BASEBOARD_FAB2_LIB.BASEBOARD_FAB2(SCH_1):A_HSC_VCAP
   2 A_HSC_ISTART      B @BASEBOARD_FAB2_LIB.BASEBOARD_FAB2(SCH_1):A_HSC_ISTART

RES_0805-0.0,5%,1/8W,CHIP,G221A  I19  R1D41
   1    GND      A @BASEBOARD_FAB2_LIB.BASEBOARD_FAB2(SCH_1):GND
   2 AGND_HSC      B @BASEBOARD_FAB2_LIB.BASEBOARD_FAB2(SCH_1):AGND_HSC

CAP_0603LF-0.033UF,50V,10%,X7RA  I24  C9P14
   1 A_HSC_TIMER      A @BASEBOARD_FAB2_LIB.BASEBOARD_FAB2(SCH_1):A_HSC_TIMER
   2 AGND_HSC      B @BASEBOARD_FAB2_LIB.BASEBOARD_FAB2(SCH_1):AGND_HSC

RES_0402-100.0,1%,1/16W,EMPTY,A  I26  R1D28
   1 PD_HSC_RETRY_N      A @BASEBOARD_FAB2_LIB.BASEBOARD_FAB2(SCH_1):PD_HSC_RETRY_N
   2 AGND_HSC      B @BASEBOARD_FAB2_LIB.BASEBOARD_FAB2(SCH_1):AGND_HSC

RES_0402-0.0,5%,1/16W,CHIP,G21A  I27  R1D24
   1 SMB_BMC_PMBUS_STBY_LVC3_SCL      A @BASEBOARD_FAB2_LIB.BASEBOARD_FAB2(SCH_1):SMB_BMC_PMBUS_STBY_LVC3_SCL
   2 SMB_3V3SB_HSC_SCL_R      B @BASEBOARD_FAB2_LIB.BASEBOARD_FAB2(SCH_1):SMB_3V3SB_HSC_SCL_R

RES_0402-0.0,5%,1/16W,CHIP,G21A  I28  R1D25
   1 SMB_BMC_PMBUS_STBY_LVC3_SDA      A @BASEBOARD_FAB2_LIB.BASEBOARD_FAB2(SCH_1):SMB_BMC_PMBUS_STBY_LVC3_SDA
   2 SMB_3V3SB_HSC_SDA_R      B @BASEBOARD_FAB2_LIB.BASEBOARD_FAB2(SCH_1):SMB_3V3SB_HSC_SDA_R

RES_0402-150.0K,1%,1/16W,CHIP,A  I33  R9P17
   1 FM_P12V_HSC_ADR1      A @BASEBOARD_FAB2_LIB.BASEBOARD_FAB2(SCH_1):FM_P12V_HSC_ADR1
   2 AGND_HSC      B @BASEBOARD_FAB2_LIB.BASEBOARD_FAB2(SCH_1):AGND_HSC

RES_0402-0.0,5%,1/16W,CHIP,G21A  I36  R9P16
   1 FM_P12V_HSC_ADR2      A @BASEBOARD_FAB2_LIB.BASEBOARD_FAB2(SCH_1):FM_P12V_HSC_ADR2
   2 AGND_HSC      B @BASEBOARD_FAB2_LIB.BASEBOARD_FAB2(SCH_1):AGND_HSC

RES_0402-4.75K,1%,1/16W,EMPTY,A  I37  R1D29
   1 A_HSC_VCAP      A @BASEBOARD_FAB2_LIB.BASEBOARD_FAB2(SCH_1):A_HSC_VCAP
   2 FM_P12V_HSC_ADR1      B @BASEBOARD_FAB2_LIB.BASEBOARD_FAB2(SCH_1):FM_P12V_HSC_ADR1

RES_0402-4.75K,1%,1/16W,EMPTY,A  I38  R1D27
   1 A_HSC_VCAP      A @BASEBOARD_FAB2_LIB.BASEBOARD_FAB2(SCH_1):A_HSC_VCAP
   2 FM_P12V_HSC_ADR2      B @BASEBOARD_FAB2_LIB.BASEBOARD_FAB2(SCH_1):FM_P12V_HSC_ADR2

RES_0402-15.0K,1%,1/16W,CHIP,GA  I41  R9P18
   1 P12V_STBY      A @BASEBOARD_FAB2_LIB.BASEBOARD_FAB2(SCH_1):P12V_STBY
   2 PWRGD_P12V_R      B @BASEBOARD_FAB2_LIB.BASEBOARD_FAB2(SCH_1):PWRGD_P12V_R

RES_0402-6.19K,1%,1/16W,CHIP,GA  I43  R1D31
   1 PWRGD_P12V_R      A @BASEBOARD_FAB2_LIB.BASEBOARD_FAB2(SCH_1):PWRGD_P12V_R
   2    GND      B @BASEBOARD_FAB2_LIB.BASEBOARD_FAB2(SCH_1):GND

CAP_A_0402V-0.1UF,16V,10%,X7R,A  I53  C1D11
   1 FM_P12V_HOTSWAP0_EN      A @BASEBOARD_FAB2_LIB.BASEBOARD_FAB2(SCH_1):FM_P12V_HOTSWAP0_EN
   2 AGND_HSC      B @BASEBOARD_FAB2_LIB.BASEBOARD_FAB2(SCH_1):AGND_HSC

RES_0402-100.0K,1%,1/16W,CHIP,A  I54  R9P23
   1 P12V_STBY      A @BASEBOARD_FAB2_LIB.BASEBOARD_FAB2(SCH_1):P12V_STBY
   2 A_HSC_PWGIN      B @BASEBOARD_FAB2_LIB.BASEBOARD_FAB2(SCH_1):A_HSC_PWGIN

RES_0402-12.1K,1%,1/16W,CHIP,GA  I55  R9P24
   1 A_HSC_PWGIN      A @BASEBOARD_FAB2_LIB.BASEBOARD_FAB2(SCH_1):A_HSC_PWGIN
   2 AGND_HSC      B @BASEBOARD_FAB2_LIB.BASEBOARD_FAB2(SCH_1):AGND_HSC

NPN_SM-MMBT3904,IC,C52245-001  I58  Q1D3
   1 A_HSC_TEMP      B @BASEBOARD_FAB2_LIB.BASEBOARD_FAB2(SCH_1):A_HSC_TEMP
   3 A_HSC_TEMP      C @BASEBOARD_FAB2_LIB.BASEBOARD_FAB2(SCH_1):A_HSC_TEMP
   2    GND      E @BASEBOARD_FAB2_LIB.BASEBOARD_FAB2(SCH_1):GND

RES_0402-1.00K,1%,1/16W,CHIP,GA  I65  R1D36
   1 P12V_STBY      A @BASEBOARD_FAB2_LIB.BASEBOARD_FAB2(SCH_1):P12V_STBY
   2 A_HSC_VOUT      B @BASEBOARD_FAB2_LIB.BASEBOARD_FAB2(SCH_1):A_HSC_VOUT

CAP_A_0402V-0.1UF,16V,10%,EMPTA  I67  C9P12
   1 A_HSC_VOUT      A @BASEBOARD_FAB2_LIB.BASEBOARD_FAB2(SCH_1):A_HSC_VOUT
   2 AGND_HSC      B @BASEBOARD_FAB2_LIB.BASEBOARD_FAB2(SCH_1):AGND_HSC

FET_N_DUAL_SMLF-2N7002DW,FET,DA  I82  Q1D1
   5 A_HSC_HIGH_EN GATE<0> @BASEBOARD_FAB2_LIB.BASEBOARD_FAB2(SCH_1):A_HSC_HIGH_EN
   4 AGND_HSC SOURCE<0> @BASEBOARD_FAB2_LIB.BASEBOARD_FAB2(SCH_1):AGND_HSC
   3 A_HSC_ISET_S DRAIN<0> @BASEBOARD_FAB2_LIB.BASEBOARD_FAB2(SCH_1):A_HSC_ISET_S

RES_0402-90.9K,1%,1/16W,CHIP,GA  I84  R1D13
   1 A_HSC_ISET_S      A @BASEBOARD_FAB2_LIB.BASEBOARD_FAB2(SCH_1):A_HSC_ISET_S
   2 A_HSC_ISET      B @BASEBOARD_FAB2_LIB.BASEBOARD_FAB2(SCH_1):A_HSC_ISET

RES_0402-69.8K,1%,1/16W,CHIP,GA  I85  R1D16
   1 A_HSC_ISET      A @BASEBOARD_FAB2_LIB.BASEBOARD_FAB2(SCH_1):A_HSC_ISET
   2 A_HSC_ISET_S2      B @BASEBOARD_FAB2_LIB.BASEBOARD_FAB2(SCH_1):A_HSC_ISET_S2

FET_N_DUAL_SMLF-2N7002DW,FET,DA  I86  Q1D1
   2 A_HSC_LOW_EN GATE<0> @BASEBOARD_FAB2_LIB.BASEBOARD_FAB2(SCH_1):A_HSC_LOW_EN
   1 AGND_HSC SOURCE<0> @BASEBOARD_FAB2_LIB.BASEBOARD_FAB2(SCH_1):AGND_HSC
   6 A_HSC_ISET_S2 DRAIN<0> @BASEBOARD_FAB2_LIB.BASEBOARD_FAB2(SCH_1):A_HSC_ISET_S2

RES_0402-100.0K,1%,1/16W,CHIP,A  I87  R1D18
   1 A_HSC_HIGH_EN      A @BASEBOARD_FAB2_LIB.BASEBOARD_FAB2(SCH_1):A_HSC_HIGH_EN
   2 AGND_HSC      B @BASEBOARD_FAB2_LIB.BASEBOARD_FAB2(SCH_1):AGND_HSC

RES_0402-100.0K,1%,1/16W,CHIP,A  I88  R1D11
   1 A_HSC_LOW_EN      A @BASEBOARD_FAB2_LIB.BASEBOARD_FAB2(SCH_1):A_HSC_LOW_EN
   2 AGND_HSC      B @BASEBOARD_FAB2_LIB.BASEBOARD_FAB2(SCH_1):AGND_HSC

RES_0402-100.0K,1%,1/16W,CHIP,A  I92  R1D15
   1 P12V_PSU      A @BASEBOARD_FAB2_LIB.BASEBOARD_FAB2(SCH_1):P12V_PSU
   2 A_HSC_OCP_SEL      B @BASEBOARD_FAB2_LIB.BASEBOARD_FAB2(SCH_1):A_HSC_OCP_SEL

ZENER_SM-13V,IC,H69095-001  I99  VR1D1
   2    GND      A @BASEBOARD_FAB2_LIB.BASEBOARD_FAB2(SCH_1):GND
   1 P12V_PSU      C @BASEBOARD_FAB2_LIB.BASEBOARD_FAB2(SCH_1):P12V_PSU

RES_0402-40.2K,1%,1/16W,CHIP,GA  I100  R1D40
   1 A_HSC_PSET      A @BASEBOARD_FAB2_LIB.BASEBOARD_FAB2(SCH_1):A_HSC_PSET
   2 AGND_HSC      B @BASEBOARD_FAB2_LIB.BASEBOARD_FAB2(SCH_1):AGND_HSC

RES_0402-16K,1.0%,1/16W,CHIP,GA  I102  R1D34
   1 A_HSC_ISTART      A @BASEBOARD_FAB2_LIB.BASEBOARD_FAB2(SCH_1):A_HSC_ISTART
   2 AGND_HSC      B @BASEBOARD_FAB2_LIB.BASEBOARD_FAB2(SCH_1):AGND_HSC

CAP_A_0402V-0.1UF,16V,10%,X7R,A  I105  C9P15
   1 A_HSC_ISET      A @BASEBOARD_FAB2_LIB.BASEBOARD_FAB2(SCH_1):A_HSC_ISET
   2 AGND_HSC      B @BASEBOARD_FAB2_LIB.BASEBOARD_FAB2(SCH_1):AGND_HSC

CAP_A_0402V-0.1UF,16V,10%,X7R,A  I107  C1D26
   1 A_HSC_UV      A @BASEBOARD_FAB2_LIB.BASEBOARD_FAB2(SCH_1):A_HSC_UV
   2 AGND_HSC      B @BASEBOARD_FAB2_LIB.BASEBOARD_FAB2(SCH_1):AGND_HSC

RES_0402-33.2,1%,1/16W,CHIP,G2A  I108  R1D33
   1 PWRGD_P12V_R      A @BASEBOARD_FAB2_LIB.BASEBOARD_FAB2(SCH_1):PWRGD_P12V_R
   2 PWRGD_P12V_HSC      B @BASEBOARD_FAB2_LIB.BASEBOARD_FAB2(SCH_1):PWRGD_P12V_HSC

RES_0402-33.2,1%,1/16W,CHIP,G2A  I109  R1D26
   1 IRQ_SML1_PMBUS_ALERT_R_N      A @BASEBOARD_FAB2_LIB.BASEBOARD_FAB2(SCH_1):IRQ_SML1_PMBUS_ALERT_R_N
   2 IRQ_SML1_PMBUS_ALERT_N      B @BASEBOARD_FAB2_LIB.BASEBOARD_FAB2(SCH_1):IRQ_SML1_PMBUS_ALERT_N

RES_0402-33.2,1%,1/16W,CHIP,G2A  I110  R1D30
   1 IRQ_HSC_FAULT_R_N      A @BASEBOARD_FAB2_LIB.BASEBOARD_FAB2(SCH_1):IRQ_HSC_FAULT_R_N
   2 IRQ_HSC_FAULT_N      B @BASEBOARD_FAB2_LIB.BASEBOARD_FAB2(SCH_1):IRQ_HSC_FAULT_N

CAP_0402-1.0UF,16V,10%,X6S,D97A  I119  C1D19
   1 A_HSC_VCAP      A @BASEBOARD_FAB2_LIB.BASEBOARD_FAB2(SCH_1):A_HSC_VCAP
   2 AGND_HSC      B @BASEBOARD_FAB2_LIB.BASEBOARD_FAB2(SCH_1):AGND_HSC

CAP_A_0402V-0.1UF,16V,10%,X7R,A  I121  C1D21
   1 A_HSC_PSET      A @BASEBOARD_FAB2_LIB.BASEBOARD_FAB2(SCH_1):A_HSC_PSET
   2 AGND_HSC      B @BASEBOARD_FAB2_LIB.BASEBOARD_FAB2(SCH_1):AGND_HSC

CONN3_C95678002_PIP-CONN,C9567A  I123  J1B3
   1 A_HSC_HIGH_EN    IO1 @BASEBOARD_FAB2_LIB.BASEBOARD_FAB2(SCH_1):A_HSC_HIGH_EN
   2 A_HSC_OCP_SEL    IO2 @BASEBOARD_FAB2_LIB.BASEBOARD_FAB2(SCH_1):A_HSC_OCP_SEL
   3 A_HSC_LOW_EN    IO3 @BASEBOARD_FAB2_LIB.BASEBOARD_FAB2(SCH_1):A_HSC_LOW_EN

SCONN3_D53458001_SM-EMPTY,D534A  I124  J1B4
   1 A_HSC_HIGH_EN    IO1 @BASEBOARD_FAB2_LIB.BASEBOARD_FAB2(SCH_1):A_HSC_HIGH_EN
   2 A_HSC_OCP_SEL    IO2 @BASEBOARD_FAB2_LIB.BASEBOARD_FAB2(SCH_1):A_HSC_OCP_SEL
   3 A_HSC_LOW_EN    IO3 @BASEBOARD_FAB2_LIB.BASEBOARD_FAB2(SCH_1):A_HSC_LOW_EN


DRAWING: @BASEBOARD_FAB2_LIB.BASEBOARD_FAB2(SCH_1):PAGE200 

CAP_A_0402V-0.1UF,16V,10%,EMPTA  I36  C9P17
   1 A_HSC_MON      A @BASEBOARD_FAB2_LIB.BASEBOARD_FAB2(SCH_1):A_HSC_MON
   2 AGND_HSC      B @BASEBOARD_FAB2_LIB.BASEBOARD_FAB2(SCH_1):AGND_HSC

CAP_A_0402V-0.1UF,16V,10%,EMPTA  I40  C9P16
   1 A_HSC_MOP      A @BASEBOARD_FAB2_LIB.BASEBOARD_FAB2(SCH_1):A_HSC_MOP
   2 AGND_HSC      B @BASEBOARD_FAB2_LIB.BASEBOARD_FAB2(SCH_1):AGND_HSC

CAP_A_0402V-0.1UF,16V,10%,EMPTA  I42  C1D22
   1 A_HSC_MON      A @BASEBOARD_FAB2_LIB.BASEBOARD_FAB2(SCH_1):A_HSC_MON
   2 A_HSC_MOP      B @BASEBOARD_FAB2_LIB.BASEBOARD_FAB2(SCH_1):A_HSC_MOP

RES_0402-0.0,5%,1/16W,CHIP,G21A  I43  R1D45
   1 A_HSC_MON      A @BASEBOARD_FAB2_LIB.BASEBOARD_FAB2(SCH_1):A_HSC_MON
   2 A_HSC_HSN      B @BASEBOARD_FAB2_LIB.BASEBOARD_FAB2(SCH_1):A_HSC_HSN

RES_0402-0.0,5%,1/16W,CHIP,G21A  I44  R1D44
   1 A_HSC_MOP      A @BASEBOARD_FAB2_LIB.BASEBOARD_FAB2(SCH_1):A_HSC_MOP
   2 A_HSC_HSP      B @BASEBOARD_FAB2_LIB.BASEBOARD_FAB2(SCH_1):A_HSC_HSP

RES_0402-10.0,1%,1/16W,CHIP,G2A  I47  R9P27
   1 P12V_HSC_SENP1      A @BASEBOARD_FAB2_LIB.BASEBOARD_FAB2(SCH_1):P12V_HSC_SENP1
   2 A_HSC_HSP      B @BASEBOARD_FAB2_LIB.BASEBOARD_FAB2(SCH_1):A_HSC_HSP

RES_0402-10.0,1%,1/16W,CHIP,G2A  I48  R1D46
   1 P12V_HSC_SENP0      A @BASEBOARD_FAB2_LIB.BASEBOARD_FAB2(SCH_1):P12V_HSC_SENP0
   2 A_HSC_HSP      B @BASEBOARD_FAB2_LIB.BASEBOARD_FAB2(SCH_1):A_HSC_HSP

RES_PWR_6PAD-0.001,1%,3W,CHIP,A  I49  R9R1
   1 P12V_PSU      1 @BASEBOARD_FAB2_LIB.BASEBOARD_FAB2(SCH_1):P12V_PSU
   2 P12V_MB0_SW      2 @BASEBOARD_FAB2_LIB.BASEBOARD_FAB2(SCH_1):P12V_MB0_SW
   3 P12V_HSC_SENP1      3 @BASEBOARD_FAB2_LIB.BASEBOARD_FAB2(SCH_1):P12V_HSC_SENP1
   4 P12V_HSC_SENN1      4 @BASEBOARD_FAB2_LIB.BASEBOARD_FAB2(SCH_1):P12V_HSC_SENN1
   5 P12V_PSU      5 @BASEBOARD_FAB2_LIB.BASEBOARD_FAB2(SCH_1):P12V_PSU
   6 P12V_MB0_SW      6 @BASEBOARD_FAB2_LIB.BASEBOARD_FAB2(SCH_1):P12V_MB0_SW

RES_PWR_6PAD-0.001,1%,3W,CHIP,A  I50  R1D49
   1 P12V_PSU      1 @BASEBOARD_FAB2_LIB.BASEBOARD_FAB2(SCH_1):P12V_PSU
   2 P12V_MB0_SW      2 @BASEBOARD_FAB2_LIB.BASEBOARD_FAB2(SCH_1):P12V_MB0_SW
   3 P12V_HSC_SENP0      3 @BASEBOARD_FAB2_LIB.BASEBOARD_FAB2(SCH_1):P12V_HSC_SENP0
   4 P12V_HSC_SENN0      4 @BASEBOARD_FAB2_LIB.BASEBOARD_FAB2(SCH_1):P12V_HSC_SENN0
   5 P12V_PSU      5 @BASEBOARD_FAB2_LIB.BASEBOARD_FAB2(SCH_1):P12V_PSU
   6 P12V_MB0_SW      6 @BASEBOARD_FAB2_LIB.BASEBOARD_FAB2(SCH_1):P12V_MB0_SW

RES_0402-10.0,1%,1/16W,CHIP,G2A  I51  R9P26
   1 P12V_HSC_SENN1      A @BASEBOARD_FAB2_LIB.BASEBOARD_FAB2(SCH_1):P12V_HSC_SENN1
   2 A_HSC_HSN      B @BASEBOARD_FAB2_LIB.BASEBOARD_FAB2(SCH_1):A_HSC_HSN

RES_0402-10.0,1%,1/16W,CHIP,G2A  I52  R1D47
   1 P12V_HSC_SENN0      A @BASEBOARD_FAB2_LIB.BASEBOARD_FAB2(SCH_1):P12V_HSC_SENN0
   2 A_HSC_HSN      B @BASEBOARD_FAB2_LIB.BASEBOARD_FAB2(SCH_1):A_HSC_HSN

MOSFETN_1D3S_SOT5-IC,G68777-001  I54  EU1E3
   1 P12V_STBY     S1 @BASEBOARD_FAB2_LIB.BASEBOARD_FAB2(SCH_1):P12V_STBY
   2 P12V_STBY     S2 @BASEBOARD_FAB2_LIB.BASEBOARD_FAB2(SCH_1):P12V_STBY
   3 P12V_STBY     S3 @BASEBOARD_FAB2_LIB.BASEBOARD_FAB2(SCH_1):P12V_STBY
   5 P12V_MB0_SW      D @BASEBOARD_FAB2_LIB.BASEBOARD_FAB2(SCH_1):P12V_MB0_SW
   4 A_HSC_GATE1_R      G @BASEBOARD_FAB2_LIB.BASEBOARD_FAB2(SCH_1):A_HSC_GATE1_R

RES_0402-10.0,1%,1/16W,CHIP,G2A  I56  R1E1
   1 A_HSC_GATE      A @BASEBOARD_FAB2_LIB.BASEBOARD_FAB2(SCH_1):A_HSC_GATE
   2 A_HSC_GATE1_R      B @BASEBOARD_FAB2_LIB.BASEBOARD_FAB2(SCH_1):A_HSC_GATE1_R

MOSFETN_1D3S_SOT5-IC,G68777-001  I57  EU9R1
   1 P12V_STBY     S1 @BASEBOARD_FAB2_LIB.BASEBOARD_FAB2(SCH_1):P12V_STBY
   2 P12V_STBY     S2 @BASEBOARD_FAB2_LIB.BASEBOARD_FAB2(SCH_1):P12V_STBY
   3 P12V_STBY     S3 @BASEBOARD_FAB2_LIB.BASEBOARD_FAB2(SCH_1):P12V_STBY
   5 P12V_MB0_SW      D @BASEBOARD_FAB2_LIB.BASEBOARD_FAB2(SCH_1):P12V_MB0_SW
   4 A_HSC_GATE2_R      G @BASEBOARD_FAB2_LIB.BASEBOARD_FAB2(SCH_1):A_HSC_GATE2_R

RES_0402-10.0,1%,1/16W,CHIP,G2A  I58  R9R4
   1 A_HSC_GATE      A @BASEBOARD_FAB2_LIB.BASEBOARD_FAB2(SCH_1):A_HSC_GATE
   2 A_HSC_GATE2_R      B @BASEBOARD_FAB2_LIB.BASEBOARD_FAB2(SCH_1):A_HSC_GATE2_R

MOSFETN_1D3S_SOT5-IC,G68777-001  I59  EU1E1
   1 P12V_STBY     S1 @BASEBOARD_FAB2_LIB.BASEBOARD_FAB2(SCH_1):P12V_STBY
   2 P12V_STBY     S2 @BASEBOARD_FAB2_LIB.BASEBOARD_FAB2(SCH_1):P12V_STBY
   3 P12V_STBY     S3 @BASEBOARD_FAB2_LIB.BASEBOARD_FAB2(SCH_1):P12V_STBY
   5 P12V_MB0_SW      D @BASEBOARD_FAB2_LIB.BASEBOARD_FAB2(SCH_1):P12V_MB0_SW
   4 A_HSC_GATE3_R      G @BASEBOARD_FAB2_LIB.BASEBOARD_FAB2(SCH_1):A_HSC_GATE3_R

RES_0402-10.0,1%,1/16W,CHIP,G2A  I60  R1D48
   1 A_HSC_GATE      A @BASEBOARD_FAB2_LIB.BASEBOARD_FAB2(SCH_1):A_HSC_GATE
   2 A_HSC_GATE3_R      B @BASEBOARD_FAB2_LIB.BASEBOARD_FAB2(SCH_1):A_HSC_GATE3_R

RES_0402-10.0K,1%,1/16W,EMPTY,A  I70  R9P19
   1 A_HSC_TIMER_R      A @BASEBOARD_FAB2_LIB.BASEBOARD_FAB2(SCH_1):A_HSC_TIMER_R
   2 AGND_HSC      B @BASEBOARD_FAB2_LIB.BASEBOARD_FAB2(SCH_1):AGND_HSC

RES_0402-0.0,5%,1/16W,CHIP,G21A  I71  R9P21
   1 A_HSC_TIMER      A @BASEBOARD_FAB2_LIB.BASEBOARD_FAB2(SCH_1):A_HSC_TIMER
   2 A_HSC_TIMER_R      B @BASEBOARD_FAB2_LIB.BASEBOARD_FAB2(SCH_1):A_HSC_TIMER_R

RES_0402-2.7K,1%,1/16W,CHIP,G2A  I86  R9P20
   1 P3V3_STBY      A @BASEBOARD_FAB2_LIB.BASEBOARD_FAB2(SCH_1):P3V3_STBY
   2 FM_HSC_TIMER_EXP_N      B @BASEBOARD_FAB2_LIB.BASEBOARD_FAB2(SCH_1):FM_HSC_TIMER_EXP_N

TTL1G126_A_SOT-74HC1G126,IC,A7B  I103  U1D1
   1 FM_OC_DETECT_EN     OE @BASEBOARD_FAB2_LIB.BASEBOARD_FAB2(SCH_1):FM_OC_DETECT_EN
   2 IRQ_OC_DETECT_N      A @BASEBOARD_FAB2_LIB.BASEBOARD_FAB2(SCH_1):IRQ_OC_DETECT_N
   4 FM_OC_DETECT_N      Y @BASEBOARD_FAB2_LIB.BASEBOARD_FAB2(SCH_1):FM_OC_DETECT_N

RES_0402-274K,1.0%,1/16W,CHIP,A  I107  R9P13
   1 P12V_STBY      A @BASEBOARD_FAB2_LIB.BASEBOARD_FAB2(SCH_1):P12V_STBY
   2 A_P12V_STBY_FP_TRIGGER      B @BASEBOARD_FAB2_LIB.BASEBOARD_FAB2(SCH_1):A_P12V_STBY_FP_TRIGGER

RES_0402-10.0K,1%,1/16W,CHIP,GA  I108  R9P11
   1 A_P12V_STBY_FP_TRIGGER      A @BASEBOARD_FAB2_LIB.BASEBOARD_FAB2(SCH_1):A_P12V_STBY_FP_TRIGGER
   2 AGND_HSC      B @BASEBOARD_FAB2_LIB.BASEBOARD_FAB2(SCH_1):AGND_HSC

RES_0402-249K,1.0%,1/16W,CHIP,A  I145  R9P7
   1 P12V_STBY      A @BASEBOARD_FAB2_LIB.BASEBOARD_FAB2(SCH_1):P12V_STBY
   2 A_P12V_STBY_ADR_TRIGGER      B @BASEBOARD_FAB2_LIB.BASEBOARD_FAB2(SCH_1):A_P12V_STBY_ADR_TRIGGER

RES_0402-10.0K,1%,1/16W,CHIP,GA  I146  R9P9
   1 A_P12V_STBY_ADR_TRIGGER      A @BASEBOARD_FAB2_LIB.BASEBOARD_FAB2(SCH_1):A_P12V_STBY_ADR_TRIGGER
   2 AGND_HSC      B @BASEBOARD_FAB2_LIB.BASEBOARD_FAB2(SCH_1):AGND_HSC

RES_0402-10.0K,1%,1/16W,CHIP,GA  I149  R9P6
   1 P3V3_STBY      A @BASEBOARD_FAB2_LIB.BASEBOARD_FAB2(SCH_1):P3V3_STBY
   2 FM_UV_ADR_TRIGGER_N      B @BASEBOARD_FAB2_LIB.BASEBOARD_FAB2(SCH_1):FM_UV_ADR_TRIGGER_N

RES_0402-10.0,1%,1/16W,CHIP,G2A  I154  R1D51
   1 A_HSC_C      A @BASEBOARD_FAB2_LIB.BASEBOARD_FAB2(SCH_1):A_HSC_C
   2 A_HSC_GATE      B @BASEBOARD_FAB2_LIB.BASEBOARD_FAB2(SCH_1):A_HSC_GATE

CAP_1206-0.068UF,50V,20%,X7R,1A  I155  C1E2
   1 A_HSC_C      A @BASEBOARD_FAB2_LIB.BASEBOARD_FAB2(SCH_1):A_HSC_C
   2    GND      B @BASEBOARD_FAB2_LIB.BASEBOARD_FAB2(SCH_1):GND

RES_0402-10.0K,1%,1/16W,CHIP,GA  I158  R1D22
   1 P3V3_STBY      A @BASEBOARD_FAB2_LIB.BASEBOARD_FAB2(SCH_1):P3V3_STBY
   2 FM_OC_DETECT_N      B @BASEBOARD_FAB2_LIB.BASEBOARD_FAB2(SCH_1):FM_OC_DETECT_N

TPS3700_SM-IC,H69492-001  I163  U9P1
   5    GND    GND @BASEBOARD_FAB2_LIB.BASEBOARD_FAB2(SCH_1):GND
   4 A_P12V_STBY_ADR_TRIGGER   INAP @BASEBOARD_FAB2_LIB.BASEBOARD_FAB2(SCH_1):A_P12V_STBY_ADR_TRIGGER
   3 A_P12V_STBY_FP_TRIGGER   INBN @BASEBOARD_FAB2_LIB.BASEBOARD_FAB2(SCH_1):A_P12V_STBY_FP_TRIGGER
   6 FM_UV_ADR_TRIGGER_N   OUTA @BASEBOARD_FAB2_LIB.BASEBOARD_FAB2(SCH_1):FM_UV_ADR_TRIGGER_N
   1 A_P12V_STBY_FPH_GATE   OUTB @BASEBOARD_FAB2_LIB.BASEBOARD_FAB2(SCH_1):A_P12V_STBY_FPH_GATE
   2 P12V_STBY    VDD @BASEBOARD_FAB2_LIB.BASEBOARD_FAB2(SCH_1):P12V_STBY

TPS3700_SM-IC,H69492-001  I170  U1D2
   5    GND    GND @BASEBOARD_FAB2_LIB.BASEBOARD_FAB2(SCH_1):GND
   4 A_HSC_LOW   INAP @BASEBOARD_FAB2_LIB.BASEBOARD_FAB2(SCH_1):A_HSC_LOW
   3 A_HSC_HIGH   INBN @BASEBOARD_FAB2_LIB.BASEBOARD_FAB2(SCH_1):A_HSC_HIGH
   6 A_HSC_LOW_GATE   OUTA @BASEBOARD_FAB2_LIB.BASEBOARD_FAB2(SCH_1):A_HSC_LOW_GATE
   1 IRQ_OC_DETECT_N   OUTB @BASEBOARD_FAB2_LIB.BASEBOARD_FAB2(SCH_1):IRQ_OC_DETECT_N
   2 P12V_STBY    VDD @BASEBOARD_FAB2_LIB.BASEBOARD_FAB2(SCH_1):P12V_STBY

RES_0402-150.0K,1%,1/16W,CHIP,A  I172  R1D20
   1 A_HSC_CSOUT      A @BASEBOARD_FAB2_LIB.BASEBOARD_FAB2(SCH_1):A_HSC_CSOUT
   2 A_HSC_HIGH      B @BASEBOARD_FAB2_LIB.BASEBOARD_FAB2(SCH_1):A_HSC_HIGH

RES_0402-105.0K,1%,1/16W,CHIP,A  I173  R1D14
   1 A_HSC_CSOUT      A @BASEBOARD_FAB2_LIB.BASEBOARD_FAB2(SCH_1):A_HSC_CSOUT
   2 A_HSC_LOW      B @BASEBOARD_FAB2_LIB.BASEBOARD_FAB2(SCH_1):A_HSC_LOW

RES_0402-10.0K,1%,1/16W,CHIP,GA  I174  R1D12
   1 A_HSC_LOW      A @BASEBOARD_FAB2_LIB.BASEBOARD_FAB2(SCH_1):A_HSC_LOW
   2 AGND_HSC      B @BASEBOARD_FAB2_LIB.BASEBOARD_FAB2(SCH_1):AGND_HSC

RES_0402-10.0K,1%,1/16W,CHIP,GA  I175  R1D19
   1 A_HSC_HIGH      A @BASEBOARD_FAB2_LIB.BASEBOARD_FAB2(SCH_1):A_HSC_HIGH
   2 AGND_HSC      B @BASEBOARD_FAB2_LIB.BASEBOARD_FAB2(SCH_1):AGND_HSC

CAP_A_0402V-0.1UF,16V,10%,X7R,A  I185  C9P6
   1 P12V_STBY      A @BASEBOARD_FAB2_LIB.BASEBOARD_FAB2(SCH_1):P12V_STBY
   2 AGND_HSC      B @BASEBOARD_FAB2_LIB.BASEBOARD_FAB2(SCH_1):AGND_HSC

CAP_A_0402V-0.1UF,16V,10%,X7R,A  I187  C1D9
   1 P12V_STBY      A @BASEBOARD_FAB2_LIB.BASEBOARD_FAB2(SCH_1):P12V_STBY
   2 AGND_HSC      B @BASEBOARD_FAB2_LIB.BASEBOARD_FAB2(SCH_1):AGND_HSC

RES_0402-10.0K,1%,1/16W,CHIP,GA  I189  R1D10
   1 P3V3_STBY      A @BASEBOARD_FAB2_LIB.BASEBOARD_FAB2(SCH_1):P3V3_STBY
   2 A_HSC_LOW_GATE      B @BASEBOARD_FAB2_LIB.BASEBOARD_FAB2(SCH_1):A_HSC_LOW_GATE

RES_0402-10.0K,1%,1/16W,CHIP,GA  I191  R1D23
   1 P3V3_STBY      A @BASEBOARD_FAB2_LIB.BASEBOARD_FAB2(SCH_1):P3V3_STBY
   2 IRQ_OC_DETECT_N      B @BASEBOARD_FAB2_LIB.BASEBOARD_FAB2(SCH_1):IRQ_OC_DETECT_N

RES_0402-10.0K,1%,1/16W,CHIP,GA  I192  R9P10
   1 P3V3_STBY      A @BASEBOARD_FAB2_LIB.BASEBOARD_FAB2(SCH_1):P3V3_STBY
   2 A_P12V_STBY_FPH_GATE      B @BASEBOARD_FAB2_LIB.BASEBOARD_FAB2(SCH_1):A_P12V_STBY_FPH_GATE

FET_N_DUAL_SMLF-2N7002DW,FET,DA  I196  Q9P1
   2 A_HSC_LOW_GATE GATE<0> @BASEBOARD_FAB2_LIB.BASEBOARD_FAB2(SCH_1):A_HSC_LOW_GATE
   1    GND SOURCE<0> @BASEBOARD_FAB2_LIB.BASEBOARD_FAB2(SCH_1):GND
   6 A_HSC_LOW_DRAIN DRAIN<0> @BASEBOARD_FAB2_LIB.BASEBOARD_FAB2(SCH_1):A_HSC_LOW_DRAIN

RES_0402-0.0,5%,1/16W,EMPTY,G2A  I198  R9P15
   1 A_HSC_LOW_DRAIN      A @BASEBOARD_FAB2_LIB.BASEBOARD_FAB2(SCH_1):A_HSC_LOW_DRAIN
   2 IRQ_OC_DETECT_N      B @BASEBOARD_FAB2_LIB.BASEBOARD_FAB2(SCH_1):IRQ_OC_DETECT_N

FET_N_DUAL_SMLF-2N7002DW,FET,DA  I199  Q9P1
   5 A_P12V_STBY_FPH_GATE GATE<0> @BASEBOARD_FAB2_LIB.BASEBOARD_FAB2(SCH_1):A_P12V_STBY_FPH_GATE
   4    GND SOURCE<0> @BASEBOARD_FAB2_LIB.BASEBOARD_FAB2(SCH_1):GND
   3 IRQ_UV_DETECT_N DRAIN<0> @BASEBOARD_FAB2_LIB.BASEBOARD_FAB2(SCH_1):IRQ_UV_DETECT_N

TPS3700_SM-IC,H69492-001  I200  U9P2
   5    GND    GND @BASEBOARD_FAB2_LIB.BASEBOARD_FAB2(SCH_1):GND
   4 A_HSC_INAP   INAP @BASEBOARD_FAB2_LIB.BASEBOARD_FAB2(SCH_1):A_HSC_INAP
   3 A_HSC_TIMER_R   INBN @BASEBOARD_FAB2_LIB.BASEBOARD_FAB2(SCH_1):A_HSC_TIMER_R
   6 PWRGD_DSW_PWROK   OUTA @BASEBOARD_FAB2_LIB.BASEBOARD_FAB2(SCH_1):PWRGD_DSW_PWROK
   1 FM_HSC_TIMER_EXP_N   OUTB @BASEBOARD_FAB2_LIB.BASEBOARD_FAB2(SCH_1):FM_HSC_TIMER_EXP_N
   2 P3V3_STBY    VDD @BASEBOARD_FAB2_LIB.BASEBOARD_FAB2(SCH_1):P3V3_STBY

CAP_A_0402V-0.1UF,16V,10%,X7R,A  I201  C9P11
   1 P3V3_STBY      A @BASEBOARD_FAB2_LIB.BASEBOARD_FAB2(SCH_1):P3V3_STBY
   2    GND      B @BASEBOARD_FAB2_LIB.BASEBOARD_FAB2(SCH_1):GND

FET_N_SOT23LF-2N7002,FET,C7925A  I203  Q1D2
   1 FM_OC_DETECT_EN_N   GATE @BASEBOARD_FAB2_LIB.BASEBOARD_FAB2(SCH_1):FM_OC_DETECT_EN_N
   2    GND    SRC @BASEBOARD_FAB2_LIB.BASEBOARD_FAB2(SCH_1):GND
   3 FM_OC_DETECT_EN    DRN @BASEBOARD_FAB2_LIB.BASEBOARD_FAB2(SCH_1):FM_OC_DETECT_EN

RES_0402-4.75K,1%,1/16W,CHIP,GA  I204  R1D21
   1 P3V3_STBY      A @BASEBOARD_FAB2_LIB.BASEBOARD_FAB2(SCH_1):P3V3_STBY
   2 FM_OC_DETECT_EN      B @BASEBOARD_FAB2_LIB.BASEBOARD_FAB2(SCH_1):FM_OC_DETECT_EN

RES_0402-2.7K,1%,1/16W,CHIP,G2A  I210  R9P4
   1 P3V3_STBY      A @BASEBOARD_FAB2_LIB.BASEBOARD_FAB2(SCH_1):P3V3_STBY
   2 IRQ_UV_DETECT_N      B @BASEBOARD_FAB2_LIB.BASEBOARD_FAB2(SCH_1):IRQ_UV_DETECT_N

DIODE_SMLF-BAT54WS,IC,C73510-0A  I213  CR9P2
   1 FM_UV_ADR_TRIGGER_N      C @BASEBOARD_FAB2_LIB.BASEBOARD_FAB2(SCH_1):FM_UV_ADR_TRIGGER_N
   2 FM_DISABLE_FAN_N      A @BASEBOARD_FAB2_LIB.BASEBOARD_FAB2(SCH_1):FM_DISABLE_FAN_N

DIODE_SMLF-BAT54WS,IC,C73510-0A  I214  CR9P1
   1 IRQ_UV_DETECT_N      C @BASEBOARD_FAB2_LIB.BASEBOARD_FAB2(SCH_1):IRQ_UV_DETECT_N
   2 FM_DISABLE_FAN_N      A @BASEBOARD_FAB2_LIB.BASEBOARD_FAB2(SCH_1):FM_DISABLE_FAN_N

RES_0402-10.0K,1%,1/16W,CHIP,GA  I215  R9P5
   1 P3V3_STBY      A @BASEBOARD_FAB2_LIB.BASEBOARD_FAB2(SCH_1):P3V3_STBY
   2 FM_DISABLE_FAN_N      B @BASEBOARD_FAB2_LIB.BASEBOARD_FAB2(SCH_1):FM_DISABLE_FAN_N

RES_0402-4.99K,1%,1/16W,CHIP,GA  I218  R9P12
   1 A_HSC_INAP      A @BASEBOARD_FAB2_LIB.BASEBOARD_FAB2(SCH_1):A_HSC_INAP
   2 AGND_HSC      B @BASEBOARD_FAB2_LIB.BASEBOARD_FAB2(SCH_1):AGND_HSC

DIODE_SM-MBRS340T3G,EMPTY,C819A  I220  CR1F5
   1 P12V_STBY      C @BASEBOARD_FAB2_LIB.BASEBOARD_FAB2(SCH_1):P12V_STBY
   2    GND      A @BASEBOARD_FAB2_LIB.BASEBOARD_FAB2(SCH_1):GND

RES_0402-100.0K,1%,1/16W,CHIP,A  I222  R9P33
   1 P12V_STBY      A @BASEBOARD_FAB2_LIB.BASEBOARD_FAB2(SCH_1):P12V_STBY
   2 A_HSC_INAP      B @BASEBOARD_FAB2_LIB.BASEBOARD_FAB2(SCH_1):A_HSC_INAP

FET_N_SOT23LF-2N7002,FET,C7925A  I225  Q6W1
   1 BMC_UV_HIGH_SET   GATE @BASEBOARD_FAB2_LIB.BASEBOARD_FAB2(SCH_1):BMC_UV_HIGH_SET
   2    GND    SRC @BASEBOARD_FAB2_LIB.BASEBOARD_FAB2(SCH_1):GND
   3 UV_HIGH_SET_N    DRN @BASEBOARD_FAB2_LIB.BASEBOARD_FAB2(SCH_1):UV_HIGH_SET_N

RES_0402-100.0K,1%,1/16W,CHIP,B  I229  R6W1
   1 P3V3_STBY      A @BASEBOARD_FAB2_LIB.BASEBOARD_FAB2(SCH_1):P3V3_STBY
   2 BMC_UV_HIGH_SET      B @BASEBOARD_FAB2_LIB.BASEBOARD_FAB2(SCH_1):BMC_UV_HIGH_SET

RES_0402-10.0K,1%,1/16W,CHIP,GA  I230  R6W2
   1 BMC_UV_HIGH_SET      A @BASEBOARD_FAB2_LIB.BASEBOARD_FAB2(SCH_1):BMC_UV_HIGH_SET
   2    GND      B @BASEBOARD_FAB2_LIB.BASEBOARD_FAB2(SCH_1):GND

SC22P50V2JN-4GP_SMD-BCG-SC22P5A  I235  C9W1
   1 A_P12V_STBY_FP_TRIGGER      1 @BASEBOARD_FAB2_LIB.BASEBOARD_FAB2(SCH_1):A_P12V_STBY_FP_TRIGGER
   2 AGND_HSC      2 @BASEBOARD_FAB2_LIB.BASEBOARD_FAB2(SCH_1):AGND_HSC

SC22P50V2JN-4GP_SMD-BCG-SC22P5A  I236  C9W2
   1 A_P12V_STBY_ADR_TRIGGER      1 @BASEBOARD_FAB2_LIB.BASEBOARD_FAB2(SCH_1):A_P12V_STBY_ADR_TRIGGER
   2 AGND_HSC      2 @BASEBOARD_FAB2_LIB.BASEBOARD_FAB2(SCH_1):AGND_HSC

232KR2F-2-GP_SMD-RG1-232KR2F-2A  I239  R6W3
   1 UV_HIGH_SET_N      1 @BASEBOARD_FAB2_LIB.BASEBOARD_FAB2(SCH_1):UV_HIGH_SET_N
   2 A_P12V_STBY_FP_TRIGGER      2 @BASEBOARD_FAB2_LIB.BASEBOARD_FAB2(SCH_1):A_P12V_STBY_FP_TRIGGER


DRAWING: @BASEBOARD_FAB2_LIB.BASEBOARD_FAB2(SCH_1):PAGE201 

RES_0402-2.26K,1.0%,1/16W,CHIPA  I19  R4E4
   1 P3V3_STBY      A @BASEBOARD_FAB2_LIB.BASEBOARD_FAB2(SCH_1):P3V3_STBY
   2 FM_PVCCIN_CPU0_PWR_IN_ALERT_N      B @BASEBOARD_FAB2_LIB.BASEBOARD_FAB2(SCH_1):FM_PVCCIN_CPU0_PWR_IN_ALERT_N

RES_0402-100.0,1%,1/16W,CHIP,GA  I20  R4E10
   1 PVCCIO_CPU0      A @BASEBOARD_FAB2_LIB.BASEBOARD_FAB2(SCH_1):PVCCIO_CPU0
   2 SVID_DIO0_CPU0_R      B @BASEBOARD_FAB2_LIB.BASEBOARD_FAB2(SCH_1):SVID_DIO0_CPU0_R

RES_0402-2.26K,1.0%,1/16W,EMPTA  I22  R4D31
   1 P3V3_STBY      A @BASEBOARD_FAB2_LIB.BASEBOARD_FAB2(SCH_1):P3V3_STBY
   2 PU_VR_PVCCIN_CPU0_IMON      B @BASEBOARD_FAB2_LIB.BASEBOARD_FAB2(SCH_1):PU_VR_PVCCIN_CPU0_IMON

RES_0402-1.00K,1%,1/16W,CHIP,GA  I25  R4D58
   1 P3V3_STBY      A @BASEBOARD_FAB2_LIB.BASEBOARD_FAB2(SCH_1):P3V3_STBY
   2 VR_VRRDY_PVCCIN_CPU0      B @BASEBOARD_FAB2_LIB.BASEBOARD_FAB2(SCH_1):VR_VRRDY_PVCCIN_CPU0

RES_0402-0.0,5%,1/16W,CHIP,G21A  I26  R4D67
   1 SVID_VALERT_VCCIN_CPU0      A @BASEBOARD_FAB2_LIB.BASEBOARD_FAB2(SCH_1):SVID_VALERT_VCCIN_CPU0
   2 SVID_ALERT0_CPU0_R_N      B @BASEBOARD_FAB2_LIB.BASEBOARD_FAB2(SCH_1):SVID_ALERT0_CPU0_R_N

RES_0402-1.00K,1%,1/16W,CHIP,GA  I27  R4E5
   1 P3V3_STBY      A @BASEBOARD_FAB2_LIB.BASEBOARD_FAB2(SCH_1):P3V3_STBY
   2 PWRGD_PVSA_CPU0_R      B @BASEBOARD_FAB2_LIB.BASEBOARD_FAB2(SCH_1):PWRGD_PVSA_CPU0_R

RES_0402-0.0,5%,1/16W,CHIP,G21A  I28  R4D50
   1 SMB_VR_SDA_R      A @BASEBOARD_FAB2_LIB.BASEBOARD_FAB2(SCH_1):SMB_VR_SDA_R
   2 SMB_VR_STBY_LVC3_SDA      B @BASEBOARD_FAB2_LIB.BASEBOARD_FAB2(SCH_1):SMB_VR_STBY_LVC3_SDA

CAP_A_0402V-1.0UF,6.3V,10%,X6SA  I30  C4D25
   1 VR_PVCCIN_CPU0_VD12      A @BASEBOARD_FAB2_LIB.BASEBOARD_FAB2(SCH_1):VR_PVCCIN_CPU0_VD12
   2    GND      B @BASEBOARD_FAB2_LIB.BASEBOARD_FAB2(SCH_1):GND

RES_0402-0.0,5%,1/16W,CHIP,G21A  I31  R4D53
   1 SMB_VR_SCL_R      A @BASEBOARD_FAB2_LIB.BASEBOARD_FAB2(SCH_1):SMB_VR_SCL_R
   2 SMB_VR_STBY_LVC3_SCL      B @BASEBOARD_FAB2_LIB.BASEBOARD_FAB2(SCH_1):SMB_VR_STBY_LVC3_SCL

CAP_A_0402V-0.1UF,16V,10%,X7R,A  I32  C4D26
   1 VR_PVCCIN_CPU0_VD12      A @BASEBOARD_FAB2_LIB.BASEBOARD_FAB2(SCH_1):VR_PVCCIN_CPU0_VD12
   2    GND      B @BASEBOARD_FAB2_LIB.BASEBOARD_FAB2(SCH_1):GND

CAP_A_0402V-1.0UF,6.3V,10%,X6SA  I37  C4D15
   1 VR_PVCCIN_CPU0_VDD      A @BASEBOARD_FAB2_LIB.BASEBOARD_FAB2(SCH_1):VR_PVCCIN_CPU0_VDD
   2    GND      B @BASEBOARD_FAB2_LIB.BASEBOARD_FAB2(SCH_1):GND

CAP_A_0402V-0.1UF,16V,10%,X7R,A  I39  C4D19
   1 VR_PVCCIN_CPU0_VDD      A @BASEBOARD_FAB2_LIB.BASEBOARD_FAB2(SCH_1):VR_PVCCIN_CPU0_VDD
   2    GND      B @BASEBOARD_FAB2_LIB.BASEBOARD_FAB2(SCH_1):GND

RES_0402-0.0,5%,1/16W,CHIP,G21A  I40  R4D26
   1 P3V3_STBY      A @BASEBOARD_FAB2_LIB.BASEBOARD_FAB2(SCH_1):P3V3_STBY
   2 VR_PVCCIN_CPU0_VDD      B @BASEBOARD_FAB2_LIB.BASEBOARD_FAB2(SCH_1):VR_PVCCIN_CPU0_VDD

RES_0402-49.9,1%,1/16W,CHIP,G2A  I52  R4E9
   1 PVCCIO_CPU0      A @BASEBOARD_FAB2_LIB.BASEBOARD_FAB2(SCH_1):PVCCIO_CPU0
   2 SVID_CLK0_CPU0_R      B @BASEBOARD_FAB2_LIB.BASEBOARD_FAB2(SCH_1):SVID_CLK0_CPU0_R

RES_0402-100.0K,1%,1/16W,CHIP,B  I54  R4D27
   1 VR_FET_SW_P12V_STBY_PVCCIN_CPU0      A @BASEBOARD_FAB2_LIB.BASEBOARD_FAB2(SCH_1):VR_FET_SW_P12V_STBY_PVCCIN_CPU0
   2 VR_PVCCIN_CPU0_AVINSEN      B @BASEBOARD_FAB2_LIB.BASEBOARD_FAB2(SCH_1):VR_PVCCIN_CPU0_AVINSEN

RES_0402-1.5K,1%,1/16W,CHIP,G2A  I55  R4D32
   1 VR_PVCCIN_CPU0_AVINSEN      A @BASEBOARD_FAB2_LIB.BASEBOARD_FAB2(SCH_1):VR_PVCCIN_CPU0_AVINSEN
   2    GND      B @BASEBOARD_FAB2_LIB.BASEBOARD_FAB2(SCH_1):GND

RES_0402-150.0,1%,1/16W,CHIP,GA  I56  R4E6
   1 SVID_CLK0_CPU0_R      A @BASEBOARD_FAB2_LIB.BASEBOARD_FAB2(SCH_1):SVID_CLK0_CPU0_R
   2 SVID_VCLK_PVCCIN_CPU0      B @BASEBOARD_FAB2_LIB.BASEBOARD_FAB2(SCH_1):SVID_VCLK_PVCCIN_CPU0

CAP_0402LF-1000PF,50V,10%,X7R,A  I60  C4D20
   1 VR_PVCCIN_CPU0_AVINSEN      A @BASEBOARD_FAB2_LIB.BASEBOARD_FAB2(SCH_1):VR_PVCCIN_CPU0_AVINSEN
   2    GND      B @BASEBOARD_FAB2_LIB.BASEBOARD_FAB2(SCH_1):GND

CAP_0402LF-220PF,50V,10%,X7R,AA  I64  C4D29
   1 VSENSE_PVSA_CPU0_BVSP      A @BASEBOARD_FAB2_LIB.BASEBOARD_FAB2(SCH_1):VSENSE_PVSA_CPU0_BVSP
   2 VSENSE_PVSA_CPU0_N      B @BASEBOARD_FAB2_LIB.BASEBOARD_FAB2(SCH_1):VSENSE_PVSA_CPU0_N

CAP_0402LF-220PF,50V,10%,X7R,AA  I66  C4D17
   1 A_TSENSE_PVCCIN_CPU0      A @BASEBOARD_FAB2_LIB.BASEBOARD_FAB2(SCH_1):A_TSENSE_PVCCIN_CPU0
   2    GND      B @BASEBOARD_FAB2_LIB.BASEBOARD_FAB2(SCH_1):GND

CAP_0402LF-220PF,50V,10%,X7R,AA  I68  C4D18
   1 A_TSENSE_PVSA_CPU0      A @BASEBOARD_FAB2_LIB.BASEBOARD_FAB2(SCH_1):A_TSENSE_PVSA_CPU0
   2    GND      B @BASEBOARD_FAB2_LIB.BASEBOARD_FAB2(SCH_1):GND

CAP_0402LF-220PF,50V,10%,X7R,AA  I70  C4D45
   1 VSENSE_PVCCIN_CPU0_AVSP      A @BASEBOARD_FAB2_LIB.BASEBOARD_FAB2(SCH_1):VSENSE_PVCCIN_CPU0_AVSP
   2 VSENSE_PVCCIN_CPU0_N      B @BASEBOARD_FAB2_LIB.BASEBOARD_FAB2(SCH_1):VSENSE_PVCCIN_CPU0_N

RES_0402-0.0,5%,1/16W,CHIP,G21A  I98  R4D66
   1 SVID_VDIO_PVCCIN_CPU0      A @BASEBOARD_FAB2_LIB.BASEBOARD_FAB2(SCH_1):SVID_VDIO_PVCCIN_CPU0
   2 SVID_DIO0_CPU0_R      B @BASEBOARD_FAB2_LIB.BASEBOARD_FAB2(SCH_1):SVID_DIO0_CPU0_R

RES_0402-2.0K,1%,1/16W,EMPTY,GA  I102  R6P32
   1 P3V3_STBY      A @BASEBOARD_FAB2_LIB.BASEBOARD_FAB2(SCH_1):P3V3_STBY
   2 SMB_VR_STBY_LVC3_SDA      B @BASEBOARD_FAB2_LIB.BASEBOARD_FAB2(SCH_1):SMB_VR_STBY_LVC3_SDA

RES_0402-2.0K,1%,1/16W,EMPTY,GA  I103  R6P37
   1 P3V3_STBY      A @BASEBOARD_FAB2_LIB.BASEBOARD_FAB2(SCH_1):P3V3_STBY
   2 SMB_VR_STBY_LVC3_SCL      B @BASEBOARD_FAB2_LIB.BASEBOARD_FAB2(SCH_1):SMB_VR_STBY_LVC3_SCL

RES_0402-10.0,1%,1/16W,CHIP,G2A  I109  R4E8
   1 VSENSE_PVCCIN_CPU0_P      A @BASEBOARD_FAB2_LIB.BASEBOARD_FAB2(SCH_1):VSENSE_PVCCIN_CPU0_P
   2 VSENSE_PVCCIN_CPU0_AVSP      B @BASEBOARD_FAB2_LIB.BASEBOARD_FAB2(SCH_1):VSENSE_PVCCIN_CPU0_AVSP

RES_0402-10.0,1%,1/16W,CHIP,G2A  I110  R4D39
   1 VSENSE_PVSA_CPU0_P      A @BASEBOARD_FAB2_LIB.BASEBOARD_FAB2(SCH_1):VSENSE_PVSA_CPU0_P
   2 VSENSE_PVSA_CPU0_BVSP      B @BASEBOARD_FAB2_LIB.BASEBOARD_FAB2(SCH_1):VSENSE_PVSA_CPU0_BVSP

RES_0402-1.00K,1%,1/16W,CHIP,GA  I111  R4E3
   1 P3V3_STBY      A @BASEBOARD_FAB2_LIB.BASEBOARD_FAB2(SCH_1):P3V3_STBY
   2 IRQ_PVCCIN_CPU0_VRHOT_LVC3_R_N      B @BASEBOARD_FAB2_LIB.BASEBOARD_FAB2(SCH_1):IRQ_PVCCIN_CPU0_VRHOT_LVC3_R_N

RES_0402-2.26K,1.0%,1/16W,EMPTA  I116  R4E20
   1 P3V3_STBY      A @BASEBOARD_FAB2_LIB.BASEBOARD_FAB2(SCH_1):P3V3_STBY
   2 PU_VR_PVCCIN_CPU0_FLT1_SMBALT_N      B @BASEBOARD_FAB2_LIB.BASEBOARD_FAB2(SCH_1):PU_VR_PVCCIN_CPU0_FLT1_SMBALT_N_IMON

RES_0402-4.02K,1%,1/16W,CHIP,GA  I120  R6P27
   1 VR_PVCCIN_CPU0_XADDR2      A @BASEBOARD_FAB2_LIB.BASEBOARD_FAB2(SCH_1):VR_PVCCIN_CPU0_XADDR2
   2    GND      B @BASEBOARD_FAB2_LIB.BASEBOARD_FAB2(SCH_1):GND

RES_0402-4.02K,1%,1/16W,CHIP,GA  I121  R6P28
   1 VR_PVCCIN_CPU0_XADDR1      A @BASEBOARD_FAB2_LIB.BASEBOARD_FAB2(SCH_1):VR_PVCCIN_CPU0_XADDR1
   2    GND      B @BASEBOARD_FAB2_LIB.BASEBOARD_FAB2(SCH_1):GND

CONN3_C95678002_PIP-CONN,C9567A  I122  J8D4
   1 SMB_VR_STBY_LVC3_SDA    IO1 @BASEBOARD_FAB2_LIB.BASEBOARD_FAB2(SCH_1):SMB_VR_STBY_LVC3_SDA
   2    GND    IO2 @BASEBOARD_FAB2_LIB.BASEBOARD_FAB2(SCH_1):GND
   3 SMB_VR_STBY_LVC3_SCL    IO3 @BASEBOARD_FAB2_LIB.BASEBOARD_FAB2(SCH_1):SMB_VR_STBY_LVC3_SCL

RES_0402-22.1,1.0%,1/16W,CHIP,A  I124  R4D63
   1 VR_VRRDY_PVCCIN_CPU0      A @BASEBOARD_FAB2_LIB.BASEBOARD_FAB2(SCH_1):VR_VRRDY_PVCCIN_CPU0
   2 PWRGD_PVCCIN_CPU0      B @BASEBOARD_FAB2_LIB.BASEBOARD_FAB2(SCH_1):PWRGD_PVCCIN_CPU0

CAP_0402LF-1000PF,50V,10%,X7R,A  I125  C4D42
   1 VR_VRRDY_PVCCIN_CPU0      A @BASEBOARD_FAB2_LIB.BASEBOARD_FAB2(SCH_1):VR_VRRDY_PVCCIN_CPU0
   2    GND      B @BASEBOARD_FAB2_LIB.BASEBOARD_FAB2(SCH_1):GND

RES_0402-33.2,1%,1/16W,CHIP,G2A  I127  R4D65
   1 PWRGD_PVSA_CPU0_R      A @BASEBOARD_FAB2_LIB.BASEBOARD_FAB2(SCH_1):PWRGD_PVSA_CPU0_R
   2 PWRGD_PVSA_CPU0      B @BASEBOARD_FAB2_LIB.BASEBOARD_FAB2(SCH_1):PWRGD_PVSA_CPU0

RES_0402-33.2,1%,1/16W,CHIP,G2A  I128  R6P45
   1 IRQ_PVCCIN_CPU0_VRHOT_LVC3_R_N      A @BASEBOARD_FAB2_LIB.BASEBOARD_FAB2(SCH_1):IRQ_PVCCIN_CPU0_VRHOT_LVC3_R_N
   2 IRQ_PVCCIN_CPU0_VRHOT_LVC3_N      B @BASEBOARD_FAB2_LIB.BASEBOARD_FAB2(SCH_1):IRQ_PVCCIN_CPU0_VRHOT_LVC3_N

RES_0402-0.0,5%,1/16W,CHIP,G21A  I131  R6P18
   1 FM_PVCCIN_PVCCSA_CPU0_EN_LVC1      A @BASEBOARD_FAB2_LIB.BASEBOARD_FAB2(SCH_1):FM_PVCCIN_PVCCSA_CPU0_EN_LVC1
   2 VR_PVCCIN_CPU0_VREN      B @BASEBOARD_FAB2_LIB.BASEBOARD_FAB2(SCH_1):VR_PVCCIN_CPU0_VREN

RES_0402-1.00K,1%,1/16W,CHIP,GA  I132  R6P16
   1 PVCCIO_CPU0      A @BASEBOARD_FAB2_LIB.BASEBOARD_FAB2(SCH_1):PVCCIO_CPU0
   2 VR_PVCCIN_CPU0_VREN      B @BASEBOARD_FAB2_LIB.BASEBOARD_FAB2(SCH_1):VR_PVCCIN_CPU0_VREN

RES_0402-0.0,5%,1/16W,CHIP,G21A  I139  R6P42
   1 VR_PVCCIN_CPU0_VD12      A @BASEBOARD_FAB2_LIB.BASEBOARD_FAB2(SCH_1):VR_PVCCIN_CPU0_VD12
   2 VR_PVCCIN_CPU0_AIREF2      B @BASEBOARD_FAB2_LIB.BASEBOARD_FAB2(SCH_1):VR_PVCCIN_CPU0_AIREF2

RES_0402-0.0,5%,1/16W,CHIP,G21A  I147  R6P38
   1 VR_PVCCIN_CPU0_VD12      A @BASEBOARD_FAB2_LIB.BASEBOARD_FAB2(SCH_1):VR_PVCCIN_CPU0_VD12
   2 VR_PVCCIN_CPU0_AIREF3      B @BASEBOARD_FAB2_LIB.BASEBOARD_FAB2(SCH_1):VR_PVCCIN_CPU0_AIREF3

RES_0402-0.0,5%,1/16W,CHIP,G21A  I148  R6P34
   1 VR_PVCCIN_CPU0_VD12      A @BASEBOARD_FAB2_LIB.BASEBOARD_FAB2(SCH_1):VR_PVCCIN_CPU0_VD12
   2 VR_PVCCIN_CPU0_AIREF4      B @BASEBOARD_FAB2_LIB.BASEBOARD_FAB2(SCH_1):VR_PVCCIN_CPU0_AIREF4

RES_0402-0.0,5%,1/16W,CHIP,G21A  I149  R6P30
   1 VR_PVCCIN_CPU0_VD12      A @BASEBOARD_FAB2_LIB.BASEBOARD_FAB2(SCH_1):VR_PVCCIN_CPU0_VD12
   2 VR_PVCCIN_CPU0_AIREF5      B @BASEBOARD_FAB2_LIB.BASEBOARD_FAB2(SCH_1):VR_PVCCIN_CPU0_AIREF5

RES_0402-0.0,5%,1/16W,CHIP,G21A  I150  R6P43
   1 VR_PVCCIN_CPU0_VD12      A @BASEBOARD_FAB2_LIB.BASEBOARD_FAB2(SCH_1):VR_PVCCIN_CPU0_VD12
   2 VR_PVCCIN_CPU0_AIREF1      B @BASEBOARD_FAB2_LIB.BASEBOARD_FAB2(SCH_1):VR_PVCCIN_CPU0_AIREF1

RES_0402-0.0,5%,1/16W,CHIP,G21A  I154  R6P29
   1 VR_PVCCIN_CPU0_VD12      A @BASEBOARD_FAB2_LIB.BASEBOARD_FAB2(SCH_1):VR_PVCCIN_CPU0_VD12
   2 VR_PVSA_CPU0_BIREF1      B @BASEBOARD_FAB2_LIB.BASEBOARD_FAB2(SCH_1):VR_PVSA_CPU0_BIREF1

PXE1610B_QFN-IC,H79206-001  I155  EU4D4
   1 VR_PVSA_CPU0_PWM  BPWM1 @BASEBOARD_FAB2_LIB.BASEBOARD_FAB2(SCH_1):VR_PVSA_CPU0_PWM
   2 TP_PVCCIN_CPU0_APWM6  APWM6 @BASEBOARD_FAB2_LIB.BASEBOARD_FAB2(SCH_1):TP_PVCCIN_CPU0_APWM6
   3 VR_PVCCIN_CPU0_PWM5  APWM5 @BASEBOARD_FAB2_LIB.BASEBOARD_FAB2(SCH_1):VR_PVCCIN_CPU0_PWM5
   4 VR_PVCCIN_CPU0_PWM4  APWM4 @BASEBOARD_FAB2_LIB.BASEBOARD_FAB2(SCH_1):VR_PVCCIN_CPU0_PWM4
   5 VR_PVCCIN_CPU0_PWM3  APWM3 @BASEBOARD_FAB2_LIB.BASEBOARD_FAB2(SCH_1):VR_PVCCIN_CPU0_PWM3
   6 VR_PVCCIN_CPU0_PWM2  APWM2 @BASEBOARD_FAB2_LIB.BASEBOARD_FAB2(SCH_1):VR_PVCCIN_CPU0_PWM2
   7 VR_PVCCIN_CPU0_PWM1  APWM1 @BASEBOARD_FAB2_LIB.BASEBOARD_FAB2(SCH_1):VR_PVCCIN_CPU0_PWM1
   8 SMB_VR_SDA_R    SDA @BASEBOARD_FAB2_LIB.BASEBOARD_FAB2(SCH_1):SMB_VR_SDA_R
   9 SMB_VR_SCL_R    SCL @BASEBOARD_FAB2_LIB.BASEBOARD_FAB2(SCH_1):SMB_VR_SCL_R
  10 TP_PVCCIN_CPU0_RESET RESET_N @BASEBOARD_FAB2_LIB.BASEBOARD_FAB2(SCH_1):TP_PVCCIN_CPU0_RESET
  11 VR_VRRDY_PVCCIN_CPU0 AVRRDY @BASEBOARD_FAB2_LIB.BASEBOARD_FAB2(SCH_1):VR_VRRDY_PVCCIN_CPU0
  12 VR_PVCCIN_CPU0_VREN  AVREN @BASEBOARD_FAB2_LIB.BASEBOARD_FAB2(SCH_1):VR_PVCCIN_CPU0_VREN
  13 IRQ_PVCCIN_CPU0_VRHOT_LVC3_R_N VRHOT_N @BASEBOARD_FAB2_LIB.BASEBOARD_FAB2(SCH_1):IRQ_PVCCIN_CPU0_VRHOT_LVC3_R_N
  14 FM_PVCCIN_CPU0_PWR_IN_ALERT_N PINALRT_N @BASEBOARD_FAB2_LIB.BASEBOARD_FAB2(SCH_1):FM_PVCCIN_CPU0_PWR_IN_ALERT_N
  15 PWRGD_PVSA_CPU0_R    MP0 @BASEBOARD_FAB2_LIB.BASEBOARD_FAB2(SCH_1):PWRGD_PVSA_CPU0_R
  16 TP_PVCCIN_CPU0_GP1    MP1 @BASEBOARD_FAB2_LIB.BASEBOARD_FAB2(SCH_1):TP_PVCCIN_CPU0_GP1
  17 SVID_VCLK_PVCCIN_CPU0   VCLK @BASEBOARD_FAB2_LIB.BASEBOARD_FAB2(SCH_1):SVID_VCLK_PVCCIN_CPU0
  18 SVID_VDIO_PVCCIN_CPU0   VDIO @BASEBOARD_FAB2_LIB.BASEBOARD_FAB2(SCH_1):SVID_VDIO_PVCCIN_CPU0
  19 SVID_VALERT_VCCIN_CPU0 VALRT_N @BASEBOARD_FAB2_LIB.BASEBOARD_FAB2(SCH_1):SVID_VALERT_VCCIN_CPU0
  20 PU_VR_PVCCIN_CPU0_FLT1_SMBALT_N    MP2 @BASEBOARD_FAB2_LIB.BASEBOARD_FAB2(SCH_1):PU_VR_PVCCIN_CPU0_FLT1_SMBALT_N_IMON
  21 VSENSE_PVCCIN_CPU0_AVSP  AVSEN @BASEBOARD_FAB2_LIB.BASEBOARD_FAB2(SCH_1):VSENSE_PVCCIN_CPU0_AVSP
  22 VSENSE_PVCCIN_CPU0_N  AVREF @BASEBOARD_FAB2_LIB.BASEBOARD_FAB2(SCH_1):VSENSE_PVCCIN_CPU0_N
  23 VR_PVCCIN_CPU0_AIREF1 AIREF1 @BASEBOARD_FAB2_LIB.BASEBOARD_FAB2(SCH_1):VR_PVCCIN_CPU0_AIREF1
  24 ISENSE_PVCCIN_CPU0_PH1_IMON AISEN1 @BASEBOARD_FAB2_LIB.BASEBOARD_FAB2(SCH_1):ISENSE_PVCCIN_CPU0_PH1_IMON
  25 VR_PVCCIN_CPU0_AIREF2 AIREF2 @BASEBOARD_FAB2_LIB.BASEBOARD_FAB2(SCH_1):VR_PVCCIN_CPU0_AIREF2
  26 ISENSE_PVCCIN_CPU0_PH2_IMON AISEN2 @BASEBOARD_FAB2_LIB.BASEBOARD_FAB2(SCH_1):ISENSE_PVCCIN_CPU0_PH2_IMON
  27 VR_PVCCIN_CPU0_AIREF3 AIREF3 @BASEBOARD_FAB2_LIB.BASEBOARD_FAB2(SCH_1):VR_PVCCIN_CPU0_AIREF3
  28 ISENSE_PVCCIN_CPU0_PH3_IMON AISEN3 @BASEBOARD_FAB2_LIB.BASEBOARD_FAB2(SCH_1):ISENSE_PVCCIN_CPU0_PH3_IMON
  29 VR_PVCCIN_CPU0_AIREF4 AIREF4 @BASEBOARD_FAB2_LIB.BASEBOARD_FAB2(SCH_1):VR_PVCCIN_CPU0_AIREF4
  30 ISENSE_PVCCIN_CPU0_PH4_IMON AISEN4 @BASEBOARD_FAB2_LIB.BASEBOARD_FAB2(SCH_1):ISENSE_PVCCIN_CPU0_PH4_IMON
  31 VR_PVCCIN_CPU0_AIREF5 AIREF5 @BASEBOARD_FAB2_LIB.BASEBOARD_FAB2(SCH_1):VR_PVCCIN_CPU0_AIREF5
  32 ISENSE_PVCCIN_CPU0_PH5_IMON AISEN5 @BASEBOARD_FAB2_LIB.BASEBOARD_FAB2(SCH_1):ISENSE_PVCCIN_CPU0_PH5_IMON
  33 TP_PVCCIN_CPU0_AIREF6 AIREF6 @BASEBOARD_FAB2_LIB.BASEBOARD_FAB2(SCH_1):TP_PVCCIN_CPU0_AIREF6
  34 TP_PVCCIN_CPU0_AISEN6 AISEN6 @BASEBOARD_FAB2_LIB.BASEBOARD_FAB2(SCH_1):TP_PVCCIN_CPU0_AISEN6
  35 VSENSE_PVSA_CPU0_BVSP  BVSEN @BASEBOARD_FAB2_LIB.BASEBOARD_FAB2(SCH_1):VSENSE_PVSA_CPU0_BVSP
  36 VSENSE_PVSA_CPU0_N  BVREF @BASEBOARD_FAB2_LIB.BASEBOARD_FAB2(SCH_1):VSENSE_PVSA_CPU0_N
  37 VR_PVSA_CPU0_BIREF1 BIREF1 @BASEBOARD_FAB2_LIB.BASEBOARD_FAB2(SCH_1):VR_PVSA_CPU0_BIREF1
  38 ISENSE_PVSA_CPU0_IMON BISEN1 @BASEBOARD_FAB2_LIB.BASEBOARD_FAB2(SCH_1):ISENSE_PVSA_CPU0_IMON
  39 PU_VR_PVCCIN_CPU0_IMON    MP3 @BASEBOARD_FAB2_LIB.BASEBOARD_FAB2(SCH_1):PU_VR_PVCCIN_CPU0_IMON
  40 TP_PVCCIN_CPU0_FAULT1_20    MP4 @BASEBOARD_FAB2_LIB.BASEBOARD_FAB2(SCH_1):TP_PVCCIN_CPU0_FAULT1_20
  41 VR_PVCCIN_CPU0_XADDR2 XADDR2 @BASEBOARD_FAB2_LIB.BASEBOARD_FAB2(SCH_1):VR_PVCCIN_CPU0_XADDR2
  42 A_TSENSE_PVSA_CPU0  BTSEN @BASEBOARD_FAB2_LIB.BASEBOARD_FAB2(SCH_1):A_TSENSE_PVSA_CPU0
  43 A_TSENSE_PVCCIN_CPU0  ATSEN @BASEBOARD_FAB2_LIB.BASEBOARD_FAB2(SCH_1):A_TSENSE_PVCCIN_CPU0
  44 VR_PVCCIN_CPU0_XADDR1 XADDR1 @BASEBOARD_FAB2_LIB.BASEBOARD_FAB2(SCH_1):VR_PVCCIN_CPU0_XADDR1
  45 VR_PVCCIN_CPU0_AVINSEN VINSEN @BASEBOARD_FAB2_LIB.BASEBOARD_FAB2(SCH_1):VR_PVCCIN_CPU0_AVINSEN
  46 PVCCIN_PVSA_CPU0_IINSEN IINSEN @BASEBOARD_FAB2_LIB.BASEBOARD_FAB2(SCH_1):PVCCIN_PVSA_CPU0_IINSEN
  47 VR_PVCCIN_CPU0_VDD    VDD @BASEBOARD_FAB2_LIB.BASEBOARD_FAB2(SCH_1):VR_PVCCIN_CPU0_VDD
  48 VR_PVCCIN_CPU0_VD12   VD12 @BASEBOARD_FAB2_LIB.BASEBOARD_FAB2(SCH_1):VR_PVCCIN_CPU0_VD12
  49    GND  THPAD @BASEBOARD_FAB2_LIB.BASEBOARD_FAB2(SCH_1):GND


DRAWING: @BASEBOARD_FAB2_LIB.BASEBOARD_FAB2(SCH_1):PAGE206 

RES_0402-100.0,1%,1/16W,CHIP,GA  I4  R9P1
   1 PVCCIO_CPU1      A @BASEBOARD_FAB2_LIB.BASEBOARD_FAB2(SCH_1):PVCCIO_CPU1
   2 SVID_DIO0_CPU1_R      B @BASEBOARD_FAB2_LIB.BASEBOARD_FAB2(SCH_1):SVID_DIO0_CPU1_R

RES_0402-1.00K,1%,1/16W,CHIP,GA  I6  R1D6
   1 P3V3_STBY      A @BASEBOARD_FAB2_LIB.BASEBOARD_FAB2(SCH_1):P3V3_STBY
   2 IRQ_PVCCIN_CPU1_VRHOT_LVC3_R_N      B @BASEBOARD_FAB2_LIB.BASEBOARD_FAB2(SCH_1):IRQ_PVCCIN_CPU1_VRHOT_LVC3_R_N

RES_0402-2.26K,1.0%,1/16W,CHIPA  I7  R1D7
   1 P3V3_STBY      A @BASEBOARD_FAB2_LIB.BASEBOARD_FAB2(SCH_1):P3V3_STBY
   2 FM_PVCCIN_CPU1_PWR_IN_ALERT_N      B @BASEBOARD_FAB2_LIB.BASEBOARD_FAB2(SCH_1):FM_PVCCIN_CPU1_PWR_IN_ALERT_N

RES_0402-0.0,5%,1/16W,CHIP,G21A  I27  R1C23
   1 SMB_VR_SDA_R1      A @BASEBOARD_FAB2_LIB.BASEBOARD_FAB2(SCH_1):SMB_VR_SDA_R1
   2 SMB_VR_STBY_LVC3_SDA      B @BASEBOARD_FAB2_LIB.BASEBOARD_FAB2(SCH_1):SMB_VR_STBY_LVC3_SDA

RES_0402-0.0,5%,1/16W,CHIP,G21A  I28  R1C25
   1 SMB_VR_SCL_R1      A @BASEBOARD_FAB2_LIB.BASEBOARD_FAB2(SCH_1):SMB_VR_SCL_R1
   2 SMB_VR_STBY_LVC3_SCL      B @BASEBOARD_FAB2_LIB.BASEBOARD_FAB2(SCH_1):SMB_VR_STBY_LVC3_SCL

CAP_A_0402V-1.0UF,6.3V,10%,X6SA  I29  C1C13
   1 VR_PVCCIN_CPU1_VD12      A @BASEBOARD_FAB2_LIB.BASEBOARD_FAB2(SCH_1):VR_PVCCIN_CPU1_VD12
   2    GND      B @BASEBOARD_FAB2_LIB.BASEBOARD_FAB2(SCH_1):GND

CAP_A_0402V-0.1UF,16V,10%,X7R,A  I31  C1C14
   1 VR_PVCCIN_CPU1_VD12      A @BASEBOARD_FAB2_LIB.BASEBOARD_FAB2(SCH_1):VR_PVCCIN_CPU1_VD12
   2    GND      B @BASEBOARD_FAB2_LIB.BASEBOARD_FAB2(SCH_1):GND

RES_0402-2.26K,1.0%,1/16W,EMPTA  I33  R1D53
   1 P3V3_STBY      A @BASEBOARD_FAB2_LIB.BASEBOARD_FAB2(SCH_1):P3V3_STBY
   2 PU_VR_PVCCIN_CPU1_FLT1_SMBALT_N      B @BASEBOARD_FAB2_LIB.BASEBOARD_FAB2(SCH_1):PU_VR_PVCCIN_CPU1_FLT1_SMBALT_N_IMON

RES_0402-2.26K,1.0%,1/16W,EMPTA  I34  R1C18
   1 P3V3_STBY      A @BASEBOARD_FAB2_LIB.BASEBOARD_FAB2(SCH_1):P3V3_STBY
   2 PU_VR_PVCCIN_CPU1_IMON      B @BASEBOARD_FAB2_LIB.BASEBOARD_FAB2(SCH_1):PU_VR_PVCCIN_CPU1_IMON

RES_0402-1.00K,1%,1/16W,CHIP,GA  I35  R1C28
   1 P3V3_STBY      A @BASEBOARD_FAB2_LIB.BASEBOARD_FAB2(SCH_1):P3V3_STBY
   2 VR_VRRDY_PVCCIN_CPU1      B @BASEBOARD_FAB2_LIB.BASEBOARD_FAB2(SCH_1):VR_VRRDY_PVCCIN_CPU1

RES_0402-1.00K,1%,1/16W,CHIP,GA  I36  R1D8
   1 P3V3_STBY      A @BASEBOARD_FAB2_LIB.BASEBOARD_FAB2(SCH_1):P3V3_STBY
   2 PWRGD_PVSA_CPU1_R      B @BASEBOARD_FAB2_LIB.BASEBOARD_FAB2(SCH_1):PWRGD_PVSA_CPU1_R

RES_0402-0.0,5%,1/16W,CHIP,G21A  I37  R1D3
   1 SVID_VALERT_VCCIN_CPU1      A @BASEBOARD_FAB2_LIB.BASEBOARD_FAB2(SCH_1):SVID_VALERT_VCCIN_CPU1
   2 SVID_ALERT0_CPU1_R_N      B @BASEBOARD_FAB2_LIB.BASEBOARD_FAB2(SCH_1):SVID_ALERT0_CPU1_R_N

RES_0402-0.0,5%,1/16W,CHIP,G21A  I38  R1D2
   1 SVID_VDIO_PVCCIN_CPU1      A @BASEBOARD_FAB2_LIB.BASEBOARD_FAB2(SCH_1):SVID_VDIO_PVCCIN_CPU1
   2 SVID_DIO0_CPU1_R      B @BASEBOARD_FAB2_LIB.BASEBOARD_FAB2(SCH_1):SVID_DIO0_CPU1_R

CAP_A_0402V-1.0UF,6.3V,10%,X6SA  I41  C1C7
   1 VR_PVCCIN_CPU1_VDD      A @BASEBOARD_FAB2_LIB.BASEBOARD_FAB2(SCH_1):VR_PVCCIN_CPU1_VDD
   2    GND      B @BASEBOARD_FAB2_LIB.BASEBOARD_FAB2(SCH_1):GND

CAP_A_0402V-0.1UF,16V,10%,X7R,A  I42  C1C9
   1 VR_PVCCIN_CPU1_VDD      A @BASEBOARD_FAB2_LIB.BASEBOARD_FAB2(SCH_1):VR_PVCCIN_CPU1_VDD
   2    GND      B @BASEBOARD_FAB2_LIB.BASEBOARD_FAB2(SCH_1):GND

RES_0402-0.0,5%,1/16W,CHIP,G21A  I46  R1C14
   1 P3V3_STBY      A @BASEBOARD_FAB2_LIB.BASEBOARD_FAB2(SCH_1):P3V3_STBY
   2 VR_PVCCIN_CPU1_VDD      B @BASEBOARD_FAB2_LIB.BASEBOARD_FAB2(SCH_1):VR_PVCCIN_CPU1_VDD

RES_0402-100.0K,1%,1/16W,CHIP,B  I49  R1C13
   1 VR_FET_SW_P12V_STBY_PVCCIN_CPU1      A @BASEBOARD_FAB2_LIB.BASEBOARD_FAB2(SCH_1):VR_FET_SW_P12V_STBY_PVCCIN_CPU1
   2 VR_PVCCIN_CPU1_AVINSEN      B @BASEBOARD_FAB2_LIB.BASEBOARD_FAB2(SCH_1):VR_PVCCIN_CPU1_AVINSEN

RES_0402-49.9,1%,1/16W,CHIP,G2A  I53  R9P2
   1 PVCCIO_CPU1      A @BASEBOARD_FAB2_LIB.BASEBOARD_FAB2(SCH_1):PVCCIO_CPU1
   2 SVID_CLK0_CPU1_R      B @BASEBOARD_FAB2_LIB.BASEBOARD_FAB2(SCH_1):SVID_CLK0_CPU1_R

RES_0402-150.0,1%,1/16W,CHIP,GA  I54  R1D9
   1 SVID_CLK0_CPU1_R      A @BASEBOARD_FAB2_LIB.BASEBOARD_FAB2(SCH_1):SVID_CLK0_CPU1_R
   2 SVID_VCLK_PVCCIN_CPU1      B @BASEBOARD_FAB2_LIB.BASEBOARD_FAB2(SCH_1):SVID_VCLK_PVCCIN_CPU1

RES_0402-1.5K,1%,1/16W,CHIP,G2A  I56  R1C16
   1 VR_PVCCIN_CPU1_AVINSEN      A @BASEBOARD_FAB2_LIB.BASEBOARD_FAB2(SCH_1):VR_PVCCIN_CPU1_AVINSEN
   2    GND      B @BASEBOARD_FAB2_LIB.BASEBOARD_FAB2(SCH_1):GND

CAP_0402LF-220PF,50V,10%,X7R,AA  I68  C1C16
   1 VSENSE_PVSA_CPU1_BVSP      A @BASEBOARD_FAB2_LIB.BASEBOARD_FAB2(SCH_1):VSENSE_PVSA_CPU1_BVSP
   2 VSENSE_PVSA_CPU1_N      B @BASEBOARD_FAB2_LIB.BASEBOARD_FAB2(SCH_1):VSENSE_PVSA_CPU1_N

CAP_0402LF-220PF,50V,10%,X7R,AA  I69  C1C10
   1 A_TSENSE_PVCCIN_CPU1      A @BASEBOARD_FAB2_LIB.BASEBOARD_FAB2(SCH_1):A_TSENSE_PVCCIN_CPU1
   2    GND      B @BASEBOARD_FAB2_LIB.BASEBOARD_FAB2(SCH_1):GND

CAP_0402LF-220PF,50V,10%,X7R,AA  I71  C1C11
   1 A_TSENSE_PVSA_CPU1      A @BASEBOARD_FAB2_LIB.BASEBOARD_FAB2(SCH_1):A_TSENSE_PVSA_CPU1
   2    GND      B @BASEBOARD_FAB2_LIB.BASEBOARD_FAB2(SCH_1):GND

CAP_0402LF-1000PF,50V,10%,X7R,A  I73  C1C8
   1 VR_PVCCIN_CPU1_AVINSEN      A @BASEBOARD_FAB2_LIB.BASEBOARD_FAB2(SCH_1):VR_PVCCIN_CPU1_AVINSEN
   2    GND      B @BASEBOARD_FAB2_LIB.BASEBOARD_FAB2(SCH_1):GND

RES_0402-10.0,1%,1/16W,CHIP,G2A  I77  R1C21
   1 VSENSE_PVSA_CPU1_P      A @BASEBOARD_FAB2_LIB.BASEBOARD_FAB2(SCH_1):VSENSE_PVSA_CPU1_P
   2 VSENSE_PVSA_CPU1_BVSP      B @BASEBOARD_FAB2_LIB.BASEBOARD_FAB2(SCH_1):VSENSE_PVSA_CPU1_BVSP

CAP_0402LF-220PF,50V,10%,X7R,AA  I78  C1D1
   1 VSENSE_PVCCIN_CPU1_AVSP      A @BASEBOARD_FAB2_LIB.BASEBOARD_FAB2(SCH_1):VSENSE_PVCCIN_CPU1_AVSP
   2 VSENSE_PVCCIN_CPU1_N      B @BASEBOARD_FAB2_LIB.BASEBOARD_FAB2(SCH_1):VSENSE_PVCCIN_CPU1_N

RES_0402-10.0,1%,1/16W,CHIP,G2A  I79  R1D4
   1 VSENSE_PVCCIN_CPU1_P      A @BASEBOARD_FAB2_LIB.BASEBOARD_FAB2(SCH_1):VSENSE_PVCCIN_CPU1_P
   2 VSENSE_PVCCIN_CPU1_AVSP      B @BASEBOARD_FAB2_LIB.BASEBOARD_FAB2(SCH_1):VSENSE_PVCCIN_CPU1_AVSP

RES_0402-3.16K,1%,1/16W,CHIP,GA  I111  R9N7
   1 VR_PVCCIN_CPU1_XADDR2      A @BASEBOARD_FAB2_LIB.BASEBOARD_FAB2(SCH_1):VR_PVCCIN_CPU1_XADDR2
   2    GND      B @BASEBOARD_FAB2_LIB.BASEBOARD_FAB2(SCH_1):GND

RES_0402-4.02K,1%,1/16W,CHIP,GA  I112  R9N8
   1 VR_PVCCIN_CPU1_XADDR1      A @BASEBOARD_FAB2_LIB.BASEBOARD_FAB2(SCH_1):VR_PVCCIN_CPU1_XADDR1
   2    GND      B @BASEBOARD_FAB2_LIB.BASEBOARD_FAB2(SCH_1):GND

RES_0402-22.1,1.0%,1/16W,CHIP,A  I113  R1C30
   1 VR_VRRDY_PVCCIN_CPU1      A @BASEBOARD_FAB2_LIB.BASEBOARD_FAB2(SCH_1):VR_VRRDY_PVCCIN_CPU1
   2 PWRGD_PVCCIN_CPU1      B @BASEBOARD_FAB2_LIB.BASEBOARD_FAB2(SCH_1):PWRGD_PVCCIN_CPU1

CAP_0402LF-1000PF,50V,10%,X7R,A  I114  C1C23
   1 VR_VRRDY_PVCCIN_CPU1      A @BASEBOARD_FAB2_LIB.BASEBOARD_FAB2(SCH_1):VR_VRRDY_PVCCIN_CPU1
   2    GND      B @BASEBOARD_FAB2_LIB.BASEBOARD_FAB2(SCH_1):GND

RES_0402-33.2,1%,1/16W,CHIP,G2A  I116  R1D1
   1 PWRGD_PVSA_CPU1_R      A @BASEBOARD_FAB2_LIB.BASEBOARD_FAB2(SCH_1):PWRGD_PVSA_CPU1_R
   2 PWRGD_PVSA_CPU1      B @BASEBOARD_FAB2_LIB.BASEBOARD_FAB2(SCH_1):PWRGD_PVSA_CPU1

RES_0402-33.2,1%,1/16W,CHIP,G2A  I117  R9P3
   1 IRQ_PVCCIN_CPU1_VRHOT_LVC3_R_N      A @BASEBOARD_FAB2_LIB.BASEBOARD_FAB2(SCH_1):IRQ_PVCCIN_CPU1_VRHOT_LVC3_R_N
   2 IRQ_PVCCIN_CPU1_VRHOT_LVC3_N      B @BASEBOARD_FAB2_LIB.BASEBOARD_FAB2(SCH_1):IRQ_PVCCIN_CPU1_VRHOT_LVC3_N

RES_0402-0.0,5%,1/16W,CHIP,G21A  I119  R9N16
   1 FM_PVCCIN_PVCCSA_CPU1_EN_LVC1      A @BASEBOARD_FAB2_LIB.BASEBOARD_FAB2(SCH_1):FM_PVCCIN_PVCCSA_CPU1_EN_LVC1
   2 VR_PVCCIN_CPU1_VREN      B @BASEBOARD_FAB2_LIB.BASEBOARD_FAB2(SCH_1):VR_PVCCIN_CPU1_VREN

RES_0402-1.00K,1%,1/16W,CHIP,GA  I120  R9N14
   1 PVCCIO_CPU1      A @BASEBOARD_FAB2_LIB.BASEBOARD_FAB2(SCH_1):PVCCIO_CPU1
   2 VR_PVCCIN_CPU1_VREN      B @BASEBOARD_FAB2_LIB.BASEBOARD_FAB2(SCH_1):VR_PVCCIN_CPU1_VREN

RES_0402-0.0,5%,1/16W,CHIP,G21A  I122  R9N15
   1 VR_PVCCIN_CPU1_VD12      A @BASEBOARD_FAB2_LIB.BASEBOARD_FAB2(SCH_1):VR_PVCCIN_CPU1_VD12
   2 VR_PVCCIN_CPU1_AIREF1      B @BASEBOARD_FAB2_LIB.BASEBOARD_FAB2(SCH_1):VR_PVCCIN_CPU1_AIREF1

RES_0402-0.0,5%,1/16W,CHIP,G21A  I123  R9N17
   1 VR_PVCCIN_CPU1_VD12      A @BASEBOARD_FAB2_LIB.BASEBOARD_FAB2(SCH_1):VR_PVCCIN_CPU1_VD12
   2 VR_PVCCIN_CPU1_AIREF2      B @BASEBOARD_FAB2_LIB.BASEBOARD_FAB2(SCH_1):VR_PVCCIN_CPU1_AIREF2

RES_0402-0.0,5%,1/16W,CHIP,G21A  I124  R9N12
   1 VR_PVCCIN_CPU1_VD12      A @BASEBOARD_FAB2_LIB.BASEBOARD_FAB2(SCH_1):VR_PVCCIN_CPU1_VD12
   2 VR_PVCCIN_CPU1_AIREF3      B @BASEBOARD_FAB2_LIB.BASEBOARD_FAB2(SCH_1):VR_PVCCIN_CPU1_AIREF3

RES_0402-0.0,5%,1/16W,CHIP,G21A  I125  R9N10
   1 VR_PVCCIN_CPU1_VD12      A @BASEBOARD_FAB2_LIB.BASEBOARD_FAB2(SCH_1):VR_PVCCIN_CPU1_VD12
   2 VR_PVCCIN_CPU1_AIREF4      B @BASEBOARD_FAB2_LIB.BASEBOARD_FAB2(SCH_1):VR_PVCCIN_CPU1_AIREF4

RES_0402-0.0,5%,1/16W,CHIP,G21A  I126  R9N9
   1 VR_PVCCIN_CPU1_VD12      A @BASEBOARD_FAB2_LIB.BASEBOARD_FAB2(SCH_1):VR_PVCCIN_CPU1_VD12
   2 VR_PVCCIN_CPU1_AIREF5      B @BASEBOARD_FAB2_LIB.BASEBOARD_FAB2(SCH_1):VR_PVCCIN_CPU1_AIREF5

RES_0402-0.0,5%,1/16W,CHIP,G21A  I128  R9N5
   1 VR_PVCCIN_CPU1_VD12      A @BASEBOARD_FAB2_LIB.BASEBOARD_FAB2(SCH_1):VR_PVCCIN_CPU1_VD12
   2 VR_PVSA_CPU1_BIREF1      B @BASEBOARD_FAB2_LIB.BASEBOARD_FAB2(SCH_1):VR_PVSA_CPU1_BIREF1

PXE1610B_QFN-IC,H79206-001  I130  EU1C2
   1 VR_PVSA_CPU1_PWM  BPWM1 @BASEBOARD_FAB2_LIB.BASEBOARD_FAB2(SCH_1):VR_PVSA_CPU1_PWM
   2 TP_PVCCIN_CPU1_APWM6  APWM6 @BASEBOARD_FAB2_LIB.BASEBOARD_FAB2(SCH_1):TP_PVCCIN_CPU1_APWM6
   3 VR_PVCCIN_CPU1_PWM5  APWM5 @BASEBOARD_FAB2_LIB.BASEBOARD_FAB2(SCH_1):VR_PVCCIN_CPU1_PWM5
   4 VR_PVCCIN_CPU1_PWM4  APWM4 @BASEBOARD_FAB2_LIB.BASEBOARD_FAB2(SCH_1):VR_PVCCIN_CPU1_PWM4
   5 VR_PVCCIN_CPU1_PWM3  APWM3 @BASEBOARD_FAB2_LIB.BASEBOARD_FAB2(SCH_1):VR_PVCCIN_CPU1_PWM3
   6 VR_PVCCIN_CPU1_PWM2  APWM2 @BASEBOARD_FAB2_LIB.BASEBOARD_FAB2(SCH_1):VR_PVCCIN_CPU1_PWM2
   7 VR_PVCCIN_CPU1_PWM1  APWM1 @BASEBOARD_FAB2_LIB.BASEBOARD_FAB2(SCH_1):VR_PVCCIN_CPU1_PWM1
   8 SMB_VR_SDA_R1    SDA @BASEBOARD_FAB2_LIB.BASEBOARD_FAB2(SCH_1):SMB_VR_SDA_R1
   9 SMB_VR_SCL_R1    SCL @BASEBOARD_FAB2_LIB.BASEBOARD_FAB2(SCH_1):SMB_VR_SCL_R1
  10 TP_PVCCIN_CPU1_RESET_N RESET_N @BASEBOARD_FAB2_LIB.BASEBOARD_FAB2(SCH_1):TP_PVCCIN_CPU1_RESET_N
  11 VR_VRRDY_PVCCIN_CPU1 AVRRDY @BASEBOARD_FAB2_LIB.BASEBOARD_FAB2(SCH_1):VR_VRRDY_PVCCIN_CPU1
  12 VR_PVCCIN_CPU1_VREN  AVREN @BASEBOARD_FAB2_LIB.BASEBOARD_FAB2(SCH_1):VR_PVCCIN_CPU1_VREN
  13 IRQ_PVCCIN_CPU1_VRHOT_LVC3_R_N VRHOT_N @BASEBOARD_FAB2_LIB.BASEBOARD_FAB2(SCH_1):IRQ_PVCCIN_CPU1_VRHOT_LVC3_R_N
  14 FM_PVCCIN_CPU1_PWR_IN_ALERT_N PINALRT_N @BASEBOARD_FAB2_LIB.BASEBOARD_FAB2(SCH_1):FM_PVCCIN_CPU1_PWR_IN_ALERT_N
  15 PWRGD_PVSA_CPU1_R    MP0 @BASEBOARD_FAB2_LIB.BASEBOARD_FAB2(SCH_1):PWRGD_PVSA_CPU1_R
  16 TP_PVCCIN_CPU1_GP1    MP1 @BASEBOARD_FAB2_LIB.BASEBOARD_FAB2(SCH_1):TP_PVCCIN_CPU1_GP1
  17 SVID_VCLK_PVCCIN_CPU1   VCLK @BASEBOARD_FAB2_LIB.BASEBOARD_FAB2(SCH_1):SVID_VCLK_PVCCIN_CPU1
  18 SVID_VDIO_PVCCIN_CPU1   VDIO @BASEBOARD_FAB2_LIB.BASEBOARD_FAB2(SCH_1):SVID_VDIO_PVCCIN_CPU1
  19 SVID_VALERT_VCCIN_CPU1 VALRT_N @BASEBOARD_FAB2_LIB.BASEBOARD_FAB2(SCH_1):SVID_VALERT_VCCIN_CPU1
  20 PU_VR_PVCCIN_CPU1_FLT1_SMBALT_N    MP2 @BASEBOARD_FAB2_LIB.BASEBOARD_FAB2(SCH_1):PU_VR_PVCCIN_CPU1_FLT1_SMBALT_N_IMON
  21 VSENSE_PVCCIN_CPU1_AVSP  AVSEN @BASEBOARD_FAB2_LIB.BASEBOARD_FAB2(SCH_1):VSENSE_PVCCIN_CPU1_AVSP
  22 VSENSE_PVCCIN_CPU1_N  AVREF @BASEBOARD_FAB2_LIB.BASEBOARD_FAB2(SCH_1):VSENSE_PVCCIN_CPU1_N
  23 VR_PVCCIN_CPU1_AIREF1 AIREF1 @BASEBOARD_FAB2_LIB.BASEBOARD_FAB2(SCH_1):VR_PVCCIN_CPU1_AIREF1
  24 ISENSE_PVCCIN_CPU1_PH1_IMON AISEN1 @BASEBOARD_FAB2_LIB.BASEBOARD_FAB2(SCH_1):ISENSE_PVCCIN_CPU1_PH1_IMON
  25 VR_PVCCIN_CPU1_AIREF2 AIREF2 @BASEBOARD_FAB2_LIB.BASEBOARD_FAB2(SCH_1):VR_PVCCIN_CPU1_AIREF2
  26 ISENSE_PVCCIN_CPU1_PH2_IMON AISEN2 @BASEBOARD_FAB2_LIB.BASEBOARD_FAB2(SCH_1):ISENSE_PVCCIN_CPU1_PH2_IMON
  27 VR_PVCCIN_CPU1_AIREF3 AIREF3 @BASEBOARD_FAB2_LIB.BASEBOARD_FAB2(SCH_1):VR_PVCCIN_CPU1_AIREF3
  28 ISENSE_PVCCIN_CPU1_PH3_IMON AISEN3 @BASEBOARD_FAB2_LIB.BASEBOARD_FAB2(SCH_1):ISENSE_PVCCIN_CPU1_PH3_IMON
  29 VR_PVCCIN_CPU1_AIREF4 AIREF4 @BASEBOARD_FAB2_LIB.BASEBOARD_FAB2(SCH_1):VR_PVCCIN_CPU1_AIREF4
  30 ISENSE_PVCCIN_CPU1_PH4_IMON AISEN4 @BASEBOARD_FAB2_LIB.BASEBOARD_FAB2(SCH_1):ISENSE_PVCCIN_CPU1_PH4_IMON
  31 VR_PVCCIN_CPU1_AIREF5 AIREF5 @BASEBOARD_FAB2_LIB.BASEBOARD_FAB2(SCH_1):VR_PVCCIN_CPU1_AIREF5
  32 ISENSE_PVCCIN_CPU1_PH5_IMON AISEN5 @BASEBOARD_FAB2_LIB.BASEBOARD_FAB2(SCH_1):ISENSE_PVCCIN_CPU1_PH5_IMON
  33 TP_PVCCIN_CPU1_AIREF6 AIREF6 @BASEBOARD_FAB2_LIB.BASEBOARD_FAB2(SCH_1):TP_PVCCIN_CPU1_AIREF6
  34 TP_PVCCIN_CPU1_AISEN6 AISEN6 @BASEBOARD_FAB2_LIB.BASEBOARD_FAB2(SCH_1):TP_PVCCIN_CPU1_AISEN6
  35 VSENSE_PVSA_CPU1_BVSP  BVSEN @BASEBOARD_FAB2_LIB.BASEBOARD_FAB2(SCH_1):VSENSE_PVSA_CPU1_BVSP
  36 VSENSE_PVSA_CPU1_N  BVREF @BASEBOARD_FAB2_LIB.BASEBOARD_FAB2(SCH_1):VSENSE_PVSA_CPU1_N
  37 VR_PVSA_CPU1_BIREF1 BIREF1 @BASEBOARD_FAB2_LIB.BASEBOARD_FAB2(SCH_1):VR_PVSA_CPU1_BIREF1
  38 ISENSE_PVSA_CPU1_IMON BISEN1 @BASEBOARD_FAB2_LIB.BASEBOARD_FAB2(SCH_1):ISENSE_PVSA_CPU1_IMON
  39 PU_VR_PVCCIN_CPU1_IMON    MP3 @BASEBOARD_FAB2_LIB.BASEBOARD_FAB2(SCH_1):PU_VR_PVCCIN_CPU1_IMON
  40 TP_PVCCIN_CPU1_FAULT1_20    MP4 @BASEBOARD_FAB2_LIB.BASEBOARD_FAB2(SCH_1):TP_PVCCIN_CPU1_FAULT1_20
  41 VR_PVCCIN_CPU1_XADDR2 XADDR2 @BASEBOARD_FAB2_LIB.BASEBOARD_FAB2(SCH_1):VR_PVCCIN_CPU1_XADDR2
  42 A_TSENSE_PVSA_CPU1  BTSEN @BASEBOARD_FAB2_LIB.BASEBOARD_FAB2(SCH_1):A_TSENSE_PVSA_CPU1
  43 A_TSENSE_PVCCIN_CPU1  ATSEN @BASEBOARD_FAB2_LIB.BASEBOARD_FAB2(SCH_1):A_TSENSE_PVCCIN_CPU1
  44 VR_PVCCIN_CPU1_XADDR1 XADDR1 @BASEBOARD_FAB2_LIB.BASEBOARD_FAB2(SCH_1):VR_PVCCIN_CPU1_XADDR1
  45 VR_PVCCIN_CPU1_AVINSEN VINSEN @BASEBOARD_FAB2_LIB.BASEBOARD_FAB2(SCH_1):VR_PVCCIN_CPU1_AVINSEN
  46 PVCCIN_PVSA_CPU1_IINSEN IINSEN @BASEBOARD_FAB2_LIB.BASEBOARD_FAB2(SCH_1):PVCCIN_PVSA_CPU1_IINSEN
  47 VR_PVCCIN_CPU1_VDD    VDD @BASEBOARD_FAB2_LIB.BASEBOARD_FAB2(SCH_1):VR_PVCCIN_CPU1_VDD
  48 VR_PVCCIN_CPU1_VD12   VD12 @BASEBOARD_FAB2_LIB.BASEBOARD_FAB2(SCH_1):VR_PVCCIN_CPU1_VD12
  49    GND  THPAD @BASEBOARD_FAB2_LIB.BASEBOARD_FAB2(SCH_1):GND


DRAWING: @BASEBOARD_FAB2_LIB.BASEBOARD_FAB2(SCH_1):PAGE211 

CAP_A_0402V-1.0UF,6.3V,10%,X6SA  I11  C3P4
   1 VR_PVCCIO_CPU0_VD12      A @BASEBOARD_FAB2_LIB.BASEBOARD_FAB2(SCH_1):VR_PVCCIO_CPU0_VD12
   2    GND      B @BASEBOARD_FAB2_LIB.BASEBOARD_FAB2(SCH_1):GND

CAP_A_0402V-0.1UF,16V,10%,X7R,A  I13  C3P5
   1 VR_PVCCIO_CPU0_VD12      A @BASEBOARD_FAB2_LIB.BASEBOARD_FAB2(SCH_1):VR_PVCCIO_CPU0_VD12
   2    GND      B @BASEBOARD_FAB2_LIB.BASEBOARD_FAB2(SCH_1):GND

RES_0402-0.0,5%,1/16W,CHIP,G21A  I16  R3P11
   1 SVID_DIO0_CPU0_R      A @BASEBOARD_FAB2_LIB.BASEBOARD_FAB2(SCH_1):SVID_DIO0_CPU0_R
   2 SVID_VDIO_PVCCIO_CPU0      B @BASEBOARD_FAB2_LIB.BASEBOARD_FAB2(SCH_1):SVID_VDIO_PVCCIO_CPU0

RES_0402-100.0,1%,1/16W,EMPTY,A  I17  R3P13
   1 PVCCIO_CPU0      A @BASEBOARD_FAB2_LIB.BASEBOARD_FAB2(SCH_1):PVCCIO_CPU0
   2 SVID_DIO0_CPU0_R      B @BASEBOARD_FAB2_LIB.BASEBOARD_FAB2(SCH_1):SVID_DIO0_CPU0_R

CAP_A_0402V-1.0UF,6.3V,10%,X6SA  I20  C3P3
   1 VR_PVCCIO_CPU0_VDD      A @BASEBOARD_FAB2_LIB.BASEBOARD_FAB2(SCH_1):VR_PVCCIO_CPU0_VDD
   2    GND      B @BASEBOARD_FAB2_LIB.BASEBOARD_FAB2(SCH_1):GND

CAP_A_0402V-0.1UF,16V,10%,X7R,A  I22  C3P7
   1 VR_PVCCIO_CPU0_VDD      A @BASEBOARD_FAB2_LIB.BASEBOARD_FAB2(SCH_1):VR_PVCCIO_CPU0_VDD
   2    GND      B @BASEBOARD_FAB2_LIB.BASEBOARD_FAB2(SCH_1):GND

RES_0402-0.0,5%,1/16W,CHIP,G21A  I24  R3P22
   1 P3V3_STBY      A @BASEBOARD_FAB2_LIB.BASEBOARD_FAB2(SCH_1):P3V3_STBY
   2 VR_PVCCIO_CPU0_VDD      B @BASEBOARD_FAB2_LIB.BASEBOARD_FAB2(SCH_1):VR_PVCCIO_CPU0_VDD

RES_0402-49.9,1%,1/16W,EMPTY,GA  I28  R3P17
   1 PVCCIO_CPU0      A @BASEBOARD_FAB2_LIB.BASEBOARD_FAB2(SCH_1):PVCCIO_CPU0
   2 SVID_CLK0_CPU0_R      B @BASEBOARD_FAB2_LIB.BASEBOARD_FAB2(SCH_1):SVID_CLK0_CPU0_R

RES_0402-150.0,1%,1/16W,CHIP,GA  I29  R3P15
   1 SVID_CLK0_CPU0_R      A @BASEBOARD_FAB2_LIB.BASEBOARD_FAB2(SCH_1):SVID_CLK0_CPU0_R
   2 SVID_CLK_PVCCIO_CPU0      B @BASEBOARD_FAB2_LIB.BASEBOARD_FAB2(SCH_1):SVID_CLK_PVCCIO_CPU0

RES_0402-100.0K,1%,1/16W,CHIP,B  I31  R3P12
   1 VR_FET_SW_P12V_STBY_PVCCIO_CPU0      A @BASEBOARD_FAB2_LIB.BASEBOARD_FAB2(SCH_1):VR_FET_SW_P12V_STBY_PVCCIO_CPU0
   2 VR_PVCCIO_CPU0_VINSEN      B @BASEBOARD_FAB2_LIB.BASEBOARD_FAB2(SCH_1):VR_PVCCIO_CPU0_VINSEN

RES_0402-1.5K,1%,1/16W,CHIP,G2A  I32  R3P16
   1 VR_PVCCIO_CPU0_VINSEN      A @BASEBOARD_FAB2_LIB.BASEBOARD_FAB2(SCH_1):VR_PVCCIO_CPU0_VINSEN
   2    GND      B @BASEBOARD_FAB2_LIB.BASEBOARD_FAB2(SCH_1):GND

CAP_0402LF-1000PF,50V,10%,X7R,A  I33  C3P2
   1 VR_PVCCIO_CPU0_VINSEN      A @BASEBOARD_FAB2_LIB.BASEBOARD_FAB2(SCH_1):VR_PVCCIO_CPU0_VINSEN
   2    GND      B @BASEBOARD_FAB2_LIB.BASEBOARD_FAB2(SCH_1):GND

RES_0402-20.0,1%,1/16W,CHIP,G2A  I46  R3P24
   1 SMB_VR_STBY_LVC3_SCL      A @BASEBOARD_FAB2_LIB.BASEBOARD_FAB2(SCH_1):SMB_VR_STBY_LVC3_SCL
   2 SMB_VR_SCL_PVCCIO_CPU0      B @BASEBOARD_FAB2_LIB.BASEBOARD_FAB2(SCH_1):SMB_VR_SCL_PVCCIO_CPU0

RES_0402-20.0,1%,1/16W,CHIP,G2A  I47  R3P23
   1 SMB_VR_STBY_LVC3_SDA      A @BASEBOARD_FAB2_LIB.BASEBOARD_FAB2(SCH_1):SMB_VR_STBY_LVC3_SDA
   2 SMB_VR_SDA_PVCCIO_CPU0      B @BASEBOARD_FAB2_LIB.BASEBOARD_FAB2(SCH_1):SMB_VR_SDA_PVCCIO_CPU0

RES_0402-3.16K,1%,1/16W,CHIP,GA  I52  R3N31
   1 VR_PVCCIO_CPU0_XADDR1      A @BASEBOARD_FAB2_LIB.BASEBOARD_FAB2(SCH_1):VR_PVCCIO_CPU0_XADDR1
   2    GND      B @BASEBOARD_FAB2_LIB.BASEBOARD_FAB2(SCH_1):GND

RES_0402-1.00K,1%,1/16W,CHIP,GA  I56  R3P25
   1 P3V3_STBY      A @BASEBOARD_FAB2_LIB.BASEBOARD_FAB2(SCH_1):P3V3_STBY
   2 PWRGD_PVCCIO_CPU0_R      B @BASEBOARD_FAB2_LIB.BASEBOARD_FAB2(SCH_1):PWRGD_PVCCIO_CPU0_R

RES_0402-22.1,1.0%,1/16W,CHIP,A  I58  R3P20
   1 PWRGD_PVCCIO_CPU0_R      A @BASEBOARD_FAB2_LIB.BASEBOARD_FAB2(SCH_1):PWRGD_PVCCIO_CPU0_R
   2 PWRGD_PVCCIO_CPU0      B @BASEBOARD_FAB2_LIB.BASEBOARD_FAB2(SCH_1):PWRGD_PVCCIO_CPU0

RES_0402-2.26K,1.0%,1/16W,EMPTA  I60  R3N23
   1 P3V3_STBY      A @BASEBOARD_FAB2_LIB.BASEBOARD_FAB2(SCH_1):P3V3_STBY
   2 PU_VR_PVCCIO_CPU0_FAULT1      B @BASEBOARD_FAB2_LIB.BASEBOARD_FAB2(SCH_1):PU_VR_PVCCIO_CPU0_FAULT1

RES_0402-0.0,5%,1/16W,CHIP,G21A  I61  R3P1
   1 SVID_ALERT_PVCCIO_CPU0      A @BASEBOARD_FAB2_LIB.BASEBOARD_FAB2(SCH_1):SVID_ALERT_PVCCIO_CPU0
   2 SVID_ALERT0_CPU0_R_N      B @BASEBOARD_FAB2_LIB.BASEBOARD_FAB2(SCH_1):SVID_ALERT0_CPU0_R_N

RES_0402-1.00K,1%,1/16W,CHIP,GA  I64  R3P18
   1 P3V3_STBY      A @BASEBOARD_FAB2_LIB.BASEBOARD_FAB2(SCH_1):P3V3_STBY
   2 IRQ_PVCCIO_CPU0_VRHOT_N      B @BASEBOARD_FAB2_LIB.BASEBOARD_FAB2(SCH_1):IRQ_PVCCIO_CPU0_VRHOT_N

RES_0402-4.02K,1%,1/16W,CHIP,GA  I65  R3N22
   1 VR_PVCCIO_CPU0_XADDR2      A @BASEBOARD_FAB2_LIB.BASEBOARD_FAB2(SCH_1):VR_PVCCIO_CPU0_XADDR2
   2    GND      B @BASEBOARD_FAB2_LIB.BASEBOARD_FAB2(SCH_1):GND

CAP_0402LF-1000PF,50V,10%,X7R,A  I71  C3P6
   1 PWRGD_PVCCIO_CPU0_R      A @BASEBOARD_FAB2_LIB.BASEBOARD_FAB2(SCH_1):PWRGD_PVCCIO_CPU0_R
   2    GND      B @BASEBOARD_FAB2_LIB.BASEBOARD_FAB2(SCH_1):GND

RES_0402-10.0,1%,1/16W,CHIP,G2A  I81  R3N19
   1 VSENSE_PVCCIO_CPU0_AVSP      A @BASEBOARD_FAB2_LIB.BASEBOARD_FAB2(SCH_1):VSENSE_PVCCIO_CPU0_AVSP
   2 VR_PVCCIO_CPU0_AVSP      B @BASEBOARD_FAB2_LIB.BASEBOARD_FAB2(SCH_1):VR_PVCCIO_CPU0_AVSP

CAP_0402LF-220PF,50V,10%,X7R,AA  I83  C3N39
   1 VR_PVCCIO_CPU0_AVSP      A @BASEBOARD_FAB2_LIB.BASEBOARD_FAB2(SCH_1):VR_PVCCIO_CPU0_AVSP
   2 VSENSE_PVCCIO_CPU0_AVSN      B @BASEBOARD_FAB2_LIB.BASEBOARD_FAB2(SCH_1):VSENSE_PVCCIO_CPU0_AVSN

RES_0402-0.0,5%,1/16W,CHIP,G21A  I87  R3P26
   1 FM_PVCCIO_CPU0_EN      A @BASEBOARD_FAB2_LIB.BASEBOARD_FAB2(SCH_1):FM_PVCCIO_CPU0_EN
   2 VR_PVCCIO_CPU0_EN      B @BASEBOARD_FAB2_LIB.BASEBOARD_FAB2(SCH_1):VR_PVCCIO_CPU0_EN

RES_0402-100.0K,1%,1/16W,EMPTYA  I88  R3P21
   1 P3V3_STBY      A @BASEBOARD_FAB2_LIB.BASEBOARD_FAB2(SCH_1):P3V3_STBY
   2 VR_PVCCIO_CPU0_EN      B @BASEBOARD_FAB2_LIB.BASEBOARD_FAB2(SCH_1):VR_PVCCIO_CPU0_EN

RES_0402-0.0,5%,1/16W,CHIP,G21A  I91  R3P57
   1 VR_PVCCIO_CPU0_VD12      A @BASEBOARD_FAB2_LIB.BASEBOARD_FAB2(SCH_1):VR_PVCCIO_CPU0_VD12
   2 VR_PVCCIO_CPU0_AIREF1      B @BASEBOARD_FAB2_LIB.BASEBOARD_FAB2(SCH_1):VR_PVCCIO_CPU0_AIREF1

PXE1110B_QFN-IC,H89187-001  I93  EU3P1
   1 NC_PVCCIO_CPU0_DNC0 DNC<0> @BASEBOARD_FAB2_LIB.BASEBOARD_FAB2(SCH_1):NC_PVCCIO_CPU0_DNC0
   2 NC_PVCCIO_CPU0_DNC1 DNC<1> @BASEBOARD_FAB2_LIB.BASEBOARD_FAB2(SCH_1):NC_PVCCIO_CPU0_DNC1
   3 TP_PVCCIO_CPU0_BPWM1  BPWM1 @BASEBOARD_FAB2_LIB.BASEBOARD_FAB2(SCH_1):TP_PVCCIO_CPU0_BPWM1
   4 NC_PVCCIO_CPU0_DNC2 DNC<2> @BASEBOARD_FAB2_LIB.BASEBOARD_FAB2(SCH_1):NC_PVCCIO_CPU0_DNC2
   5 VR_PVCCIO_CPU0_PWM1  APWM1 @BASEBOARD_FAB2_LIB.BASEBOARD_FAB2(SCH_1):VR_PVCCIO_CPU0_PWM1
   6 SMB_VR_SDA_PVCCIO_CPU0    SDA @BASEBOARD_FAB2_LIB.BASEBOARD_FAB2(SCH_1):SMB_VR_SDA_PVCCIO_CPU0
   7 SMB_VR_SCL_PVCCIO_CPU0    SCL @BASEBOARD_FAB2_LIB.BASEBOARD_FAB2(SCH_1):SMB_VR_SCL_PVCCIO_CPU0
   8 TP_PVCCIO_CPU0_RESET_N RESET_N @BASEBOARD_FAB2_LIB.BASEBOARD_FAB2(SCH_1):TP_PVCCIO_CPU0_RESET_N
   9 PWRGD_PVCCIO_CPU0_R AVRRDY @BASEBOARD_FAB2_LIB.BASEBOARD_FAB2(SCH_1):PWRGD_PVCCIO_CPU0_R
  10 VR_PVCCIO_CPU0_EN  AVREN @BASEBOARD_FAB2_LIB.BASEBOARD_FAB2(SCH_1):VR_PVCCIO_CPU0_EN
  11 IRQ_PVCCIO_CPU0_VRHOT_N VRHOT_N @BASEBOARD_FAB2_LIB.BASEBOARD_FAB2(SCH_1):IRQ_PVCCIO_CPU0_VRHOT_N
  12 TP_PVCCIO_CPU0_PINALRT_N PINALRT_N @BASEBOARD_FAB2_LIB.BASEBOARD_FAB2(SCH_1):TP_PVCCIO_CPU0_PINALRT_N
  13 TP_VR_PVCCIO_CPU0_MP0    MP0 @BASEBOARD_FAB2_LIB.BASEBOARD_FAB2(SCH_1):TP_VR_PVCCIO_CPU0_MP0
  14 TP_VR_PVCCIO_CPU0_MP1    MP1 @BASEBOARD_FAB2_LIB.BASEBOARD_FAB2(SCH_1):TP_VR_PVCCIO_CPU0_MP1
  15 SVID_CLK_PVCCIO_CPU0   VCLK @BASEBOARD_FAB2_LIB.BASEBOARD_FAB2(SCH_1):SVID_CLK_PVCCIO_CPU0
  16 SVID_VDIO_PVCCIO_CPU0   VDIO @BASEBOARD_FAB2_LIB.BASEBOARD_FAB2(SCH_1):SVID_VDIO_PVCCIO_CPU0
  17 SVID_ALERT_PVCCIO_CPU0 VALRT_N @BASEBOARD_FAB2_LIB.BASEBOARD_FAB2(SCH_1):SVID_ALERT_PVCCIO_CPU0
  18 TP_VR_PVCCIO_CPU0_MP2    MP2 @BASEBOARD_FAB2_LIB.BASEBOARD_FAB2(SCH_1):TP_VR_PVCCIO_CPU0_MP2
  19 VR_PVCCIO_CPU0_AVSP  AVSEN @BASEBOARD_FAB2_LIB.BASEBOARD_FAB2(SCH_1):VR_PVCCIO_CPU0_AVSP
  20 VSENSE_PVCCIO_CPU0_AVSN  AVREF @BASEBOARD_FAB2_LIB.BASEBOARD_FAB2(SCH_1):VSENSE_PVCCIO_CPU0_AVSN
  21 VR_PVCCIO_CPU0_AIREF1 AIREF1 @BASEBOARD_FAB2_LIB.BASEBOARD_FAB2(SCH_1):VR_PVCCIO_CPU0_AIREF1
  22 ISENSE_PVCCIO_CPU0_PH1_IMON AISEN1 @BASEBOARD_FAB2_LIB.BASEBOARD_FAB2(SCH_1):ISENSE_PVCCIO_CPU0_PH1_IMON
  23    GND GND<1> @BASEBOARD_FAB2_LIB.BASEBOARD_FAB2(SCH_1):GND
  24 NC_PVCCIO_CPU0_DNC3 DNC<3> @BASEBOARD_FAB2_LIB.BASEBOARD_FAB2(SCH_1):NC_PVCCIO_CPU0_DNC3
  25 TP_PVCCIO_CPU0_BIREF1 BIREF1 @BASEBOARD_FAB2_LIB.BASEBOARD_FAB2(SCH_1):TP_PVCCIO_CPU0_BIREF1
  26    GND BISEN1 @BASEBOARD_FAB2_LIB.BASEBOARD_FAB2(SCH_1):GND
  27    GND GND<0> @BASEBOARD_FAB2_LIB.BASEBOARD_FAB2(SCH_1):GND
  28 NC_PVCCIO_CPU0_DNC4 DNC<4> @BASEBOARD_FAB2_LIB.BASEBOARD_FAB2(SCH_1):NC_PVCCIO_CPU0_DNC4
  29 TP_PVCCIO_CPU0_BVSEN  BVSEN @BASEBOARD_FAB2_LIB.BASEBOARD_FAB2(SCH_1):TP_PVCCIO_CPU0_BVSEN
  30 TP_PVCCIO_CPU0_BVREF  BVREF @BASEBOARD_FAB2_LIB.BASEBOARD_FAB2(SCH_1):TP_PVCCIO_CPU0_BVREF
  31 TP_VR_PVCCIO_CPU0_MP3    MP3 @BASEBOARD_FAB2_LIB.BASEBOARD_FAB2(SCH_1):TP_VR_PVCCIO_CPU0_MP3
  32 PU_VR_PVCCIO_CPU0_FAULT1    MP4 @BASEBOARD_FAB2_LIB.BASEBOARD_FAB2(SCH_1):PU_VR_PVCCIO_CPU0_FAULT1
  33 VR_PVCCIO_CPU0_XADDR2 XADDR2 @BASEBOARD_FAB2_LIB.BASEBOARD_FAB2(SCH_1):VR_PVCCIO_CPU0_XADDR2
  34 TP_PVCCIO_CPU0_BTSEN  BTSEN @BASEBOARD_FAB2_LIB.BASEBOARD_FAB2(SCH_1):TP_PVCCIO_CPU0_BTSEN
  35 A_TSENSE_PVCCIO_CPU0  ATSEN @BASEBOARD_FAB2_LIB.BASEBOARD_FAB2(SCH_1):A_TSENSE_PVCCIO_CPU0
  36 VR_PVCCIO_CPU0_XADDR1 XADDR1 @BASEBOARD_FAB2_LIB.BASEBOARD_FAB2(SCH_1):VR_PVCCIO_CPU0_XADDR1
  37 VR_PVCCIO_CPU0_VINSEN VINSEN @BASEBOARD_FAB2_LIB.BASEBOARD_FAB2(SCH_1):VR_PVCCIO_CPU0_VINSEN
  38 TP_VR_PVCCIO_CPU0_AIINSEN IINSEN @BASEBOARD_FAB2_LIB.BASEBOARD_FAB2(SCH_1):TP_VR_PVCCIO_CPU0_AIINSEN
  39 VR_PVCCIO_CPU0_VDD    VDD @BASEBOARD_FAB2_LIB.BASEBOARD_FAB2(SCH_1):VR_PVCCIO_CPU0_VDD
  40 VR_PVCCIO_CPU0_VD12   VD12 @BASEBOARD_FAB2_LIB.BASEBOARD_FAB2(SCH_1):VR_PVCCIO_CPU0_VD12
  41    GND  THPAD @BASEBOARD_FAB2_LIB.BASEBOARD_FAB2(SCH_1):GND


DRAWING: @BASEBOARD_FAB2_LIB.BASEBOARD_FAB2(SCH_1):PAGE213 

CAP_A_0402V-1.0UF,6.3V,10%,X6SA  I9  C4D31
   1 VR_PVCCIO_CPU1_VD12      A @BASEBOARD_FAB2_LIB.BASEBOARD_FAB2(SCH_1):VR_PVCCIO_CPU1_VD12
   2    GND      B @BASEBOARD_FAB2_LIB.BASEBOARD_FAB2(SCH_1):GND

CAP_A_0402V-0.1UF,16V,10%,X7R,A  I11  C4D32
   1 VR_PVCCIO_CPU1_VD12      A @BASEBOARD_FAB2_LIB.BASEBOARD_FAB2(SCH_1):VR_PVCCIO_CPU1_VD12
   2    GND      B @BASEBOARD_FAB2_LIB.BASEBOARD_FAB2(SCH_1):GND

RES_0402-22.1,1.0%,1/16W,CHIP,A  I13  R4D46
   1 PWRGD_PVCCIO_CPU1_R      A @BASEBOARD_FAB2_LIB.BASEBOARD_FAB2(SCH_1):PWRGD_PVCCIO_CPU1_R
   2 PWRGD_PVCCIO_CPU1      B @BASEBOARD_FAB2_LIB.BASEBOARD_FAB2(SCH_1):PWRGD_PVCCIO_CPU1

RES_0402-2.26K,1.0%,1/16W,EMPTA  I14  R6P49
   1 P3V3_STBY      A @BASEBOARD_FAB2_LIB.BASEBOARD_FAB2(SCH_1):P3V3_STBY
   2 PU_VR_PVCCIO_CPU1_FAULT1      B @BASEBOARD_FAB2_LIB.BASEBOARD_FAB2(SCH_1):PU_VR_PVCCIO_CPU1_FAULT1

RES_0402-1.00K,1%,1/16W,CHIP,GA  I15  R4D42
   1 P3V3_STBY      A @BASEBOARD_FAB2_LIB.BASEBOARD_FAB2(SCH_1):P3V3_STBY
   2 PWRGD_PVCCIO_CPU1_R      B @BASEBOARD_FAB2_LIB.BASEBOARD_FAB2(SCH_1):PWRGD_PVCCIO_CPU1_R

RES_0402-0.0,5%,1/16W,CHIP,G21A  I16  R4D56
   1 SVID_ALERT_PVCCIO_CPU1      A @BASEBOARD_FAB2_LIB.BASEBOARD_FAB2(SCH_1):SVID_ALERT_PVCCIO_CPU1
   2 SVID_ALERT0_CPU1_R_N      B @BASEBOARD_FAB2_LIB.BASEBOARD_FAB2(SCH_1):SVID_ALERT0_CPU1_R_N

CAP_A_0402V-1.0UF,6.3V,10%,X6SA  I17  C4D36
   1 VR_PVCCIO_CPU1_VDD      A @BASEBOARD_FAB2_LIB.BASEBOARD_FAB2(SCH_1):VR_PVCCIO_CPU1_VDD
   2    GND      B @BASEBOARD_FAB2_LIB.BASEBOARD_FAB2(SCH_1):GND

RES_0402-0.0,5%,1/16W,CHIP,G21A  I25  R4D47
   1 P3V3_STBY      A @BASEBOARD_FAB2_LIB.BASEBOARD_FAB2(SCH_1):P3V3_STBY
   2 VR_PVCCIO_CPU1_VDD      B @BASEBOARD_FAB2_LIB.BASEBOARD_FAB2(SCH_1):VR_PVCCIO_CPU1_VDD

RES_0402-100.0,1%,1/16W,EMPTY,A  I27  R6P35
   1 PVCCIO_CPU1      A @BASEBOARD_FAB2_LIB.BASEBOARD_FAB2(SCH_1):PVCCIO_CPU1
   2 SVID_DIO0_CPU1_R      B @BASEBOARD_FAB2_LIB.BASEBOARD_FAB2(SCH_1):SVID_DIO0_CPU1_R

RES_0402-110,1%,1/16W,EMPTY,G2A  I30  R6P33
   1 PVCCIO_CPU1      A @BASEBOARD_FAB2_LIB.BASEBOARD_FAB2(SCH_1):PVCCIO_CPU1
   2 SVID_CLK0_CPU1_R      B @BASEBOARD_FAB2_LIB.BASEBOARD_FAB2(SCH_1):SVID_CLK0_CPU1_R

RES_0402-100.0K,1%,1/16W,CHIP,B  I31  R4D60
   1 VR_FET_SW_P12V_STBY_PVCCIN_CPU0      A @BASEBOARD_FAB2_LIB.BASEBOARD_FAB2(SCH_1):VR_FET_SW_P12V_STBY_PVCCIN_CPU0
   2 VR_PVCCIO_CPU1_VINSEN      B @BASEBOARD_FAB2_LIB.BASEBOARD_FAB2(SCH_1):VR_PVCCIO_CPU1_VINSEN

RES_0402-1.5K,1%,1/16W,CHIP,G2A  I32  R4D57
   1 VR_PVCCIO_CPU1_VINSEN      A @BASEBOARD_FAB2_LIB.BASEBOARD_FAB2(SCH_1):VR_PVCCIO_CPU1_VINSEN
   2    GND      B @BASEBOARD_FAB2_LIB.BASEBOARD_FAB2(SCH_1):GND

CAP_0402LF-1000PF,50V,10%,X7R,A  I33  C4D40
   1 VR_PVCCIO_CPU1_VINSEN      A @BASEBOARD_FAB2_LIB.BASEBOARD_FAB2(SCH_1):VR_PVCCIO_CPU1_VINSEN
   2    GND      B @BASEBOARD_FAB2_LIB.BASEBOARD_FAB2(SCH_1):GND

CAP_A_0402V-0.1UF,16V,10%,X7R,A  I35  C4D38
   1 VR_PVCCIO_CPU1_VDD      A @BASEBOARD_FAB2_LIB.BASEBOARD_FAB2(SCH_1):VR_PVCCIO_CPU1_VDD
   2    GND      B @BASEBOARD_FAB2_LIB.BASEBOARD_FAB2(SCH_1):GND

RES_0402-0.0,5%,1/16W,CHIP,G21A  I37  R4D54
   1 SVID_DIO0_CPU1_R      A @BASEBOARD_FAB2_LIB.BASEBOARD_FAB2(SCH_1):SVID_DIO0_CPU1_R
   2 SVID_VDIO_PVCCIO_CPU1      B @BASEBOARD_FAB2_LIB.BASEBOARD_FAB2(SCH_1):SVID_VDIO_PVCCIO_CPU1

RES_0402-20.0,1%,1/16W,CHIP,G2A  I38  R4D44
   1 SMB_VR_STBY_LVC3_SDA      A @BASEBOARD_FAB2_LIB.BASEBOARD_FAB2(SCH_1):SMB_VR_STBY_LVC3_SDA
   2 SMB_VR_SDA_PVCCIO_CPU1      B @BASEBOARD_FAB2_LIB.BASEBOARD_FAB2(SCH_1):SMB_VR_SDA_PVCCIO_CPU1

RES_0402-20.0,1%,1/16W,CHIP,G2A  I39  R4D43
   1 SMB_VR_STBY_LVC3_SCL      A @BASEBOARD_FAB2_LIB.BASEBOARD_FAB2(SCH_1):SMB_VR_STBY_LVC3_SCL
   2 SMB_VR_SCL_PVCCIO_CPU1      B @BASEBOARD_FAB2_LIB.BASEBOARD_FAB2(SCH_1):SMB_VR_SCL_PVCCIO_CPU1

RES_0402-3.16K,1%,1/16W,CHIP,GA  I42  R4D64
   1 VR_PVCCIO_CPU1_XADDR1      A @BASEBOARD_FAB2_LIB.BASEBOARD_FAB2(SCH_1):VR_PVCCIO_CPU1_XADDR1
   2    GND      B @BASEBOARD_FAB2_LIB.BASEBOARD_FAB2(SCH_1):GND

RES_0402-150.0,1%,1/16W,CHIP,GA  I46  R4D51
   1 SVID_CLK0_CPU1_R      A @BASEBOARD_FAB2_LIB.BASEBOARD_FAB2(SCH_1):SVID_CLK0_CPU1_R
   2 SVID_CLK_PVCCIO_CPU1      B @BASEBOARD_FAB2_LIB.BASEBOARD_FAB2(SCH_1):SVID_CLK_PVCCIO_CPU1

RES_0402-1.00K,1%,1/16W,CHIP,GA  I63  R4D49
   1 P3V3_STBY      A @BASEBOARD_FAB2_LIB.BASEBOARD_FAB2(SCH_1):P3V3_STBY
   2 IRQ_PVCCIO_CPU1_VRHOT_N      B @BASEBOARD_FAB2_LIB.BASEBOARD_FAB2(SCH_1):IRQ_PVCCIO_CPU1_VRHOT_N

RES_0402-3.16K,1%,1/16W,CHIP,GA  I65  R4E2
   1 VR_PVCCIO_CPU1_XADDR2      A @BASEBOARD_FAB2_LIB.BASEBOARD_FAB2(SCH_1):VR_PVCCIO_CPU1_XADDR2
   2    GND      B @BASEBOARD_FAB2_LIB.BASEBOARD_FAB2(SCH_1):GND

CAP_0402LF-1000PF,50V,10%,X7R,A  I73  C4D33
   1 PWRGD_PVCCIO_CPU1_R      A @BASEBOARD_FAB2_LIB.BASEBOARD_FAB2(SCH_1):PWRGD_PVCCIO_CPU1_R
   2    GND      B @BASEBOARD_FAB2_LIB.BASEBOARD_FAB2(SCH_1):GND

CAP_0402LF-220PF,50V,10%,X7R,AA  I83  C4D44
   1 VR_PVCCIO_CPU1_AVSP      A @BASEBOARD_FAB2_LIB.BASEBOARD_FAB2(SCH_1):VR_PVCCIO_CPU1_AVSP
   2 VSENSE_PVCCIO_CPU1_AVSN      B @BASEBOARD_FAB2_LIB.BASEBOARD_FAB2(SCH_1):VSENSE_PVCCIO_CPU1_AVSN

RES_0402-10.0,1%,1/16W,CHIP,G2A  I84  R4E7
   1 VSENSE_PVCCIO_CPU1_AVSP      A @BASEBOARD_FAB2_LIB.BASEBOARD_FAB2(SCH_1):VSENSE_PVCCIO_CPU1_AVSP
   2 VR_PVCCIO_CPU1_AVSP      B @BASEBOARD_FAB2_LIB.BASEBOARD_FAB2(SCH_1):VR_PVCCIO_CPU1_AVSP

RES_0402-0.0,5%,1/16W,CHIP,G21A  I90  R6P41
   1 FM_PVCCIO_CPU1_EN      A @BASEBOARD_FAB2_LIB.BASEBOARD_FAB2(SCH_1):FM_PVCCIO_CPU1_EN
   2 VR_PVCCIO_CPU1_EN      B @BASEBOARD_FAB2_LIB.BASEBOARD_FAB2(SCH_1):VR_PVCCIO_CPU1_EN

RES_0402-100.0K,1%,1/16W,EMPTYA  I91  R6P40
   1 P3V3_STBY      A @BASEBOARD_FAB2_LIB.BASEBOARD_FAB2(SCH_1):P3V3_STBY
   2 VR_PVCCIO_CPU1_EN      B @BASEBOARD_FAB2_LIB.BASEBOARD_FAB2(SCH_1):VR_PVCCIO_CPU1_EN

RES_0402-0.0,5%,1/16W,CHIP,G21A  I94  R4D45
   1 VR_PVCCIO_CPU1_VD12      A @BASEBOARD_FAB2_LIB.BASEBOARD_FAB2(SCH_1):VR_PVCCIO_CPU1_VD12
   2 VR_PVCCIO_CPU1_AIREF1      B @BASEBOARD_FAB2_LIB.BASEBOARD_FAB2(SCH_1):VR_PVCCIO_CPU1_AIREF1

PXE1110B_QFN-IC,H89187-001  I96  EU4D5
   1 NC_PVCCIO_CPU1_DNC0 DNC<0> @BASEBOARD_FAB2_LIB.BASEBOARD_FAB2(SCH_1):NC_PVCCIO_CPU1_DNC0
   2 NC_PVCCIO_CPU1_DNC1 DNC<1> @BASEBOARD_FAB2_LIB.BASEBOARD_FAB2(SCH_1):NC_PVCCIO_CPU1_DNC1
   3 TP_PVCCIO_CPU1_BPWM1  BPWM1 @BASEBOARD_FAB2_LIB.BASEBOARD_FAB2(SCH_1):TP_PVCCIO_CPU1_BPWM1
   4 NC_PVCCIO_CPU1_DNC2 DNC<2> @BASEBOARD_FAB2_LIB.BASEBOARD_FAB2(SCH_1):NC_PVCCIO_CPU1_DNC2
   5 VR_PVCCIO_CPU1_PWM1  APWM1 @BASEBOARD_FAB2_LIB.BASEBOARD_FAB2(SCH_1):VR_PVCCIO_CPU1_PWM1
   6 SMB_VR_SDA_PVCCIO_CPU1    SDA @BASEBOARD_FAB2_LIB.BASEBOARD_FAB2(SCH_1):SMB_VR_SDA_PVCCIO_CPU1
   7 SMB_VR_SCL_PVCCIO_CPU1    SCL @BASEBOARD_FAB2_LIB.BASEBOARD_FAB2(SCH_1):SMB_VR_SCL_PVCCIO_CPU1
   8 TP_PVCCIO_CPU1_RESET_N RESET_N @BASEBOARD_FAB2_LIB.BASEBOARD_FAB2(SCH_1):TP_PVCCIO_CPU1_RESET_N
   9 PWRGD_PVCCIO_CPU1_R AVRRDY @BASEBOARD_FAB2_LIB.BASEBOARD_FAB2(SCH_1):PWRGD_PVCCIO_CPU1_R
  10 VR_PVCCIO_CPU1_EN  AVREN @BASEBOARD_FAB2_LIB.BASEBOARD_FAB2(SCH_1):VR_PVCCIO_CPU1_EN
  11 IRQ_PVCCIO_CPU1_VRHOT_N VRHOT_N @BASEBOARD_FAB2_LIB.BASEBOARD_FAB2(SCH_1):IRQ_PVCCIO_CPU1_VRHOT_N
  12 TP_PVCCIO_CPU1_PINALRT_N PINALRT_N @BASEBOARD_FAB2_LIB.BASEBOARD_FAB2(SCH_1):TP_PVCCIO_CPU1_PINALRT_N
  13 TP_VR_PVCCIO_CPU1_MP0    MP0 @BASEBOARD_FAB2_LIB.BASEBOARD_FAB2(SCH_1):TP_VR_PVCCIO_CPU1_MP0
  14 TP_VR_PVCCIO_CPU1_MP1    MP1 @BASEBOARD_FAB2_LIB.BASEBOARD_FAB2(SCH_1):TP_VR_PVCCIO_CPU1_MP1
  15 SVID_CLK_PVCCIO_CPU1   VCLK @BASEBOARD_FAB2_LIB.BASEBOARD_FAB2(SCH_1):SVID_CLK_PVCCIO_CPU1
  16 SVID_VDIO_PVCCIO_CPU1   VDIO @BASEBOARD_FAB2_LIB.BASEBOARD_FAB2(SCH_1):SVID_VDIO_PVCCIO_CPU1
  17 SVID_ALERT_PVCCIO_CPU1 VALRT_N @BASEBOARD_FAB2_LIB.BASEBOARD_FAB2(SCH_1):SVID_ALERT_PVCCIO_CPU1
  18 TP_VR_PVCCIO_CPU1_MP2    MP2 @BASEBOARD_FAB2_LIB.BASEBOARD_FAB2(SCH_1):TP_VR_PVCCIO_CPU1_MP2
  19 VR_PVCCIO_CPU1_AVSP  AVSEN @BASEBOARD_FAB2_LIB.BASEBOARD_FAB2(SCH_1):VR_PVCCIO_CPU1_AVSP
  20 VSENSE_PVCCIO_CPU1_AVSN  AVREF @BASEBOARD_FAB2_LIB.BASEBOARD_FAB2(SCH_1):VSENSE_PVCCIO_CPU1_AVSN
  21 VR_PVCCIO_CPU1_AIREF1 AIREF1 @BASEBOARD_FAB2_LIB.BASEBOARD_FAB2(SCH_1):VR_PVCCIO_CPU1_AIREF1
  22 ISENSE_PVCCIO_CPU1_PH1_IMON AISEN1 @BASEBOARD_FAB2_LIB.BASEBOARD_FAB2(SCH_1):ISENSE_PVCCIO_CPU1_PH1_IMON
  23    GND GND<1> @BASEBOARD_FAB2_LIB.BASEBOARD_FAB2(SCH_1):GND
  24 NC_PVCCIO_CPU1_DNC3 DNC<3> @BASEBOARD_FAB2_LIB.BASEBOARD_FAB2(SCH_1):NC_PVCCIO_CPU1_DNC3
  25 TP_PVCCIO_CPU1_BIREF1 BIREF1 @BASEBOARD_FAB2_LIB.BASEBOARD_FAB2(SCH_1):TP_PVCCIO_CPU1_BIREF1
  26    GND BISEN1 @BASEBOARD_FAB2_LIB.BASEBOARD_FAB2(SCH_1):GND
  27    GND GND<0> @BASEBOARD_FAB2_LIB.BASEBOARD_FAB2(SCH_1):GND
  28 NC_PVCCIO_CPU1_DNC4 DNC<4> @BASEBOARD_FAB2_LIB.BASEBOARD_FAB2(SCH_1):NC_PVCCIO_CPU1_DNC4
  29 TP_PVCCIO_CPU1_BVSEN  BVSEN @BASEBOARD_FAB2_LIB.BASEBOARD_FAB2(SCH_1):TP_PVCCIO_CPU1_BVSEN
  30 TP_PVCCIO_CPU1_BVREF  BVREF @BASEBOARD_FAB2_LIB.BASEBOARD_FAB2(SCH_1):TP_PVCCIO_CPU1_BVREF
  31 TP_VR_PVCCIO_CPU1_MP3    MP3 @BASEBOARD_FAB2_LIB.BASEBOARD_FAB2(SCH_1):TP_VR_PVCCIO_CPU1_MP3
  32 PU_VR_PVCCIO_CPU1_FAULT1    MP4 @BASEBOARD_FAB2_LIB.BASEBOARD_FAB2(SCH_1):PU_VR_PVCCIO_CPU1_FAULT1
  33 VR_PVCCIO_CPU1_XADDR2 XADDR2 @BASEBOARD_FAB2_LIB.BASEBOARD_FAB2(SCH_1):VR_PVCCIO_CPU1_XADDR2
  34 TP_PVCCIO_CPU1_BTSEN  BTSEN @BASEBOARD_FAB2_LIB.BASEBOARD_FAB2(SCH_1):TP_PVCCIO_CPU1_BTSEN
  35 A_TSENSE_PVCCIO_CPU1  ATSEN @BASEBOARD_FAB2_LIB.BASEBOARD_FAB2(SCH_1):A_TSENSE_PVCCIO_CPU1
  36 VR_PVCCIO_CPU1_XADDR1 XADDR1 @BASEBOARD_FAB2_LIB.BASEBOARD_FAB2(SCH_1):VR_PVCCIO_CPU1_XADDR1
  37 VR_PVCCIO_CPU1_VINSEN VINSEN @BASEBOARD_FAB2_LIB.BASEBOARD_FAB2(SCH_1):VR_PVCCIO_CPU1_VINSEN
  38 TP_VR_PVCCIO_CPU1_AIINSEN IINSEN @BASEBOARD_FAB2_LIB.BASEBOARD_FAB2(SCH_1):TP_VR_PVCCIO_CPU1_AIINSEN
  39 VR_PVCCIO_CPU1_VDD    VDD @BASEBOARD_FAB2_LIB.BASEBOARD_FAB2(SCH_1):VR_PVCCIO_CPU1_VDD
  40 VR_PVCCIO_CPU1_VD12   VD12 @BASEBOARD_FAB2_LIB.BASEBOARD_FAB2(SCH_1):VR_PVCCIO_CPU1_VD12
  41    GND  THPAD @BASEBOARD_FAB2_LIB.BASEBOARD_FAB2(SCH_1):GND


DRAWING: @BASEBOARD_FAB2_LIB.BASEBOARD_FAB2(SCH_1):PAGE215 

RES_0402-100.0,1%,1/16W,CHIP,GA  I295  R3U2
   1 PVCCIO_CPU0      A @BASEBOARD_FAB2_LIB.BASEBOARD_FAB2(SCH_1):PVCCIO_CPU0
   2 SVID_DIO1_CPU0_R      B @BASEBOARD_FAB2_LIB.BASEBOARD_FAB2(SCH_1):SVID_DIO1_CPU0_R

RES_0402-22.1,1.0%,1/16W,CHIP,A  I296  R7F24
   1 PWRGD_PVDDQ_ABC_R      A @BASEBOARD_FAB2_LIB.BASEBOARD_FAB2(SCH_1):PWRGD_PVDDQ_ABC_R
   2 PWRGD_PVDDQ_ABC      B @BASEBOARD_FAB2_LIB.BASEBOARD_FAB2(SCH_1):PWRGD_PVDDQ_ABC

RES_0402-33.2,1%,1/16W,CHIP,G2A  I297  R7F23
   1 IRQ_PVDDQ_ABC_VRHOT_LVT3_R_N      A @BASEBOARD_FAB2_LIB.BASEBOARD_FAB2(SCH_1):IRQ_PVDDQ_ABC_VRHOT_LVT3_R_N
   2 IRQ_PVDDQ_ABC_VRHOT_LVT3_N      B @BASEBOARD_FAB2_LIB.BASEBOARD_FAB2(SCH_1):IRQ_PVDDQ_ABC_VRHOT_LVT3_N

RES_0402-20.0,1%,1/16W,CHIP,G2A  I298  R7F25
   1 SMB_VR_SCL_VDDQ_ABC      A @BASEBOARD_FAB2_LIB.BASEBOARD_FAB2(SCH_1):SMB_VR_SCL_VDDQ_ABC
   2 SMB_VR_STBY_LVC3_SCL      B @BASEBOARD_FAB2_LIB.BASEBOARD_FAB2(SCH_1):SMB_VR_STBY_LVC3_SCL

RES_0402-2.26K,1.0%,1/16W,EMPTA  I300  R7F36
   1 P3V3_STBY      A @BASEBOARD_FAB2_LIB.BASEBOARD_FAB2(SCH_1):P3V3_STBY
   2 PU_VR_PVDDQ_ABC_FAULT1      B @BASEBOARD_FAB2_LIB.BASEBOARD_FAB2(SCH_1):PU_VR_PVDDQ_ABC_FAULT1

RES_0402-1.00K,1%,1/16W,CHIP,GA  I301  R7F22
   1 P3V3_STBY      A @BASEBOARD_FAB2_LIB.BASEBOARD_FAB2(SCH_1):P3V3_STBY
   2 PWRGD_PVDDQ_ABC_R      B @BASEBOARD_FAB2_LIB.BASEBOARD_FAB2(SCH_1):PWRGD_PVDDQ_ABC_R

RES_0402-0.0,5%,1/16W,CHIP,G21A  I302  R7G4
   1 SVID_ALERT_PVDDQ_ABC      A @BASEBOARD_FAB2_LIB.BASEBOARD_FAB2(SCH_1):SVID_ALERT_PVDDQ_ABC
   2 SVID_ALERT1_CPU0_R_N      B @BASEBOARD_FAB2_LIB.BASEBOARD_FAB2(SCH_1):SVID_ALERT1_CPU0_R_N

RES_0402-1.00K,1%,1/16W,CHIP,GA  I303  R7F27
   1 P3V3_STBY      A @BASEBOARD_FAB2_LIB.BASEBOARD_FAB2(SCH_1):P3V3_STBY
   2 IRQ_PVDDQ_ABC_VRHOT_LVT3_R_N      B @BASEBOARD_FAB2_LIB.BASEBOARD_FAB2(SCH_1):IRQ_PVDDQ_ABC_VRHOT_LVT3_R_N

RES_0402-20.0,1%,1/16W,CHIP,G2A  I304  R7F26
   1 SMB_VR_SDA_VDDQ_ABC      A @BASEBOARD_FAB2_LIB.BASEBOARD_FAB2(SCH_1):SMB_VR_SDA_VDDQ_ABC
   2 SMB_VR_STBY_LVC3_SDA      B @BASEBOARD_FAB2_LIB.BASEBOARD_FAB2(SCH_1):SMB_VR_STBY_LVC3_SDA

CAP_0402LF-1000PF,50V,10%,X7R,A  I305  C7F14
   1 PWRGD_PVDDQ_ABC_R      A @BASEBOARD_FAB2_LIB.BASEBOARD_FAB2(SCH_1):PWRGD_PVDDQ_ABC_R
   2    GND      B @BASEBOARD_FAB2_LIB.BASEBOARD_FAB2(SCH_1):GND

RES_0402-0.0,5%,1/16W,CHIP,G21A  I307  R7G2
   1 SVID_VDIO_PVDDQ_ABC      A @BASEBOARD_FAB2_LIB.BASEBOARD_FAB2(SCH_1):SVID_VDIO_PVDDQ_ABC
   2 SVID_DIO1_CPU0_R      B @BASEBOARD_FAB2_LIB.BASEBOARD_FAB2(SCH_1):SVID_DIO1_CPU0_R

CAP_A_0402V-1.0UF,6.3V,10%,X6SA  I309  C7F18
   1 VR_PVDDQ_ABC_VDD      A @BASEBOARD_FAB2_LIB.BASEBOARD_FAB2(SCH_1):VR_PVDDQ_ABC_VDD
   2    GND      B @BASEBOARD_FAB2_LIB.BASEBOARD_FAB2(SCH_1):GND

CAP_A_0402V-0.1UF,16V,10%,X7R,A  I311  C7F17
   1 VR_PVDDQ_ABC_VDD      A @BASEBOARD_FAB2_LIB.BASEBOARD_FAB2(SCH_1):VR_PVDDQ_ABC_VDD
   2    GND      B @BASEBOARD_FAB2_LIB.BASEBOARD_FAB2(SCH_1):GND

RES_0402-0.0,5%,1/16W,CHIP,G21A  I313  R3T13
   1 P3V3_STBY      A @BASEBOARD_FAB2_LIB.BASEBOARD_FAB2(SCH_1):P3V3_STBY
   2 VR_PVDDQ_ABC_VDD      B @BASEBOARD_FAB2_LIB.BASEBOARD_FAB2(SCH_1):VR_PVDDQ_ABC_VDD

RES_0402-100.0K,1%,1/16W,EMPTYA  I315  R7F20
   1 P3V3_STBY      A @BASEBOARD_FAB2_LIB.BASEBOARD_FAB2(SCH_1):P3V3_STBY
   2 VR_PVDDQ_ABC_VREN      B @BASEBOARD_FAB2_LIB.BASEBOARD_FAB2(SCH_1):VR_PVDDQ_ABC_VREN

RES_0402-8.06K,1%,1/16W,CHIP,GA  I317  R7G10
   1 VR_PVDDQ_ABC_XADDR2      A @BASEBOARD_FAB2_LIB.BASEBOARD_FAB2(SCH_1):VR_PVDDQ_ABC_XADDR2
   2    GND      B @BASEBOARD_FAB2_LIB.BASEBOARD_FAB2(SCH_1):GND

CAP_0402LF-220PF,50V,10%,X7R,AA  I320  C7G3
   1 A_TSENSE_PVDDQ_ABC      A @BASEBOARD_FAB2_LIB.BASEBOARD_FAB2(SCH_1):A_TSENSE_PVDDQ_ABC
   2    GND      B @BASEBOARD_FAB2_LIB.BASEBOARD_FAB2(SCH_1):GND

RES_0402-4.02K,1%,1/16W,CHIP,GA  I321  R7G8
   1 VR_PVDDQ_ABC_XADDR1      A @BASEBOARD_FAB2_LIB.BASEBOARD_FAB2(SCH_1):VR_PVDDQ_ABC_XADDR1
   2    GND      B @BASEBOARD_FAB2_LIB.BASEBOARD_FAB2(SCH_1):GND

CAP_A_0402V-1.0UF,6.3V,10%,X6SA  I325  C7F16
   1 VR_PVDDQ_ABC_VD12      A @BASEBOARD_FAB2_LIB.BASEBOARD_FAB2(SCH_1):VR_PVDDQ_ABC_VD12
   2    GND      B @BASEBOARD_FAB2_LIB.BASEBOARD_FAB2(SCH_1):GND

CAP_A_0402V-0.1UF,16V,10%,X7R,A  I327  C7F15
   1 VR_PVDDQ_ABC_VD12      A @BASEBOARD_FAB2_LIB.BASEBOARD_FAB2(SCH_1):VR_PVDDQ_ABC_VD12
   2    GND      B @BASEBOARD_FAB2_LIB.BASEBOARD_FAB2(SCH_1):GND

RES_0402-49.9,1%,1/16W,EMPTY,GA  I330  R3T11
   1 PVCCIO_CPU0      A @BASEBOARD_FAB2_LIB.BASEBOARD_FAB2(SCH_1):PVCCIO_CPU0
   2 SVID_CLK1_CPU0_R      B @BASEBOARD_FAB2_LIB.BASEBOARD_FAB2(SCH_1):SVID_CLK1_CPU0_R

RES_0402-150.0,1%,1/16W,CHIP,GA  I331  R7G24
   1 SVID_CLK1_CPU0_R      A @BASEBOARD_FAB2_LIB.BASEBOARD_FAB2(SCH_1):SVID_CLK1_CPU0_R
   2 SVID_CLK_PVDDQ_ABC      B @BASEBOARD_FAB2_LIB.BASEBOARD_FAB2(SCH_1):SVID_CLK_PVDDQ_ABC

RES_0402-0.0,5%,1/16W,CHIP,G21A  I332  R3U3
   1 VR_PVDDQ_ABC_VD12      A @BASEBOARD_FAB2_LIB.BASEBOARD_FAB2(SCH_1):VR_PVDDQ_ABC_VD12
   2 VR_PVDDQ_ABC_AIREF2      B @BASEBOARD_FAB2_LIB.BASEBOARD_FAB2(SCH_1):VR_PVDDQ_ABC_AIREF2

RES_0402-100.0K,1%,1/16W,CHIP,B  I336  R7F34
   1 VR_FET_SW_P12V_STBY_PVDDQ_ABC      A @BASEBOARD_FAB2_LIB.BASEBOARD_FAB2(SCH_1):VR_FET_SW_P12V_STBY_PVDDQ_ABC
   2 VR_PVDDQ_ABC_VINSEN      B @BASEBOARD_FAB2_LIB.BASEBOARD_FAB2(SCH_1):VR_PVDDQ_ABC_VINSEN

RES_0402-1.5K,1%,1/16W,CHIP,G2A  I337  R7G3
   1 VR_PVDDQ_ABC_VINSEN      A @BASEBOARD_FAB2_LIB.BASEBOARD_FAB2(SCH_1):VR_PVDDQ_ABC_VINSEN
   2    GND      B @BASEBOARD_FAB2_LIB.BASEBOARD_FAB2(SCH_1):GND

CAP_0402LF-1000PF,50V,10%,X7R,A  I339  C7G1
   1 VR_PVDDQ_ABC_VINSEN      A @BASEBOARD_FAB2_LIB.BASEBOARD_FAB2(SCH_1):VR_PVDDQ_ABC_VINSEN
   2    GND      B @BASEBOARD_FAB2_LIB.BASEBOARD_FAB2(SCH_1):GND

RES_0402-0.0,5%,1/16W,CHIP,G21A  I341  R3U10
   1 VR_PVDDQ_ABC_VD12      A @BASEBOARD_FAB2_LIB.BASEBOARD_FAB2(SCH_1):VR_PVDDQ_ABC_VD12
   2 VR_PVDDQ_ABC_AIREF1      B @BASEBOARD_FAB2_LIB.BASEBOARD_FAB2(SCH_1):VR_PVDDQ_ABC_AIREF1

CAP_0402LF-220PF,50V,10%,X7R,AA  I342  C7G4
   1 VR_PVDDQ_ABC_AVSP      A @BASEBOARD_FAB2_LIB.BASEBOARD_FAB2(SCH_1):VR_PVDDQ_ABC_AVSP
   2 VSENSE_PVDDQ_ABC_N      B @BASEBOARD_FAB2_LIB.BASEBOARD_FAB2(SCH_1):VSENSE_PVDDQ_ABC_N

RES_0402-0.0,5%,1/16W,CHIP,G21A  I343  R7F21
   1 FM_PVDDQ_ABC_EN      A @BASEBOARD_FAB2_LIB.BASEBOARD_FAB2(SCH_1):FM_PVDDQ_ABC_EN
   2 VR_PVDDQ_ABC_VREN      B @BASEBOARD_FAB2_LIB.BASEBOARD_FAB2(SCH_1):VR_PVDDQ_ABC_VREN

RES_0402-10.0,1%,1/16W,CHIP,G2A  I344  R7G9
   1 VSENSE_PVDDQ_ABC_P      A @BASEBOARD_FAB2_LIB.BASEBOARD_FAB2(SCH_1):VSENSE_PVDDQ_ABC_P
   2 VR_PVDDQ_ABC_AVSP      B @BASEBOARD_FAB2_LIB.BASEBOARD_FAB2(SCH_1):VR_PVDDQ_ABC_AVSP

PXM1310B_QFN-IC,H89186-001  I358  EU7G1
   1 TP_PVDDQ_ABC_BPWM1  BPWM1 @BASEBOARD_FAB2_LIB.BASEBOARD_FAB2(SCH_1):TP_PVDDQ_ABC_BPWM1
   2 NC_PVDDQ_ABC_DNC0 DNC<0> @BASEBOARD_FAB2_LIB.BASEBOARD_FAB2(SCH_1):NC_PVDDQ_ABC_DNC0
   3 TP_PVDDQ_ABC_PWM3  APWM3 @BASEBOARD_FAB2_LIB.BASEBOARD_FAB2(SCH_1):TP_PVDDQ_ABC_PWM3
   4 VR_PVDDQ_ABC_PWM2  APWM2 @BASEBOARD_FAB2_LIB.BASEBOARD_FAB2(SCH_1):VR_PVDDQ_ABC_PWM2
   5 VR_PVDDQ_ABC_PWM1  APWM1 @BASEBOARD_FAB2_LIB.BASEBOARD_FAB2(SCH_1):VR_PVDDQ_ABC_PWM1
   6 SMB_VR_SDA_VDDQ_ABC    SDA @BASEBOARD_FAB2_LIB.BASEBOARD_FAB2(SCH_1):SMB_VR_SDA_VDDQ_ABC
   7 SMB_VR_SCL_VDDQ_ABC    SCL @BASEBOARD_FAB2_LIB.BASEBOARD_FAB2(SCH_1):SMB_VR_SCL_VDDQ_ABC
   8 TP_PVDDQ_ABC_RESET_N RESET_N @BASEBOARD_FAB2_LIB.BASEBOARD_FAB2(SCH_1):TP_PVDDQ_ABC_RESET_N
   9 PWRGD_PVDDQ_ABC_R AVRRDY @BASEBOARD_FAB2_LIB.BASEBOARD_FAB2(SCH_1):PWRGD_PVDDQ_ABC_R
  10 VR_PVDDQ_ABC_VREN  AVREN @BASEBOARD_FAB2_LIB.BASEBOARD_FAB2(SCH_1):VR_PVDDQ_ABC_VREN
  11 IRQ_PVDDQ_ABC_VRHOT_LVT3_R_N VRHOT_N @BASEBOARD_FAB2_LIB.BASEBOARD_FAB2(SCH_1):IRQ_PVDDQ_ABC_VRHOT_LVT3_R_N
  12 TP_PVDDQ_ABC_PINALRT_N PINALRT_N @BASEBOARD_FAB2_LIB.BASEBOARD_FAB2(SCH_1):TP_PVDDQ_ABC_PINALRT_N
  13 PU_VR_PVDDQ_ABC_FAULT1    MP0 @BASEBOARD_FAB2_LIB.BASEBOARD_FAB2(SCH_1):PU_VR_PVDDQ_ABC_FAULT1
  14 TP_PVDDQ_ABC_MP1    MP1 @BASEBOARD_FAB2_LIB.BASEBOARD_FAB2(SCH_1):TP_PVDDQ_ABC_MP1
  15 SVID_CLK_PVDDQ_ABC   VCLK @BASEBOARD_FAB2_LIB.BASEBOARD_FAB2(SCH_1):SVID_CLK_PVDDQ_ABC
  16 SVID_VDIO_PVDDQ_ABC   VDIO @BASEBOARD_FAB2_LIB.BASEBOARD_FAB2(SCH_1):SVID_VDIO_PVDDQ_ABC
  17 SVID_ALERT_PVDDQ_ABC VALRT_N @BASEBOARD_FAB2_LIB.BASEBOARD_FAB2(SCH_1):SVID_ALERT_PVDDQ_ABC
  18 TP_PVDDQ_ABC_MP2    MP2 @BASEBOARD_FAB2_LIB.BASEBOARD_FAB2(SCH_1):TP_PVDDQ_ABC_MP2
  19 VR_PVDDQ_ABC_AVSP  AVSEN @BASEBOARD_FAB2_LIB.BASEBOARD_FAB2(SCH_1):VR_PVDDQ_ABC_AVSP
  20 VSENSE_PVDDQ_ABC_N  AVREF @BASEBOARD_FAB2_LIB.BASEBOARD_FAB2(SCH_1):VSENSE_PVDDQ_ABC_N
  21 VR_PVDDQ_ABC_AIREF1 AIREF1 @BASEBOARD_FAB2_LIB.BASEBOARD_FAB2(SCH_1):VR_PVDDQ_ABC_AIREF1
  22 ISENSE_PVDDQ_ABC_PH1_IMON AISEN1 @BASEBOARD_FAB2_LIB.BASEBOARD_FAB2(SCH_1):ISENSE_PVDDQ_ABC_PH1_IMON
  23 VR_PVDDQ_ABC_AIREF2 AIREF2 @BASEBOARD_FAB2_LIB.BASEBOARD_FAB2(SCH_1):VR_PVDDQ_ABC_AIREF2
  24 ISENSE_PVDDQ_ABC_PH2_IMON AISEN2 @BASEBOARD_FAB2_LIB.BASEBOARD_FAB2(SCH_1):ISENSE_PVDDQ_ABC_PH2_IMON
  25 TP_PVDDQ_ABC_PH3_IMON_REF AIREF3 @BASEBOARD_FAB2_LIB.BASEBOARD_FAB2(SCH_1):TP_PVDDQ_ABC_PH3_IMON_REF
  26 TP_PVDDQ_ABC_PH3_IMON AISEN3 @BASEBOARD_FAB2_LIB.BASEBOARD_FAB2(SCH_1):TP_PVDDQ_ABC_PH3_IMON
  27    GND    GND @BASEBOARD_FAB2_LIB.BASEBOARD_FAB2(SCH_1):GND
  28 NC_PVDDQ_ABC_DNC1 DNC<1> @BASEBOARD_FAB2_LIB.BASEBOARD_FAB2(SCH_1):NC_PVDDQ_ABC_DNC1
  29 TP_PVDDQ_ABC_BVSEN  BVSEN @BASEBOARD_FAB2_LIB.BASEBOARD_FAB2(SCH_1):TP_PVDDQ_ABC_BVSEN
  30 TP_PVDDQ_ABC_BVREF  BVREF @BASEBOARD_FAB2_LIB.BASEBOARD_FAB2(SCH_1):TP_PVDDQ_ABC_BVREF
  31 TP_PVDDQ_ABC_BREF1 BIREF1 @BASEBOARD_FAB2_LIB.BASEBOARD_FAB2(SCH_1):TP_PVDDQ_ABC_BREF1
  32    GND BISEN1 @BASEBOARD_FAB2_LIB.BASEBOARD_FAB2(SCH_1):GND
  33 VR_PVDDQ_ABC_XADDR2 XADDR2 @BASEBOARD_FAB2_LIB.BASEBOARD_FAB2(SCH_1):VR_PVDDQ_ABC_XADDR2
  34 TP_PVDDQ_ABC_BTSEN  BTSEN @BASEBOARD_FAB2_LIB.BASEBOARD_FAB2(SCH_1):TP_PVDDQ_ABC_BTSEN
  35 A_TSENSE_PVDDQ_ABC  ATSEN @BASEBOARD_FAB2_LIB.BASEBOARD_FAB2(SCH_1):A_TSENSE_PVDDQ_ABC
  36 VR_PVDDQ_ABC_XADDR1 XADDR1 @BASEBOARD_FAB2_LIB.BASEBOARD_FAB2(SCH_1):VR_PVDDQ_ABC_XADDR1
  37 VR_PVDDQ_ABC_VINSEN VINSEN @BASEBOARD_FAB2_LIB.BASEBOARD_FAB2(SCH_1):VR_PVDDQ_ABC_VINSEN
  38 VR_PVDDQ_ABC_AIINSEN IINSEN @BASEBOARD_FAB2_LIB.BASEBOARD_FAB2(SCH_1):VR_PVDDQ_ABC_AIINSEN
  39 VR_PVDDQ_ABC_VDD    VDD @BASEBOARD_FAB2_LIB.BASEBOARD_FAB2(SCH_1):VR_PVDDQ_ABC_VDD
  40 VR_PVDDQ_ABC_VD12   VD12 @BASEBOARD_FAB2_LIB.BASEBOARD_FAB2(SCH_1):VR_PVDDQ_ABC_VD12
  41    GND  THPAD @BASEBOARD_FAB2_LIB.BASEBOARD_FAB2(SCH_1):GND

CAP_A_0402V-0.1UF,16V,10%,X7R,A  I360  C3U10
   1 VR_PVDDQ_ABC_AIINSEN      A @BASEBOARD_FAB2_LIB.BASEBOARD_FAB2(SCH_1):VR_PVDDQ_ABC_AIINSEN
   2    GND      B @BASEBOARD_FAB2_LIB.BASEBOARD_FAB2(SCH_1):GND


DRAWING: @BASEBOARD_FAB2_LIB.BASEBOARD_FAB2(SCH_1):PAGE217 

RES_0603-120.0,1%,1/10W,CHIP,GA  I58  R3U4
   1 PVDDQ_ABC      A @BASEBOARD_FAB2_LIB.BASEBOARD_FAB2(SCH_1):PVDDQ_ABC
   2    GND      B @BASEBOARD_FAB2_LIB.BASEBOARD_FAB2(SCH_1):GND

RES_0402-100.0,1%,1/16W,EMPTY,A  I74  R4U6
   1 VSENSE_PVDDQ_ABC_P      A @BASEBOARD_FAB2_LIB.BASEBOARD_FAB2(SCH_1):VSENSE_PVDDQ_ABC_P
   2 VSENSE_PVDDQ_ABC_N      B @BASEBOARD_FAB2_LIB.BASEBOARD_FAB2(SCH_1):VSENSE_PVDDQ_ABC_N

CAPP_3018-470UF,2.5V,20%,ALUM,A  I75  C7G28
   1 PVDDQ_ABC      A @BASEBOARD_FAB2_LIB.BASEBOARD_FAB2(SCH_1):PVDDQ_ABC
   2    GND      B @BASEBOARD_FAB2_LIB.BASEBOARD_FAB2(SCH_1):GND

CAPP_3018-470UF,2.5V,20%,ALUM,A  I76  C3U1
   1 PVDDQ_ABC      A @BASEBOARD_FAB2_LIB.BASEBOARD_FAB2(SCH_1):PVDDQ_ABC
   2    GND      B @BASEBOARD_FAB2_LIB.BASEBOARD_FAB2(SCH_1):GND

CAPP_3018-470UF,2.5V,20%,ALUM,A  I77  C3U5
   1 PVDDQ_ABC      A @BASEBOARD_FAB2_LIB.BASEBOARD_FAB2(SCH_1):PVDDQ_ABC
   2    GND      B @BASEBOARD_FAB2_LIB.BASEBOARD_FAB2(SCH_1):GND

CAPP_3018-470UF,2.5V,20%,ALUM,A  I78  C3U8
   1 PVDDQ_ABC      A @BASEBOARD_FAB2_LIB.BASEBOARD_FAB2(SCH_1):PVDDQ_ABC
   2    GND      B @BASEBOARD_FAB2_LIB.BASEBOARD_FAB2(SCH_1):GND

CAP_0805-100UF,4V,20%,X5R,6024A  I82  C5U13
   1 PVDDQ_ABC      A @BASEBOARD_FAB2_LIB.BASEBOARD_FAB2(SCH_1):PVDDQ_ABC
   2    GND      B @BASEBOARD_FAB2_LIB.BASEBOARD_FAB2(SCH_1):GND

CAP_0805-100UF,4V,20%,X5R,6024A  I83  C5U10
   1 PVDDQ_ABC      A @BASEBOARD_FAB2_LIB.BASEBOARD_FAB2(SCH_1):PVDDQ_ABC
   2    GND      B @BASEBOARD_FAB2_LIB.BASEBOARD_FAB2(SCH_1):GND

CAP_0805-100UF,4V,20%,X5R,6024A  I88  C5U1
   1 PVDDQ_ABC      A @BASEBOARD_FAB2_LIB.BASEBOARD_FAB2(SCH_1):PVDDQ_ABC
   2    GND      B @BASEBOARD_FAB2_LIB.BASEBOARD_FAB2(SCH_1):GND

CAP_0805-100UF,4V,20%,X5R,6024A  I89  C5U14
   1 PVDDQ_ABC      A @BASEBOARD_FAB2_LIB.BASEBOARD_FAB2(SCH_1):PVDDQ_ABC
   2    GND      B @BASEBOARD_FAB2_LIB.BASEBOARD_FAB2(SCH_1):GND

CAP_0805-100UF,4V,20%,X5R,6024A  I90  C5U15
   1 PVDDQ_ABC      A @BASEBOARD_FAB2_LIB.BASEBOARD_FAB2(SCH_1):PVDDQ_ABC
   2    GND      B @BASEBOARD_FAB2_LIB.BASEBOARD_FAB2(SCH_1):GND

CAP_0805-100UF,4V,20%,X5R,6024A  I91  C4T4
   1 PVDDQ_ABC      A @BASEBOARD_FAB2_LIB.BASEBOARD_FAB2(SCH_1):PVDDQ_ABC
   2    GND      B @BASEBOARD_FAB2_LIB.BASEBOARD_FAB2(SCH_1):GND

CAP_0805-100UF,4V,20%,X5R,6024A  I92  C5G9
   1 PVDDQ_ABC      A @BASEBOARD_FAB2_LIB.BASEBOARD_FAB2(SCH_1):PVDDQ_ABC
   2    GND      B @BASEBOARD_FAB2_LIB.BASEBOARD_FAB2(SCH_1):GND

CAP_0805-100UF,4V,20%,X5R,6024A  I110  C5G20
   1 PVDDQ_ABC      A @BASEBOARD_FAB2_LIB.BASEBOARD_FAB2(SCH_1):PVDDQ_ABC
   2    GND      B @BASEBOARD_FAB2_LIB.BASEBOARD_FAB2(SCH_1):GND

INDUCTOR_SM-100NH,IND,D92183-0B  I124  L7F2
   1 P12V_STBY    INA @BASEBOARD_FAB2_LIB.BASEBOARD_FAB2(SCH_1):P12V_STBY
   2 VR_FET_SW_P12V_STBY_PVDDQ_ABC    INB @BASEBOARD_FAB2_LIB.BASEBOARD_FAB2(SCH_1):VR_FET_SW_P12V_STBY_PVDDQ_ABC

CAPP_2626-270UF,16V,20%,OSCON,A  I175  C7G2
   1 VR_FET_SW_P12V_STBY_PVDDQ_ABC      A @BASEBOARD_FAB2_LIB.BASEBOARD_FAB2(SCH_1):VR_FET_SW_P12V_STBY_PVDDQ_ABC
   2    GND      B @BASEBOARD_FAB2_LIB.BASEBOARD_FAB2(SCH_1):GND

CAP_0805LF-22UF,4V,20%,X6S,C95A  I184  C5P39
   1 PVDDQ_ABC      A @BASEBOARD_FAB2_LIB.BASEBOARD_FAB2(SCH_1):PVDDQ_ABC
   2    GND      B @BASEBOARD_FAB2_LIB.BASEBOARD_FAB2(SCH_1):GND

CAP_0603LF-10UF,4V,20%,X6S,E15A  I186  C5D57
   1 PVDDQ_ABC      A @BASEBOARD_FAB2_LIB.BASEBOARD_FAB2(SCH_1):PVDDQ_ABC
   2    GND      B @BASEBOARD_FAB2_LIB.BASEBOARD_FAB2(SCH_1):GND

CAP_0603LF-10UF,4V,20%,X6S,E15A  I188  C5D56
   1 PVDDQ_ABC      A @BASEBOARD_FAB2_LIB.BASEBOARD_FAB2(SCH_1):PVDDQ_ABC
   2    GND      B @BASEBOARD_FAB2_LIB.BASEBOARD_FAB2(SCH_1):GND

CAP_0603LF-10UF,4V,20%,X6S,E15A  I189  C5D55
   1 PVDDQ_ABC      A @BASEBOARD_FAB2_LIB.BASEBOARD_FAB2(SCH_1):PVDDQ_ABC
   2    GND      B @BASEBOARD_FAB2_LIB.BASEBOARD_FAB2(SCH_1):GND

CAP_0603LF-10UF,4V,20%,X6S,E15A  I190  C5D54
   1 PVDDQ_ABC      A @BASEBOARD_FAB2_LIB.BASEBOARD_FAB2(SCH_1):PVDDQ_ABC
   2    GND      B @BASEBOARD_FAB2_LIB.BASEBOARD_FAB2(SCH_1):GND

CAP_0805LF-22UF,4V,20%,X6S,C95A  I193  C5P38
   1 PVDDQ_ABC      A @BASEBOARD_FAB2_LIB.BASEBOARD_FAB2(SCH_1):PVDDQ_ABC
   2    GND      B @BASEBOARD_FAB2_LIB.BASEBOARD_FAB2(SCH_1):GND

CAP_A_0603V-47UF,4V,20%,X5R,60A  I205  C5F2
   1 PVDDQ_ABC      A @BASEBOARD_FAB2_LIB.BASEBOARD_FAB2(SCH_1):PVDDQ_ABC
   2    GND      B @BASEBOARD_FAB2_LIB.BASEBOARD_FAB2(SCH_1):GND

CAP_A_0603V-47UF,4V,20%,X5R,60A  I206  C5F1
   1 PVDDQ_ABC      A @BASEBOARD_FAB2_LIB.BASEBOARD_FAB2(SCH_1):PVDDQ_ABC
   2    GND      B @BASEBOARD_FAB2_LIB.BASEBOARD_FAB2(SCH_1):GND

CAP_A_0603V-47UF,4V,20%,X5R,60A  I207  C5G10
   1 PVDDQ_ABC      A @BASEBOARD_FAB2_LIB.BASEBOARD_FAB2(SCH_1):PVDDQ_ABC
   2    GND      B @BASEBOARD_FAB2_LIB.BASEBOARD_FAB2(SCH_1):GND

CAP_A_0603V-47UF,4V,20%,X5R,60A  I208  C5T2
   1 PVDDQ_ABC      A @BASEBOARD_FAB2_LIB.BASEBOARD_FAB2(SCH_1):PVDDQ_ABC
   2    GND      B @BASEBOARD_FAB2_LIB.BASEBOARD_FAB2(SCH_1):GND

CAP_A_0603V-47UF,4V,20%,X5R,60A  I209  C5U11
   1 PVDDQ_ABC      A @BASEBOARD_FAB2_LIB.BASEBOARD_FAB2(SCH_1):PVDDQ_ABC
   2    GND      B @BASEBOARD_FAB2_LIB.BASEBOARD_FAB2(SCH_1):GND

CAP_A_0603V-47UF,4V,20%,X5R,60A  I210  C5T13
   1 PVDDQ_ABC      A @BASEBOARD_FAB2_LIB.BASEBOARD_FAB2(SCH_1):PVDDQ_ABC
   2    GND      B @BASEBOARD_FAB2_LIB.BASEBOARD_FAB2(SCH_1):GND

CAP_A_0603V-47UF,4V,20%,X5R,60A  I211  C5T4
   1 PVDDQ_ABC      A @BASEBOARD_FAB2_LIB.BASEBOARD_FAB2(SCH_1):PVDDQ_ABC
   2    GND      B @BASEBOARD_FAB2_LIB.BASEBOARD_FAB2(SCH_1):GND

CAP_A_0603V-47UF,4V,20%,X5R,60A  I212  C5T1
   1 PVDDQ_ABC      A @BASEBOARD_FAB2_LIB.BASEBOARD_FAB2(SCH_1):PVDDQ_ABC
   2    GND      B @BASEBOARD_FAB2_LIB.BASEBOARD_FAB2(SCH_1):GND

CAP_A_0603V-47UF,4V,20%,X5R,60A  I213  C5G19
   1 PVDDQ_ABC      A @BASEBOARD_FAB2_LIB.BASEBOARD_FAB2(SCH_1):PVDDQ_ABC
   2    GND      B @BASEBOARD_FAB2_LIB.BASEBOARD_FAB2(SCH_1):GND

CAP_A_0603V-22.0UF,4V,20%,X6S,A  I216  C5T5
   1 PVDDQ_ABC      A @BASEBOARD_FAB2_LIB.BASEBOARD_FAB2(SCH_1):PVDDQ_ABC
   2    GND      B @BASEBOARD_FAB2_LIB.BASEBOARD_FAB2(SCH_1):GND

CAP_A_0603V-22.0UF,4V,20%,X6S,A  I217  C5G3
   1 PVDDQ_ABC      A @BASEBOARD_FAB2_LIB.BASEBOARD_FAB2(SCH_1):PVDDQ_ABC
   2    GND      B @BASEBOARD_FAB2_LIB.BASEBOARD_FAB2(SCH_1):GND

CAP_A_0603V-22.0UF,4V,20%,X6S,A  I218  C5T6
   1 PVDDQ_ABC      A @BASEBOARD_FAB2_LIB.BASEBOARD_FAB2(SCH_1):PVDDQ_ABC
   2    GND      B @BASEBOARD_FAB2_LIB.BASEBOARD_FAB2(SCH_1):GND

CAP_A_0603V-22.0UF,4V,20%,X6S,A  I219  C5T7
   1 PVDDQ_ABC      A @BASEBOARD_FAB2_LIB.BASEBOARD_FAB2(SCH_1):PVDDQ_ABC
   2    GND      B @BASEBOARD_FAB2_LIB.BASEBOARD_FAB2(SCH_1):GND

CAP_A_0603V-22.0UF,4V,20%,X6S,A  I220  C5G15
   1 PVDDQ_ABC      A @BASEBOARD_FAB2_LIB.BASEBOARD_FAB2(SCH_1):PVDDQ_ABC
   2    GND      B @BASEBOARD_FAB2_LIB.BASEBOARD_FAB2(SCH_1):GND

CAP_A_0603V-22.0UF,4V,20%,X6S,A  I221  C5G16
   1 PVDDQ_ABC      A @BASEBOARD_FAB2_LIB.BASEBOARD_FAB2(SCH_1):PVDDQ_ABC
   2    GND      B @BASEBOARD_FAB2_LIB.BASEBOARD_FAB2(SCH_1):GND

CAP_A_0603V-22.0UF,4V,20%,X6S,A  I222  C5T8
   1 PVDDQ_ABC      A @BASEBOARD_FAB2_LIB.BASEBOARD_FAB2(SCH_1):PVDDQ_ABC
   2    GND      B @BASEBOARD_FAB2_LIB.BASEBOARD_FAB2(SCH_1):GND

CAP_A_0603V-22.0UF,4V,20%,X6S,A  I223  C5G14
   1 PVDDQ_ABC      A @BASEBOARD_FAB2_LIB.BASEBOARD_FAB2(SCH_1):PVDDQ_ABC
   2    GND      B @BASEBOARD_FAB2_LIB.BASEBOARD_FAB2(SCH_1):GND

CAP_A_0603V-22.0UF,4V,20%,X6S,A  I224  C5T9
   1 PVDDQ_ABC      A @BASEBOARD_FAB2_LIB.BASEBOARD_FAB2(SCH_1):PVDDQ_ABC
   2    GND      B @BASEBOARD_FAB2_LIB.BASEBOARD_FAB2(SCH_1):GND

CAP_A_0603V-22.0UF,4V,20%,X6S,A  I225  C5T10
   1 PVDDQ_ABC      A @BASEBOARD_FAB2_LIB.BASEBOARD_FAB2(SCH_1):PVDDQ_ABC
   2    GND      B @BASEBOARD_FAB2_LIB.BASEBOARD_FAB2(SCH_1):GND

CAP_A_0603V-22.0UF,4V,20%,X6S,A  I226  C5G17
   1 PVDDQ_ABC      A @BASEBOARD_FAB2_LIB.BASEBOARD_FAB2(SCH_1):PVDDQ_ABC
   2    GND      B @BASEBOARD_FAB2_LIB.BASEBOARD_FAB2(SCH_1):GND

CAP_A_0603V-22.0UF,4V,20%,X6S,A  I227  C5G18
   1 PVDDQ_ABC      A @BASEBOARD_FAB2_LIB.BASEBOARD_FAB2(SCH_1):PVDDQ_ABC
   2    GND      B @BASEBOARD_FAB2_LIB.BASEBOARD_FAB2(SCH_1):GND

CAP_A_0603V-22.0UF,4V,20%,X6S,A  I228  C5T11
   1 PVDDQ_ABC      A @BASEBOARD_FAB2_LIB.BASEBOARD_FAB2(SCH_1):PVDDQ_ABC
   2    GND      B @BASEBOARD_FAB2_LIB.BASEBOARD_FAB2(SCH_1):GND

CAP_A_0603V-22.0UF,4V,20%,X6S,A  I229  C5T12
   1 PVDDQ_ABC      A @BASEBOARD_FAB2_LIB.BASEBOARD_FAB2(SCH_1):PVDDQ_ABC
   2    GND      B @BASEBOARD_FAB2_LIB.BASEBOARD_FAB2(SCH_1):GND

CAP_A_0603V-22.0UF,4V,20%,X6S,A  I230  C5G8
   1 PVDDQ_ABC      A @BASEBOARD_FAB2_LIB.BASEBOARD_FAB2(SCH_1):PVDDQ_ABC
   2    GND      B @BASEBOARD_FAB2_LIB.BASEBOARD_FAB2(SCH_1):GND

CAP_A_0603V-22.0UF,4V,20%,X6S,A  I231  C5G1
   1 PVDDQ_ABC      A @BASEBOARD_FAB2_LIB.BASEBOARD_FAB2(SCH_1):PVDDQ_ABC
   2    GND      B @BASEBOARD_FAB2_LIB.BASEBOARD_FAB2(SCH_1):GND

CAP_A_0603V-22.0UF,4V,20%,X6S,A  I232  C5U9
   1 PVDDQ_ABC      A @BASEBOARD_FAB2_LIB.BASEBOARD_FAB2(SCH_1):PVDDQ_ABC
   2    GND      B @BASEBOARD_FAB2_LIB.BASEBOARD_FAB2(SCH_1):GND

CAP_A_0603V-22.0UF,4V,20%,X6S,A  I233  C5U8
   1 PVDDQ_ABC      A @BASEBOARD_FAB2_LIB.BASEBOARD_FAB2(SCH_1):PVDDQ_ABC
   2    GND      B @BASEBOARD_FAB2_LIB.BASEBOARD_FAB2(SCH_1):GND

CAP_A_0603V-22.0UF,4V,20%,X6S,A  I234  C5G7
   1 PVDDQ_ABC      A @BASEBOARD_FAB2_LIB.BASEBOARD_FAB2(SCH_1):PVDDQ_ABC
   2    GND      B @BASEBOARD_FAB2_LIB.BASEBOARD_FAB2(SCH_1):GND

CAP_A_0603V-22.0UF,4V,20%,X6S,A  I235  C5G5
   1 PVDDQ_ABC      A @BASEBOARD_FAB2_LIB.BASEBOARD_FAB2(SCH_1):PVDDQ_ABC
   2    GND      B @BASEBOARD_FAB2_LIB.BASEBOARD_FAB2(SCH_1):GND

CAP_A_0603V-22.0UF,4V,20%,X6S,A  I236  C5U7
   1 PVDDQ_ABC      A @BASEBOARD_FAB2_LIB.BASEBOARD_FAB2(SCH_1):PVDDQ_ABC
   2    GND      B @BASEBOARD_FAB2_LIB.BASEBOARD_FAB2(SCH_1):GND

CAP_A_0603V-22.0UF,4V,20%,X6S,A  I237  C5G6
   1 PVDDQ_ABC      A @BASEBOARD_FAB2_LIB.BASEBOARD_FAB2(SCH_1):PVDDQ_ABC
   2    GND      B @BASEBOARD_FAB2_LIB.BASEBOARD_FAB2(SCH_1):GND

CAP_A_0603V-22.0UF,4V,20%,X6S,A  I238  C5U6
   1 PVDDQ_ABC      A @BASEBOARD_FAB2_LIB.BASEBOARD_FAB2(SCH_1):PVDDQ_ABC
   2    GND      B @BASEBOARD_FAB2_LIB.BASEBOARD_FAB2(SCH_1):GND

CAP_A_0603V-22.0UF,4V,20%,X6S,A  I239  C5U5
   1 PVDDQ_ABC      A @BASEBOARD_FAB2_LIB.BASEBOARD_FAB2(SCH_1):PVDDQ_ABC
   2    GND      B @BASEBOARD_FAB2_LIB.BASEBOARD_FAB2(SCH_1):GND

CAP_A_0603V-22.0UF,4V,20%,X6S,A  I240  C5G13
   1 PVDDQ_ABC      A @BASEBOARD_FAB2_LIB.BASEBOARD_FAB2(SCH_1):PVDDQ_ABC
   2    GND      B @BASEBOARD_FAB2_LIB.BASEBOARD_FAB2(SCH_1):GND

CAP_A_0603V-22.0UF,4V,20%,X6S,A  I241  C5G4
   1 PVDDQ_ABC      A @BASEBOARD_FAB2_LIB.BASEBOARD_FAB2(SCH_1):PVDDQ_ABC
   2    GND      B @BASEBOARD_FAB2_LIB.BASEBOARD_FAB2(SCH_1):GND

CAP_A_0603V-22.0UF,4V,20%,X6S,A  I243  C5U4
   1 PVDDQ_ABC      A @BASEBOARD_FAB2_LIB.BASEBOARD_FAB2(SCH_1):PVDDQ_ABC
   2    GND      B @BASEBOARD_FAB2_LIB.BASEBOARD_FAB2(SCH_1):GND

CAP_A_0603V-22.0UF,4V,20%,X6S,A  I244  C5U3
   1 PVDDQ_ABC      A @BASEBOARD_FAB2_LIB.BASEBOARD_FAB2(SCH_1):PVDDQ_ABC
   2    GND      B @BASEBOARD_FAB2_LIB.BASEBOARD_FAB2(SCH_1):GND

CAP_A_0603V-22.0UF,4V,20%,X6S,A  I245  C5G2
   1 PVDDQ_ABC      A @BASEBOARD_FAB2_LIB.BASEBOARD_FAB2(SCH_1):PVDDQ_ABC
   2    GND      B @BASEBOARD_FAB2_LIB.BASEBOARD_FAB2(SCH_1):GND

CAP_A_0603V-22.0UF,4V,20%,X6S,A  I246  C5G12
   1 PVDDQ_ABC      A @BASEBOARD_FAB2_LIB.BASEBOARD_FAB2(SCH_1):PVDDQ_ABC
   2    GND      B @BASEBOARD_FAB2_LIB.BASEBOARD_FAB2(SCH_1):GND

CAP_A_0603V-22.0UF,4V,20%,X6S,A  I247  C5U2
   1 PVDDQ_ABC      A @BASEBOARD_FAB2_LIB.BASEBOARD_FAB2(SCH_1):PVDDQ_ABC
   2    GND      B @BASEBOARD_FAB2_LIB.BASEBOARD_FAB2(SCH_1):GND

CAP_A_0603V-22.0UF,4V,20%,X6S,A  I250  C5G11
   1 PVDDQ_ABC      A @BASEBOARD_FAB2_LIB.BASEBOARD_FAB2(SCH_1):PVDDQ_ABC
   2    GND      B @BASEBOARD_FAB2_LIB.BASEBOARD_FAB2(SCH_1):GND

SHUNT_SH0201-EMPTY,N_A  I259  SH4U1
   1 VSENSE_PVDDQ_ABC_N      A @BASEBOARD_FAB2_LIB.BASEBOARD_FAB2(SCH_1):VSENSE_PVDDQ_ABC_N
   2    GND      B @BASEBOARD_FAB2_LIB.BASEBOARD_FAB2(SCH_1):GND

SHUNT_SH0201-EMPTY,N_A  I260  SH4U2
   1 VSENSE_PVDDQ_ABC_P      A @BASEBOARD_FAB2_LIB.BASEBOARD_FAB2(SCH_1):VSENSE_PVDDQ_ABC_P
   2 PVDDQ_ABC      B @BASEBOARD_FAB2_LIB.BASEBOARD_FAB2(SCH_1):PVDDQ_ABC


DRAWING: @BASEBOARD_FAB2_LIB.BASEBOARD_FAB2(SCH_1):PAGE218 

RES_0402-100.0,1%,1/16W,EMPTY,A  I7  R3L11
   1 PVCCIO_CPU0      A @BASEBOARD_FAB2_LIB.BASEBOARD_FAB2(SCH_1):PVCCIO_CPU0
   2 SVID_DIO1_CPU0_R      B @BASEBOARD_FAB2_LIB.BASEBOARD_FAB2(SCH_1):SVID_DIO1_CPU0_R

RES_0402-22.1,1.0%,1/16W,CHIP,A  I11  R3M3
   1 PWRGD_PVDDQ_DEF_R      A @BASEBOARD_FAB2_LIB.BASEBOARD_FAB2(SCH_1):PWRGD_PVDDQ_DEF_R
   2 PWRGD_PVDDQ_DEF      B @BASEBOARD_FAB2_LIB.BASEBOARD_FAB2(SCH_1):PWRGD_PVDDQ_DEF

RES_0402-33.2,1%,1/16W,CHIP,G2A  I12  R7B1
   1 IRQ_PVDDQ_DEF_VRHOT_LVT3_R_N      A @BASEBOARD_FAB2_LIB.BASEBOARD_FAB2(SCH_1):IRQ_PVDDQ_DEF_VRHOT_LVT3_R_N
   2 IRQ_PVDDQ_DEF_VRHOT_LVT3_N      B @BASEBOARD_FAB2_LIB.BASEBOARD_FAB2(SCH_1):IRQ_PVDDQ_DEF_VRHOT_LVT3_N

RES_0402-2.26K,1.0%,1/16W,EMPTA  I14  R7A9
   1 P3V3_STBY      A @BASEBOARD_FAB2_LIB.BASEBOARD_FAB2(SCH_1):P3V3_STBY
   2 PU_VR_PVDDQ_DEF_FAULT1      B @BASEBOARD_FAB2_LIB.BASEBOARD_FAB2(SCH_1):PU_VR_PVDDQ_DEF_FAULT1

RES_0402-0.0,5%,1/16W,CHIP,G21A  I15  R7A11
   1 SVID_ALERT_PVDDQ_DEF      A @BASEBOARD_FAB2_LIB.BASEBOARD_FAB2(SCH_1):SVID_ALERT_PVDDQ_DEF
   2 SVID_ALERT1_CPU0_R_N      B @BASEBOARD_FAB2_LIB.BASEBOARD_FAB2(SCH_1):SVID_ALERT1_CPU0_R_N

RES_0402-1.00K,1%,1/16W,CHIP,GA  I16  R7B5
   1 P3V3_STBY      A @BASEBOARD_FAB2_LIB.BASEBOARD_FAB2(SCH_1):P3V3_STBY
   2 PWRGD_PVDDQ_DEF_R      B @BASEBOARD_FAB2_LIB.BASEBOARD_FAB2(SCH_1):PWRGD_PVDDQ_DEF_R

RES_0402-1.00K,1%,1/16W,CHIP,GA  I17  R7B4
   1 P3V3_STBY      A @BASEBOARD_FAB2_LIB.BASEBOARD_FAB2(SCH_1):P3V3_STBY
   2 IRQ_PVDDQ_DEF_VRHOT_LVT3_R_N      B @BASEBOARD_FAB2_LIB.BASEBOARD_FAB2(SCH_1):IRQ_PVDDQ_DEF_VRHOT_LVT3_R_N

RES_0402-20.0,1%,1/16W,CHIP,G2A  I21  R7B3
   1 SMB_VR_SCL_VDDQ_DEF      A @BASEBOARD_FAB2_LIB.BASEBOARD_FAB2(SCH_1):SMB_VR_SCL_VDDQ_DEF
   2 SMB_VR_STBY_LVC3_SCL      B @BASEBOARD_FAB2_LIB.BASEBOARD_FAB2(SCH_1):SMB_VR_STBY_LVC3_SCL

CAP_A_0402V-1.0UF,6.3V,10%,X6SA  I22  C7B1
   1 VR_PVDDQ_DEF_VD12      A @BASEBOARD_FAB2_LIB.BASEBOARD_FAB2(SCH_1):VR_PVDDQ_DEF_VD12
   2    GND      B @BASEBOARD_FAB2_LIB.BASEBOARD_FAB2(SCH_1):GND

CAP_A_0402V-0.1UF,16V,10%,X7R,A  I23  C7B2
   1 VR_PVDDQ_DEF_VD12      A @BASEBOARD_FAB2_LIB.BASEBOARD_FAB2(SCH_1):VR_PVDDQ_DEF_VD12
   2    GND      B @BASEBOARD_FAB2_LIB.BASEBOARD_FAB2(SCH_1):GND

RES_0402-20.0,1%,1/16W,CHIP,G2A  I24  R7B2
   1 SMB_VR_SDA_VDDQ_DEF      A @BASEBOARD_FAB2_LIB.BASEBOARD_FAB2(SCH_1):SMB_VR_SDA_VDDQ_DEF
   2 SMB_VR_STBY_LVC3_SDA      B @BASEBOARD_FAB2_LIB.BASEBOARD_FAB2(SCH_1):SMB_VR_STBY_LVC3_SDA

RES_0402-0.0,5%,1/16W,CHIP,G21A  I25  R7A12
   1 SVID_VDIO_PVDDQ_DEF      A @BASEBOARD_FAB2_LIB.BASEBOARD_FAB2(SCH_1):SVID_VDIO_PVDDQ_DEF
   2 SVID_DIO1_CPU0_R      B @BASEBOARD_FAB2_LIB.BASEBOARD_FAB2(SCH_1):SVID_DIO1_CPU0_R

CAP_0402LF-1000PF,50V,10%,X7R,A  I26  C7B3
   1 PWRGD_PVDDQ_DEF_R      A @BASEBOARD_FAB2_LIB.BASEBOARD_FAB2(SCH_1):PWRGD_PVDDQ_DEF_R
   2    GND      B @BASEBOARD_FAB2_LIB.BASEBOARD_FAB2(SCH_1):GND

CAP_A_0402V-1.0UF,6.3V,10%,X6SA  I29  C7A37
   1 VR_PVDDQ_DEF_VDD      A @BASEBOARD_FAB2_LIB.BASEBOARD_FAB2(SCH_1):VR_PVDDQ_DEF_VDD
   2    GND      B @BASEBOARD_FAB2_LIB.BASEBOARD_FAB2(SCH_1):GND

CAP_A_0402V-0.1UF,16V,10%,X7R,A  I31  C7A38
   1 VR_PVDDQ_DEF_VDD      A @BASEBOARD_FAB2_LIB.BASEBOARD_FAB2(SCH_1):VR_PVDDQ_DEF_VDD
   2    GND      B @BASEBOARD_FAB2_LIB.BASEBOARD_FAB2(SCH_1):GND

RES_0402-0.0,5%,1/16W,CHIP,G21A  I34  R3M1
   1 P3V3_STBY      A @BASEBOARD_FAB2_LIB.BASEBOARD_FAB2(SCH_1):P3V3_STBY
   2 VR_PVDDQ_DEF_VDD      B @BASEBOARD_FAB2_LIB.BASEBOARD_FAB2(SCH_1):VR_PVDDQ_DEF_VDD

RES_0402-100.0K,1%,1/16W,EMPTYA  I35  R3M5
   1 P3V3_STBY      A @BASEBOARD_FAB2_LIB.BASEBOARD_FAB2(SCH_1):P3V3_STBY
   2 VR_PVDDQ_DEF_VREN      B @BASEBOARD_FAB2_LIB.BASEBOARD_FAB2(SCH_1):VR_PVDDQ_DEF_VREN

RES_0402-8.06K,1%,1/16W,CHIP,GA  I37  R7A8
   1 VR_PVDDQ_DEF_XADDR2      A @BASEBOARD_FAB2_LIB.BASEBOARD_FAB2(SCH_1):VR_PVDDQ_DEF_XADDR2
   2    GND      B @BASEBOARD_FAB2_LIB.BASEBOARD_FAB2(SCH_1):GND

CAP_0402LF-220PF,50V,10%,X7R,AA  I39  C7A29
   1 A_TSENSE_PVDDQ_DEF      A @BASEBOARD_FAB2_LIB.BASEBOARD_FAB2(SCH_1):A_TSENSE_PVDDQ_DEF
   2    GND      B @BASEBOARD_FAB2_LIB.BASEBOARD_FAB2(SCH_1):GND

RES_0402-3.16K,1%,1/16W,CHIP,GA  I40  R7A10
   1 VR_PVDDQ_DEF_XADDR1      A @BASEBOARD_FAB2_LIB.BASEBOARD_FAB2(SCH_1):VR_PVDDQ_DEF_XADDR1
   2    GND      B @BASEBOARD_FAB2_LIB.BASEBOARD_FAB2(SCH_1):GND

RES_0402-49.9,1%,1/16W,CHIP,G2A  I47  R3L13
   1 PVCCIO_CPU0      A @BASEBOARD_FAB2_LIB.BASEBOARD_FAB2(SCH_1):PVCCIO_CPU0
   2 SVID_CLK1_CPU0_R      B @BASEBOARD_FAB2_LIB.BASEBOARD_FAB2(SCH_1):SVID_CLK1_CPU0_R

RES_0402-150.0,1%,1/16W,CHIP,GA  I48  R7A17
   1 SVID_CLK1_CPU0_R      A @BASEBOARD_FAB2_LIB.BASEBOARD_FAB2(SCH_1):SVID_CLK1_CPU0_R
   2 SVID_CLK_PVDDQ_DEF      B @BASEBOARD_FAB2_LIB.BASEBOARD_FAB2(SCH_1):SVID_CLK_PVDDQ_DEF

RES_0402-0.0,5%,1/16W,CHIP,G21A  I50  R3L10
   1 VR_PVDDQ_DEF_VD12      A @BASEBOARD_FAB2_LIB.BASEBOARD_FAB2(SCH_1):VR_PVDDQ_DEF_VD12
   2 VR_PVDDQ_DEF_AIREF2      B @BASEBOARD_FAB2_LIB.BASEBOARD_FAB2(SCH_1):VR_PVDDQ_DEF_AIREF2

RES_0402-100.0K,1%,1/16W,CHIP,B  I53  R3L12
   1 VR_FET_SW_P12V_STBY_PVDDQ_DEF      A @BASEBOARD_FAB2_LIB.BASEBOARD_FAB2(SCH_1):VR_FET_SW_P12V_STBY_PVDDQ_DEF
   2 VR_PVDDQ_DEF_VINSEN      B @BASEBOARD_FAB2_LIB.BASEBOARD_FAB2(SCH_1):VR_PVDDQ_DEF_VINSEN

RES_0402-1.5K,1%,1/16W,CHIP,G2A  I54  R7A16
   1 VR_PVDDQ_DEF_VINSEN      A @BASEBOARD_FAB2_LIB.BASEBOARD_FAB2(SCH_1):VR_PVDDQ_DEF_VINSEN
   2    GND      B @BASEBOARD_FAB2_LIB.BASEBOARD_FAB2(SCH_1):GND

CAP_0402LF-1000PF,50V,10%,X7R,A  I55  C7A35
   1 VR_PVDDQ_DEF_VINSEN      A @BASEBOARD_FAB2_LIB.BASEBOARD_FAB2(SCH_1):VR_PVDDQ_DEF_VINSEN
   2    GND      B @BASEBOARD_FAB2_LIB.BASEBOARD_FAB2(SCH_1):GND

RES_0402-0.0,5%,1/16W,CHIP,G21A  I57  R3L9
   1 VR_PVDDQ_DEF_VD12      A @BASEBOARD_FAB2_LIB.BASEBOARD_FAB2(SCH_1):VR_PVDDQ_DEF_VD12
   2 VR_PVDDQ_DEF_AIREF1      B @BASEBOARD_FAB2_LIB.BASEBOARD_FAB2(SCH_1):VR_PVDDQ_DEF_AIREF1

RES_0402-0.0,5%,1/16W,CHIP,G21A  I59  R3M6
   1 FM_PVDDQ_DEF_EN      A @BASEBOARD_FAB2_LIB.BASEBOARD_FAB2(SCH_1):FM_PVDDQ_DEF_EN
   2 VR_PVDDQ_DEF_VREN      B @BASEBOARD_FAB2_LIB.BASEBOARD_FAB2(SCH_1):VR_PVDDQ_DEF_VREN

RES_0402-10.0,1%,1/16W,CHIP,G2A  I60  R7A7
   1 VSENSE_PVDDQ_DEF_P      A @BASEBOARD_FAB2_LIB.BASEBOARD_FAB2(SCH_1):VSENSE_PVDDQ_DEF_P
   2 VR_PVDDQ_DEF_AVSP      B @BASEBOARD_FAB2_LIB.BASEBOARD_FAB2(SCH_1):VR_PVDDQ_DEF_AVSP

CAP_0402LF-220PF,50V,10%,X7R,AA  I61  C7A28
   1 VR_PVDDQ_DEF_AVSP      A @BASEBOARD_FAB2_LIB.BASEBOARD_FAB2(SCH_1):VR_PVDDQ_DEF_AVSP
   2 VSENSE_PVDDQ_DEF_N      B @BASEBOARD_FAB2_LIB.BASEBOARD_FAB2(SCH_1):VSENSE_PVDDQ_DEF_N

PXM1310B_QFN-IC,H89186-001  I75  EU7A5
   1 TP_PVDDQ_DEF_BPWM1  BPWM1 @BASEBOARD_FAB2_LIB.BASEBOARD_FAB2(SCH_1):TP_PVDDQ_DEF_BPWM1
   2 NC_PVDDQ_DEF_DNC0 DNC<0> @BASEBOARD_FAB2_LIB.BASEBOARD_FAB2(SCH_1):NC_PVDDQ_DEF_DNC0
   3 TP_PVDDQ_DEF_PWM3  APWM3 @BASEBOARD_FAB2_LIB.BASEBOARD_FAB2(SCH_1):TP_PVDDQ_DEF_PWM3
   4 VR_PVDDQ_DEF_PWM2  APWM2 @BASEBOARD_FAB2_LIB.BASEBOARD_FAB2(SCH_1):VR_PVDDQ_DEF_PWM2
   5 VR_PVDDQ_DEF_PWM1  APWM1 @BASEBOARD_FAB2_LIB.BASEBOARD_FAB2(SCH_1):VR_PVDDQ_DEF_PWM1
   6 SMB_VR_SDA_VDDQ_DEF    SDA @BASEBOARD_FAB2_LIB.BASEBOARD_FAB2(SCH_1):SMB_VR_SDA_VDDQ_DEF
   7 SMB_VR_SCL_VDDQ_DEF    SCL @BASEBOARD_FAB2_LIB.BASEBOARD_FAB2(SCH_1):SMB_VR_SCL_VDDQ_DEF
   8 TP_PVDDQ_DEF_RESET_N RESET_N @BASEBOARD_FAB2_LIB.BASEBOARD_FAB2(SCH_1):TP_PVDDQ_DEF_RESET_N
   9 PWRGD_PVDDQ_DEF_R AVRRDY @BASEBOARD_FAB2_LIB.BASEBOARD_FAB2(SCH_1):PWRGD_PVDDQ_DEF_R
  10 VR_PVDDQ_DEF_VREN  AVREN @BASEBOARD_FAB2_LIB.BASEBOARD_FAB2(SCH_1):VR_PVDDQ_DEF_VREN
  11 IRQ_PVDDQ_DEF_VRHOT_LVT3_R_N VRHOT_N @BASEBOARD_FAB2_LIB.BASEBOARD_FAB2(SCH_1):IRQ_PVDDQ_DEF_VRHOT_LVT3_R_N
  12 TP_PVDDQ_DEF_PINALRT_N PINALRT_N @BASEBOARD_FAB2_LIB.BASEBOARD_FAB2(SCH_1):TP_PVDDQ_DEF_PINALRT_N
  13 PU_VR_PVDDQ_DEF_FAULT1    MP0 @BASEBOARD_FAB2_LIB.BASEBOARD_FAB2(SCH_1):PU_VR_PVDDQ_DEF_FAULT1
  14 TP_PVDDQ_DEF_MP1    MP1 @BASEBOARD_FAB2_LIB.BASEBOARD_FAB2(SCH_1):TP_PVDDQ_DEF_MP1
  15 SVID_CLK_PVDDQ_DEF   VCLK @BASEBOARD_FAB2_LIB.BASEBOARD_FAB2(SCH_1):SVID_CLK_PVDDQ_DEF
  16 SVID_VDIO_PVDDQ_DEF   VDIO @BASEBOARD_FAB2_LIB.BASEBOARD_FAB2(SCH_1):SVID_VDIO_PVDDQ_DEF
  17 SVID_ALERT_PVDDQ_DEF VALRT_N @BASEBOARD_FAB2_LIB.BASEBOARD_FAB2(SCH_1):SVID_ALERT_PVDDQ_DEF
  18 TP_PVDDQ_DEF_MP2    MP2 @BASEBOARD_FAB2_LIB.BASEBOARD_FAB2(SCH_1):TP_PVDDQ_DEF_MP2
  19 VR_PVDDQ_DEF_AVSP  AVSEN @BASEBOARD_FAB2_LIB.BASEBOARD_FAB2(SCH_1):VR_PVDDQ_DEF_AVSP
  20 VSENSE_PVDDQ_DEF_N  AVREF @BASEBOARD_FAB2_LIB.BASEBOARD_FAB2(SCH_1):VSENSE_PVDDQ_DEF_N
  21 VR_PVDDQ_DEF_AIREF1 AIREF1 @BASEBOARD_FAB2_LIB.BASEBOARD_FAB2(SCH_1):VR_PVDDQ_DEF_AIREF1
  22 ISENSE_PVDDQ_DEF_PH1_IMON AISEN1 @BASEBOARD_FAB2_LIB.BASEBOARD_FAB2(SCH_1):ISENSE_PVDDQ_DEF_PH1_IMON
  23 VR_PVDDQ_DEF_AIREF2 AIREF2 @BASEBOARD_FAB2_LIB.BASEBOARD_FAB2(SCH_1):VR_PVDDQ_DEF_AIREF2
  24 ISENSE_PVDDQ_DEF_PH2_IMON AISEN2 @BASEBOARD_FAB2_LIB.BASEBOARD_FAB2(SCH_1):ISENSE_PVDDQ_DEF_PH2_IMON
  25 TP_PVDDQ_DEF_PH3_IMON_REF AIREF3 @BASEBOARD_FAB2_LIB.BASEBOARD_FAB2(SCH_1):TP_PVDDQ_DEF_PH3_IMON_REF
  26 TP_PVDDQ_DEF_PH3_IMON AISEN3 @BASEBOARD_FAB2_LIB.BASEBOARD_FAB2(SCH_1):TP_PVDDQ_DEF_PH3_IMON
  27    GND    GND @BASEBOARD_FAB2_LIB.BASEBOARD_FAB2(SCH_1):GND
  28 NC_PVDDQ_DEF_DNC1 DNC<1> @BASEBOARD_FAB2_LIB.BASEBOARD_FAB2(SCH_1):NC_PVDDQ_DEF_DNC1
  29 TP_PVDDQ_DEF_BVSEN  BVSEN @BASEBOARD_FAB2_LIB.BASEBOARD_FAB2(SCH_1):TP_PVDDQ_DEF_BVSEN
  30 TP_PVDDQ_DEF_BVREF  BVREF @BASEBOARD_FAB2_LIB.BASEBOARD_FAB2(SCH_1):TP_PVDDQ_DEF_BVREF
  31 TP_PVDDQ_DEF_BREF1 BIREF1 @BASEBOARD_FAB2_LIB.BASEBOARD_FAB2(SCH_1):TP_PVDDQ_DEF_BREF1
  32    GND BISEN1 @BASEBOARD_FAB2_LIB.BASEBOARD_FAB2(SCH_1):GND
  33 VR_PVDDQ_DEF_XADDR2 XADDR2 @BASEBOARD_FAB2_LIB.BASEBOARD_FAB2(SCH_1):VR_PVDDQ_DEF_XADDR2
  34 TP_PVDDQ_DEF_BTSEN  BTSEN @BASEBOARD_FAB2_LIB.BASEBOARD_FAB2(SCH_1):TP_PVDDQ_DEF_BTSEN
  35 A_TSENSE_PVDDQ_DEF  ATSEN @BASEBOARD_FAB2_LIB.BASEBOARD_FAB2(SCH_1):A_TSENSE_PVDDQ_DEF
  36 VR_PVDDQ_DEF_XADDR1 XADDR1 @BASEBOARD_FAB2_LIB.BASEBOARD_FAB2(SCH_1):VR_PVDDQ_DEF_XADDR1
  37 VR_PVDDQ_DEF_VINSEN VINSEN @BASEBOARD_FAB2_LIB.BASEBOARD_FAB2(SCH_1):VR_PVDDQ_DEF_VINSEN
  38 VR_PVDDQ_DEF_AIINSEN IINSEN @BASEBOARD_FAB2_LIB.BASEBOARD_FAB2(SCH_1):VR_PVDDQ_DEF_AIINSEN
  39 VR_PVDDQ_DEF_VDD    VDD @BASEBOARD_FAB2_LIB.BASEBOARD_FAB2(SCH_1):VR_PVDDQ_DEF_VDD
  40 VR_PVDDQ_DEF_VD12   VD12 @BASEBOARD_FAB2_LIB.BASEBOARD_FAB2(SCH_1):VR_PVDDQ_DEF_VD12
  41    GND  THPAD @BASEBOARD_FAB2_LIB.BASEBOARD_FAB2(SCH_1):GND

CAP_A_0402V-0.1UF,16V,10%,X7R,A  I77  C3L31
   1 VR_PVDDQ_DEF_AIINSEN      A @BASEBOARD_FAB2_LIB.BASEBOARD_FAB2(SCH_1):VR_PVDDQ_DEF_AIINSEN
   2    GND      B @BASEBOARD_FAB2_LIB.BASEBOARD_FAB2(SCH_1):GND


DRAWING: @BASEBOARD_FAB2_LIB.BASEBOARD_FAB2(SCH_1):PAGE220 

RES_0603-120.0,1%,1/10W,CHIP,GA  I58  R4L4
   1 PVDDQ_DEF      A @BASEBOARD_FAB2_LIB.BASEBOARD_FAB2(SCH_1):PVDDQ_DEF
   2    GND      B @BASEBOARD_FAB2_LIB.BASEBOARD_FAB2(SCH_1):GND

RES_0402-100.0,1%,1/16W,EMPTY,A  I74  R4L2
   1 VSENSE_PVDDQ_DEF_P      A @BASEBOARD_FAB2_LIB.BASEBOARD_FAB2(SCH_1):VSENSE_PVDDQ_DEF_P
   2 VSENSE_PVDDQ_DEF_N      B @BASEBOARD_FAB2_LIB.BASEBOARD_FAB2(SCH_1):VSENSE_PVDDQ_DEF_N

CAPP_3018-470UF,2.5V,20%,ALUM,A  I75  C3L6
   1 PVDDQ_DEF      A @BASEBOARD_FAB2_LIB.BASEBOARD_FAB2(SCH_1):PVDDQ_DEF
   2    GND      B @BASEBOARD_FAB2_LIB.BASEBOARD_FAB2(SCH_1):GND

CAPP_3018-470UF,2.5V,20%,ALUM,A  I76  C3L14
   1 PVDDQ_DEF      A @BASEBOARD_FAB2_LIB.BASEBOARD_FAB2(SCH_1):PVDDQ_DEF
   2    GND      B @BASEBOARD_FAB2_LIB.BASEBOARD_FAB2(SCH_1):GND

CAPP_3018-470UF,2.5V,20%,ALUM,A  I77  C6A5
   1 PVDDQ_DEF      A @BASEBOARD_FAB2_LIB.BASEBOARD_FAB2(SCH_1):PVDDQ_DEF
   2    GND      B @BASEBOARD_FAB2_LIB.BASEBOARD_FAB2(SCH_1):GND

CAPP_3018-470UF,2.5V,20%,ALUM,A  I78  C4L5
   1 PVDDQ_DEF      A @BASEBOARD_FAB2_LIB.BASEBOARD_FAB2(SCH_1):PVDDQ_DEF
   2    GND      B @BASEBOARD_FAB2_LIB.BASEBOARD_FAB2(SCH_1):GND

CAP_0805-100UF,4V,20%,X5R,6024A  I82  C5M8
   1 PVDDQ_DEF      A @BASEBOARD_FAB2_LIB.BASEBOARD_FAB2(SCH_1):PVDDQ_DEF
   2    GND      B @BASEBOARD_FAB2_LIB.BASEBOARD_FAB2(SCH_1):GND

CAP_0805-100UF,4V,20%,X5R,6024A  I83  C5L14
   1 PVDDQ_DEF      A @BASEBOARD_FAB2_LIB.BASEBOARD_FAB2(SCH_1):PVDDQ_DEF
   2    GND      B @BASEBOARD_FAB2_LIB.BASEBOARD_FAB2(SCH_1):GND

CAP_0805-100UF,4V,20%,X5R,6024A  I88  C5M12
   1 PVDDQ_DEF      A @BASEBOARD_FAB2_LIB.BASEBOARD_FAB2(SCH_1):PVDDQ_DEF
   2    GND      B @BASEBOARD_FAB2_LIB.BASEBOARD_FAB2(SCH_1):GND

CAP_0805-100UF,4V,20%,X5R,6024A  I89  C5L3
   1 PVDDQ_DEF      A @BASEBOARD_FAB2_LIB.BASEBOARD_FAB2(SCH_1):PVDDQ_DEF
   2    GND      B @BASEBOARD_FAB2_LIB.BASEBOARD_FAB2(SCH_1):GND

CAP_0805-100UF,4V,20%,X5R,6024A  I90  C5L2
   1 PVDDQ_DEF      A @BASEBOARD_FAB2_LIB.BASEBOARD_FAB2(SCH_1):PVDDQ_DEF
   2    GND      B @BASEBOARD_FAB2_LIB.BASEBOARD_FAB2(SCH_1):GND

CAP_0805-100UF,4V,20%,X5R,6024A  I91  C5L1
   1 PVDDQ_DEF      A @BASEBOARD_FAB2_LIB.BASEBOARD_FAB2(SCH_1):PVDDQ_DEF
   2    GND      B @BASEBOARD_FAB2_LIB.BASEBOARD_FAB2(SCH_1):GND

CAP_0805-100UF,4V,20%,X5R,6024A  I92  C5A20
   1 PVDDQ_DEF      A @BASEBOARD_FAB2_LIB.BASEBOARD_FAB2(SCH_1):PVDDQ_DEF
   2    GND      B @BASEBOARD_FAB2_LIB.BASEBOARD_FAB2(SCH_1):GND

CAP_0805-100UF,4V,20%,X5R,6024A  I110  C5A10
   1 PVDDQ_DEF      A @BASEBOARD_FAB2_LIB.BASEBOARD_FAB2(SCH_1):PVDDQ_DEF
   2    GND      B @BASEBOARD_FAB2_LIB.BASEBOARD_FAB2(SCH_1):GND

INDUCTOR_SM-100NH,IND,D92183-0B  I124  L7A5
   1 P12V_STBY    INA @BASEBOARD_FAB2_LIB.BASEBOARD_FAB2(SCH_1):P12V_STBY
   2 VR_FET_SW_P12V_STBY_PVDDQ_DEF    INB @BASEBOARD_FAB2_LIB.BASEBOARD_FAB2(SCH_1):VR_FET_SW_P12V_STBY_PVDDQ_DEF

CAPP_2626-270UF,16V,20%,OSCON,A  I175  C7A19
   1 VR_FET_SW_P12V_STBY_PVDDQ_DEF      A @BASEBOARD_FAB2_LIB.BASEBOARD_FAB2(SCH_1):VR_FET_SW_P12V_STBY_PVDDQ_DEF
   2    GND      B @BASEBOARD_FAB2_LIB.BASEBOARD_FAB2(SCH_1):GND

CAP_0805LF-22UF,4V,20%,X6S,C95A  I177  C5P2
   1 PVDDQ_DEF      A @BASEBOARD_FAB2_LIB.BASEBOARD_FAB2(SCH_1):PVDDQ_DEF
   2    GND      B @BASEBOARD_FAB2_LIB.BASEBOARD_FAB2(SCH_1):GND

CAP_0805LF-22UF,4V,20%,X6S,C95A  I179  C5P1
   1 PVDDQ_DEF      A @BASEBOARD_FAB2_LIB.BASEBOARD_FAB2(SCH_1):PVDDQ_DEF
   2    GND      B @BASEBOARD_FAB2_LIB.BASEBOARD_FAB2(SCH_1):GND

CAP_0603LF-10UF,4V,20%,X6S,E15A  I180  C5D9
   1 PVDDQ_DEF      A @BASEBOARD_FAB2_LIB.BASEBOARD_FAB2(SCH_1):PVDDQ_DEF
   2    GND      B @BASEBOARD_FAB2_LIB.BASEBOARD_FAB2(SCH_1):GND

CAP_0603LF-10UF,4V,20%,X6S,E15A  I182  C5D6
   1 PVDDQ_DEF      A @BASEBOARD_FAB2_LIB.BASEBOARD_FAB2(SCH_1):PVDDQ_DEF
   2    GND      B @BASEBOARD_FAB2_LIB.BASEBOARD_FAB2(SCH_1):GND

CAP_0603LF-10UF,4V,20%,X6S,E15A  I183  C5D7
   1 PVDDQ_DEF      A @BASEBOARD_FAB2_LIB.BASEBOARD_FAB2(SCH_1):PVDDQ_DEF
   2    GND      B @BASEBOARD_FAB2_LIB.BASEBOARD_FAB2(SCH_1):GND

CAP_0603LF-10UF,4V,20%,X6S,E15A  I184  C5D8
   1 PVDDQ_DEF      A @BASEBOARD_FAB2_LIB.BASEBOARD_FAB2(SCH_1):PVDDQ_DEF
   2    GND      B @BASEBOARD_FAB2_LIB.BASEBOARD_FAB2(SCH_1):GND

CAP_A_0603V-47UF,4V,20%,X5R,60A  I192  C5L15
   1 PVDDQ_DEF      A @BASEBOARD_FAB2_LIB.BASEBOARD_FAB2(SCH_1):PVDDQ_DEF
   2    GND      B @BASEBOARD_FAB2_LIB.BASEBOARD_FAB2(SCH_1):GND

CAP_A_0603V-47UF,4V,20%,X5R,60A  I193  C5A5
   1 PVDDQ_DEF      A @BASEBOARD_FAB2_LIB.BASEBOARD_FAB2(SCH_1):PVDDQ_DEF
   2    GND      B @BASEBOARD_FAB2_LIB.BASEBOARD_FAB2(SCH_1):GND

CAP_A_0603V-47UF,4V,20%,X5R,60A  I194  C5B1
   1 PVDDQ_DEF      A @BASEBOARD_FAB2_LIB.BASEBOARD_FAB2(SCH_1):PVDDQ_DEF
   2    GND      B @BASEBOARD_FAB2_LIB.BASEBOARD_FAB2(SCH_1):GND

CAP_A_0603V-47UF,4V,20%,X5R,60A  I195  C5M9
   1 PVDDQ_DEF      A @BASEBOARD_FAB2_LIB.BASEBOARD_FAB2(SCH_1):PVDDQ_DEF
   2    GND      B @BASEBOARD_FAB2_LIB.BASEBOARD_FAB2(SCH_1):GND

CAP_A_0603V-47UF,4V,20%,X5R,60A  I196  C4M5
   1 PVDDQ_DEF      A @BASEBOARD_FAB2_LIB.BASEBOARD_FAB2(SCH_1):PVDDQ_DEF
   2    GND      B @BASEBOARD_FAB2_LIB.BASEBOARD_FAB2(SCH_1):GND

CAP_A_0603V-47UF,4V,20%,X5R,60A  I197  C5B2
   1 PVDDQ_DEF      A @BASEBOARD_FAB2_LIB.BASEBOARD_FAB2(SCH_1):PVDDQ_DEF
   2    GND      B @BASEBOARD_FAB2_LIB.BASEBOARD_FAB2(SCH_1):GND

CAP_A_0603V-47UF,4V,20%,X5R,60A  I198  C5M10
   1 PVDDQ_DEF      A @BASEBOARD_FAB2_LIB.BASEBOARD_FAB2(SCH_1):PVDDQ_DEF
   2    GND      B @BASEBOARD_FAB2_LIB.BASEBOARD_FAB2(SCH_1):GND

CAP_A_0603V-47UF,4V,20%,X5R,60A  I199  C5M3
   1 PVDDQ_DEF      A @BASEBOARD_FAB2_LIB.BASEBOARD_FAB2(SCH_1):PVDDQ_DEF
   2    GND      B @BASEBOARD_FAB2_LIB.BASEBOARD_FAB2(SCH_1):GND

CAP_A_0603V-47UF,4V,20%,X5R,60A  I200  C5M11
   1 PVDDQ_DEF      A @BASEBOARD_FAB2_LIB.BASEBOARD_FAB2(SCH_1):PVDDQ_DEF
   2    GND      B @BASEBOARD_FAB2_LIB.BASEBOARD_FAB2(SCH_1):GND

CAP_A_0603V-22.0UF,4V,20%,X6S,A  I203  C5A19
   1 PVDDQ_DEF      A @BASEBOARD_FAB2_LIB.BASEBOARD_FAB2(SCH_1):PVDDQ_DEF
   2    GND      B @BASEBOARD_FAB2_LIB.BASEBOARD_FAB2(SCH_1):GND

CAP_A_0603V-22.0UF,4V,20%,X6S,A  I204  C5A18
   1 PVDDQ_DEF      A @BASEBOARD_FAB2_LIB.BASEBOARD_FAB2(SCH_1):PVDDQ_DEF
   2    GND      B @BASEBOARD_FAB2_LIB.BASEBOARD_FAB2(SCH_1):GND

CAP_A_0603V-22.0UF,4V,20%,X6S,A  I205  C5A17
   1 PVDDQ_DEF      A @BASEBOARD_FAB2_LIB.BASEBOARD_FAB2(SCH_1):PVDDQ_DEF
   2    GND      B @BASEBOARD_FAB2_LIB.BASEBOARD_FAB2(SCH_1):GND

CAP_A_0603V-22.0UF,4V,20%,X6S,A  I206  C5A4
   1 PVDDQ_DEF      A @BASEBOARD_FAB2_LIB.BASEBOARD_FAB2(SCH_1):PVDDQ_DEF
   2    GND      B @BASEBOARD_FAB2_LIB.BASEBOARD_FAB2(SCH_1):GND

CAP_A_0603V-22.0UF,4V,20%,X6S,A  I207  C5A16
   1 PVDDQ_DEF      A @BASEBOARD_FAB2_LIB.BASEBOARD_FAB2(SCH_1):PVDDQ_DEF
   2    GND      B @BASEBOARD_FAB2_LIB.BASEBOARD_FAB2(SCH_1):GND

CAP_A_0603V-22.0UF,4V,20%,X6S,A  I208  C5A9
   1 PVDDQ_DEF      A @BASEBOARD_FAB2_LIB.BASEBOARD_FAB2(SCH_1):PVDDQ_DEF
   2    GND      B @BASEBOARD_FAB2_LIB.BASEBOARD_FAB2(SCH_1):GND

CAP_A_0603V-22.0UF,4V,20%,X6S,A  I209  C5A8
   1 PVDDQ_DEF      A @BASEBOARD_FAB2_LIB.BASEBOARD_FAB2(SCH_1):PVDDQ_DEF
   2    GND      B @BASEBOARD_FAB2_LIB.BASEBOARD_FAB2(SCH_1):GND

CAP_A_0603V-22.0UF,4V,20%,X6S,A  I210  C5A3
   1 PVDDQ_DEF      A @BASEBOARD_FAB2_LIB.BASEBOARD_FAB2(SCH_1):PVDDQ_DEF
   2    GND      B @BASEBOARD_FAB2_LIB.BASEBOARD_FAB2(SCH_1):GND

CAP_A_0603V-22.0UF,4V,20%,X6S,A  I211  C5A7
   1 PVDDQ_DEF      A @BASEBOARD_FAB2_LIB.BASEBOARD_FAB2(SCH_1):PVDDQ_DEF
   2    GND      B @BASEBOARD_FAB2_LIB.BASEBOARD_FAB2(SCH_1):GND

CAP_A_0603V-22.0UF,4V,20%,X6S,A  I212  C5A6
   1 PVDDQ_DEF      A @BASEBOARD_FAB2_LIB.BASEBOARD_FAB2(SCH_1):PVDDQ_DEF
   2    GND      B @BASEBOARD_FAB2_LIB.BASEBOARD_FAB2(SCH_1):GND

CAP_A_0603V-22.0UF,4V,20%,X6S,A  I213  C5A14
   1 PVDDQ_DEF      A @BASEBOARD_FAB2_LIB.BASEBOARD_FAB2(SCH_1):PVDDQ_DEF
   2    GND      B @BASEBOARD_FAB2_LIB.BASEBOARD_FAB2(SCH_1):GND

CAP_A_0603V-22.0UF,4V,20%,X6S,A  I214  C5A2
   1 PVDDQ_DEF      A @BASEBOARD_FAB2_LIB.BASEBOARD_FAB2(SCH_1):PVDDQ_DEF
   2    GND      B @BASEBOARD_FAB2_LIB.BASEBOARD_FAB2(SCH_1):GND

CAP_A_0603V-22.0UF,4V,20%,X6S,A  I215  C5A13
   1 PVDDQ_DEF      A @BASEBOARD_FAB2_LIB.BASEBOARD_FAB2(SCH_1):PVDDQ_DEF
   2    GND      B @BASEBOARD_FAB2_LIB.BASEBOARD_FAB2(SCH_1):GND

CAP_A_0603V-22.0UF,4V,20%,X6S,A  I216  C5A12
   1 PVDDQ_DEF      A @BASEBOARD_FAB2_LIB.BASEBOARD_FAB2(SCH_1):PVDDQ_DEF
   2    GND      B @BASEBOARD_FAB2_LIB.BASEBOARD_FAB2(SCH_1):GND

CAP_A_0603V-22.0UF,4V,20%,X6S,A  I217  C5A15
   1 PVDDQ_DEF      A @BASEBOARD_FAB2_LIB.BASEBOARD_FAB2(SCH_1):PVDDQ_DEF
   2    GND      B @BASEBOARD_FAB2_LIB.BASEBOARD_FAB2(SCH_1):GND

CAP_A_0603V-22.0UF,4V,20%,X6S,A  I219  C5A1
   1 PVDDQ_DEF      A @BASEBOARD_FAB2_LIB.BASEBOARD_FAB2(SCH_1):PVDDQ_DEF
   2    GND      B @BASEBOARD_FAB2_LIB.BASEBOARD_FAB2(SCH_1):GND

CAP_A_0603V-22.0UF,4V,20%,X6S,A  I221  C5A11
   1 PVDDQ_DEF      A @BASEBOARD_FAB2_LIB.BASEBOARD_FAB2(SCH_1):PVDDQ_DEF
   2    GND      B @BASEBOARD_FAB2_LIB.BASEBOARD_FAB2(SCH_1):GND

CAP_A_0603V-22.0UF,4V,20%,X6S,A  I222  C4M2
   1 PVDDQ_DEF      A @BASEBOARD_FAB2_LIB.BASEBOARD_FAB2(SCH_1):PVDDQ_DEF
   2    GND      B @BASEBOARD_FAB2_LIB.BASEBOARD_FAB2(SCH_1):GND

CAP_A_0603V-22.0UF,4V,20%,X6S,A  I223  C5M1
   1 PVDDQ_DEF      A @BASEBOARD_FAB2_LIB.BASEBOARD_FAB2(SCH_1):PVDDQ_DEF
   2    GND      B @BASEBOARD_FAB2_LIB.BASEBOARD_FAB2(SCH_1):GND

CAP_A_0603V-22.0UF,4V,20%,X6S,A  I224  C5M2
   1 PVDDQ_DEF      A @BASEBOARD_FAB2_LIB.BASEBOARD_FAB2(SCH_1):PVDDQ_DEF
   2    GND      B @BASEBOARD_FAB2_LIB.BASEBOARD_FAB2(SCH_1):GND

CAP_A_0603V-22.0UF,4V,20%,X6S,A  I225  C5M4
   1 PVDDQ_DEF      A @BASEBOARD_FAB2_LIB.BASEBOARD_FAB2(SCH_1):PVDDQ_DEF
   2    GND      B @BASEBOARD_FAB2_LIB.BASEBOARD_FAB2(SCH_1):GND

CAP_A_0603V-22.0UF,4V,20%,X6S,A  I226  C5M5
   1 PVDDQ_DEF      A @BASEBOARD_FAB2_LIB.BASEBOARD_FAB2(SCH_1):PVDDQ_DEF
   2    GND      B @BASEBOARD_FAB2_LIB.BASEBOARD_FAB2(SCH_1):GND

CAP_A_0603V-22.0UF,4V,20%,X6S,A  I227  C5M6
   1 PVDDQ_DEF      A @BASEBOARD_FAB2_LIB.BASEBOARD_FAB2(SCH_1):PVDDQ_DEF
   2    GND      B @BASEBOARD_FAB2_LIB.BASEBOARD_FAB2(SCH_1):GND

CAP_A_0603V-22.0UF,4V,20%,X6S,A  I228  C5M7
   1 PVDDQ_DEF      A @BASEBOARD_FAB2_LIB.BASEBOARD_FAB2(SCH_1):PVDDQ_DEF
   2    GND      B @BASEBOARD_FAB2_LIB.BASEBOARD_FAB2(SCH_1):GND

CAP_A_0603V-22.0UF,4V,20%,X6S,A  I229  C5L13
   1 PVDDQ_DEF      A @BASEBOARD_FAB2_LIB.BASEBOARD_FAB2(SCH_1):PVDDQ_DEF
   2    GND      B @BASEBOARD_FAB2_LIB.BASEBOARD_FAB2(SCH_1):GND

CAP_A_0603V-22.0UF,4V,20%,X6S,A  I230  C5L12
   1 PVDDQ_DEF      A @BASEBOARD_FAB2_LIB.BASEBOARD_FAB2(SCH_1):PVDDQ_DEF
   2    GND      B @BASEBOARD_FAB2_LIB.BASEBOARD_FAB2(SCH_1):GND

CAP_A_0603V-22.0UF,4V,20%,X6S,A  I231  C5L11
   1 PVDDQ_DEF      A @BASEBOARD_FAB2_LIB.BASEBOARD_FAB2(SCH_1):PVDDQ_DEF
   2    GND      B @BASEBOARD_FAB2_LIB.BASEBOARD_FAB2(SCH_1):GND

CAP_A_0603V-22.0UF,4V,20%,X6S,A  I232  C5L10
   1 PVDDQ_DEF      A @BASEBOARD_FAB2_LIB.BASEBOARD_FAB2(SCH_1):PVDDQ_DEF
   2    GND      B @BASEBOARD_FAB2_LIB.BASEBOARD_FAB2(SCH_1):GND

CAP_A_0603V-22.0UF,4V,20%,X6S,A  I233  C5L9
   1 PVDDQ_DEF      A @BASEBOARD_FAB2_LIB.BASEBOARD_FAB2(SCH_1):PVDDQ_DEF
   2    GND      B @BASEBOARD_FAB2_LIB.BASEBOARD_FAB2(SCH_1):GND

CAP_A_0603V-22.0UF,4V,20%,X6S,A  I234  C5L8
   1 PVDDQ_DEF      A @BASEBOARD_FAB2_LIB.BASEBOARD_FAB2(SCH_1):PVDDQ_DEF
   2    GND      B @BASEBOARD_FAB2_LIB.BASEBOARD_FAB2(SCH_1):GND

CAP_A_0603V-22.0UF,4V,20%,X6S,A  I236  C5L7
   1 PVDDQ_DEF      A @BASEBOARD_FAB2_LIB.BASEBOARD_FAB2(SCH_1):PVDDQ_DEF
   2    GND      B @BASEBOARD_FAB2_LIB.BASEBOARD_FAB2(SCH_1):GND

CAP_A_0603V-22.0UF,4V,20%,X6S,A  I237  C5L6
   1 PVDDQ_DEF      A @BASEBOARD_FAB2_LIB.BASEBOARD_FAB2(SCH_1):PVDDQ_DEF
   2    GND      B @BASEBOARD_FAB2_LIB.BASEBOARD_FAB2(SCH_1):GND

SHUNT_SH0201-EMPTY,N_A  I239  SH4L2
   1 VSENSE_PVDDQ_DEF_P      A @BASEBOARD_FAB2_LIB.BASEBOARD_FAB2(SCH_1):VSENSE_PVDDQ_DEF_P
   2 PVDDQ_DEF      B @BASEBOARD_FAB2_LIB.BASEBOARD_FAB2(SCH_1):PVDDQ_DEF

SHUNT_SH0201-EMPTY,N_A  I240  SH4L1
   1 VSENSE_PVDDQ_DEF_N      A @BASEBOARD_FAB2_LIB.BASEBOARD_FAB2(SCH_1):VSENSE_PVDDQ_DEF_N
   2    GND      B @BASEBOARD_FAB2_LIB.BASEBOARD_FAB2(SCH_1):GND


DRAWING: @BASEBOARD_FAB2_LIB.BASEBOARD_FAB2(SCH_1):PAGE221 

MIC5166_DFN-IC,H55101-001  I1  EU4G3
   7 FM_PVTT_ABC_EN_R     EN @BASEBOARD_FAB2_LIB.BASEBOARD_FAB2(SCH_1):FM_PVTT_ABC_EN_R
  10 PVDDQ_ABC    VIN @BASEBOARD_FAB2_LIB.BASEBOARD_FAB2(SCH_1):PVDDQ_ABC
   1 VR_PVTT_ABC_VREF   VREF @BASEBOARD_FAB2_LIB.BASEBOARD_FAB2(SCH_1):VR_PVTT_ABC_VREF
   2 VR_PVTT_ABC_BIAS   BIAS @BASEBOARD_FAB2_LIB.BASEBOARD_FAB2(SCH_1):VR_PVTT_ABC_BIAS
   3    GND   AGND @BASEBOARD_FAB2_LIB.BASEBOARD_FAB2(SCH_1):GND
   5 PWRGD_PVTT_ABC_CPU0_R     PG @BASEBOARD_FAB2_LIB.BASEBOARD_FAB2(SCH_1):PWRGD_PVTT_ABC_CPU0_R
   4 VSENSE_PVDDQ_ABC_VTT   VDDQ @BASEBOARD_FAB2_LIB.BASEBOARD_FAB2(SCH_1):VSENSE_PVDDQ_ABC_VTT
   6 VR_PVTT_ABC_SNS    SNS @BASEBOARD_FAB2_LIB.BASEBOARD_FAB2(SCH_1):VR_PVTT_ABC_SNS
   8    GND   PGND @BASEBOARD_FAB2_LIB.BASEBOARD_FAB2(SCH_1):GND
   9 PVTT_ABC    VTT @BASEBOARD_FAB2_LIB.BASEBOARD_FAB2(SCH_1):PVTT_ABC
  11    GND  THPAD @BASEBOARD_FAB2_LIB.BASEBOARD_FAB2(SCH_1):GND

CAP_0402LF-1000PF,50V,10%,X7R,A  I15  C4G14
   1 PWRGD_PVTT_ABC_CPU0_R      A @BASEBOARD_FAB2_LIB.BASEBOARD_FAB2(SCH_1):PWRGD_PVTT_ABC_CPU0_R
   2    GND      B @BASEBOARD_FAB2_LIB.BASEBOARD_FAB2(SCH_1):GND

CAP_0805LF-22UF,4V,20%,X6S,C95A  I20  C4G24
   1 PVTT_ABC      A @BASEBOARD_FAB2_LIB.BASEBOARD_FAB2(SCH_1):PVTT_ABC
   2    GND      B @BASEBOARD_FAB2_LIB.BASEBOARD_FAB2(SCH_1):GND

CAP_0603LF-10UF,4V,20%,X6S,E15A  I22  C6U16
   1 PVDDQ_ABC      A @BASEBOARD_FAB2_LIB.BASEBOARD_FAB2(SCH_1):PVDDQ_ABC
   2    GND      B @BASEBOARD_FAB2_LIB.BASEBOARD_FAB2(SCH_1):GND

CAP_0402-1.0UF,16V,10%,X6S,D97A  I24  C4G15
   1 VR_PVTT_ABC_BIAS      A @BASEBOARD_FAB2_LIB.BASEBOARD_FAB2(SCH_1):VR_PVTT_ABC_BIAS
   2    GND      B @BASEBOARD_FAB2_LIB.BASEBOARD_FAB2(SCH_1):GND

CAP_0603LF-10UF,4V,20%,X6S,E15A  I26  C6U15
   1 PVDDQ_ABC      A @BASEBOARD_FAB2_LIB.BASEBOARD_FAB2(SCH_1):PVDDQ_ABC
   2    GND      B @BASEBOARD_FAB2_LIB.BASEBOARD_FAB2(SCH_1):GND

RES_0402-0.0,5%,1/16W,CHIP,G21A  I28  R6U4
   1   P3V3      A @BASEBOARD_FAB2_LIB.BASEBOARD_FAB2(SCH_1):P3V3
   2 VR_PVTT_ABC_BIAS      B @BASEBOARD_FAB2_LIB.BASEBOARD_FAB2(SCH_1):VR_PVTT_ABC_BIAS

RES_0402-0.0,5%,1/16W,CHIP,G21A  I32  R6U5
   1 PVDDQ_ABC      A @BASEBOARD_FAB2_LIB.BASEBOARD_FAB2(SCH_1):PVDDQ_ABC
   2 VSENSE_PVDDQ_ABC_VTT      B @BASEBOARD_FAB2_LIB.BASEBOARD_FAB2(SCH_1):VSENSE_PVDDQ_ABC_VTT

CAP_0402-1.0UF,16V,10%,X6S,D97A  I34  C4G16
   1 VR_PVTT_ABC_VREF      A @BASEBOARD_FAB2_LIB.BASEBOARD_FAB2(SCH_1):VR_PVTT_ABC_VREF
   2    GND      B @BASEBOARD_FAB2_LIB.BASEBOARD_FAB2(SCH_1):GND

RES_0402-1.0M,1%,1/16W,EMPTY,GA  I37  R6U15
   1   P3V3      A @BASEBOARD_FAB2_LIB.BASEBOARD_FAB2(SCH_1):P3V3
   2 FM_PVTT_ABC_EN_R      B @BASEBOARD_FAB2_LIB.BASEBOARD_FAB2(SCH_1):FM_PVTT_ABC_EN_R

RES_0402-0.0,5%,1/16W,CHIP,G21A  I38  R4G23
   1 PWRGD_PVDDQ_ABC      A @BASEBOARD_FAB2_LIB.BASEBOARD_FAB2(SCH_1):PWRGD_PVDDQ_ABC
   2 FM_PVTT_ABC_EN_R      B @BASEBOARD_FAB2_LIB.BASEBOARD_FAB2(SCH_1):FM_PVTT_ABC_EN_R

CAP_0402LF-1000PF,50V,10%,EMPTA  I39  C4G23
   1 FM_PVTT_ABC_EN_R      A @BASEBOARD_FAB2_LIB.BASEBOARD_FAB2(SCH_1):FM_PVTT_ABC_EN_R
   2    GND      B @BASEBOARD_FAB2_LIB.BASEBOARD_FAB2(SCH_1):GND

RES_0402-10.0K,1%,1/16W,CHIP,GA  I45  R4G18
   1   P3V3      A @BASEBOARD_FAB2_LIB.BASEBOARD_FAB2(SCH_1):P3V3
   2 PWRGD_PVTT_ABC_CPU0_R      B @BASEBOARD_FAB2_LIB.BASEBOARD_FAB2(SCH_1):PWRGD_PVTT_ABC_CPU0_R

CAP_0603-4.7UF,6.3V,10%,X6S,E1A  I49  C6U12
   1 VSENSE_PVDDQ_ABC_VTT      A @BASEBOARD_FAB2_LIB.BASEBOARD_FAB2(SCH_1):VSENSE_PVDDQ_ABC_VTT
   2    GND      B @BASEBOARD_FAB2_LIB.BASEBOARD_FAB2(SCH_1):GND

CAP_A_0603V-47UF,4V,20%,X5R,60A  I50  C5U12
   1 PVTT_ABC      A @BASEBOARD_FAB2_LIB.BASEBOARD_FAB2(SCH_1):PVTT_ABC
   2    GND      B @BASEBOARD_FAB2_LIB.BASEBOARD_FAB2(SCH_1):GND

CAP_A_0603V-47UF,4V,20%,X5R,60A  I51  C5T3
   1 PVTT_ABC      A @BASEBOARD_FAB2_LIB.BASEBOARD_FAB2(SCH_1):PVTT_ABC
   2    GND      B @BASEBOARD_FAB2_LIB.BASEBOARD_FAB2(SCH_1):GND

CAP_A_0603V-47UF,4V,20%,X5R,60A  I52  C5U16
   1 PVTT_ABC      A @BASEBOARD_FAB2_LIB.BASEBOARD_FAB2(SCH_1):PVTT_ABC
   2    GND      B @BASEBOARD_FAB2_LIB.BASEBOARD_FAB2(SCH_1):GND

RES_0402-33.2,1%,1/16W,CHIP,G2A  I54  R4G19
   1 PWRGD_PVTT_ABC_CPU0_R      A @BASEBOARD_FAB2_LIB.BASEBOARD_FAB2(SCH_1):PWRGD_PVTT_ABC_CPU0_R
   2 PWRGD_PVTT_CPU0      B @BASEBOARD_FAB2_LIB.BASEBOARD_FAB2(SCH_1):PWRGD_PVTT_CPU0

RES_0402-51.1,1.0%,1/16W,CHIP,A  I55  R6U16
   1    GND      A @BASEBOARD_FAB2_LIB.BASEBOARD_FAB2(SCH_1):GND
   2 PVTT_ABC      B @BASEBOARD_FAB2_LIB.BASEBOARD_FAB2(SCH_1):PVTT_ABC

SHUNT_SH0201-EMPTY,N_A  I56  SH5U1
   1 VR_PVTT_ABC_SNS      A @BASEBOARD_FAB2_LIB.BASEBOARD_FAB2(SCH_1):VR_PVTT_ABC_SNS
   2 PVTT_ABC      B @BASEBOARD_FAB2_LIB.BASEBOARD_FAB2(SCH_1):PVTT_ABC


DRAWING: @BASEBOARD_FAB2_LIB.BASEBOARD_FAB2(SCH_1):PAGE222 

CAP_0402LF-1000PF,50V,10%,X7R,A  I12  C4A12
   1 PWRGD_PVTT_DEF_CPU0_R      A @BASEBOARD_FAB2_LIB.BASEBOARD_FAB2(SCH_1):PWRGD_PVTT_DEF_CPU0_R
   2    GND      B @BASEBOARD_FAB2_LIB.BASEBOARD_FAB2(SCH_1):GND

CAP_0805LF-22UF,4V,20%,X6S,C95A  I16  C4A1
   1 PVTT_DEF      A @BASEBOARD_FAB2_LIB.BASEBOARD_FAB2(SCH_1):PVTT_DEF
   2    GND      B @BASEBOARD_FAB2_LIB.BASEBOARD_FAB2(SCH_1):GND

RES_0402-10.0K,1%,1/16W,CHIP,GA  I19  R6L9
   1   P3V3      A @BASEBOARD_FAB2_LIB.BASEBOARD_FAB2(SCH_1):P3V3
   2 PWRGD_PVTT_DEF_CPU0_R      B @BASEBOARD_FAB2_LIB.BASEBOARD_FAB2(SCH_1):PWRGD_PVTT_DEF_CPU0_R

CAP_0402-1.0UF,16V,10%,X6S,D97A  I21  C4A9
   1 VR_PVTT_DEF_VREF      A @BASEBOARD_FAB2_LIB.BASEBOARD_FAB2(SCH_1):VR_PVTT_DEF_VREF
   2    GND      B @BASEBOARD_FAB2_LIB.BASEBOARD_FAB2(SCH_1):GND

CAP_0603LF-10UF,4V,20%,X6S,E15A  I24  C6L3
   1 PVDDQ_DEF      A @BASEBOARD_FAB2_LIB.BASEBOARD_FAB2(SCH_1):PVDDQ_DEF
   2    GND      B @BASEBOARD_FAB2_LIB.BASEBOARD_FAB2(SCH_1):GND

CAP_0603LF-10UF,4V,20%,X6S,E15A  I26  C6L4
   1 PVDDQ_DEF      A @BASEBOARD_FAB2_LIB.BASEBOARD_FAB2(SCH_1):PVDDQ_DEF
   2    GND      B @BASEBOARD_FAB2_LIB.BASEBOARD_FAB2(SCH_1):GND

CAP_0402-1.0UF,16V,10%,X6S,D97A  I28  C4A10
   1 VR_PVTT_DEF_BIAS      A @BASEBOARD_FAB2_LIB.BASEBOARD_FAB2(SCH_1):VR_PVTT_DEF_BIAS
   2    GND      B @BASEBOARD_FAB2_LIB.BASEBOARD_FAB2(SCH_1):GND

RES_0402-0.0,5%,1/16W,CHIP,G21A  I30  R6L11
   1   P3V3      A @BASEBOARD_FAB2_LIB.BASEBOARD_FAB2(SCH_1):P3V3
   2 VR_PVTT_DEF_BIAS      B @BASEBOARD_FAB2_LIB.BASEBOARD_FAB2(SCH_1):VR_PVTT_DEF_BIAS

MIC5166_DFN-IC,H55101-001  I31  EU4A1
   7 FM_PVTT_DEF_EN_R     EN @BASEBOARD_FAB2_LIB.BASEBOARD_FAB2(SCH_1):FM_PVTT_DEF_EN_R
  10 PVDDQ_DEF    VIN @BASEBOARD_FAB2_LIB.BASEBOARD_FAB2(SCH_1):PVDDQ_DEF
   1 VR_PVTT_DEF_VREF   VREF @BASEBOARD_FAB2_LIB.BASEBOARD_FAB2(SCH_1):VR_PVTT_DEF_VREF
   2 VR_PVTT_DEF_BIAS   BIAS @BASEBOARD_FAB2_LIB.BASEBOARD_FAB2(SCH_1):VR_PVTT_DEF_BIAS
   3    GND   AGND @BASEBOARD_FAB2_LIB.BASEBOARD_FAB2(SCH_1):GND
   5 PWRGD_PVTT_DEF_CPU0_R     PG @BASEBOARD_FAB2_LIB.BASEBOARD_FAB2(SCH_1):PWRGD_PVTT_DEF_CPU0_R
   4 VSENSE_PVDDQ_DEF_VTT   VDDQ @BASEBOARD_FAB2_LIB.BASEBOARD_FAB2(SCH_1):VSENSE_PVDDQ_DEF_VTT
   6 VR_PVTT_DEF_SNS    SNS @BASEBOARD_FAB2_LIB.BASEBOARD_FAB2(SCH_1):VR_PVTT_DEF_SNS
   8    GND   PGND @BASEBOARD_FAB2_LIB.BASEBOARD_FAB2(SCH_1):GND
   9 PVTT_DEF    VTT @BASEBOARD_FAB2_LIB.BASEBOARD_FAB2(SCH_1):PVTT_DEF
  11    GND  THPAD @BASEBOARD_FAB2_LIB.BASEBOARD_FAB2(SCH_1):GND

RES_0402-0.0,5%,1/16W,CHIP,G21A  I34  R6L10
   1 PVDDQ_DEF      A @BASEBOARD_FAB2_LIB.BASEBOARD_FAB2(SCH_1):PVDDQ_DEF
   2 VSENSE_PVDDQ_DEF_VTT      B @BASEBOARD_FAB2_LIB.BASEBOARD_FAB2(SCH_1):VSENSE_PVDDQ_DEF_VTT

RES_0402-1.0M,1%,1/16W,EMPTY,GA  I37  R6L4
   1   P3V3      A @BASEBOARD_FAB2_LIB.BASEBOARD_FAB2(SCH_1):P3V3
   2 FM_PVTT_DEF_EN_R      B @BASEBOARD_FAB2_LIB.BASEBOARD_FAB2(SCH_1):FM_PVTT_DEF_EN_R

RES_0402-0.0,5%,1/16W,CHIP,G21A  I38  R4A2
   1 PWRGD_PVDDQ_DEF      A @BASEBOARD_FAB2_LIB.BASEBOARD_FAB2(SCH_1):PWRGD_PVDDQ_DEF
   2 FM_PVTT_DEF_EN_R      B @BASEBOARD_FAB2_LIB.BASEBOARD_FAB2(SCH_1):FM_PVTT_DEF_EN_R

CAP_0402LF-1000PF,50V,10%,EMPTA  I40  C4A2
   1 FM_PVTT_DEF_EN_R      A @BASEBOARD_FAB2_LIB.BASEBOARD_FAB2(SCH_1):FM_PVTT_DEF_EN_R
   2    GND      B @BASEBOARD_FAB2_LIB.BASEBOARD_FAB2(SCH_1):GND

CAP_0603-4.7UF,6.3V,10%,X6S,E1A  I46  C4A11
   1 VSENSE_PVDDQ_DEF_VTT      A @BASEBOARD_FAB2_LIB.BASEBOARD_FAB2(SCH_1):VSENSE_PVDDQ_DEF_VTT
   2    GND      B @BASEBOARD_FAB2_LIB.BASEBOARD_FAB2(SCH_1):GND

CAP_A_0603V-47UF,4V,20%,X5R,60A  I47  C5L4
   1 PVTT_DEF      A @BASEBOARD_FAB2_LIB.BASEBOARD_FAB2(SCH_1):PVTT_DEF
   2    GND      B @BASEBOARD_FAB2_LIB.BASEBOARD_FAB2(SCH_1):GND

CAP_A_0603V-47UF,4V,20%,X5R,60A  I48  C5M13
   1 PVTT_DEF      A @BASEBOARD_FAB2_LIB.BASEBOARD_FAB2(SCH_1):PVTT_DEF
   2    GND      B @BASEBOARD_FAB2_LIB.BASEBOARD_FAB2(SCH_1):GND

CAP_A_0603V-47UF,4V,20%,X5R,60A  I49  C5L5
   1 PVTT_DEF      A @BASEBOARD_FAB2_LIB.BASEBOARD_FAB2(SCH_1):PVTT_DEF
   2    GND      B @BASEBOARD_FAB2_LIB.BASEBOARD_FAB2(SCH_1):GND

RES_0402-33.2,1%,1/16W,CHIP,G2A  I51  R4A6
   1 PWRGD_PVTT_DEF_CPU0_R      A @BASEBOARD_FAB2_LIB.BASEBOARD_FAB2(SCH_1):PWRGD_PVTT_DEF_CPU0_R
   2 PWRGD_PVTT_CPU0      B @BASEBOARD_FAB2_LIB.BASEBOARD_FAB2(SCH_1):PWRGD_PVTT_CPU0

RES_0402-51.1,1.0%,1/16W,CHIP,A  I52  R4A1
   1    GND      A @BASEBOARD_FAB2_LIB.BASEBOARD_FAB2(SCH_1):GND
   2 PVTT_DEF      B @BASEBOARD_FAB2_LIB.BASEBOARD_FAB2(SCH_1):PVTT_DEF

SHUNT_SH0201-EMPTY,N_A  I53  SH5L1
   1 VR_PVTT_DEF_SNS      A @BASEBOARD_FAB2_LIB.BASEBOARD_FAB2(SCH_1):VR_PVTT_DEF_SNS
   2 PVTT_DEF      B @BASEBOARD_FAB2_LIB.BASEBOARD_FAB2(SCH_1):PVTT_DEF


DRAWING: @BASEBOARD_FAB2_LIB.BASEBOARD_FAB2(SCH_1):PAGE223 

RES_0402-100.0,1%,1/16W,CHIP,GA  I8  R9U3
   1 PVCCIO_CPU1      A @BASEBOARD_FAB2_LIB.BASEBOARD_FAB2(SCH_1):PVCCIO_CPU1
   2 SVID_DIO1_CPU1_R      B @BASEBOARD_FAB2_LIB.BASEBOARD_FAB2(SCH_1):SVID_DIO1_CPU1_R

RES_0402-2.26K,1.0%,1/16W,EMPTA  I13  R1G6
   1 P3V3_STBY      A @BASEBOARD_FAB2_LIB.BASEBOARD_FAB2(SCH_1):P3V3_STBY
   2 PU_VR_PVDDQ_GHJ_FAULT1      B @BASEBOARD_FAB2_LIB.BASEBOARD_FAB2(SCH_1):PU_VR_PVDDQ_GHJ_FAULT1

RES_0402-22.1,1.0%,1/16W,CHIP,A  I14  R1G12
   1 PWRGD_PVDDQ_GHJ_R      A @BASEBOARD_FAB2_LIB.BASEBOARD_FAB2(SCH_1):PWRGD_PVDDQ_GHJ_R
   2 PWRGD_PVDDQ_GHJ      B @BASEBOARD_FAB2_LIB.BASEBOARD_FAB2(SCH_1):PWRGD_PVDDQ_GHJ

RES_0402-0.0,5%,1/16W,CHIP,G21A  I16  R1G9
   1 SVID_ALERT_PVDDQ_GHJ      A @BASEBOARD_FAB2_LIB.BASEBOARD_FAB2(SCH_1):SVID_ALERT_PVDDQ_GHJ
   2 SVID_ALERT1_CPU1_R_N      B @BASEBOARD_FAB2_LIB.BASEBOARD_FAB2(SCH_1):SVID_ALERT1_CPU1_R_N

RES_0402-1.00K,1%,1/16W,CHIP,GA  I17  R1G16
   1 P3V3_STBY      A @BASEBOARD_FAB2_LIB.BASEBOARD_FAB2(SCH_1):P3V3_STBY
   2 PWRGD_PVDDQ_GHJ_R      B @BASEBOARD_FAB2_LIB.BASEBOARD_FAB2(SCH_1):PWRGD_PVDDQ_GHJ_R

RES_0402-0.0,5%,1/16W,CHIP,G21A  I21  R1G19
   1 SMB_VR_SCL_VDDQ_GHJ      A @BASEBOARD_FAB2_LIB.BASEBOARD_FAB2(SCH_1):SMB_VR_SCL_VDDQ_GHJ
   2 SMB_VR_STBY_LVC3_SCL      B @BASEBOARD_FAB2_LIB.BASEBOARD_FAB2(SCH_1):SMB_VR_STBY_LVC3_SCL

RES_0402-0.0,5%,1/16W,CHIP,G21A  I22  R1G21
   1 SMB_VR_SDA_VDDQ_GHJ      A @BASEBOARD_FAB2_LIB.BASEBOARD_FAB2(SCH_1):SMB_VR_SDA_VDDQ_GHJ
   2 SMB_VR_STBY_LVC3_SDA      B @BASEBOARD_FAB2_LIB.BASEBOARD_FAB2(SCH_1):SMB_VR_STBY_LVC3_SDA

RES_0402-0.0,5%,1/16W,CHIP,G21A  I23  R1G10
   1 SVID_VDIO_PVDDQ_GHJ      A @BASEBOARD_FAB2_LIB.BASEBOARD_FAB2(SCH_1):SVID_VDIO_PVDDQ_GHJ
   2 SVID_DIO1_CPU1_R      B @BASEBOARD_FAB2_LIB.BASEBOARD_FAB2(SCH_1):SVID_DIO1_CPU1_R

CAP_A_0402V-1.0UF,6.3V,10%,X6SA  I25  C1G27
   1 VR_PVDDQ_GHJ_VDD      A @BASEBOARD_FAB2_LIB.BASEBOARD_FAB2(SCH_1):VR_PVDDQ_GHJ_VDD
   2    GND      B @BASEBOARD_FAB2_LIB.BASEBOARD_FAB2(SCH_1):GND

CAP_A_0402V-0.1UF,16V,10%,X7R,A  I27  C1G25
   1 VR_PVDDQ_GHJ_VDD      A @BASEBOARD_FAB2_LIB.BASEBOARD_FAB2(SCH_1):VR_PVDDQ_GHJ_VDD
   2    GND      B @BASEBOARD_FAB2_LIB.BASEBOARD_FAB2(SCH_1):GND

RES_0402-0.0,5%,1/16W,CHIP,G21A  I30  R9U10
   1 P3V3_STBY      A @BASEBOARD_FAB2_LIB.BASEBOARD_FAB2(SCH_1):P3V3_STBY
   2 VR_PVDDQ_GHJ_VDD      B @BASEBOARD_FAB2_LIB.BASEBOARD_FAB2(SCH_1):VR_PVDDQ_GHJ_VDD

RES_0402-10.0,1%,1/16W,CHIP,G2A  I32  R1G5
   1 VSENSE_PVDDQ_GHJ_P      A @BASEBOARD_FAB2_LIB.BASEBOARD_FAB2(SCH_1):VSENSE_PVDDQ_GHJ_P
   2 VR_PVDDQ_GHJ_AVSP      B @BASEBOARD_FAB2_LIB.BASEBOARD_FAB2(SCH_1):VR_PVDDQ_GHJ_AVSP

CAP_0402LF-220PF,50V,10%,X7R,AA  I36  C1G24
   1 A_TSENSE_PVDDQ_GHJ      A @BASEBOARD_FAB2_LIB.BASEBOARD_FAB2(SCH_1):A_TSENSE_PVDDQ_GHJ
   2    GND      B @BASEBOARD_FAB2_LIB.BASEBOARD_FAB2(SCH_1):GND

CAP_0402LF-220PF,50V,10%,X7R,AA  I39  C1G16
   1 VR_PVDDQ_GHJ_AVSP      A @BASEBOARD_FAB2_LIB.BASEBOARD_FAB2(SCH_1):VR_PVDDQ_GHJ_AVSP
   2 VSENSE_PVDDQ_GHJ_N      B @BASEBOARD_FAB2_LIB.BASEBOARD_FAB2(SCH_1):VSENSE_PVDDQ_GHJ_N

CAP_A_0402V-1.0UF,6.3V,10%,X6SA  I41  C1G23
   1 VR_PVDDQ_GHJ_VD12      A @BASEBOARD_FAB2_LIB.BASEBOARD_FAB2(SCH_1):VR_PVDDQ_GHJ_VD12
   2    GND      B @BASEBOARD_FAB2_LIB.BASEBOARD_FAB2(SCH_1):GND

CAP_A_0402V-0.1UF,16V,10%,X7R,A  I44  C1G22
   1 VR_PVDDQ_GHJ_VD12      A @BASEBOARD_FAB2_LIB.BASEBOARD_FAB2(SCH_1):VR_PVDDQ_GHJ_VD12
   2    GND      B @BASEBOARD_FAB2_LIB.BASEBOARD_FAB2(SCH_1):GND

RES_0402-49.9,1%,1/16W,EMPTY,GA  I50  R9U4
   1 PVCCIO_CPU1      A @BASEBOARD_FAB2_LIB.BASEBOARD_FAB2(SCH_1):PVCCIO_CPU1
   2 SVID_CLK1_CPU1_R      B @BASEBOARD_FAB2_LIB.BASEBOARD_FAB2(SCH_1):SVID_CLK1_CPU1_R

RES_0402-150.0,1%,1/16W,CHIP,GA  I53  R1G7
   1 SVID_CLK1_CPU1_R      A @BASEBOARD_FAB2_LIB.BASEBOARD_FAB2(SCH_1):SVID_CLK1_CPU1_R
   2 SVID_CLK_PVDDQ_GHJ      B @BASEBOARD_FAB2_LIB.BASEBOARD_FAB2(SCH_1):SVID_CLK_PVDDQ_GHJ

RES_0402-100.0K,1%,1/16W,CHIP,B  I57  R9U11
   1 VR_FET_SW_P12V_STBY_PVDDQ_GHJ      A @BASEBOARD_FAB2_LIB.BASEBOARD_FAB2(SCH_1):VR_FET_SW_P12V_STBY_PVDDQ_GHJ
   2 VR_PVDDQ_GHJ_VINSEN      B @BASEBOARD_FAB2_LIB.BASEBOARD_FAB2(SCH_1):VR_PVDDQ_GHJ_VINSEN

RES_0402-1.5K,1%,1/16W,CHIP,G2A  I58  R1G24
   1 VR_PVDDQ_GHJ_VINSEN      A @BASEBOARD_FAB2_LIB.BASEBOARD_FAB2(SCH_1):VR_PVDDQ_GHJ_VINSEN
   2    GND      B @BASEBOARD_FAB2_LIB.BASEBOARD_FAB2(SCH_1):GND

CAP_0402LF-1000PF,50V,10%,X7R,A  I59  C1G26
   1 VR_PVDDQ_GHJ_VINSEN      A @BASEBOARD_FAB2_LIB.BASEBOARD_FAB2(SCH_1):VR_PVDDQ_GHJ_VINSEN
   2    GND      B @BASEBOARD_FAB2_LIB.BASEBOARD_FAB2(SCH_1):GND

RES_0402-4.02K,1%,1/16W,CHIP,GA  I77  R1G23
   1 VR_PVDDQ_GHJ_XADDR1      A @BASEBOARD_FAB2_LIB.BASEBOARD_FAB2(SCH_1):VR_PVDDQ_GHJ_XADDR1
   2    GND      B @BASEBOARD_FAB2_LIB.BASEBOARD_FAB2(SCH_1):GND

RES_0402-5.36K,1.0%,1/16W,CHIPA  I78  R1G22
   1 VR_PVDDQ_GHJ_XADDR2      A @BASEBOARD_FAB2_LIB.BASEBOARD_FAB2(SCH_1):VR_PVDDQ_GHJ_XADDR2
   2    GND      B @BASEBOARD_FAB2_LIB.BASEBOARD_FAB2(SCH_1):GND

RES_0402-1.00K,1%,1/16W,CHIP,GA  I79  R1G11
   1 P3V3_STBY      A @BASEBOARD_FAB2_LIB.BASEBOARD_FAB2(SCH_1):P3V3_STBY
   2 IRQ_PVDDQ_GHJ_VRHOT_LVT3_R_N      B @BASEBOARD_FAB2_LIB.BASEBOARD_FAB2(SCH_1):IRQ_PVDDQ_GHJ_VRHOT_LVT3_R_N

CAP_0402LF-1000PF,50V,10%,X7R,A  I80  C1G21
   1 PWRGD_PVDDQ_GHJ_R      A @BASEBOARD_FAB2_LIB.BASEBOARD_FAB2(SCH_1):PWRGD_PVDDQ_GHJ_R
   2    GND      B @BASEBOARD_FAB2_LIB.BASEBOARD_FAB2(SCH_1):GND

RES_0402-33.2,1%,1/16W,CHIP,G2A  I82  R1G8
   1 IRQ_PVDDQ_GHJ_VRHOT_LVT3_R_N      A @BASEBOARD_FAB2_LIB.BASEBOARD_FAB2(SCH_1):IRQ_PVDDQ_GHJ_VRHOT_LVT3_R_N
   2 IRQ_PVDDQ_GHJ_VRHOT_LVT3_N      B @BASEBOARD_FAB2_LIB.BASEBOARD_FAB2(SCH_1):IRQ_PVDDQ_GHJ_VRHOT_LVT3_N

RES_0402-0.0,5%,1/16W,CHIP,G21A  I84  R9U7
   1 FM_PVDDQ_GHJ_EN      A @BASEBOARD_FAB2_LIB.BASEBOARD_FAB2(SCH_1):FM_PVDDQ_GHJ_EN
   2 VR_PVDDQ_GHJ_VREN      B @BASEBOARD_FAB2_LIB.BASEBOARD_FAB2(SCH_1):VR_PVDDQ_GHJ_VREN

RES_0402-100.0K,1%,1/16W,EMPTYA  I85  R9U8
   1 P3V3_STBY      A @BASEBOARD_FAB2_LIB.BASEBOARD_FAB2(SCH_1):P3V3_STBY
   2 VR_PVDDQ_GHJ_VREN      B @BASEBOARD_FAB2_LIB.BASEBOARD_FAB2(SCH_1):VR_PVDDQ_GHJ_VREN

RES_0402-0.0,5%,1/16W,CHIP,G21A  I87  R1G28
   1 VR_PVDDQ_GHJ_VD12      A @BASEBOARD_FAB2_LIB.BASEBOARD_FAB2(SCH_1):VR_PVDDQ_GHJ_VD12
   2 VR_PVDDQ_GHJ_AIREF1      B @BASEBOARD_FAB2_LIB.BASEBOARD_FAB2(SCH_1):VR_PVDDQ_GHJ_AIREF1

RES_0402-0.0,5%,1/16W,CHIP,G21A  I88  R1G27
   1 VR_PVDDQ_GHJ_VD12      A @BASEBOARD_FAB2_LIB.BASEBOARD_FAB2(SCH_1):VR_PVDDQ_GHJ_VD12
   2 VR_PVDDQ_GHJ_AIREF2      B @BASEBOARD_FAB2_LIB.BASEBOARD_FAB2(SCH_1):VR_PVDDQ_GHJ_AIREF2

PXM1310B_QFN-IC,H89186-001  I90  EU1G2
   1 TP_PVDDQ_GHJ_BPWM1  BPWM1 @BASEBOARD_FAB2_LIB.BASEBOARD_FAB2(SCH_1):TP_PVDDQ_GHJ_BPWM1
   2 NC_PVDDQ_GHJ_DNC0 DNC<0> @BASEBOARD_FAB2_LIB.BASEBOARD_FAB2(SCH_1):NC_PVDDQ_GHJ_DNC0
   3 TP_PVDDQ_GHJ_PWM3  APWM3 @BASEBOARD_FAB2_LIB.BASEBOARD_FAB2(SCH_1):TP_PVDDQ_GHJ_PWM3
   4 VR_PVDDQ_GHJ_PWM2  APWM2 @BASEBOARD_FAB2_LIB.BASEBOARD_FAB2(SCH_1):VR_PVDDQ_GHJ_PWM2
   5 VR_PVDDQ_GHJ_PWM1  APWM1 @BASEBOARD_FAB2_LIB.BASEBOARD_FAB2(SCH_1):VR_PVDDQ_GHJ_PWM1
   6 SMB_VR_SDA_VDDQ_GHJ    SDA @BASEBOARD_FAB2_LIB.BASEBOARD_FAB2(SCH_1):SMB_VR_SDA_VDDQ_GHJ
   7 SMB_VR_SCL_VDDQ_GHJ    SCL @BASEBOARD_FAB2_LIB.BASEBOARD_FAB2(SCH_1):SMB_VR_SCL_VDDQ_GHJ
   8 TP_PVDDQ_GHJ_RESET_N RESET_N @BASEBOARD_FAB2_LIB.BASEBOARD_FAB2(SCH_1):TP_PVDDQ_GHJ_RESET_N
   9 PWRGD_PVDDQ_GHJ_R AVRRDY @BASEBOARD_FAB2_LIB.BASEBOARD_FAB2(SCH_1):PWRGD_PVDDQ_GHJ_R
  10 VR_PVDDQ_GHJ_VREN  AVREN @BASEBOARD_FAB2_LIB.BASEBOARD_FAB2(SCH_1):VR_PVDDQ_GHJ_VREN
  11 IRQ_PVDDQ_GHJ_VRHOT_LVT3_R_N VRHOT_N @BASEBOARD_FAB2_LIB.BASEBOARD_FAB2(SCH_1):IRQ_PVDDQ_GHJ_VRHOT_LVT3_R_N
  12 NC_PVDDQ_GHJ_PINALRT_N PINALRT_N @BASEBOARD_FAB2_LIB.BASEBOARD_FAB2(SCH_1):NC_PVDDQ_GHJ_PINALRT_N
  13 PU_VR_PVDDQ_GHJ_FAULT1    MP0 @BASEBOARD_FAB2_LIB.BASEBOARD_FAB2(SCH_1):PU_VR_PVDDQ_GHJ_FAULT1
  14 TP_PVDDQ_GHJ_MP1    MP1 @BASEBOARD_FAB2_LIB.BASEBOARD_FAB2(SCH_1):TP_PVDDQ_GHJ_MP1
  15 SVID_CLK_PVDDQ_GHJ   VCLK @BASEBOARD_FAB2_LIB.BASEBOARD_FAB2(SCH_1):SVID_CLK_PVDDQ_GHJ
  16 SVID_VDIO_PVDDQ_GHJ   VDIO @BASEBOARD_FAB2_LIB.BASEBOARD_FAB2(SCH_1):SVID_VDIO_PVDDQ_GHJ
  17 SVID_ALERT_PVDDQ_GHJ VALRT_N @BASEBOARD_FAB2_LIB.BASEBOARD_FAB2(SCH_1):SVID_ALERT_PVDDQ_GHJ
  18 TP_PVDDQ_GHJ_MP2    MP2 @BASEBOARD_FAB2_LIB.BASEBOARD_FAB2(SCH_1):TP_PVDDQ_GHJ_MP2
  19 VR_PVDDQ_GHJ_AVSP  AVSEN @BASEBOARD_FAB2_LIB.BASEBOARD_FAB2(SCH_1):VR_PVDDQ_GHJ_AVSP
  20 VSENSE_PVDDQ_GHJ_N  AVREF @BASEBOARD_FAB2_LIB.BASEBOARD_FAB2(SCH_1):VSENSE_PVDDQ_GHJ_N
  21 VR_PVDDQ_GHJ_AIREF1 AIREF1 @BASEBOARD_FAB2_LIB.BASEBOARD_FAB2(SCH_1):VR_PVDDQ_GHJ_AIREF1
  22 ISENSE_PVDDQ_GHJ_PH1_IMON AISEN1 @BASEBOARD_FAB2_LIB.BASEBOARD_FAB2(SCH_1):ISENSE_PVDDQ_GHJ_PH1_IMON
  23 VR_PVDDQ_GHJ_AIREF2 AIREF2 @BASEBOARD_FAB2_LIB.BASEBOARD_FAB2(SCH_1):VR_PVDDQ_GHJ_AIREF2
  24 ISENSE_PVDDQ_GHJ_PH2_IMON AISEN2 @BASEBOARD_FAB2_LIB.BASEBOARD_FAB2(SCH_1):ISENSE_PVDDQ_GHJ_PH2_IMON
  25 TP_PVDDQ_GHJ_PH3_IMON_REF AIREF3 @BASEBOARD_FAB2_LIB.BASEBOARD_FAB2(SCH_1):TP_PVDDQ_GHJ_PH3_IMON_REF
  26 TP_PVDDQ_GHJ_PH3_IMON AISEN3 @BASEBOARD_FAB2_LIB.BASEBOARD_FAB2(SCH_1):TP_PVDDQ_GHJ_PH3_IMON
  27    GND    GND @BASEBOARD_FAB2_LIB.BASEBOARD_FAB2(SCH_1):GND
  28 NC_PVDDQ_GHJ_DNC1 DNC<1> @BASEBOARD_FAB2_LIB.BASEBOARD_FAB2(SCH_1):NC_PVDDQ_GHJ_DNC1
  29 TP_PVDDQ_GHJ_BVSEN  BVSEN @BASEBOARD_FAB2_LIB.BASEBOARD_FAB2(SCH_1):TP_PVDDQ_GHJ_BVSEN
  30 TP_PVDDQ_GHJ_BVREF  BVREF @BASEBOARD_FAB2_LIB.BASEBOARD_FAB2(SCH_1):TP_PVDDQ_GHJ_BVREF
  31 TP_PVDDQ_GHJ_BREF1 BIREF1 @BASEBOARD_FAB2_LIB.BASEBOARD_FAB2(SCH_1):TP_PVDDQ_GHJ_BREF1
  32    GND BISEN1 @BASEBOARD_FAB2_LIB.BASEBOARD_FAB2(SCH_1):GND
  33 VR_PVDDQ_GHJ_XADDR2 XADDR2 @BASEBOARD_FAB2_LIB.BASEBOARD_FAB2(SCH_1):VR_PVDDQ_GHJ_XADDR2
  34 TP_PVDDQ_GHJ_BTSEN  BTSEN @BASEBOARD_FAB2_LIB.BASEBOARD_FAB2(SCH_1):TP_PVDDQ_GHJ_BTSEN
  35 A_TSENSE_PVDDQ_GHJ  ATSEN @BASEBOARD_FAB2_LIB.BASEBOARD_FAB2(SCH_1):A_TSENSE_PVDDQ_GHJ
  36 VR_PVDDQ_GHJ_XADDR1 XADDR1 @BASEBOARD_FAB2_LIB.BASEBOARD_FAB2(SCH_1):VR_PVDDQ_GHJ_XADDR1
  37 VR_PVDDQ_GHJ_VINSEN VINSEN @BASEBOARD_FAB2_LIB.BASEBOARD_FAB2(SCH_1):VR_PVDDQ_GHJ_VINSEN
  38 VR_PVDDQ_GHJ_AIINSEN IINSEN @BASEBOARD_FAB2_LIB.BASEBOARD_FAB2(SCH_1):VR_PVDDQ_GHJ_AIINSEN
  39 VR_PVDDQ_GHJ_VDD    VDD @BASEBOARD_FAB2_LIB.BASEBOARD_FAB2(SCH_1):VR_PVDDQ_GHJ_VDD
  40 VR_PVDDQ_GHJ_VD12   VD12 @BASEBOARD_FAB2_LIB.BASEBOARD_FAB2(SCH_1):VR_PVDDQ_GHJ_VD12
  41    GND  THPAD @BASEBOARD_FAB2_LIB.BASEBOARD_FAB2(SCH_1):GND

CAP_A_0402V-0.1UF,16V,10%,X7R,A  I92  C9U12
   1 VR_PVDDQ_GHJ_AIINSEN      A @BASEBOARD_FAB2_LIB.BASEBOARD_FAB2(SCH_1):VR_PVDDQ_GHJ_AIINSEN
   2    GND      B @BASEBOARD_FAB2_LIB.BASEBOARD_FAB2(SCH_1):GND


DRAWING: @BASEBOARD_FAB2_LIB.BASEBOARD_FAB2(SCH_1):PAGE225 

RES_0603-120.0,1%,1/10W,CHIP,GA  I58  R1G20
   1 PVDDQ_GHJ      A @BASEBOARD_FAB2_LIB.BASEBOARD_FAB2(SCH_1):PVDDQ_GHJ
   2    GND      B @BASEBOARD_FAB2_LIB.BASEBOARD_FAB2(SCH_1):GND

RES_0402-100.0,1%,1/16W,EMPTY,A  I74  R7U2
   1 VSENSE_PVDDQ_GHJ_P      A @BASEBOARD_FAB2_LIB.BASEBOARD_FAB2(SCH_1):VSENSE_PVDDQ_GHJ_P
   2 VSENSE_PVDDQ_GHJ_N      B @BASEBOARD_FAB2_LIB.BASEBOARD_FAB2(SCH_1):VSENSE_PVDDQ_GHJ_N

CAPP_3018-470UF,2.5V,20%,ALUM,A  I75  C9T5
   1 PVDDQ_GHJ      A @BASEBOARD_FAB2_LIB.BASEBOARD_FAB2(SCH_1):PVDDQ_GHJ
   2    GND      B @BASEBOARD_FAB2_LIB.BASEBOARD_FAB2(SCH_1):GND

CAPP_3018-470UF,2.5V,20%,ALUM,A  I76  C9U2
   1 PVDDQ_GHJ      A @BASEBOARD_FAB2_LIB.BASEBOARD_FAB2(SCH_1):PVDDQ_GHJ
   2    GND      B @BASEBOARD_FAB2_LIB.BASEBOARD_FAB2(SCH_1):GND

CAPP_3018-470UF,2.5V,20%,ALUM,A  I77  C9U9
   1 PVDDQ_GHJ      A @BASEBOARD_FAB2_LIB.BASEBOARD_FAB2(SCH_1):PVDDQ_GHJ
   2    GND      B @BASEBOARD_FAB2_LIB.BASEBOARD_FAB2(SCH_1):GND

CAPP_3018-470UF,2.5V,20%,ALUM,A  I78  C9U5
   1 PVDDQ_GHJ      A @BASEBOARD_FAB2_LIB.BASEBOARD_FAB2(SCH_1):PVDDQ_GHJ
   2    GND      B @BASEBOARD_FAB2_LIB.BASEBOARD_FAB2(SCH_1):GND

CAP_0805-100UF,4V,20%,X5R,6024A  I82  C8U1
   1 PVDDQ_GHJ      A @BASEBOARD_FAB2_LIB.BASEBOARD_FAB2(SCH_1):PVDDQ_GHJ
   2    GND      B @BASEBOARD_FAB2_LIB.BASEBOARD_FAB2(SCH_1):GND

CAP_0805-100UF,4V,20%,X5R,6024A  I83  C8U8
   1 PVDDQ_GHJ      A @BASEBOARD_FAB2_LIB.BASEBOARD_FAB2(SCH_1):PVDDQ_GHJ
   2    GND      B @BASEBOARD_FAB2_LIB.BASEBOARD_FAB2(SCH_1):GND

CAP_0805-100UF,4V,20%,X5R,6024A  I88  C8U12
   1 PVDDQ_GHJ      A @BASEBOARD_FAB2_LIB.BASEBOARD_FAB2(SCH_1):PVDDQ_GHJ
   2    GND      B @BASEBOARD_FAB2_LIB.BASEBOARD_FAB2(SCH_1):GND

CAP_0805-100UF,4V,20%,X5R,6024A  I89  C8U11
   1 PVDDQ_GHJ      A @BASEBOARD_FAB2_LIB.BASEBOARD_FAB2(SCH_1):PVDDQ_GHJ
   2    GND      B @BASEBOARD_FAB2_LIB.BASEBOARD_FAB2(SCH_1):GND

CAP_0805-100UF,4V,20%,X5R,6024A  I90  C7T1
   1 PVDDQ_GHJ      A @BASEBOARD_FAB2_LIB.BASEBOARD_FAB2(SCH_1):PVDDQ_GHJ
   2    GND      B @BASEBOARD_FAB2_LIB.BASEBOARD_FAB2(SCH_1):GND

CAP_0805-100UF,4V,20%,X5R,6024A  I91  C7U7
   1 PVDDQ_GHJ      A @BASEBOARD_FAB2_LIB.BASEBOARD_FAB2(SCH_1):PVDDQ_GHJ
   2    GND      B @BASEBOARD_FAB2_LIB.BASEBOARD_FAB2(SCH_1):GND

CAP_0805-100UF,4V,20%,X5R,6024A  I92  C2G7
   1 PVDDQ_GHJ      A @BASEBOARD_FAB2_LIB.BASEBOARD_FAB2(SCH_1):PVDDQ_GHJ
   2    GND      B @BASEBOARD_FAB2_LIB.BASEBOARD_FAB2(SCH_1):GND

CAP_0805-100UF,4V,20%,X5R,6024A  I110  C2G16
   1 PVDDQ_GHJ      A @BASEBOARD_FAB2_LIB.BASEBOARD_FAB2(SCH_1):PVDDQ_GHJ
   2    GND      B @BASEBOARD_FAB2_LIB.BASEBOARD_FAB2(SCH_1):GND

INDUCTOR_SM-100NH,IND,D92183-0B  I124  L1F1
   1 P12V_STBY    INA @BASEBOARD_FAB2_LIB.BASEBOARD_FAB2(SCH_1):P12V_STBY
   2 VR_FET_SW_P12V_STBY_PVDDQ_GHJ    INB @BASEBOARD_FAB2_LIB.BASEBOARD_FAB2(SCH_1):VR_FET_SW_P12V_STBY_PVDDQ_GHJ

CAP_0805LF-22UF,4V,20%,X6S,C95A  I178  C8P31
   1 PVDDQ_GHJ      A @BASEBOARD_FAB2_LIB.BASEBOARD_FAB2(SCH_1):PVDDQ_GHJ
   2    GND      B @BASEBOARD_FAB2_LIB.BASEBOARD_FAB2(SCH_1):GND

CAP_0603LF-10UF,4V,20%,X6S,E15A  I179  C2D43
   1 PVDDQ_GHJ      A @BASEBOARD_FAB2_LIB.BASEBOARD_FAB2(SCH_1):PVDDQ_GHJ
   2    GND      B @BASEBOARD_FAB2_LIB.BASEBOARD_FAB2(SCH_1):GND

CAP_0603LF-10UF,4V,20%,X6S,E15A  I180  C2D41
   1 PVDDQ_GHJ      A @BASEBOARD_FAB2_LIB.BASEBOARD_FAB2(SCH_1):PVDDQ_GHJ
   2    GND      B @BASEBOARD_FAB2_LIB.BASEBOARD_FAB2(SCH_1):GND

CAP_0603LF-10UF,4V,20%,X6S,E15A  I181  C2D44
   1 PVDDQ_GHJ      A @BASEBOARD_FAB2_LIB.BASEBOARD_FAB2(SCH_1):PVDDQ_GHJ
   2    GND      B @BASEBOARD_FAB2_LIB.BASEBOARD_FAB2(SCH_1):GND

CAP_0603LF-10UF,4V,20%,X6S,E15A  I183  C2D42
   1 PVDDQ_GHJ      A @BASEBOARD_FAB2_LIB.BASEBOARD_FAB2(SCH_1):PVDDQ_GHJ
   2    GND      B @BASEBOARD_FAB2_LIB.BASEBOARD_FAB2(SCH_1):GND

CAP_0805LF-22UF,4V,20%,X6S,C95A  I184  C8P30
   1 PVDDQ_GHJ      A @BASEBOARD_FAB2_LIB.BASEBOARD_FAB2(SCH_1):PVDDQ_GHJ
   2    GND      B @BASEBOARD_FAB2_LIB.BASEBOARD_FAB2(SCH_1):GND

CAP_1210-47UF,16V,20%,X6S,D384A  I192  C1G15
   1 VR_FET_SW_P12V_STBY_PVDDQ_GHJ      A @BASEBOARD_FAB2_LIB.BASEBOARD_FAB2(SCH_1):VR_FET_SW_P12V_STBY_PVDDQ_GHJ
   2    GND      B @BASEBOARD_FAB2_LIB.BASEBOARD_FAB2(SCH_1):GND

CAP_1210-47UF,16V,20%,X6S,D384A  I193  C1G12
   1 VR_FET_SW_P12V_STBY_PVDDQ_GHJ      A @BASEBOARD_FAB2_LIB.BASEBOARD_FAB2(SCH_1):VR_FET_SW_P12V_STBY_PVDDQ_GHJ
   2    GND      B @BASEBOARD_FAB2_LIB.BASEBOARD_FAB2(SCH_1):GND

CAP_1210-47UF,16V,20%,X6S,D384A  I194  C1G2
   1 VR_FET_SW_P12V_STBY_PVDDQ_GHJ      A @BASEBOARD_FAB2_LIB.BASEBOARD_FAB2(SCH_1):VR_FET_SW_P12V_STBY_PVDDQ_GHJ
   2    GND      B @BASEBOARD_FAB2_LIB.BASEBOARD_FAB2(SCH_1):GND

CAP_1210-47UF,16V,20%,X6S,D384A  I195  C1G7
   1 VR_FET_SW_P12V_STBY_PVDDQ_GHJ      A @BASEBOARD_FAB2_LIB.BASEBOARD_FAB2(SCH_1):VR_FET_SW_P12V_STBY_PVDDQ_GHJ
   2    GND      B @BASEBOARD_FAB2_LIB.BASEBOARD_FAB2(SCH_1):GND

CAP_A_0603V-47UF,4V,20%,X5R,60A  I196  C8T4
   1 PVDDQ_GHJ      A @BASEBOARD_FAB2_LIB.BASEBOARD_FAB2(SCH_1):PVDDQ_GHJ
   2    GND      B @BASEBOARD_FAB2_LIB.BASEBOARD_FAB2(SCH_1):GND

CAP_A_0603V-47UF,4V,20%,X5R,60A  I197  C2G8
   1 PVDDQ_GHJ      A @BASEBOARD_FAB2_LIB.BASEBOARD_FAB2(SCH_1):PVDDQ_GHJ
   2    GND      B @BASEBOARD_FAB2_LIB.BASEBOARD_FAB2(SCH_1):GND

CAP_A_0603V-47UF,4V,20%,X5R,60A  I198  C8T2
   1 PVDDQ_GHJ      A @BASEBOARD_FAB2_LIB.BASEBOARD_FAB2(SCH_1):PVDDQ_GHJ
   2    GND      B @BASEBOARD_FAB2_LIB.BASEBOARD_FAB2(SCH_1):GND

CAP_A_0603V-47UF,4V,20%,X5R,60A  I199  C8U13
   1 PVDDQ_GHJ      A @BASEBOARD_FAB2_LIB.BASEBOARD_FAB2(SCH_1):PVDDQ_GHJ
   2    GND      B @BASEBOARD_FAB2_LIB.BASEBOARD_FAB2(SCH_1):GND

CAP_A_0603V-47UF,4V,20%,X5R,60A  I200  C2G15
   1 PVDDQ_GHJ      A @BASEBOARD_FAB2_LIB.BASEBOARD_FAB2(SCH_1):PVDDQ_GHJ
   2    GND      B @BASEBOARD_FAB2_LIB.BASEBOARD_FAB2(SCH_1):GND

CAP_A_0603V-47UF,4V,20%,X5R,60A  I201  C2F1
   1 PVDDQ_GHJ      A @BASEBOARD_FAB2_LIB.BASEBOARD_FAB2(SCH_1):PVDDQ_GHJ
   2    GND      B @BASEBOARD_FAB2_LIB.BASEBOARD_FAB2(SCH_1):GND

CAP_A_0603V-47UF,4V,20%,X5R,60A  I202  C8T1
   1 PVDDQ_GHJ      A @BASEBOARD_FAB2_LIB.BASEBOARD_FAB2(SCH_1):PVDDQ_GHJ
   2    GND      B @BASEBOARD_FAB2_LIB.BASEBOARD_FAB2(SCH_1):GND

CAP_A_0603V-47UF,4V,20%,X5R,60A  I203  C8U9
   1 PVDDQ_GHJ      A @BASEBOARD_FAB2_LIB.BASEBOARD_FAB2(SCH_1):PVDDQ_GHJ
   2    GND      B @BASEBOARD_FAB2_LIB.BASEBOARD_FAB2(SCH_1):GND

CAP_A_0603V-47UF,4V,20%,X5R,60A  I204  C8T11
   1 PVDDQ_GHJ      A @BASEBOARD_FAB2_LIB.BASEBOARD_FAB2(SCH_1):PVDDQ_GHJ
   2    GND      B @BASEBOARD_FAB2_LIB.BASEBOARD_FAB2(SCH_1):GND

CAP_A_0603V-22.0UF,4V,20%,X6S,A  I207  C3G6
   1 PVDDQ_GHJ      A @BASEBOARD_FAB2_LIB.BASEBOARD_FAB2(SCH_1):PVDDQ_GHJ
   2    GND      B @BASEBOARD_FAB2_LIB.BASEBOARD_FAB2(SCH_1):GND

CAP_A_0603V-22.0UF,4V,20%,X6S,A  I208  C3G5
   1 PVDDQ_GHJ      A @BASEBOARD_FAB2_LIB.BASEBOARD_FAB2(SCH_1):PVDDQ_GHJ
   2    GND      B @BASEBOARD_FAB2_LIB.BASEBOARD_FAB2(SCH_1):GND

CAP_A_0603V-22.0UF,4V,20%,X6S,A  I209  C2G14
   1 PVDDQ_GHJ      A @BASEBOARD_FAB2_LIB.BASEBOARD_FAB2(SCH_1):PVDDQ_GHJ
   2    GND      B @BASEBOARD_FAB2_LIB.BASEBOARD_FAB2(SCH_1):GND

CAP_A_0603V-22.0UF,4V,20%,X6S,A  I210  C2G13
   1 PVDDQ_GHJ      A @BASEBOARD_FAB2_LIB.BASEBOARD_FAB2(SCH_1):PVDDQ_GHJ
   2    GND      B @BASEBOARD_FAB2_LIB.BASEBOARD_FAB2(SCH_1):GND

CAP_A_0603V-22.0UF,4V,20%,X6S,A  I211  C3G2
   1 PVDDQ_GHJ      A @BASEBOARD_FAB2_LIB.BASEBOARD_FAB2(SCH_1):PVDDQ_GHJ
   2    GND      B @BASEBOARD_FAB2_LIB.BASEBOARD_FAB2(SCH_1):GND

CAP_A_0603V-22.0UF,4V,20%,X6S,A  I212  C3G1
   1 PVDDQ_GHJ      A @BASEBOARD_FAB2_LIB.BASEBOARD_FAB2(SCH_1):PVDDQ_GHJ
   2    GND      B @BASEBOARD_FAB2_LIB.BASEBOARD_FAB2(SCH_1):GND

CAP_A_0603V-22.0UF,4V,20%,X6S,A  I213  C2G6
   1 PVDDQ_GHJ      A @BASEBOARD_FAB2_LIB.BASEBOARD_FAB2(SCH_1):PVDDQ_GHJ
   2    GND      B @BASEBOARD_FAB2_LIB.BASEBOARD_FAB2(SCH_1):GND

CAP_A_0603V-22.0UF,4V,20%,X6S,A  I214  C2G5
   1 PVDDQ_GHJ      A @BASEBOARD_FAB2_LIB.BASEBOARD_FAB2(SCH_1):PVDDQ_GHJ
   2    GND      B @BASEBOARD_FAB2_LIB.BASEBOARD_FAB2(SCH_1):GND

CAP_A_0603V-22.0UF,4V,20%,X6S,A  I215  C2G4
   1 PVDDQ_GHJ      A @BASEBOARD_FAB2_LIB.BASEBOARD_FAB2(SCH_1):PVDDQ_GHJ
   2    GND      B @BASEBOARD_FAB2_LIB.BASEBOARD_FAB2(SCH_1):GND

CAP_A_0603V-22.0UF,4V,20%,X6S,A  I216  C2G3
   1 PVDDQ_GHJ      A @BASEBOARD_FAB2_LIB.BASEBOARD_FAB2(SCH_1):PVDDQ_GHJ
   2    GND      B @BASEBOARD_FAB2_LIB.BASEBOARD_FAB2(SCH_1):GND

CAP_A_0603V-22.0UF,4V,20%,X6S,A  I217  C2G2
   1 PVDDQ_GHJ      A @BASEBOARD_FAB2_LIB.BASEBOARD_FAB2(SCH_1):PVDDQ_GHJ
   2    GND      B @BASEBOARD_FAB2_LIB.BASEBOARD_FAB2(SCH_1):GND

CAP_A_0603V-22.0UF,4V,20%,X6S,A  I218  C2G9
   1 PVDDQ_GHJ      A @BASEBOARD_FAB2_LIB.BASEBOARD_FAB2(SCH_1):PVDDQ_GHJ
   2    GND      B @BASEBOARD_FAB2_LIB.BASEBOARD_FAB2(SCH_1):GND

CAP_A_0603V-22.0UF,4V,20%,X6S,A  I219  C2G1
   1 PVDDQ_GHJ      A @BASEBOARD_FAB2_LIB.BASEBOARD_FAB2(SCH_1):PVDDQ_GHJ
   2    GND      B @BASEBOARD_FAB2_LIB.BASEBOARD_FAB2(SCH_1):GND

CAP_A_0603V-22.0UF,4V,20%,X6S,A  I220  C2G12
   1 PVDDQ_GHJ      A @BASEBOARD_FAB2_LIB.BASEBOARD_FAB2(SCH_1):PVDDQ_GHJ
   2    GND      B @BASEBOARD_FAB2_LIB.BASEBOARD_FAB2(SCH_1):GND

CAP_A_0603V-22.0UF,4V,20%,X6S,A  I221  C2G11
   1 PVDDQ_GHJ      A @BASEBOARD_FAB2_LIB.BASEBOARD_FAB2(SCH_1):PVDDQ_GHJ
   2    GND      B @BASEBOARD_FAB2_LIB.BASEBOARD_FAB2(SCH_1):GND

CAP_A_0603V-22.0UF,4V,20%,X6S,A  I223  C2G10
   1 PVDDQ_GHJ      A @BASEBOARD_FAB2_LIB.BASEBOARD_FAB2(SCH_1):PVDDQ_GHJ
   2    GND      B @BASEBOARD_FAB2_LIB.BASEBOARD_FAB2(SCH_1):GND

CAP_A_0603V-22.0UF,4V,20%,X6S,A  I225  C8U4
   1 PVDDQ_GHJ      A @BASEBOARD_FAB2_LIB.BASEBOARD_FAB2(SCH_1):PVDDQ_GHJ
   2    GND      B @BASEBOARD_FAB2_LIB.BASEBOARD_FAB2(SCH_1):GND

CAP_A_0603V-22.0UF,4V,20%,X6S,A  I226  C8T10
   1 PVDDQ_GHJ      A @BASEBOARD_FAB2_LIB.BASEBOARD_FAB2(SCH_1):PVDDQ_GHJ
   2    GND      B @BASEBOARD_FAB2_LIB.BASEBOARD_FAB2(SCH_1):GND

CAP_A_0603V-22.0UF,4V,20%,X6S,A  I227  C8T9
   1 PVDDQ_GHJ      A @BASEBOARD_FAB2_LIB.BASEBOARD_FAB2(SCH_1):PVDDQ_GHJ
   2    GND      B @BASEBOARD_FAB2_LIB.BASEBOARD_FAB2(SCH_1):GND

CAP_A_0603V-22.0UF,4V,20%,X6S,A  I228  C8U5
   1 PVDDQ_GHJ      A @BASEBOARD_FAB2_LIB.BASEBOARD_FAB2(SCH_1):PVDDQ_GHJ
   2    GND      B @BASEBOARD_FAB2_LIB.BASEBOARD_FAB2(SCH_1):GND

CAP_A_0603V-22.0UF,4V,20%,X6S,A  I229  C8T8
   1 PVDDQ_GHJ      A @BASEBOARD_FAB2_LIB.BASEBOARD_FAB2(SCH_1):PVDDQ_GHJ
   2    GND      B @BASEBOARD_FAB2_LIB.BASEBOARD_FAB2(SCH_1):GND

CAP_A_0603V-22.0UF,4V,20%,X6S,A  I230  C8T7
   1 PVDDQ_GHJ      A @BASEBOARD_FAB2_LIB.BASEBOARD_FAB2(SCH_1):PVDDQ_GHJ
   2    GND      B @BASEBOARD_FAB2_LIB.BASEBOARD_FAB2(SCH_1):GND

CAP_A_0603V-22.0UF,4V,20%,X6S,A  I231  C8T6
   1 PVDDQ_GHJ      A @BASEBOARD_FAB2_LIB.BASEBOARD_FAB2(SCH_1):PVDDQ_GHJ
   2    GND      B @BASEBOARD_FAB2_LIB.BASEBOARD_FAB2(SCH_1):GND

CAP_A_0603V-22.0UF,4V,20%,X6S,A  I232  C8U6
   1 PVDDQ_GHJ      A @BASEBOARD_FAB2_LIB.BASEBOARD_FAB2(SCH_1):PVDDQ_GHJ
   2    GND      B @BASEBOARD_FAB2_LIB.BASEBOARD_FAB2(SCH_1):GND

CAP_A_0603V-22.0UF,4V,20%,X6S,A  I233  C8T5
   1 PVDDQ_GHJ      A @BASEBOARD_FAB2_LIB.BASEBOARD_FAB2(SCH_1):PVDDQ_GHJ
   2    GND      B @BASEBOARD_FAB2_LIB.BASEBOARD_FAB2(SCH_1):GND

CAP_A_0603V-22.0UF,4V,20%,X6S,A  I234  C7T5
   1 PVDDQ_GHJ      A @BASEBOARD_FAB2_LIB.BASEBOARD_FAB2(SCH_1):PVDDQ_GHJ
   2    GND      B @BASEBOARD_FAB2_LIB.BASEBOARD_FAB2(SCH_1):GND

CAP_A_0603V-22.0UF,4V,20%,X6S,A  I235  C7T4
   1 PVDDQ_GHJ      A @BASEBOARD_FAB2_LIB.BASEBOARD_FAB2(SCH_1):PVDDQ_GHJ
   2    GND      B @BASEBOARD_FAB2_LIB.BASEBOARD_FAB2(SCH_1):GND

CAP_A_0603V-22.0UF,4V,20%,X6S,A  I236  C8U3
   1 PVDDQ_GHJ      A @BASEBOARD_FAB2_LIB.BASEBOARD_FAB2(SCH_1):PVDDQ_GHJ
   2    GND      B @BASEBOARD_FAB2_LIB.BASEBOARD_FAB2(SCH_1):GND

CAP_A_0603V-22.0UF,4V,20%,X6S,A  I237  C7U1
   1 PVDDQ_GHJ      A @BASEBOARD_FAB2_LIB.BASEBOARD_FAB2(SCH_1):PVDDQ_GHJ
   2    GND      B @BASEBOARD_FAB2_LIB.BASEBOARD_FAB2(SCH_1):GND

CAP_A_0603V-22.0UF,4V,20%,X6S,A  I238  C7U2
   1 PVDDQ_GHJ      A @BASEBOARD_FAB2_LIB.BASEBOARD_FAB2(SCH_1):PVDDQ_GHJ
   2    GND      B @BASEBOARD_FAB2_LIB.BASEBOARD_FAB2(SCH_1):GND

CAP_A_0603V-22.0UF,4V,20%,X6S,A  I239  C8U2
   1 PVDDQ_GHJ      A @BASEBOARD_FAB2_LIB.BASEBOARD_FAB2(SCH_1):PVDDQ_GHJ
   2    GND      B @BASEBOARD_FAB2_LIB.BASEBOARD_FAB2(SCH_1):GND

CAP_A_0603V-22.0UF,4V,20%,X6S,A  I241  C8U7
   1 PVDDQ_GHJ      A @BASEBOARD_FAB2_LIB.BASEBOARD_FAB2(SCH_1):PVDDQ_GHJ
   2    GND      B @BASEBOARD_FAB2_LIB.BASEBOARD_FAB2(SCH_1):GND

SHUNT_SH0201-EMPTY,N_A  I243  SH7U1
   1 VSENSE_PVDDQ_GHJ_P      A @BASEBOARD_FAB2_LIB.BASEBOARD_FAB2(SCH_1):VSENSE_PVDDQ_GHJ_P
   2 PVDDQ_GHJ      B @BASEBOARD_FAB2_LIB.BASEBOARD_FAB2(SCH_1):PVDDQ_GHJ

SHUNT_SH0201-EMPTY,N_A  I244  SH7U2
   1 VSENSE_PVDDQ_GHJ_N      A @BASEBOARD_FAB2_LIB.BASEBOARD_FAB2(SCH_1):VSENSE_PVDDQ_GHJ_N
   2    GND      B @BASEBOARD_FAB2_LIB.BASEBOARD_FAB2(SCH_1):GND


DRAWING: @BASEBOARD_FAB2_LIB.BASEBOARD_FAB2(SCH_1):PAGE226 

RES_0402-100.0,1%,1/16W,EMPTY,A  I8  R9M7
   1 PVCCIO_CPU1      A @BASEBOARD_FAB2_LIB.BASEBOARD_FAB2(SCH_1):PVCCIO_CPU1
   2 SVID_DIO1_CPU1_R      B @BASEBOARD_FAB2_LIB.BASEBOARD_FAB2(SCH_1):SVID_DIO1_CPU1_R

RES_0402-2.26K,1.0%,1/16W,EMPTA  I13  R1B13
   1 P3V3_STBY      A @BASEBOARD_FAB2_LIB.BASEBOARD_FAB2(SCH_1):P3V3_STBY
   2 PU_VR_PVDDQ_KLM_FAULT1      B @BASEBOARD_FAB2_LIB.BASEBOARD_FAB2(SCH_1):PU_VR_PVDDQ_KLM_FAULT1

RES_0402-22.1,1.0%,1/16W,CHIP,A  I14  R1B5
   1 PWRGD_PVDDQ_KLM_R      A @BASEBOARD_FAB2_LIB.BASEBOARD_FAB2(SCH_1):PWRGD_PVDDQ_KLM_R
   2 PWRGD_PVDDQ_KLM      B @BASEBOARD_FAB2_LIB.BASEBOARD_FAB2(SCH_1):PWRGD_PVDDQ_KLM

RES_0402-0.0,5%,1/16W,CHIP,G21A  I16  R1B11
   1 SVID_ALERT_PVDDQ_KLM      A @BASEBOARD_FAB2_LIB.BASEBOARD_FAB2(SCH_1):SVID_ALERT_PVDDQ_KLM
   2 SVID_ALERT1_CPU1_R_N      B @BASEBOARD_FAB2_LIB.BASEBOARD_FAB2(SCH_1):SVID_ALERT1_CPU1_R_N

RES_0402-1.00K,1%,1/16W,CHIP,GA  I17  R1B2
   1 P3V3_STBY      A @BASEBOARD_FAB2_LIB.BASEBOARD_FAB2(SCH_1):P3V3_STBY
   2 PWRGD_PVDDQ_KLM_R      B @BASEBOARD_FAB2_LIB.BASEBOARD_FAB2(SCH_1):PWRGD_PVDDQ_KLM_R

RES_0402-20.0,1%,1/16W,CHIP,G2A  I21  R1B6
   1 SMB_VR_SCL_VDDQ_KLM      A @BASEBOARD_FAB2_LIB.BASEBOARD_FAB2(SCH_1):SMB_VR_SCL_VDDQ_KLM
   2 SMB_VR_STBY_LVC3_SCL      B @BASEBOARD_FAB2_LIB.BASEBOARD_FAB2(SCH_1):SMB_VR_STBY_LVC3_SCL

RES_0402-20.0,1%,1/16W,CHIP,G2A  I22  R1B7
   1 SMB_VR_SDA_VDDQ_KLM      A @BASEBOARD_FAB2_LIB.BASEBOARD_FAB2(SCH_1):SMB_VR_SDA_VDDQ_KLM
   2 SMB_VR_STBY_LVC3_SDA      B @BASEBOARD_FAB2_LIB.BASEBOARD_FAB2(SCH_1):SMB_VR_STBY_LVC3_SDA

RES_0402-0.0,5%,1/16W,CHIP,G21A  I23  R1B10
   1 SVID_VDIO_PVDDQ_KLM      A @BASEBOARD_FAB2_LIB.BASEBOARD_FAB2(SCH_1):SVID_VDIO_PVDDQ_KLM
   2 SVID_DIO1_CPU1_R      B @BASEBOARD_FAB2_LIB.BASEBOARD_FAB2(SCH_1):SVID_DIO1_CPU1_R

CAP_A_0402V-1.0UF,6.3V,10%,X6SA  I25  C1B6
   1 VR_PVDDQ_KLM_VDD      A @BASEBOARD_FAB2_LIB.BASEBOARD_FAB2(SCH_1):VR_PVDDQ_KLM_VDD
   2    GND      B @BASEBOARD_FAB2_LIB.BASEBOARD_FAB2(SCH_1):GND

CAP_A_0402V-0.1UF,16V,10%,X7R,A  I27  C1B5
   1 VR_PVDDQ_KLM_VDD      A @BASEBOARD_FAB2_LIB.BASEBOARD_FAB2(SCH_1):VR_PVDDQ_KLM_VDD
   2    GND      B @BASEBOARD_FAB2_LIB.BASEBOARD_FAB2(SCH_1):GND

RES_0402-0.0,5%,1/16W,CHIP,G21A  I30  R9M3
   1 P3V3_STBY      A @BASEBOARD_FAB2_LIB.BASEBOARD_FAB2(SCH_1):P3V3_STBY
   2 VR_PVDDQ_KLM_VDD      B @BASEBOARD_FAB2_LIB.BASEBOARD_FAB2(SCH_1):VR_PVDDQ_KLM_VDD

RES_0402-10.0,1%,1/16W,CHIP,G2A  I32  R1B16
   1 VSENSE_PVDDQ_KLM_P      A @BASEBOARD_FAB2_LIB.BASEBOARD_FAB2(SCH_1):VSENSE_PVDDQ_KLM_P
   2 VR_PVDDQ_KLM_AVSP      B @BASEBOARD_FAB2_LIB.BASEBOARD_FAB2(SCH_1):VR_PVDDQ_KLM_AVSP

CAP_0402LF-220PF,50V,10%,X7R,AA  I36  C1B11
   1 A_TSENSE_PVDDQ_KLM      A @BASEBOARD_FAB2_LIB.BASEBOARD_FAB2(SCH_1):A_TSENSE_PVDDQ_KLM
   2    GND      B @BASEBOARD_FAB2_LIB.BASEBOARD_FAB2(SCH_1):GND

CAP_0402LF-220PF,50V,10%,X7R,AA  I39  C1B12
   1 VR_PVDDQ_KLM_AVSP      A @BASEBOARD_FAB2_LIB.BASEBOARD_FAB2(SCH_1):VR_PVDDQ_KLM_AVSP
   2 VSENSE_PVDDQ_KLM_N      B @BASEBOARD_FAB2_LIB.BASEBOARD_FAB2(SCH_1):VSENSE_PVDDQ_KLM_N

CAP_A_0402V-1.0UF,6.3V,10%,X6SA  I41  C1B3
   1 VR_PVDDQ_KLM_VD12      A @BASEBOARD_FAB2_LIB.BASEBOARD_FAB2(SCH_1):VR_PVDDQ_KLM_VD12
   2    GND      B @BASEBOARD_FAB2_LIB.BASEBOARD_FAB2(SCH_1):GND

CAP_A_0402V-0.1UF,16V,10%,X7R,A  I44  C1B2
   1 VR_PVDDQ_KLM_VD12      A @BASEBOARD_FAB2_LIB.BASEBOARD_FAB2(SCH_1):VR_PVDDQ_KLM_VD12
   2    GND      B @BASEBOARD_FAB2_LIB.BASEBOARD_FAB2(SCH_1):GND

RES_0402-49.9,1%,1/16W,CHIP,G2A  I50  R9M6
   1 PVCCIO_CPU1      A @BASEBOARD_FAB2_LIB.BASEBOARD_FAB2(SCH_1):PVCCIO_CPU1
   2 SVID_CLK1_CPU1_R      B @BASEBOARD_FAB2_LIB.BASEBOARD_FAB2(SCH_1):SVID_CLK1_CPU1_R

RES_0402-150.0,1%,1/16W,CHIP,GA  I53  R1B8
   1 SVID_CLK1_CPU1_R      A @BASEBOARD_FAB2_LIB.BASEBOARD_FAB2(SCH_1):SVID_CLK1_CPU1_R
   2 SVID_CLK_PVDDQ_KLM      B @BASEBOARD_FAB2_LIB.BASEBOARD_FAB2(SCH_1):SVID_CLK_PVDDQ_KLM

RES_0402-100.0K,1%,1/16W,CHIP,B  I57  R9M8
   1 VR_FET_SW_P12V_STBY_PVDDQ_KLM      A @BASEBOARD_FAB2_LIB.BASEBOARD_FAB2(SCH_1):VR_FET_SW_P12V_STBY_PVDDQ_KLM
   2 VR_PVDDQ_KLM_VINSEN      B @BASEBOARD_FAB2_LIB.BASEBOARD_FAB2(SCH_1):VR_PVDDQ_KLM_VINSEN

RES_0402-1.5K,1%,1/16W,CHIP,G2A  I58  R1B9
   1 VR_PVDDQ_KLM_VINSEN      A @BASEBOARD_FAB2_LIB.BASEBOARD_FAB2(SCH_1):VR_PVDDQ_KLM_VINSEN
   2    GND      B @BASEBOARD_FAB2_LIB.BASEBOARD_FAB2(SCH_1):GND

CAP_0402LF-1000PF,50V,10%,X7R,A  I59  C1B8
   1 VR_PVDDQ_KLM_VINSEN      A @BASEBOARD_FAB2_LIB.BASEBOARD_FAB2(SCH_1):VR_PVDDQ_KLM_VINSEN
   2    GND      B @BASEBOARD_FAB2_LIB.BASEBOARD_FAB2(SCH_1):GND

RES_0402-5.36K,1.0%,1/16W,CHIPA  I77  R1B15
   1 VR_PVDDQ_KLM_XADDR2      A @BASEBOARD_FAB2_LIB.BASEBOARD_FAB2(SCH_1):VR_PVDDQ_KLM_XADDR2
   2    GND      B @BASEBOARD_FAB2_LIB.BASEBOARD_FAB2(SCH_1):GND

RES_0402-3.16K,1%,1/16W,CHIP,GA  I78  R1B12
   1 VR_PVDDQ_KLM_XADDR1      A @BASEBOARD_FAB2_LIB.BASEBOARD_FAB2(SCH_1):VR_PVDDQ_KLM_XADDR1
   2    GND      B @BASEBOARD_FAB2_LIB.BASEBOARD_FAB2(SCH_1):GND

RES_0402-1.00K,1%,1/16W,CHIP,GA  I79  R1B1
   1 P3V3_STBY      A @BASEBOARD_FAB2_LIB.BASEBOARD_FAB2(SCH_1):P3V3_STBY
   2 IRQ_PVDDQ_KLM_VRHOT_LVT3_R_N      B @BASEBOARD_FAB2_LIB.BASEBOARD_FAB2(SCH_1):IRQ_PVDDQ_KLM_VRHOT_LVT3_R_N

CAP_0402LF-1000PF,50V,10%,X7R,A  I80  C1B4
   1 PWRGD_PVDDQ_KLM_R      A @BASEBOARD_FAB2_LIB.BASEBOARD_FAB2(SCH_1):PWRGD_PVDDQ_KLM_R
   2    GND      B @BASEBOARD_FAB2_LIB.BASEBOARD_FAB2(SCH_1):GND

RES_0402-33.2,1%,1/16W,CHIP,G2A  I82  R1B4
   1 IRQ_PVDDQ_KLM_VRHOT_LVT3_R_N      A @BASEBOARD_FAB2_LIB.BASEBOARD_FAB2(SCH_1):IRQ_PVDDQ_KLM_VRHOT_LVT3_R_N
   2 IRQ_PVDDQ_KLM_VRHOT_LVT3_N      B @BASEBOARD_FAB2_LIB.BASEBOARD_FAB2(SCH_1):IRQ_PVDDQ_KLM_VRHOT_LVT3_N

RES_0402-0.0,5%,1/16W,CHIP,G21A  I84  R9M9
   1 FM_PVDDQ_KLM_EN      A @BASEBOARD_FAB2_LIB.BASEBOARD_FAB2(SCH_1):FM_PVDDQ_KLM_EN
   2 VR_PVDDQ_KLM_VREN      B @BASEBOARD_FAB2_LIB.BASEBOARD_FAB2(SCH_1):VR_PVDDQ_KLM_VREN

RES_0402-100.0K,1%,1/16W,EMPTYA  I85  R9M5
   1 P3V3_STBY      A @BASEBOARD_FAB2_LIB.BASEBOARD_FAB2(SCH_1):P3V3_STBY
   2 VR_PVDDQ_KLM_VREN      B @BASEBOARD_FAB2_LIB.BASEBOARD_FAB2(SCH_1):VR_PVDDQ_KLM_VREN

RES_0402-0.0,5%,1/16W,CHIP,G21A  I87  R9M11
   1 VR_PVDDQ_KLM_VD12      A @BASEBOARD_FAB2_LIB.BASEBOARD_FAB2(SCH_1):VR_PVDDQ_KLM_VD12
   2 VR_PVDDQ_KLM_AIREF1      B @BASEBOARD_FAB2_LIB.BASEBOARD_FAB2(SCH_1):VR_PVDDQ_KLM_AIREF1

RES_0402-0.0,5%,1/16W,CHIP,G21A  I88  R9M10
   1 VR_PVDDQ_KLM_VD12      A @BASEBOARD_FAB2_LIB.BASEBOARD_FAB2(SCH_1):VR_PVDDQ_KLM_VD12
   2 VR_PVDDQ_KLM_AIREF2      B @BASEBOARD_FAB2_LIB.BASEBOARD_FAB2(SCH_1):VR_PVDDQ_KLM_AIREF2

PXM1310B_QFN-IC,H89186-001  I90  EU1B1
   1 TP_PVDDQ_KLM_BPWM1  BPWM1 @BASEBOARD_FAB2_LIB.BASEBOARD_FAB2(SCH_1):TP_PVDDQ_KLM_BPWM1
   2 NC_PVDDQ_KLM_DNC0 DNC<0> @BASEBOARD_FAB2_LIB.BASEBOARD_FAB2(SCH_1):NC_PVDDQ_KLM_DNC0
   3 NC_PVDDQ_KLM_PWM3  APWM3 @BASEBOARD_FAB2_LIB.BASEBOARD_FAB2(SCH_1):NC_PVDDQ_KLM_PWM3
   4 VR_PVDDQ_KLM_PWM2  APWM2 @BASEBOARD_FAB2_LIB.BASEBOARD_FAB2(SCH_1):VR_PVDDQ_KLM_PWM2
   5 VR_PVDDQ_KLM_PWM1  APWM1 @BASEBOARD_FAB2_LIB.BASEBOARD_FAB2(SCH_1):VR_PVDDQ_KLM_PWM1
   6 SMB_VR_SDA_VDDQ_KLM    SDA @BASEBOARD_FAB2_LIB.BASEBOARD_FAB2(SCH_1):SMB_VR_SDA_VDDQ_KLM
   7 SMB_VR_SCL_VDDQ_KLM    SCL @BASEBOARD_FAB2_LIB.BASEBOARD_FAB2(SCH_1):SMB_VR_SCL_VDDQ_KLM
   8 TP_PVDDQ_KLM_RESET_N RESET_N @BASEBOARD_FAB2_LIB.BASEBOARD_FAB2(SCH_1):TP_PVDDQ_KLM_RESET_N
   9 PWRGD_PVDDQ_KLM_R AVRRDY @BASEBOARD_FAB2_LIB.BASEBOARD_FAB2(SCH_1):PWRGD_PVDDQ_KLM_R
  10 VR_PVDDQ_KLM_VREN  AVREN @BASEBOARD_FAB2_LIB.BASEBOARD_FAB2(SCH_1):VR_PVDDQ_KLM_VREN
  11 IRQ_PVDDQ_KLM_VRHOT_LVT3_R_N VRHOT_N @BASEBOARD_FAB2_LIB.BASEBOARD_FAB2(SCH_1):IRQ_PVDDQ_KLM_VRHOT_LVT3_R_N
  12 NC_PVDDQ_KLM_PINALRT_N PINALRT_N @BASEBOARD_FAB2_LIB.BASEBOARD_FAB2(SCH_1):NC_PVDDQ_KLM_PINALRT_N
  13 PU_VR_PVDDQ_KLM_FAULT1    MP0 @BASEBOARD_FAB2_LIB.BASEBOARD_FAB2(SCH_1):PU_VR_PVDDQ_KLM_FAULT1
  14 NC_PVDDQ_KLM_GP1    MP1 @BASEBOARD_FAB2_LIB.BASEBOARD_FAB2(SCH_1):NC_PVDDQ_KLM_GP1
  15 SVID_CLK_PVDDQ_KLM   VCLK @BASEBOARD_FAB2_LIB.BASEBOARD_FAB2(SCH_1):SVID_CLK_PVDDQ_KLM
  16 SVID_VDIO_PVDDQ_KLM   VDIO @BASEBOARD_FAB2_LIB.BASEBOARD_FAB2(SCH_1):SVID_VDIO_PVDDQ_KLM
  17 SVID_ALERT_PVDDQ_KLM VALRT_N @BASEBOARD_FAB2_LIB.BASEBOARD_FAB2(SCH_1):SVID_ALERT_PVDDQ_KLM
  18 NC_PVDDQ_KLM_GP0    MP2 @BASEBOARD_FAB2_LIB.BASEBOARD_FAB2(SCH_1):NC_PVDDQ_KLM_GP0
  19 VR_PVDDQ_KLM_AVSP  AVSEN @BASEBOARD_FAB2_LIB.BASEBOARD_FAB2(SCH_1):VR_PVDDQ_KLM_AVSP
  20 VSENSE_PVDDQ_KLM_N  AVREF @BASEBOARD_FAB2_LIB.BASEBOARD_FAB2(SCH_1):VSENSE_PVDDQ_KLM_N
  21 VR_PVDDQ_KLM_AIREF1 AIREF1 @BASEBOARD_FAB2_LIB.BASEBOARD_FAB2(SCH_1):VR_PVDDQ_KLM_AIREF1
  22 ISENSE_PVDDQ_KLM_PH1_IMON AISEN1 @BASEBOARD_FAB2_LIB.BASEBOARD_FAB2(SCH_1):ISENSE_PVDDQ_KLM_PH1_IMON
  23 VR_PVDDQ_KLM_AIREF2 AIREF2 @BASEBOARD_FAB2_LIB.BASEBOARD_FAB2(SCH_1):VR_PVDDQ_KLM_AIREF2
  24 ISENSE_PVDDQ_KLM_PH2_IMON AISEN2 @BASEBOARD_FAB2_LIB.BASEBOARD_FAB2(SCH_1):ISENSE_PVDDQ_KLM_PH2_IMON
  25 TP_PVDDQ_KLM_PH3_IMON_REF AIREF3 @BASEBOARD_FAB2_LIB.BASEBOARD_FAB2(SCH_1):TP_PVDDQ_KLM_PH3_IMON_REF
  26 TP_PVDDQ_KLM_PH3_IMON AISEN3 @BASEBOARD_FAB2_LIB.BASEBOARD_FAB2(SCH_1):TP_PVDDQ_KLM_PH3_IMON
  27    GND    GND @BASEBOARD_FAB2_LIB.BASEBOARD_FAB2(SCH_1):GND
  28 NC_PVDDQ_KLM_DNC1 DNC<1> @BASEBOARD_FAB2_LIB.BASEBOARD_FAB2(SCH_1):NC_PVDDQ_KLM_DNC1
  29 TP_PVDDQ_KLM_BVSEN  BVSEN @BASEBOARD_FAB2_LIB.BASEBOARD_FAB2(SCH_1):TP_PVDDQ_KLM_BVSEN
  30 TP_PVDDQ_KLM_BVREF  BVREF @BASEBOARD_FAB2_LIB.BASEBOARD_FAB2(SCH_1):TP_PVDDQ_KLM_BVREF
  31 TP_PVDDQ_KLM_BREF1 BIREF1 @BASEBOARD_FAB2_LIB.BASEBOARD_FAB2(SCH_1):TP_PVDDQ_KLM_BREF1
  32    GND BISEN1 @BASEBOARD_FAB2_LIB.BASEBOARD_FAB2(SCH_1):GND
  33 VR_PVDDQ_KLM_XADDR2 XADDR2 @BASEBOARD_FAB2_LIB.BASEBOARD_FAB2(SCH_1):VR_PVDDQ_KLM_XADDR2
  34 TP_PVDDQ_KLM_BTSEN  BTSEN @BASEBOARD_FAB2_LIB.BASEBOARD_FAB2(SCH_1):TP_PVDDQ_KLM_BTSEN
  35 A_TSENSE_PVDDQ_KLM  ATSEN @BASEBOARD_FAB2_LIB.BASEBOARD_FAB2(SCH_1):A_TSENSE_PVDDQ_KLM
  36 VR_PVDDQ_KLM_XADDR1 XADDR1 @BASEBOARD_FAB2_LIB.BASEBOARD_FAB2(SCH_1):VR_PVDDQ_KLM_XADDR1
  37 VR_PVDDQ_KLM_VINSEN VINSEN @BASEBOARD_FAB2_LIB.BASEBOARD_FAB2(SCH_1):VR_PVDDQ_KLM_VINSEN
  38 VR_PVDDQ_KLM_AIINSEN IINSEN @BASEBOARD_FAB2_LIB.BASEBOARD_FAB2(SCH_1):VR_PVDDQ_KLM_AIINSEN
  39 VR_PVDDQ_KLM_VDD    VDD @BASEBOARD_FAB2_LIB.BASEBOARD_FAB2(SCH_1):VR_PVDDQ_KLM_VDD
  40 VR_PVDDQ_KLM_VD12   VD12 @BASEBOARD_FAB2_LIB.BASEBOARD_FAB2(SCH_1):VR_PVDDQ_KLM_VD12
  41    GND  THPAD @BASEBOARD_FAB2_LIB.BASEBOARD_FAB2(SCH_1):GND

CAP_A_0402V-0.1UF,16V,10%,X7R,A  I92  C9M11
   1 VR_PVDDQ_KLM_AIINSEN      A @BASEBOARD_FAB2_LIB.BASEBOARD_FAB2(SCH_1):VR_PVDDQ_KLM_AIINSEN
   2    GND      B @BASEBOARD_FAB2_LIB.BASEBOARD_FAB2(SCH_1):GND


DRAWING: @BASEBOARD_FAB2_LIB.BASEBOARD_FAB2(SCH_1):PAGE228 

RES_0603-120.0,1%,1/10W,CHIP,GA  I58  R1A1
   1 PVDDQ_KLM      A @BASEBOARD_FAB2_LIB.BASEBOARD_FAB2(SCH_1):PVDDQ_KLM
   2    GND      B @BASEBOARD_FAB2_LIB.BASEBOARD_FAB2(SCH_1):GND

RES_0402-100.0,1%,1/16W,EMPTY,A  I74  R7L2
   1 VSENSE_PVDDQ_KLM_P      A @BASEBOARD_FAB2_LIB.BASEBOARD_FAB2(SCH_1):VSENSE_PVDDQ_KLM_P
   2 VSENSE_PVDDQ_KLM_N      B @BASEBOARD_FAB2_LIB.BASEBOARD_FAB2(SCH_1):VSENSE_PVDDQ_KLM_N

CAPP_3018-470UF,2.5V,20%,ALUM,A  I75  C9L9
   1 PVDDQ_KLM      A @BASEBOARD_FAB2_LIB.BASEBOARD_FAB2(SCH_1):PVDDQ_KLM
   2    GND      B @BASEBOARD_FAB2_LIB.BASEBOARD_FAB2(SCH_1):GND

CAPP_3018-470UF,2.5V,20%,ALUM,A  I76  C9L12
   1 PVDDQ_KLM      A @BASEBOARD_FAB2_LIB.BASEBOARD_FAB2(SCH_1):PVDDQ_KLM
   2    GND      B @BASEBOARD_FAB2_LIB.BASEBOARD_FAB2(SCH_1):GND

CAPP_3018-470UF,2.5V,20%,ALUM,A  I77  C9L4
   1 PVDDQ_KLM      A @BASEBOARD_FAB2_LIB.BASEBOARD_FAB2(SCH_1):PVDDQ_KLM
   2    GND      B @BASEBOARD_FAB2_LIB.BASEBOARD_FAB2(SCH_1):GND

CAPP_3018-470UF,2.5V,20%,ALUM,A  I78  C9L2
   1 PVDDQ_KLM      A @BASEBOARD_FAB2_LIB.BASEBOARD_FAB2(SCH_1):PVDDQ_KLM
   2    GND      B @BASEBOARD_FAB2_LIB.BASEBOARD_FAB2(SCH_1):GND

CAP_0805-100UF,4V,20%,X5R,6024A  I82  C2A8
   1 PVDDQ_KLM      A @BASEBOARD_FAB2_LIB.BASEBOARD_FAB2(SCH_1):PVDDQ_KLM
   2    GND      B @BASEBOARD_FAB2_LIB.BASEBOARD_FAB2(SCH_1):GND

CAP_0805-100UF,4V,20%,X5R,6024A  I83  C8L2
   1 PVDDQ_KLM      A @BASEBOARD_FAB2_LIB.BASEBOARD_FAB2(SCH_1):PVDDQ_KLM
   2    GND      B @BASEBOARD_FAB2_LIB.BASEBOARD_FAB2(SCH_1):GND

CAP_0805-100UF,4V,20%,X5R,6024A  I88  C8L11
   1 PVDDQ_KLM      A @BASEBOARD_FAB2_LIB.BASEBOARD_FAB2(SCH_1):PVDDQ_KLM
   2    GND      B @BASEBOARD_FAB2_LIB.BASEBOARD_FAB2(SCH_1):GND

CAP_0805-100UF,4V,20%,X5R,6024A  I89  C2A16
   1 PVDDQ_KLM      A @BASEBOARD_FAB2_LIB.BASEBOARD_FAB2(SCH_1):PVDDQ_KLM
   2    GND      B @BASEBOARD_FAB2_LIB.BASEBOARD_FAB2(SCH_1):GND

CAP_0805-100UF,4V,20%,X5R,6024A  I90  C8M7
   1 PVDDQ_KLM      A @BASEBOARD_FAB2_LIB.BASEBOARD_FAB2(SCH_1):PVDDQ_KLM
   2    GND      B @BASEBOARD_FAB2_LIB.BASEBOARD_FAB2(SCH_1):GND

CAP_0805-100UF,4V,20%,X5R,6024A  I91  C8M11
   1 PVDDQ_KLM      A @BASEBOARD_FAB2_LIB.BASEBOARD_FAB2(SCH_1):PVDDQ_KLM
   2    GND      B @BASEBOARD_FAB2_LIB.BASEBOARD_FAB2(SCH_1):GND

CAP_0805-100UF,4V,20%,X5R,6024A  I92  C7L1
   1 PVDDQ_KLM      A @BASEBOARD_FAB2_LIB.BASEBOARD_FAB2(SCH_1):PVDDQ_KLM
   2    GND      B @BASEBOARD_FAB2_LIB.BASEBOARD_FAB2(SCH_1):GND

CAP_0805-100UF,4V,20%,X5R,6024A  I110  C8L1
   1 PVDDQ_KLM      A @BASEBOARD_FAB2_LIB.BASEBOARD_FAB2(SCH_1):PVDDQ_KLM
   2    GND      B @BASEBOARD_FAB2_LIB.BASEBOARD_FAB2(SCH_1):GND

INDUCTOR_SM-100NH,IND,D92183-0B  I124  L1B1
   1 P12V_STBY    INA @BASEBOARD_FAB2_LIB.BASEBOARD_FAB2(SCH_1):P12V_STBY
   2 VR_FET_SW_P12V_STBY_PVDDQ_KLM    INB @BASEBOARD_FAB2_LIB.BASEBOARD_FAB2(SCH_1):VR_FET_SW_P12V_STBY_PVDDQ_KLM

CAPP_2626-270UF,16V,20%,OSCON,A  I175  C1B10
   1 VR_FET_SW_P12V_STBY_PVDDQ_KLM      A @BASEBOARD_FAB2_LIB.BASEBOARD_FAB2(SCH_1):VR_FET_SW_P12V_STBY_PVDDQ_KLM
   2    GND      B @BASEBOARD_FAB2_LIB.BASEBOARD_FAB2(SCH_1):GND

CAP_0805LF-22UF,4V,20%,X6S,C95A  I183  C8P2
   1 PVDDQ_KLM      A @BASEBOARD_FAB2_LIB.BASEBOARD_FAB2(SCH_1):PVDDQ_KLM
   2    GND      B @BASEBOARD_FAB2_LIB.BASEBOARD_FAB2(SCH_1):GND

CAP_0805LF-22UF,4V,20%,X6S,C95A  I185  C8P1
   1 PVDDQ_KLM      A @BASEBOARD_FAB2_LIB.BASEBOARD_FAB2(SCH_1):PVDDQ_KLM
   2    GND      B @BASEBOARD_FAB2_LIB.BASEBOARD_FAB2(SCH_1):GND

CAP_0603LF-10UF,4V,20%,X6S,E15A  I186  C2D7
   1 PVDDQ_KLM      A @BASEBOARD_FAB2_LIB.BASEBOARD_FAB2(SCH_1):PVDDQ_KLM
   2    GND      B @BASEBOARD_FAB2_LIB.BASEBOARD_FAB2(SCH_1):GND

CAP_0603LF-10UF,4V,20%,X6S,E15A  I187  C2D4
   1 PVDDQ_KLM      A @BASEBOARD_FAB2_LIB.BASEBOARD_FAB2(SCH_1):PVDDQ_KLM
   2    GND      B @BASEBOARD_FAB2_LIB.BASEBOARD_FAB2(SCH_1):GND

CAP_0603LF-10UF,4V,20%,X6S,E15A  I188  C2D5
   1 PVDDQ_KLM      A @BASEBOARD_FAB2_LIB.BASEBOARD_FAB2(SCH_1):PVDDQ_KLM
   2    GND      B @BASEBOARD_FAB2_LIB.BASEBOARD_FAB2(SCH_1):GND

CAP_0603LF-10UF,4V,20%,X6S,E15A  I190  C2D6
   1 PVDDQ_KLM      A @BASEBOARD_FAB2_LIB.BASEBOARD_FAB2(SCH_1):PVDDQ_KLM
   2    GND      B @BASEBOARD_FAB2_LIB.BASEBOARD_FAB2(SCH_1):GND

CAP_A_0603V-47UF,4V,20%,X5R,60A  I198  C8M8
   1 PVDDQ_KLM      A @BASEBOARD_FAB2_LIB.BASEBOARD_FAB2(SCH_1):PVDDQ_KLM
   2    GND      B @BASEBOARD_FAB2_LIB.BASEBOARD_FAB2(SCH_1):GND

CAP_A_0603V-47UF,4V,20%,X5R,60A  I199  C2A5
   1 PVDDQ_KLM      A @BASEBOARD_FAB2_LIB.BASEBOARD_FAB2(SCH_1):PVDDQ_KLM
   2    GND      B @BASEBOARD_FAB2_LIB.BASEBOARD_FAB2(SCH_1):GND

CAP_A_0603V-47UF,4V,20%,X5R,60A  I200  C2B1
   1 PVDDQ_KLM      A @BASEBOARD_FAB2_LIB.BASEBOARD_FAB2(SCH_1):PVDDQ_KLM
   2    GND      B @BASEBOARD_FAB2_LIB.BASEBOARD_FAB2(SCH_1):GND

CAP_A_0603V-47UF,4V,20%,X5R,60A  I201  C8L12
   1 PVDDQ_KLM      A @BASEBOARD_FAB2_LIB.BASEBOARD_FAB2(SCH_1):PVDDQ_KLM
   2    GND      B @BASEBOARD_FAB2_LIB.BASEBOARD_FAB2(SCH_1):GND

CAP_A_0603V-47UF,4V,20%,X5R,60A  I202  C7M5
   1 PVDDQ_KLM      A @BASEBOARD_FAB2_LIB.BASEBOARD_FAB2(SCH_1):PVDDQ_KLM
   2    GND      B @BASEBOARD_FAB2_LIB.BASEBOARD_FAB2(SCH_1):GND

CAP_A_0603V-47UF,4V,20%,X5R,60A  I203  C8M10
   1 PVDDQ_KLM      A @BASEBOARD_FAB2_LIB.BASEBOARD_FAB2(SCH_1):PVDDQ_KLM
   2    GND      B @BASEBOARD_FAB2_LIB.BASEBOARD_FAB2(SCH_1):GND

CAP_A_0603V-47UF,4V,20%,X5R,60A  I204  C2B2
   1 PVDDQ_KLM      A @BASEBOARD_FAB2_LIB.BASEBOARD_FAB2(SCH_1):PVDDQ_KLM
   2    GND      B @BASEBOARD_FAB2_LIB.BASEBOARD_FAB2(SCH_1):GND

CAP_A_0603V-47UF,4V,20%,X5R,60A  I205  C8M9
   1 PVDDQ_KLM      A @BASEBOARD_FAB2_LIB.BASEBOARD_FAB2(SCH_1):PVDDQ_KLM
   2    GND      B @BASEBOARD_FAB2_LIB.BASEBOARD_FAB2(SCH_1):GND

CAP_A_0603V-47UF,4V,20%,X5R,60A  I206  C8M2
   1 PVDDQ_KLM      A @BASEBOARD_FAB2_LIB.BASEBOARD_FAB2(SCH_1):PVDDQ_KLM
   2    GND      B @BASEBOARD_FAB2_LIB.BASEBOARD_FAB2(SCH_1):GND

CAP_A_0603V-22.0UF,4V,20%,X6S,A  I209  C2A2
   1 PVDDQ_KLM      A @BASEBOARD_FAB2_LIB.BASEBOARD_FAB2(SCH_1):PVDDQ_KLM
   2    GND      B @BASEBOARD_FAB2_LIB.BASEBOARD_FAB2(SCH_1):GND

CAP_A_0603V-22.0UF,4V,20%,X6S,A  I210  C2A1
   1 PVDDQ_KLM      A @BASEBOARD_FAB2_LIB.BASEBOARD_FAB2(SCH_1):PVDDQ_KLM
   2    GND      B @BASEBOARD_FAB2_LIB.BASEBOARD_FAB2(SCH_1):GND

CAP_A_0603V-22.0UF,4V,20%,X6S,A  I211  C2A12
   1 PVDDQ_KLM      A @BASEBOARD_FAB2_LIB.BASEBOARD_FAB2(SCH_1):PVDDQ_KLM
   2    GND      B @BASEBOARD_FAB2_LIB.BASEBOARD_FAB2(SCH_1):GND

CAP_A_0603V-22.0UF,4V,20%,X6S,A  I212  C2A13
   1 PVDDQ_KLM      A @BASEBOARD_FAB2_LIB.BASEBOARD_FAB2(SCH_1):PVDDQ_KLM
   2    GND      B @BASEBOARD_FAB2_LIB.BASEBOARD_FAB2(SCH_1):GND

CAP_A_0603V-22.0UF,4V,20%,X6S,A  I213  C2A11
   1 PVDDQ_KLM      A @BASEBOARD_FAB2_LIB.BASEBOARD_FAB2(SCH_1):PVDDQ_KLM
   2    GND      B @BASEBOARD_FAB2_LIB.BASEBOARD_FAB2(SCH_1):GND

CAP_A_0603V-22.0UF,4V,20%,X6S,A  I214  C2A10
   1 PVDDQ_KLM      A @BASEBOARD_FAB2_LIB.BASEBOARD_FAB2(SCH_1):PVDDQ_KLM
   2    GND      B @BASEBOARD_FAB2_LIB.BASEBOARD_FAB2(SCH_1):GND

CAP_A_0603V-22.0UF,4V,20%,X6S,A  I215  C2A9
   1 PVDDQ_KLM      A @BASEBOARD_FAB2_LIB.BASEBOARD_FAB2(SCH_1):PVDDQ_KLM
   2    GND      B @BASEBOARD_FAB2_LIB.BASEBOARD_FAB2(SCH_1):GND

CAP_A_0603V-22.0UF,4V,20%,X6S,A  I216  C3A2
   1 PVDDQ_KLM      A @BASEBOARD_FAB2_LIB.BASEBOARD_FAB2(SCH_1):PVDDQ_KLM
   2    GND      B @BASEBOARD_FAB2_LIB.BASEBOARD_FAB2(SCH_1):GND

CAP_A_0603V-22.0UF,4V,20%,X6S,A  I217  C3A1
   1 PVDDQ_KLM      A @BASEBOARD_FAB2_LIB.BASEBOARD_FAB2(SCH_1):PVDDQ_KLM
   2    GND      B @BASEBOARD_FAB2_LIB.BASEBOARD_FAB2(SCH_1):GND

CAP_A_0603V-22.0UF,4V,20%,X6S,A  I218  C2A7
   1 PVDDQ_KLM      A @BASEBOARD_FAB2_LIB.BASEBOARD_FAB2(SCH_1):PVDDQ_KLM
   2    GND      B @BASEBOARD_FAB2_LIB.BASEBOARD_FAB2(SCH_1):GND

CAP_A_0603V-22.0UF,4V,20%,X6S,A  I219  C2A6
   1 PVDDQ_KLM      A @BASEBOARD_FAB2_LIB.BASEBOARD_FAB2(SCH_1):PVDDQ_KLM
   2    GND      B @BASEBOARD_FAB2_LIB.BASEBOARD_FAB2(SCH_1):GND

CAP_A_0603V-22.0UF,4V,20%,X6S,A  I220  C2A14
   1 PVDDQ_KLM      A @BASEBOARD_FAB2_LIB.BASEBOARD_FAB2(SCH_1):PVDDQ_KLM
   2    GND      B @BASEBOARD_FAB2_LIB.BASEBOARD_FAB2(SCH_1):GND

CAP_A_0603V-22.0UF,4V,20%,X6S,A  I221  C2A15
   1 PVDDQ_KLM      A @BASEBOARD_FAB2_LIB.BASEBOARD_FAB2(SCH_1):PVDDQ_KLM
   2    GND      B @BASEBOARD_FAB2_LIB.BASEBOARD_FAB2(SCH_1):GND

CAP_A_0603V-22.0UF,4V,20%,X6S,A  I222  C3A5
   1 PVDDQ_KLM      A @BASEBOARD_FAB2_LIB.BASEBOARD_FAB2(SCH_1):PVDDQ_KLM
   2    GND      B @BASEBOARD_FAB2_LIB.BASEBOARD_FAB2(SCH_1):GND

CAP_A_0603V-22.0UF,4V,20%,X6S,A  I223  C3A6
   1 PVDDQ_KLM      A @BASEBOARD_FAB2_LIB.BASEBOARD_FAB2(SCH_1):PVDDQ_KLM
   2    GND      B @BASEBOARD_FAB2_LIB.BASEBOARD_FAB2(SCH_1):GND

CAP_A_0603V-22.0UF,4V,20%,X6S,A  I225  C7L5
   1 PVDDQ_KLM      A @BASEBOARD_FAB2_LIB.BASEBOARD_FAB2(SCH_1):PVDDQ_KLM
   2    GND      B @BASEBOARD_FAB2_LIB.BASEBOARD_FAB2(SCH_1):GND

CAP_A_0603V-22.0UF,4V,20%,X6S,A  I227  C8M3
   1 PVDDQ_KLM      A @BASEBOARD_FAB2_LIB.BASEBOARD_FAB2(SCH_1):PVDDQ_KLM
   2    GND      B @BASEBOARD_FAB2_LIB.BASEBOARD_FAB2(SCH_1):GND

CAP_A_0603V-22.0UF,4V,20%,X6S,A  I228  C8M5
   1 PVDDQ_KLM      A @BASEBOARD_FAB2_LIB.BASEBOARD_FAB2(SCH_1):PVDDQ_KLM
   2    GND      B @BASEBOARD_FAB2_LIB.BASEBOARD_FAB2(SCH_1):GND

CAP_A_0603V-22.0UF,4V,20%,X6S,A  I229  C8L10
   1 PVDDQ_KLM      A @BASEBOARD_FAB2_LIB.BASEBOARD_FAB2(SCH_1):PVDDQ_KLM
   2    GND      B @BASEBOARD_FAB2_LIB.BASEBOARD_FAB2(SCH_1):GND

CAP_A_0603V-22.0UF,4V,20%,X6S,A  I230  C2A3
   1 PVDDQ_KLM      A @BASEBOARD_FAB2_LIB.BASEBOARD_FAB2(SCH_1):PVDDQ_KLM
   2    GND      B @BASEBOARD_FAB2_LIB.BASEBOARD_FAB2(SCH_1):GND

CAP_A_0603V-22.0UF,4V,20%,X6S,A  I231  C7M1
   1 PVDDQ_KLM      A @BASEBOARD_FAB2_LIB.BASEBOARD_FAB2(SCH_1):PVDDQ_KLM
   2    GND      B @BASEBOARD_FAB2_LIB.BASEBOARD_FAB2(SCH_1):GND

CAP_A_0603V-22.0UF,4V,20%,X6S,A  I232  C7M2
   1 PVDDQ_KLM      A @BASEBOARD_FAB2_LIB.BASEBOARD_FAB2(SCH_1):PVDDQ_KLM
   2    GND      B @BASEBOARD_FAB2_LIB.BASEBOARD_FAB2(SCH_1):GND

CAP_A_0603V-22.0UF,4V,20%,X6S,A  I233  C8M4
   1 PVDDQ_KLM      A @BASEBOARD_FAB2_LIB.BASEBOARD_FAB2(SCH_1):PVDDQ_KLM
   2    GND      B @BASEBOARD_FAB2_LIB.BASEBOARD_FAB2(SCH_1):GND

CAP_A_0603V-22.0UF,4V,20%,X6S,A  I234  C2A4
   1 PVDDQ_KLM      A @BASEBOARD_FAB2_LIB.BASEBOARD_FAB2(SCH_1):PVDDQ_KLM
   2    GND      B @BASEBOARD_FAB2_LIB.BASEBOARD_FAB2(SCH_1):GND

CAP_A_0603V-22.0UF,4V,20%,X6S,A  I235  C8M6
   1 PVDDQ_KLM      A @BASEBOARD_FAB2_LIB.BASEBOARD_FAB2(SCH_1):PVDDQ_KLM
   2    GND      B @BASEBOARD_FAB2_LIB.BASEBOARD_FAB2(SCH_1):GND

CAP_A_0603V-22.0UF,4V,20%,X6S,A  I236  C8L9
   1 PVDDQ_KLM      A @BASEBOARD_FAB2_LIB.BASEBOARD_FAB2(SCH_1):PVDDQ_KLM
   2    GND      B @BASEBOARD_FAB2_LIB.BASEBOARD_FAB2(SCH_1):GND

CAP_A_0603V-22.0UF,4V,20%,X6S,A  I237  C8L8
   1 PVDDQ_KLM      A @BASEBOARD_FAB2_LIB.BASEBOARD_FAB2(SCH_1):PVDDQ_KLM
   2    GND      B @BASEBOARD_FAB2_LIB.BASEBOARD_FAB2(SCH_1):GND

CAP_A_0603V-22.0UF,4V,20%,X6S,A  I238  C7L4
   1 PVDDQ_KLM      A @BASEBOARD_FAB2_LIB.BASEBOARD_FAB2(SCH_1):PVDDQ_KLM
   2    GND      B @BASEBOARD_FAB2_LIB.BASEBOARD_FAB2(SCH_1):GND

CAP_A_0603V-22.0UF,4V,20%,X6S,A  I239  C8L7
   1 PVDDQ_KLM      A @BASEBOARD_FAB2_LIB.BASEBOARD_FAB2(SCH_1):PVDDQ_KLM
   2    GND      B @BASEBOARD_FAB2_LIB.BASEBOARD_FAB2(SCH_1):GND

CAP_A_0603V-22.0UF,4V,20%,X6S,A  I240  C8L6
   1 PVDDQ_KLM      A @BASEBOARD_FAB2_LIB.BASEBOARD_FAB2(SCH_1):PVDDQ_KLM
   2    GND      B @BASEBOARD_FAB2_LIB.BASEBOARD_FAB2(SCH_1):GND

CAP_A_0603V-22.0UF,4V,20%,X6S,A  I241  C8L5
   1 PVDDQ_KLM      A @BASEBOARD_FAB2_LIB.BASEBOARD_FAB2(SCH_1):PVDDQ_KLM
   2    GND      B @BASEBOARD_FAB2_LIB.BASEBOARD_FAB2(SCH_1):GND

CAP_A_0603V-22.0UF,4V,20%,X6S,A  I243  C8M1
   1 PVDDQ_KLM      A @BASEBOARD_FAB2_LIB.BASEBOARD_FAB2(SCH_1):PVDDQ_KLM
   2    GND      B @BASEBOARD_FAB2_LIB.BASEBOARD_FAB2(SCH_1):GND

SHUNT_SH0201-EMPTY,N_A  I245  SH7L2
   1 VSENSE_PVDDQ_KLM_P      A @BASEBOARD_FAB2_LIB.BASEBOARD_FAB2(SCH_1):VSENSE_PVDDQ_KLM_P
   2 PVDDQ_KLM      B @BASEBOARD_FAB2_LIB.BASEBOARD_FAB2(SCH_1):PVDDQ_KLM

SHUNT_SH0201-EMPTY,N_A  I246  SH7L1
   1 VSENSE_PVDDQ_KLM_N      A @BASEBOARD_FAB2_LIB.BASEBOARD_FAB2(SCH_1):VSENSE_PVDDQ_KLM_N
   2    GND      B @BASEBOARD_FAB2_LIB.BASEBOARD_FAB2(SCH_1):GND


DRAWING: @BASEBOARD_FAB2_LIB.BASEBOARD_FAB2(SCH_1):PAGE229 

RES_0402-10.0K,1%,1/16W,CHIP,GA  I14  R4G17
   1   P3V3      A @BASEBOARD_FAB2_LIB.BASEBOARD_FAB2(SCH_1):P3V3
   2 PWRGD_PVTT_GHJ_CPU1_R      B @BASEBOARD_FAB2_LIB.BASEBOARD_FAB2(SCH_1):PWRGD_PVTT_GHJ_CPU1_R

CAP_0402LF-1000PF,50V,10%,X7R,A  I15  C4G13
   1 PWRGD_PVTT_GHJ_CPU1_R      A @BASEBOARD_FAB2_LIB.BASEBOARD_FAB2(SCH_1):PWRGD_PVTT_GHJ_CPU1_R
   2    GND      B @BASEBOARD_FAB2_LIB.BASEBOARD_FAB2(SCH_1):GND

CAP_0805LF-22UF,4V,20%,X6S,C95A  I17  C4G20
   1 PVTT_GHJ      A @BASEBOARD_FAB2_LIB.BASEBOARD_FAB2(SCH_1):PVTT_GHJ
   2    GND      B @BASEBOARD_FAB2_LIB.BASEBOARD_FAB2(SCH_1):GND

CAP_0402-1.0UF,16V,10%,X6S,D97A  I21  C4G21
   1 VR_PVTT_GHJ_VREF      A @BASEBOARD_FAB2_LIB.BASEBOARD_FAB2(SCH_1):VR_PVTT_GHJ_VREF
   2    GND      B @BASEBOARD_FAB2_LIB.BASEBOARD_FAB2(SCH_1):GND

MIC5166_DFN-IC,H55101-001  I24  EU4G2
   7 FM_PVTT_GHJ_EN_R     EN @BASEBOARD_FAB2_LIB.BASEBOARD_FAB2(SCH_1):FM_PVTT_GHJ_EN_R
  10 PVDDQ_GHJ    VIN @BASEBOARD_FAB2_LIB.BASEBOARD_FAB2(SCH_1):PVDDQ_GHJ
   1 VR_PVTT_GHJ_VREF   VREF @BASEBOARD_FAB2_LIB.BASEBOARD_FAB2(SCH_1):VR_PVTT_GHJ_VREF
   2 VR_PVTT_GHJ_BIAS   BIAS @BASEBOARD_FAB2_LIB.BASEBOARD_FAB2(SCH_1):VR_PVTT_GHJ_BIAS
   3    GND   AGND @BASEBOARD_FAB2_LIB.BASEBOARD_FAB2(SCH_1):GND
   5 PWRGD_PVTT_GHJ_CPU1_R     PG @BASEBOARD_FAB2_LIB.BASEBOARD_FAB2(SCH_1):PWRGD_PVTT_GHJ_CPU1_R
   4 VSENSE_PVDDQ_GHJ_VTT   VDDQ @BASEBOARD_FAB2_LIB.BASEBOARD_FAB2(SCH_1):VSENSE_PVDDQ_GHJ_VTT
   6 VR_PVTT_GHJ_SNS    SNS @BASEBOARD_FAB2_LIB.BASEBOARD_FAB2(SCH_1):VR_PVTT_GHJ_SNS
   8    GND   PGND @BASEBOARD_FAB2_LIB.BASEBOARD_FAB2(SCH_1):GND
   9 PVTT_GHJ    VTT @BASEBOARD_FAB2_LIB.BASEBOARD_FAB2(SCH_1):PVTT_GHJ
  11    GND  THPAD @BASEBOARD_FAB2_LIB.BASEBOARD_FAB2(SCH_1):GND

CAP_0603LF-10UF,4V,20%,X6S,E15A  I25  C6U14
   1 PVDDQ_GHJ      A @BASEBOARD_FAB2_LIB.BASEBOARD_FAB2(SCH_1):PVDDQ_GHJ
   2    GND      B @BASEBOARD_FAB2_LIB.BASEBOARD_FAB2(SCH_1):GND

CAP_0402-1.0UF,16V,10%,X6S,D97A  I27  C4G18
   1 VR_PVTT_GHJ_BIAS      A @BASEBOARD_FAB2_LIB.BASEBOARD_FAB2(SCH_1):VR_PVTT_GHJ_BIAS
   2    GND      B @BASEBOARD_FAB2_LIB.BASEBOARD_FAB2(SCH_1):GND

CAP_0603LF-10UF,4V,20%,X6S,E15A  I29  C6U13
   1 PVDDQ_GHJ      A @BASEBOARD_FAB2_LIB.BASEBOARD_FAB2(SCH_1):PVDDQ_GHJ
   2    GND      B @BASEBOARD_FAB2_LIB.BASEBOARD_FAB2(SCH_1):GND

RES_0402-0.0,5%,1/16W,CHIP,G21A  I32  R6U7
   1   P3V3      A @BASEBOARD_FAB2_LIB.BASEBOARD_FAB2(SCH_1):P3V3
   2 VR_PVTT_GHJ_BIAS      B @BASEBOARD_FAB2_LIB.BASEBOARD_FAB2(SCH_1):VR_PVTT_GHJ_BIAS

RES_0402-1.0M,1%,1/16W,EMPTY,GA  I34  R6U3
   1   P3V3      A @BASEBOARD_FAB2_LIB.BASEBOARD_FAB2(SCH_1):P3V3
   2 FM_PVTT_GHJ_EN_R      B @BASEBOARD_FAB2_LIB.BASEBOARD_FAB2(SCH_1):FM_PVTT_GHJ_EN_R

RES_0402-0.0,5%,1/16W,CHIP,G21A  I35  R4G16
   1 PWRGD_PVDDQ_GHJ      A @BASEBOARD_FAB2_LIB.BASEBOARD_FAB2(SCH_1):PWRGD_PVDDQ_GHJ
   2 FM_PVTT_GHJ_EN_R      B @BASEBOARD_FAB2_LIB.BASEBOARD_FAB2(SCH_1):FM_PVTT_GHJ_EN_R

CAP_0402LF-1000PF,50V,10%,EMPTA  I36  C4G12
   1 FM_PVTT_GHJ_EN_R      A @BASEBOARD_FAB2_LIB.BASEBOARD_FAB2(SCH_1):FM_PVTT_GHJ_EN_R
   2    GND      B @BASEBOARD_FAB2_LIB.BASEBOARD_FAB2(SCH_1):GND

RES_0402-0.0,5%,1/16W,CHIP,G21A  I39  R6U6
   1 PVDDQ_GHJ      A @BASEBOARD_FAB2_LIB.BASEBOARD_FAB2(SCH_1):PVDDQ_GHJ
   2 VSENSE_PVDDQ_GHJ_VTT      B @BASEBOARD_FAB2_LIB.BASEBOARD_FAB2(SCH_1):VSENSE_PVDDQ_GHJ_VTT

CAP_0603-4.7UF,6.3V,10%,X6S,E1A  I46  C6U11
   1 VSENSE_PVDDQ_GHJ_VTT      A @BASEBOARD_FAB2_LIB.BASEBOARD_FAB2(SCH_1):VSENSE_PVDDQ_GHJ_VTT
   2    GND      B @BASEBOARD_FAB2_LIB.BASEBOARD_FAB2(SCH_1):GND

CAP_A_0603V-47UF,4V,20%,X5R,60A  I47  C2F2
   1 PVTT_GHJ      A @BASEBOARD_FAB2_LIB.BASEBOARD_FAB2(SCH_1):PVTT_GHJ
   2    GND      B @BASEBOARD_FAB2_LIB.BASEBOARD_FAB2(SCH_1):GND

CAP_A_0603V-47UF,4V,20%,X5R,60A  I48  C8T3
   1 PVTT_GHJ      A @BASEBOARD_FAB2_LIB.BASEBOARD_FAB2(SCH_1):PVTT_GHJ
   2    GND      B @BASEBOARD_FAB2_LIB.BASEBOARD_FAB2(SCH_1):GND

CAP_A_0603V-47UF,4V,20%,X5R,60A  I49  C8U10
   1 PVTT_GHJ      A @BASEBOARD_FAB2_LIB.BASEBOARD_FAB2(SCH_1):PVTT_GHJ
   2    GND      B @BASEBOARD_FAB2_LIB.BASEBOARD_FAB2(SCH_1):GND

RES_0402-33.2,1%,1/16W,CHIP,G2A  I51  R4G15
   1 PWRGD_PVTT_GHJ_CPU1_R      A @BASEBOARD_FAB2_LIB.BASEBOARD_FAB2(SCH_1):PWRGD_PVTT_GHJ_CPU1_R
   2 PWRGD_PVTT_CPU1      B @BASEBOARD_FAB2_LIB.BASEBOARD_FAB2(SCH_1):PWRGD_PVTT_CPU1

RES_0402-51.1,1.0%,1/16W,CHIP,A  I52  R6U8
   1    GND      A @BASEBOARD_FAB2_LIB.BASEBOARD_FAB2(SCH_1):GND
   2 PVTT_GHJ      B @BASEBOARD_FAB2_LIB.BASEBOARD_FAB2(SCH_1):PVTT_GHJ

SHUNT_SH0201-EMPTY,N_A  I53  SH8U1
   1 VR_PVTT_GHJ_SNS      A @BASEBOARD_FAB2_LIB.BASEBOARD_FAB2(SCH_1):VR_PVTT_GHJ_SNS
   2 PVTT_GHJ      B @BASEBOARD_FAB2_LIB.BASEBOARD_FAB2(SCH_1):PVTT_GHJ


DRAWING: @BASEBOARD_FAB2_LIB.BASEBOARD_FAB2(SCH_1):PAGE230 

CAP_0402LF-1000PF,50V,10%,X7R,A  I16  C4A3
   1 PWRGD_PVTT_KLM_CPU1_R      A @BASEBOARD_FAB2_LIB.BASEBOARD_FAB2(SCH_1):PWRGD_PVTT_KLM_CPU1_R
   2    GND      B @BASEBOARD_FAB2_LIB.BASEBOARD_FAB2(SCH_1):GND

RES_0402-10.0K,1%,1/16W,CHIP,GA  I17  R4A5
   1   P3V3      A @BASEBOARD_FAB2_LIB.BASEBOARD_FAB2(SCH_1):P3V3
   2 PWRGD_PVTT_KLM_CPU1_R      B @BASEBOARD_FAB2_LIB.BASEBOARD_FAB2(SCH_1):PWRGD_PVTT_KLM_CPU1_R

CAP_0805LF-22UF,4V,20%,X6S,C95A  I18  C4A13
   1 PVTT_KLM      A @BASEBOARD_FAB2_LIB.BASEBOARD_FAB2(SCH_1):PVTT_KLM
   2    GND      B @BASEBOARD_FAB2_LIB.BASEBOARD_FAB2(SCH_1):GND

CAP_0402-1.0UF,16V,10%,X6S,D97A  I21  C4A14
   1 VR_PVTT_KLM_VREF      A @BASEBOARD_FAB2_LIB.BASEBOARD_FAB2(SCH_1):VR_PVTT_KLM_VREF
   2    GND      B @BASEBOARD_FAB2_LIB.BASEBOARD_FAB2(SCH_1):GND

CAP_0603LF-10UF,4V,20%,X6S,E15A  I25  C4A15
   1 PVDDQ_KLM      A @BASEBOARD_FAB2_LIB.BASEBOARD_FAB2(SCH_1):PVDDQ_KLM
   2    GND      B @BASEBOARD_FAB2_LIB.BASEBOARD_FAB2(SCH_1):GND

CAP_0603LF-10UF,4V,20%,X6S,E15A  I26  C6L5
   1 PVDDQ_KLM      A @BASEBOARD_FAB2_LIB.BASEBOARD_FAB2(SCH_1):PVDDQ_KLM
   2    GND      B @BASEBOARD_FAB2_LIB.BASEBOARD_FAB2(SCH_1):GND

CAP_0402-1.0UF,16V,10%,X6S,D97A  I28  C4A8
   1 VR_PVTT_KLM_BIAS      A @BASEBOARD_FAB2_LIB.BASEBOARD_FAB2(SCH_1):VR_PVTT_KLM_BIAS
   2    GND      B @BASEBOARD_FAB2_LIB.BASEBOARD_FAB2(SCH_1):GND

RES_0402-0.0,5%,1/16W,CHIP,G21A  I30  R6L8
   1   P3V3      A @BASEBOARD_FAB2_LIB.BASEBOARD_FAB2(SCH_1):P3V3
   2 VR_PVTT_KLM_BIAS      B @BASEBOARD_FAB2_LIB.BASEBOARD_FAB2(SCH_1):VR_PVTT_KLM_BIAS

MIC5166_DFN-IC,H55101-001  I31  EU4A2
   7 FM_PVTT_KLM_EN_R     EN @BASEBOARD_FAB2_LIB.BASEBOARD_FAB2(SCH_1):FM_PVTT_KLM_EN_R
  10 PVDDQ_KLM    VIN @BASEBOARD_FAB2_LIB.BASEBOARD_FAB2(SCH_1):PVDDQ_KLM
   1 VR_PVTT_KLM_VREF   VREF @BASEBOARD_FAB2_LIB.BASEBOARD_FAB2(SCH_1):VR_PVTT_KLM_VREF
   2 VR_PVTT_KLM_BIAS   BIAS @BASEBOARD_FAB2_LIB.BASEBOARD_FAB2(SCH_1):VR_PVTT_KLM_BIAS
   3    GND   AGND @BASEBOARD_FAB2_LIB.BASEBOARD_FAB2(SCH_1):GND
   5 PWRGD_PVTT_KLM_CPU1_R     PG @BASEBOARD_FAB2_LIB.BASEBOARD_FAB2(SCH_1):PWRGD_PVTT_KLM_CPU1_R
   4 VSENSE_PVDDQ_KLM_VTT   VDDQ @BASEBOARD_FAB2_LIB.BASEBOARD_FAB2(SCH_1):VSENSE_PVDDQ_KLM_VTT
   6 VR_PVTT_KLM_SNS    SNS @BASEBOARD_FAB2_LIB.BASEBOARD_FAB2(SCH_1):VR_PVTT_KLM_SNS
   8    GND   PGND @BASEBOARD_FAB2_LIB.BASEBOARD_FAB2(SCH_1):GND
   9 PVTT_KLM    VTT @BASEBOARD_FAB2_LIB.BASEBOARD_FAB2(SCH_1):PVTT_KLM
  11    GND  THPAD @BASEBOARD_FAB2_LIB.BASEBOARD_FAB2(SCH_1):GND

RES_0402-0.0,5%,1/16W,CHIP,G21A  I34  R6L6
   1 PVDDQ_KLM      A @BASEBOARD_FAB2_LIB.BASEBOARD_FAB2(SCH_1):PVDDQ_KLM
   2 VSENSE_PVDDQ_KLM_VTT      B @BASEBOARD_FAB2_LIB.BASEBOARD_FAB2(SCH_1):VSENSE_PVDDQ_KLM_VTT

RES_0402-1.0M,1%,1/16W,EMPTY,GA  I37  R6L5
   1   P3V3      A @BASEBOARD_FAB2_LIB.BASEBOARD_FAB2(SCH_1):P3V3
   2 FM_PVTT_KLM_EN_R      B @BASEBOARD_FAB2_LIB.BASEBOARD_FAB2(SCH_1):FM_PVTT_KLM_EN_R

RES_0402-0.0,5%,1/16W,CHIP,G21A  I38  R4A3
   1 PWRGD_PVDDQ_KLM      A @BASEBOARD_FAB2_LIB.BASEBOARD_FAB2(SCH_1):PWRGD_PVDDQ_KLM
   2 FM_PVTT_KLM_EN_R      B @BASEBOARD_FAB2_LIB.BASEBOARD_FAB2(SCH_1):FM_PVTT_KLM_EN_R

CAP_0402LF-1000PF,50V,10%,EMPTA  I39  C4A6
   1 FM_PVTT_KLM_EN_R      A @BASEBOARD_FAB2_LIB.BASEBOARD_FAB2(SCH_1):FM_PVTT_KLM_EN_R
   2    GND      B @BASEBOARD_FAB2_LIB.BASEBOARD_FAB2(SCH_1):GND

CAP_0603-4.7UF,6.3V,10%,X6S,E1A  I46  C4A7
   1 VSENSE_PVDDQ_KLM_VTT      A @BASEBOARD_FAB2_LIB.BASEBOARD_FAB2(SCH_1):VSENSE_PVDDQ_KLM_VTT
   2    GND      B @BASEBOARD_FAB2_LIB.BASEBOARD_FAB2(SCH_1):GND

CAP_A_0603V-47UF,4V,20%,X5R,60A  I47  C8M12
   1 PVTT_KLM      A @BASEBOARD_FAB2_LIB.BASEBOARD_FAB2(SCH_1):PVTT_KLM
   2    GND      B @BASEBOARD_FAB2_LIB.BASEBOARD_FAB2(SCH_1):GND

CAP_A_0603V-47UF,4V,20%,X5R,60A  I48  C8L3
   1 PVTT_KLM      A @BASEBOARD_FAB2_LIB.BASEBOARD_FAB2(SCH_1):PVTT_KLM
   2    GND      B @BASEBOARD_FAB2_LIB.BASEBOARD_FAB2(SCH_1):GND

CAP_A_0603V-47UF,4V,20%,X5R,60A  I49  C8L4
   1 PVTT_KLM      A @BASEBOARD_FAB2_LIB.BASEBOARD_FAB2(SCH_1):PVTT_KLM
   2    GND      B @BASEBOARD_FAB2_LIB.BASEBOARD_FAB2(SCH_1):GND

RES_0402-33.2,1%,1/16W,CHIP,G2A  I51  R4A4
   1 PWRGD_PVTT_KLM_CPU1_R      A @BASEBOARD_FAB2_LIB.BASEBOARD_FAB2(SCH_1):PWRGD_PVTT_KLM_CPU1_R
   2 PWRGD_PVTT_CPU1      B @BASEBOARD_FAB2_LIB.BASEBOARD_FAB2(SCH_1):PWRGD_PVTT_CPU1

RES_0402-51.1,1.0%,1/16W,CHIP,A  I52  R6L7
   1    GND      A @BASEBOARD_FAB2_LIB.BASEBOARD_FAB2(SCH_1):GND
   2 PVTT_KLM      B @BASEBOARD_FAB2_LIB.BASEBOARD_FAB2(SCH_1):PVTT_KLM

SHUNT_SH0201-EMPTY,N_A  I53  SH8L1
   1 VR_PVTT_KLM_SNS      A @BASEBOARD_FAB2_LIB.BASEBOARD_FAB2(SCH_1):VR_PVTT_KLM_SNS
   2 PVTT_KLM      B @BASEBOARD_FAB2_LIB.BASEBOARD_FAB2(SCH_1):PVTT_KLM


DRAWING: @BASEBOARD_FAB2_LIB.BASEBOARD_FAB2(SCH_1):PAGE231 

CAP_0603LF-10UF,4V,20%,X6S,E15A  I122  C6F6
   1 PVPP_ABC      A @BASEBOARD_FAB2_LIB.BASEBOARD_FAB2(SCH_1):PVPP_ABC
   2    GND      B @BASEBOARD_FAB2_LIB.BASEBOARD_FAB2(SCH_1):GND

CAP_0603LF-10UF,4V,20%,X6S,E15A  I124  C4T6
   1 PVPP_ABC      A @BASEBOARD_FAB2_LIB.BASEBOARD_FAB2(SCH_1):PVPP_ABC
   2    GND      B @BASEBOARD_FAB2_LIB.BASEBOARD_FAB2(SCH_1):GND

CAP_0603LF-10UF,4V,20%,X6S,E15A  I125  C4T5
   1 PVPP_ABC      A @BASEBOARD_FAB2_LIB.BASEBOARD_FAB2(SCH_1):PVPP_ABC
   2    GND      B @BASEBOARD_FAB2_LIB.BASEBOARD_FAB2(SCH_1):GND

CAP_0603LF-10UF,4V,20%,X6S,E15A  I126  C6G1
   1 PVPP_ABC      A @BASEBOARD_FAB2_LIB.BASEBOARD_FAB2(SCH_1):PVPP_ABC
   2    GND      B @BASEBOARD_FAB2_LIB.BASEBOARD_FAB2(SCH_1):GND

CAP_0603LF-10UF,4V,20%,X6S,E15A  I128  C6G2
   1 PVPP_ABC      A @BASEBOARD_FAB2_LIB.BASEBOARD_FAB2(SCH_1):PVPP_ABC
   2    GND      B @BASEBOARD_FAB2_LIB.BASEBOARD_FAB2(SCH_1):GND

CAP_0603LF-10UF,4V,20%,X6S,E15A  I129  C4U2
   1 PVPP_ABC      A @BASEBOARD_FAB2_LIB.BASEBOARD_FAB2(SCH_1):PVPP_ABC
   2    GND      B @BASEBOARD_FAB2_LIB.BASEBOARD_FAB2(SCH_1):GND

CAP_0603LF-10UF,4V,20%,X6S,E15A  I130  C4U1
   1 PVPP_ABC      A @BASEBOARD_FAB2_LIB.BASEBOARD_FAB2(SCH_1):PVPP_ABC
   2    GND      B @BASEBOARD_FAB2_LIB.BASEBOARD_FAB2(SCH_1):GND

CAP_0603LF-10UF,4V,20%,X6S,E15A  I131  C6G4
   1 PVPP_ABC      A @BASEBOARD_FAB2_LIB.BASEBOARD_FAB2(SCH_1):PVPP_ABC
   2    GND      B @BASEBOARD_FAB2_LIB.BASEBOARD_FAB2(SCH_1):GND

RES_0402-7.87K,1.0%,1/16W,CHIPA  I134  R7F15
   1 VR_PVPP_ABC_ISET      A @BASEBOARD_FAB2_LIB.BASEBOARD_FAB2(SCH_1):VR_PVPP_ABC_ISET
   2 AGND_PVPP_ABC      B @BASEBOARD_FAB2_LIB.BASEBOARD_FAB2(SCH_1):AGND_PVPP_ABC

RES_0402-10.0K,1%,1/16W,CHIP,GA  I136  R7F14
   1 FM_PVPP_CPU0_EN      A @BASEBOARD_FAB2_LIB.BASEBOARD_FAB2(SCH_1):FM_PVPP_CPU0_EN
   2    GND      B @BASEBOARD_FAB2_LIB.BASEBOARD_FAB2(SCH_1):GND

CAP_0402LF-1000PF,50V,10%,EMPTA  I140  C7F8
   1 FM_PVPP_CPU0_EN      A @BASEBOARD_FAB2_LIB.BASEBOARD_FAB2(SCH_1):FM_PVPP_CPU0_EN
   2 AGND_PVPP_ABC      B @BASEBOARD_FAB2_LIB.BASEBOARD_FAB2(SCH_1):AGND_PVPP_ABC

CAP_0402LF-1000PF,50V,10%,X7R,A  I142  C7F11
   1 PWRGD_PVPP_ABC_R      A @BASEBOARD_FAB2_LIB.BASEBOARD_FAB2(SCH_1):PWRGD_PVPP_ABC_R
   2    GND      B @BASEBOARD_FAB2_LIB.BASEBOARD_FAB2(SCH_1):GND

RES_0402-1.00K,1%,1/16W,CHIP,GA  I143  R7F19
   1 P3V3_STBY      A @BASEBOARD_FAB2_LIB.BASEBOARD_FAB2(SCH_1):P3V3_STBY
   2 PWRGD_PVPP_ABC_R      B @BASEBOARD_FAB2_LIB.BASEBOARD_FAB2(SCH_1):PWRGD_PVPP_ABC_R

CAP_0603LF-10UF,4V,20%,X6S,E15A  I145  C6G5
   1 PVPP_ABC      A @BASEBOARD_FAB2_LIB.BASEBOARD_FAB2(SCH_1):PVPP_ABC
   2    GND      B @BASEBOARD_FAB2_LIB.BASEBOARD_FAB2(SCH_1):GND

CAP_0603LF-10UF,4V,20%,X6S,E15A  I146  C4U4
   1 PVPP_ABC      A @BASEBOARD_FAB2_LIB.BASEBOARD_FAB2(SCH_1):PVPP_ABC
   2    GND      B @BASEBOARD_FAB2_LIB.BASEBOARD_FAB2(SCH_1):GND

CAP_0603LF-10UF,4V,20%,X6S,E15A  I148  C4U3
   1 PVPP_ABC      A @BASEBOARD_FAB2_LIB.BASEBOARD_FAB2(SCH_1):PVPP_ABC
   2    GND      B @BASEBOARD_FAB2_LIB.BASEBOARD_FAB2(SCH_1):GND

CAP_0603LF-10UF,4V,20%,X6S,E15A  I149  C6F5
   1 PVPP_ABC      A @BASEBOARD_FAB2_LIB.BASEBOARD_FAB2(SCH_1):PVPP_ABC
   2    GND      B @BASEBOARD_FAB2_LIB.BASEBOARD_FAB2(SCH_1):GND

CAP_1210-47UF,16V,20%,X6S,D384A  I151  C7F7
   1 VR_FET_SW_P12V_STBY_PVPP_ABC      A @BASEBOARD_FAB2_LIB.BASEBOARD_FAB2(SCH_1):VR_FET_SW_P12V_STBY_PVPP_ABC
   2    GND      B @BASEBOARD_FAB2_LIB.BASEBOARD_FAB2(SCH_1):GND

RES_0402-0.0,5%,1/16W,CHIP,G21A  I154  R7F8
   1 VR_PVPP_ABC_BOOT      A @BASEBOARD_FAB2_LIB.BASEBOARD_FAB2(SCH_1):VR_PVPP_ABC_BOOT
   2 VR_PVPP_ABC_BOOT_R      B @BASEBOARD_FAB2_LIB.BASEBOARD_FAB2(SCH_1):VR_PVPP_ABC_BOOT_R

CAP_0603LF-0.1UF,25V,10%,X7R,6A  I159  C7F4
   1 VR_PVPP_ABC_PHASE      A @BASEBOARD_FAB2_LIB.BASEBOARD_FAB2(SCH_1):VR_PVPP_ABC_PHASE
   2 VR_PVPP_ABC_BOOT_R      B @BASEBOARD_FAB2_LIB.BASEBOARD_FAB2(SCH_1):VR_PVPP_ABC_BOOT_R

CAP_0402-1.0UF,16V,10%,X6S,D97A  I161  C3T10
   1 VR_FET_SW_P12V_STBY_PVPP_ABC      A @BASEBOARD_FAB2_LIB.BASEBOARD_FAB2(SCH_1):VR_FET_SW_P12V_STBY_PVPP_ABC
   2    GND      B @BASEBOARD_FAB2_LIB.BASEBOARD_FAB2(SCH_1):GND

FERRITE_SM-22,FB,656554-051  I162  FB7F1
   1 P12V_STBY      A @BASEBOARD_FAB2_LIB.BASEBOARD_FAB2(SCH_1):P12V_STBY
   2 VR_FET_SW_P12V_STBY_PVPP_ABC      B @BASEBOARD_FAB2_LIB.BASEBOARD_FAB2(SCH_1):VR_FET_SW_P12V_STBY_PVPP_ABC

RES_0402-6.34K,1%,1/16W,CHIP,GA  I166  R7F11
   1 VR_FB_PVPP_ABC      A @BASEBOARD_FAB2_LIB.BASEBOARD_FAB2(SCH_1):VR_FB_PVPP_ABC
   2 AGND_PVPP_ABC      B @BASEBOARD_FAB2_LIB.BASEBOARD_FAB2(SCH_1):AGND_PVPP_ABC

RES_0402-20.0K,1%,1/16W,CHIP,GA  I167  R7F13
   1 VSENSE_PVPP_ABC      A @BASEBOARD_FAB2_LIB.BASEBOARD_FAB2(SCH_1):VSENSE_PVPP_ABC
   2 VR_FB_PVPP_ABC      B @BASEBOARD_FAB2_LIB.BASEBOARD_FAB2(SCH_1):VR_FB_PVPP_ABC

RES_0402-0.0,5%,1/16W,CHIP,G21A  I168  R7F12
   1 PVPP_ABC      A @BASEBOARD_FAB2_LIB.BASEBOARD_FAB2(SCH_1):PVPP_ABC
   2 VSENSE_PVPP_ABC      B @BASEBOARD_FAB2_LIB.BASEBOARD_FAB2(SCH_1):VSENSE_PVPP_ABC

RES_0402-0.0,5%,1/16W,CHIP,G21A  I170  R7F35
   1    GND      A @BASEBOARD_FAB2_LIB.BASEBOARD_FAB2(SCH_1):GND
   2 AGND_PVPP_ABC      B @BASEBOARD_FAB2_LIB.BASEBOARD_FAB2(SCH_1):AGND_PVPP_ABC

RES_0402-2.2,5%,1/16W,EMPTY,G2A  I174  R7F7
   1 VR_PVPP_ABC_SNUB      A @BASEBOARD_FAB2_LIB.BASEBOARD_FAB2(SCH_1):VR_PVPP_ABC_SNUB
   2    GND      B @BASEBOARD_FAB2_LIB.BASEBOARD_FAB2(SCH_1):GND

CAP_0402LF-3300PF,50V,10%,EMPTA  I175  C7F3
   1 VR_PVPP_ABC_PHASE      A @BASEBOARD_FAB2_LIB.BASEBOARD_FAB2(SCH_1):VR_PVPP_ABC_PHASE
   2 VR_PVPP_ABC_SNUB      B @BASEBOARD_FAB2_LIB.BASEBOARD_FAB2(SCH_1):VR_PVPP_ABC_SNUB

RES_0603-120.0,1%,1/10W,CHIP,GA  I177  R7F10
   1 PVPP_ABC      A @BASEBOARD_FAB2_LIB.BASEBOARD_FAB2(SCH_1):PVPP_ABC
   2    GND      B @BASEBOARD_FAB2_LIB.BASEBOARD_FAB2(SCH_1):GND

INDUCTOR_SM-0.47UH,IND,E13358-A  I178  L7F1
   1 VR_PVPP_ABC_PHASE    INA @BASEBOARD_FAB2_LIB.BASEBOARD_FAB2(SCH_1):VR_PVPP_ABC_PHASE
   2 PVPP_ABC    INB @BASEBOARD_FAB2_LIB.BASEBOARD_FAB2(SCH_1):PVPP_ABC

CAPP_7343LF-330UF,6.3V,20%,POSA  I180  C6F4
   1 PVPP_ABC      A @BASEBOARD_FAB2_LIB.BASEBOARD_FAB2(SCH_1):PVPP_ABC
   2    GND      B @BASEBOARD_FAB2_LIB.BASEBOARD_FAB2(SCH_1):GND

CAP_0805-47UF,4V,20%,X6S,C9533A  I184  C3T7
   1 PVPP_ABC      A @BASEBOARD_FAB2_LIB.BASEBOARD_FAB2(SCH_1):PVPP_ABC
   2    GND      B @BASEBOARD_FAB2_LIB.BASEBOARD_FAB2(SCH_1):GND

CAP_0805-47UF,4V,20%,X6S,C9533A  I186  C3T9
   1 PVPP_ABC      A @BASEBOARD_FAB2_LIB.BASEBOARD_FAB2(SCH_1):PVPP_ABC
   2    GND      B @BASEBOARD_FAB2_LIB.BASEBOARD_FAB2(SCH_1):GND

NCP3232L_SM-IC,H86355-001  I193  EU7F1
   5 AGND_PVPP_ABC   AGND @BASEBOARD_FAB2_LIB.BASEBOARD_FAB2(SCH_1):AGND_PVPP_ABC
  36 VR_PVPP_ABC_BOOT    BST @BASEBOARD_FAB2_LIB.BASEBOARD_FAB2(SCH_1):VR_PVPP_ABC_BOOT
   3 VR_COMP_PVPP_ABC_3   COMP @BASEBOARD_FAB2_LIB.BASEBOARD_FAB2(SCH_1):VR_COMP_PVPP_ABC_3
  40 FM_PVPP_PVDDQ_CPU0_EN_ABC     EN @BASEBOARD_FAB2_LIB.BASEBOARD_FAB2(SCH_1):FM_PVPP_PVDDQ_CPU0_EN_ABC
   2 VR_FB_PVPP_ABC     FB @BASEBOARD_FAB2_LIB.BASEBOARD_FAB2(SCH_1):VR_FB_PVPP_ABC
  41    GND    GND @BASEBOARD_FAB2_LIB.BASEBOARD_FAB2(SCH_1):GND
   4 VR_PVPP_ABC_ISET   ISET @BASEBOARD_FAB2_LIB.BASEBOARD_FAB2(SCH_1):VR_PVPP_ABC_ISET
   6 AGND_PVPP_ABC    OTS @BASEBOARD_FAB2_LIB.BASEBOARD_FAB2(SCH_1):AGND_PVPP_ABC
   7 PWRGD_PVPP_ABC_R     PG @BASEBOARD_FAB2_LIB.BASEBOARD_FAB2(SCH_1):PWRGD_PVPP_ABC_R
  37    GND PGND<13> @BASEBOARD_FAB2_LIB.BASEBOARD_FAB2(SCH_1):GND
  28    GND PGND<12> @BASEBOARD_FAB2_LIB.BASEBOARD_FAB2(SCH_1):GND
  27    GND PGND<11> @BASEBOARD_FAB2_LIB.BASEBOARD_FAB2(SCH_1):GND
  26    GND PGND<10> @BASEBOARD_FAB2_LIB.BASEBOARD_FAB2(SCH_1):GND
  25    GND PGND<9> @BASEBOARD_FAB2_LIB.BASEBOARD_FAB2(SCH_1):GND
  24    GND PGND<8> @BASEBOARD_FAB2_LIB.BASEBOARD_FAB2(SCH_1):GND
  23    GND PGND<7> @BASEBOARD_FAB2_LIB.BASEBOARD_FAB2(SCH_1):GND
  22    GND PGND<6> @BASEBOARD_FAB2_LIB.BASEBOARD_FAB2(SCH_1):GND
  21    GND PGND<5> @BASEBOARD_FAB2_LIB.BASEBOARD_FAB2(SCH_1):GND
  20    GND PGND<4> @BASEBOARD_FAB2_LIB.BASEBOARD_FAB2(SCH_1):GND
  19    GND PGND<3> @BASEBOARD_FAB2_LIB.BASEBOARD_FAB2(SCH_1):GND
  18    GND PGND<2> @BASEBOARD_FAB2_LIB.BASEBOARD_FAB2(SCH_1):GND
  17    GND PGND<1> @BASEBOARD_FAB2_LIB.BASEBOARD_FAB2(SCH_1):GND
  16    GND PGND<0> @BASEBOARD_FAB2_LIB.BASEBOARD_FAB2(SCH_1):GND
   1 VR_PVPP_ABC_SS     SS @BASEBOARD_FAB2_LIB.BASEBOARD_FAB2(SCH_1):VR_PVPP_ABC_SS
  38 VR_VB_PVPP_ABC     VB @BASEBOARD_FAB2_LIB.BASEBOARD_FAB2(SCH_1):VR_VB_PVPP_ABC
  39 VR_FET_SW_P12V_STBY_PVPP_ABC    VCC @BASEBOARD_FAB2_LIB.BASEBOARD_FAB2(SCH_1):VR_FET_SW_P12V_STBY_PVPP_ABC
  42 VR_FET_SW_P12V_STBY_PVPP_ABC VIN<7> @BASEBOARD_FAB2_LIB.BASEBOARD_FAB2(SCH_1):VR_FET_SW_P12V_STBY_PVPP_ABC
  14 VR_FET_SW_P12V_STBY_PVPP_ABC VIN<6> @BASEBOARD_FAB2_LIB.BASEBOARD_FAB2(SCH_1):VR_FET_SW_P12V_STBY_PVPP_ABC
  13 VR_FET_SW_P12V_STBY_PVPP_ABC VIN<5> @BASEBOARD_FAB2_LIB.BASEBOARD_FAB2(SCH_1):VR_FET_SW_P12V_STBY_PVPP_ABC
  12 VR_FET_SW_P12V_STBY_PVPP_ABC VIN<4> @BASEBOARD_FAB2_LIB.BASEBOARD_FAB2(SCH_1):VR_FET_SW_P12V_STBY_PVPP_ABC
  11 VR_FET_SW_P12V_STBY_PVPP_ABC VIN<3> @BASEBOARD_FAB2_LIB.BASEBOARD_FAB2(SCH_1):VR_FET_SW_P12V_STBY_PVPP_ABC
  10 VR_FET_SW_P12V_STBY_PVPP_ABC VIN<2> @BASEBOARD_FAB2_LIB.BASEBOARD_FAB2(SCH_1):VR_FET_SW_P12V_STBY_PVPP_ABC
   9 VR_FET_SW_P12V_STBY_PVPP_ABC VIN<1> @BASEBOARD_FAB2_LIB.BASEBOARD_FAB2(SCH_1):VR_FET_SW_P12V_STBY_PVPP_ABC
   8 VR_FET_SW_P12V_STBY_PVPP_ABC VIN<0> @BASEBOARD_FAB2_LIB.BASEBOARD_FAB2(SCH_1):VR_FET_SW_P12V_STBY_PVPP_ABC
  35 VR_PVPP_ABC_PHASE    VSW @BASEBOARD_FAB2_LIB.BASEBOARD_FAB2(SCH_1):VR_PVPP_ABC_PHASE
  43 VR_PVPP_ABC_PHASE VSWH<7> @BASEBOARD_FAB2_LIB.BASEBOARD_FAB2(SCH_1):VR_PVPP_ABC_PHASE
  34 VR_PVPP_ABC_PHASE VSWH<6> @BASEBOARD_FAB2_LIB.BASEBOARD_FAB2(SCH_1):VR_PVPP_ABC_PHASE
  33 VR_PVPP_ABC_PHASE VSWH<5> @BASEBOARD_FAB2_LIB.BASEBOARD_FAB2(SCH_1):VR_PVPP_ABC_PHASE
  32 VR_PVPP_ABC_PHASE VSWH<4> @BASEBOARD_FAB2_LIB.BASEBOARD_FAB2(SCH_1):VR_PVPP_ABC_PHASE
  31 VR_PVPP_ABC_PHASE VSWH<3> @BASEBOARD_FAB2_LIB.BASEBOARD_FAB2(SCH_1):VR_PVPP_ABC_PHASE
  30 VR_PVPP_ABC_PHASE VSWH<2> @BASEBOARD_FAB2_LIB.BASEBOARD_FAB2(SCH_1):VR_PVPP_ABC_PHASE
  29 VR_PVPP_ABC_PHASE VSWH<1> @BASEBOARD_FAB2_LIB.BASEBOARD_FAB2(SCH_1):VR_PVPP_ABC_PHASE
  15 VR_PVPP_ABC_PHASE VSWH<0> @BASEBOARD_FAB2_LIB.BASEBOARD_FAB2(SCH_1):VR_PVPP_ABC_PHASE

CAP_0402-0.027UF,16V,10%,X7R,AA  I194  C7F10
   1 VR_PVPP_ABC_SS      A @BASEBOARD_FAB2_LIB.BASEBOARD_FAB2(SCH_1):VR_PVPP_ABC_SS
   2 AGND_PVPP_ABC      B @BASEBOARD_FAB2_LIB.BASEBOARD_FAB2(SCH_1):AGND_PVPP_ABC

CAP_0402LF-100.0PF,50V,5%,COG,A  I199  C7F9
   1 VR_FB_PVPP_ABC      A @BASEBOARD_FAB2_LIB.BASEBOARD_FAB2(SCH_1):VR_FB_PVPP_ABC
   2 VR_COMP_PVPP_ABC_3      B @BASEBOARD_FAB2_LIB.BASEBOARD_FAB2(SCH_1):VR_COMP_PVPP_ABC_3

CAP_0402LF-2200PF,50V,10%,X7R,A  I200  C7F12
   1 VR_COMP_RC_PVPP_ABC      A @BASEBOARD_FAB2_LIB.BASEBOARD_FAB2(SCH_1):VR_COMP_RC_PVPP_ABC
   2 VR_COMP_PVPP_ABC_3      B @BASEBOARD_FAB2_LIB.BASEBOARD_FAB2(SCH_1):VR_COMP_PVPP_ABC_3

RES_0402-7.87K,1.0%,1/16W,CHIPA  I201  R7F18
   1 VR_COMP_RC_PVPP_ABC      A @BASEBOARD_FAB2_LIB.BASEBOARD_FAB2(SCH_1):VR_COMP_RC_PVPP_ABC
   2 VR_FB_PVPP_ABC      B @BASEBOARD_FAB2_LIB.BASEBOARD_FAB2(SCH_1):VR_FB_PVPP_ABC

CAP_0603-4.7UF,6.3V,10%,X6S,E1A  I202  C3T11
   1 VR_VB_PVPP_ABC      A @BASEBOARD_FAB2_LIB.BASEBOARD_FAB2(SCH_1):VR_VB_PVPP_ABC
   2 AGND_PVPP_ABC      B @BASEBOARD_FAB2_LIB.BASEBOARD_FAB2(SCH_1):AGND_PVPP_ABC

CAP_A_0402V-0.1UF,16V,10%,X7R,A  I205  C7F6
   1 VR_FET_SW_P12V_STBY_PVPP_ABC      A @BASEBOARD_FAB2_LIB.BASEBOARD_FAB2(SCH_1):VR_FET_SW_P12V_STBY_PVPP_ABC
   2    GND      B @BASEBOARD_FAB2_LIB.BASEBOARD_FAB2(SCH_1):GND

RES_0402-22.1,1.0%,1/16W,CHIP,A  I208  R7F16
   1 PWRGD_PVPP_ABC_R      A @BASEBOARD_FAB2_LIB.BASEBOARD_FAB2(SCH_1):PWRGD_PVPP_ABC_R
   2 PWRGD_PVPP_ABC      B @BASEBOARD_FAB2_LIB.BASEBOARD_FAB2(SCH_1):PWRGD_PVPP_ABC

CAP_0805-10UF,16V,10%,X6S,C953A  I209  C7F5
   1 VR_FET_SW_P12V_STBY_PVPP_ABC      A @BASEBOARD_FAB2_LIB.BASEBOARD_FAB2(SCH_1):VR_FET_SW_P12V_STBY_PVPP_ABC
   2    GND      B @BASEBOARD_FAB2_LIB.BASEBOARD_FAB2(SCH_1):GND

CAP_0805-10UF,16V,10%,X6S,C953A  I210  C3T8
   1 VR_FET_SW_P12V_STBY_PVPP_ABC      A @BASEBOARD_FAB2_LIB.BASEBOARD_FAB2(SCH_1):VR_FET_SW_P12V_STBY_PVPP_ABC
   2    GND      B @BASEBOARD_FAB2_LIB.BASEBOARD_FAB2(SCH_1):GND

CAP_0805-10UF,16V,10%,X6S,C953A  I211  C3T14
   1 VR_FET_SW_P12V_STBY_PVPP_ABC      A @BASEBOARD_FAB2_LIB.BASEBOARD_FAB2(SCH_1):VR_FET_SW_P12V_STBY_PVPP_ABC
   2    GND      B @BASEBOARD_FAB2_LIB.BASEBOARD_FAB2(SCH_1):GND

CAP_0805-10UF,16V,10%,X6S,C953A  I215  C3T12
   1 VR_FET_SW_P12V_STBY_PVPP_ABC      A @BASEBOARD_FAB2_LIB.BASEBOARD_FAB2(SCH_1):VR_FET_SW_P12V_STBY_PVPP_ABC
   2    GND      B @BASEBOARD_FAB2_LIB.BASEBOARD_FAB2(SCH_1):GND

CAPP_7343-220UF,4V,20%,POSCAP,A  I217  C4T3
   1 PVPP_ABC      A @BASEBOARD_FAB2_LIB.BASEBOARD_FAB2(SCH_1):PVPP_ABC
   2    GND      B @BASEBOARD_FAB2_LIB.BASEBOARD_FAB2(SCH_1):GND

RES_0402-1.0K,0.1%,1/16W,CHIP,A  I218  R7F17
   1 VSENSE_PVPP_ABC      A @BASEBOARD_FAB2_LIB.BASEBOARD_FAB2(SCH_1):VSENSE_PVPP_ABC
   2 VR_COMP_PVPP_ABC      B @BASEBOARD_FAB2_LIB.BASEBOARD_FAB2(SCH_1):VR_COMP_PVPP_ABC

CAP_0402LF-2200PF,50V,10%,X7R,A  I219  C7F13
   1 VR_COMP_PVPP_ABC      A @BASEBOARD_FAB2_LIB.BASEBOARD_FAB2(SCH_1):VR_COMP_PVPP_ABC
   2 VR_FB_PVPP_ABC      B @BASEBOARD_FAB2_LIB.BASEBOARD_FAB2(SCH_1):VR_FB_PVPP_ABC

RES_0402-0.0,5%,1/16W,CHIP,G21A  I220  R7F9
   1 FM_PVPP_CPU0_EN      A @BASEBOARD_FAB2_LIB.BASEBOARD_FAB2(SCH_1):FM_PVPP_CPU0_EN
   2 FM_PVPP_PVDDQ_CPU0_EN_ABC      B @BASEBOARD_FAB2_LIB.BASEBOARD_FAB2(SCH_1):FM_PVPP_PVDDQ_CPU0_EN_ABC


DRAWING: @BASEBOARD_FAB2_LIB.BASEBOARD_FAB2(SCH_1):PAGE232 

CAP_0603LF-10UF,4V,20%,X6S,E15A  I102  C4L2
   1 PVPP_DEF      A @BASEBOARD_FAB2_LIB.BASEBOARD_FAB2(SCH_1):PVPP_DEF
   2    GND      B @BASEBOARD_FAB2_LIB.BASEBOARD_FAB2(SCH_1):GND

CAP_0603LF-10UF,4V,20%,X6S,E15A  I104  C6A3
   1 PVPP_DEF      A @BASEBOARD_FAB2_LIB.BASEBOARD_FAB2(SCH_1):PVPP_DEF
   2    GND      B @BASEBOARD_FAB2_LIB.BASEBOARD_FAB2(SCH_1):GND

CAP_0603LF-10UF,4V,20%,X6S,E15A  I105  C6A2
   1 PVPP_DEF      A @BASEBOARD_FAB2_LIB.BASEBOARD_FAB2(SCH_1):PVPP_DEF
   2    GND      B @BASEBOARD_FAB2_LIB.BASEBOARD_FAB2(SCH_1):GND

CAP_0603LF-10UF,4V,20%,X6S,E15A  I106  C4L3
   1 PVPP_DEF      A @BASEBOARD_FAB2_LIB.BASEBOARD_FAB2(SCH_1):PVPP_DEF
   2    GND      B @BASEBOARD_FAB2_LIB.BASEBOARD_FAB2(SCH_1):GND

CAP_0603LF-10UF,4V,20%,X6S,E15A  I108  C4L4
   1 PVPP_DEF      A @BASEBOARD_FAB2_LIB.BASEBOARD_FAB2(SCH_1):PVPP_DEF
   2    GND      B @BASEBOARD_FAB2_LIB.BASEBOARD_FAB2(SCH_1):GND

CAP_0603LF-10UF,4V,20%,X6S,E15A  I109  C6A7
   1 PVPP_DEF      A @BASEBOARD_FAB2_LIB.BASEBOARD_FAB2(SCH_1):PVPP_DEF
   2    GND      B @BASEBOARD_FAB2_LIB.BASEBOARD_FAB2(SCH_1):GND

CAP_0603LF-10UF,4V,20%,X6S,E15A  I110  C6A6
   1 PVPP_DEF      A @BASEBOARD_FAB2_LIB.BASEBOARD_FAB2(SCH_1):PVPP_DEF
   2    GND      B @BASEBOARD_FAB2_LIB.BASEBOARD_FAB2(SCH_1):GND

CAP_0603LF-10UF,4V,20%,X6S,E15A  I111  C4M3
   1 PVPP_DEF      A @BASEBOARD_FAB2_LIB.BASEBOARD_FAB2(SCH_1):PVPP_DEF
   2    GND      B @BASEBOARD_FAB2_LIB.BASEBOARD_FAB2(SCH_1):GND

CAP_0603LF-10UF,4V,20%,X6S,E15A  I125  C4M4
   1 PVPP_DEF      A @BASEBOARD_FAB2_LIB.BASEBOARD_FAB2(SCH_1):PVPP_DEF
   2    GND      B @BASEBOARD_FAB2_LIB.BASEBOARD_FAB2(SCH_1):GND

CAP_0603LF-10UF,4V,20%,X6S,E15A  I126  C6B2
   1 PVPP_DEF      A @BASEBOARD_FAB2_LIB.BASEBOARD_FAB2(SCH_1):PVPP_DEF
   2    GND      B @BASEBOARD_FAB2_LIB.BASEBOARD_FAB2(SCH_1):GND

CAP_0603LF-10UF,4V,20%,X6S,E15A  I128  C6B1
   1 PVPP_DEF      A @BASEBOARD_FAB2_LIB.BASEBOARD_FAB2(SCH_1):PVPP_DEF
   2    GND      B @BASEBOARD_FAB2_LIB.BASEBOARD_FAB2(SCH_1):GND

CAP_0603LF-10UF,4V,20%,X6S,E15A  I129  C4L1
   1 PVPP_DEF      A @BASEBOARD_FAB2_LIB.BASEBOARD_FAB2(SCH_1):PVPP_DEF
   2    GND      B @BASEBOARD_FAB2_LIB.BASEBOARD_FAB2(SCH_1):GND

RES_0402-0.0,5%,1/16W,CHIP,G21A  I150  R7B20
   1    GND      A @BASEBOARD_FAB2_LIB.BASEBOARD_FAB2(SCH_1):GND
   2 AGND_PVPP_DEF      B @BASEBOARD_FAB2_LIB.BASEBOARD_FAB2(SCH_1):AGND_PVPP_DEF

CAP_0402LF-1000PF,50V,10%,EMPTA  I185  C7B9
   1 FM_PVPP_CPU0_EN      A @BASEBOARD_FAB2_LIB.BASEBOARD_FAB2(SCH_1):FM_PVPP_CPU0_EN
   2 AGND_PVPP_DEF      B @BASEBOARD_FAB2_LIB.BASEBOARD_FAB2(SCH_1):AGND_PVPP_DEF

RES_0402-7.87K,1.0%,1/16W,CHIPA  I193  R7B14
   1 VR_PVPP_DEF_ISET      A @BASEBOARD_FAB2_LIB.BASEBOARD_FAB2(SCH_1):VR_PVPP_DEF_ISET
   2 AGND_PVPP_DEF      B @BASEBOARD_FAB2_LIB.BASEBOARD_FAB2(SCH_1):AGND_PVPP_DEF

CAP_0402-0.027UF,16V,10%,X7R,AA  I197  C7B11
   1 VR_PVPP_DEF_SS      A @BASEBOARD_FAB2_LIB.BASEBOARD_FAB2(SCH_1):VR_PVPP_DEF_SS
   2 AGND_PVPP_DEF      B @BASEBOARD_FAB2_LIB.BASEBOARD_FAB2(SCH_1):AGND_PVPP_DEF

FERRITE_SM-22,FB,656554-051  I200  FB7B1
   1 P12V_STBY      A @BASEBOARD_FAB2_LIB.BASEBOARD_FAB2(SCH_1):P12V_STBY
   2 VR_FET_SW_P12V_STBY_PVPP_DEF      B @BASEBOARD_FAB2_LIB.BASEBOARD_FAB2(SCH_1):VR_FET_SW_P12V_STBY_PVPP_DEF

CAP_1210-47UF,16V,20%,X6S,D384A  I202  C7B8
   1 VR_FET_SW_P12V_STBY_PVPP_DEF      A @BASEBOARD_FAB2_LIB.BASEBOARD_FAB2(SCH_1):VR_FET_SW_P12V_STBY_PVPP_DEF
   2    GND      B @BASEBOARD_FAB2_LIB.BASEBOARD_FAB2(SCH_1):GND

CAP_0402-1.0UF,16V,10%,X6S,D97A  I207  C3M9
   1 VR_FET_SW_P12V_STBY_PVPP_DEF      A @BASEBOARD_FAB2_LIB.BASEBOARD_FAB2(SCH_1):VR_FET_SW_P12V_STBY_PVPP_DEF
   2    GND      B @BASEBOARD_FAB2_LIB.BASEBOARD_FAB2(SCH_1):GND

CAP_0402LF-1000PF,50V,10%,X7R,A  I209  C7B12
   1 PWRGD_PVPP_DEF_R      A @BASEBOARD_FAB2_LIB.BASEBOARD_FAB2(SCH_1):PWRGD_PVPP_DEF_R
   2    GND      B @BASEBOARD_FAB2_LIB.BASEBOARD_FAB2(SCH_1):GND

RES_0402-1.00K,1%,1/16W,CHIP,GA  I210  R7B17
   1 P3V3_STBY      A @BASEBOARD_FAB2_LIB.BASEBOARD_FAB2(SCH_1):P3V3_STBY
   2 PWRGD_PVPP_DEF_R      B @BASEBOARD_FAB2_LIB.BASEBOARD_FAB2(SCH_1):PWRGD_PVPP_DEF_R

NCP3232L_SM-IC,H86355-001  I214  EU7B1
   5 AGND_PVPP_DEF   AGND @BASEBOARD_FAB2_LIB.BASEBOARD_FAB2(SCH_1):AGND_PVPP_DEF
  36 VR_PVPP_DEF_BOOT    BST @BASEBOARD_FAB2_LIB.BASEBOARD_FAB2(SCH_1):VR_PVPP_DEF_BOOT
   3 VR_COMP_PVPP_DEF_3   COMP @BASEBOARD_FAB2_LIB.BASEBOARD_FAB2(SCH_1):VR_COMP_PVPP_DEF_3
  40 FM_PVPP_PVDDQ_CPU0_EN_DEF     EN @BASEBOARD_FAB2_LIB.BASEBOARD_FAB2(SCH_1):FM_PVPP_PVDDQ_CPU0_EN_DEF
   2 VR_FB_PVPP_DEF     FB @BASEBOARD_FAB2_LIB.BASEBOARD_FAB2(SCH_1):VR_FB_PVPP_DEF
  41    GND    GND @BASEBOARD_FAB2_LIB.BASEBOARD_FAB2(SCH_1):GND
   4 VR_PVPP_DEF_ISET   ISET @BASEBOARD_FAB2_LIB.BASEBOARD_FAB2(SCH_1):VR_PVPP_DEF_ISET
   6 AGND_PVPP_DEF    OTS @BASEBOARD_FAB2_LIB.BASEBOARD_FAB2(SCH_1):AGND_PVPP_DEF
   7 PWRGD_PVPP_DEF_R     PG @BASEBOARD_FAB2_LIB.BASEBOARD_FAB2(SCH_1):PWRGD_PVPP_DEF_R
  37    GND PGND<13> @BASEBOARD_FAB2_LIB.BASEBOARD_FAB2(SCH_1):GND
  28    GND PGND<12> @BASEBOARD_FAB2_LIB.BASEBOARD_FAB2(SCH_1):GND
  27    GND PGND<11> @BASEBOARD_FAB2_LIB.BASEBOARD_FAB2(SCH_1):GND
  26    GND PGND<10> @BASEBOARD_FAB2_LIB.BASEBOARD_FAB2(SCH_1):GND
  25    GND PGND<9> @BASEBOARD_FAB2_LIB.BASEBOARD_FAB2(SCH_1):GND
  24    GND PGND<8> @BASEBOARD_FAB2_LIB.BASEBOARD_FAB2(SCH_1):GND
  23    GND PGND<7> @BASEBOARD_FAB2_LIB.BASEBOARD_FAB2(SCH_1):GND
  22    GND PGND<6> @BASEBOARD_FAB2_LIB.BASEBOARD_FAB2(SCH_1):GND
  21    GND PGND<5> @BASEBOARD_FAB2_LIB.BASEBOARD_FAB2(SCH_1):GND
  20    GND PGND<4> @BASEBOARD_FAB2_LIB.BASEBOARD_FAB2(SCH_1):GND
  19    GND PGND<3> @BASEBOARD_FAB2_LIB.BASEBOARD_FAB2(SCH_1):GND
  18    GND PGND<2> @BASEBOARD_FAB2_LIB.BASEBOARD_FAB2(SCH_1):GND
  17    GND PGND<1> @BASEBOARD_FAB2_LIB.BASEBOARD_FAB2(SCH_1):GND
  16    GND PGND<0> @BASEBOARD_FAB2_LIB.BASEBOARD_FAB2(SCH_1):GND
   1 VR_PVPP_DEF_SS     SS @BASEBOARD_FAB2_LIB.BASEBOARD_FAB2(SCH_1):VR_PVPP_DEF_SS
  38 VR_VB_PVPP_DEF     VB @BASEBOARD_FAB2_LIB.BASEBOARD_FAB2(SCH_1):VR_VB_PVPP_DEF
  39 VR_FET_SW_P12V_STBY_PVPP_DEF    VCC @BASEBOARD_FAB2_LIB.BASEBOARD_FAB2(SCH_1):VR_FET_SW_P12V_STBY_PVPP_DEF
  42 VR_FET_SW_P12V_STBY_PVPP_DEF VIN<7> @BASEBOARD_FAB2_LIB.BASEBOARD_FAB2(SCH_1):VR_FET_SW_P12V_STBY_PVPP_DEF
  14 VR_FET_SW_P12V_STBY_PVPP_DEF VIN<6> @BASEBOARD_FAB2_LIB.BASEBOARD_FAB2(SCH_1):VR_FET_SW_P12V_STBY_PVPP_DEF
  13 VR_FET_SW_P12V_STBY_PVPP_DEF VIN<5> @BASEBOARD_FAB2_LIB.BASEBOARD_FAB2(SCH_1):VR_FET_SW_P12V_STBY_PVPP_DEF
  12 VR_FET_SW_P12V_STBY_PVPP_DEF VIN<4> @BASEBOARD_FAB2_LIB.BASEBOARD_FAB2(SCH_1):VR_FET_SW_P12V_STBY_PVPP_DEF
  11 VR_FET_SW_P12V_STBY_PVPP_DEF VIN<3> @BASEBOARD_FAB2_LIB.BASEBOARD_FAB2(SCH_1):VR_FET_SW_P12V_STBY_PVPP_DEF
  10 VR_FET_SW_P12V_STBY_PVPP_DEF VIN<2> @BASEBOARD_FAB2_LIB.BASEBOARD_FAB2(SCH_1):VR_FET_SW_P12V_STBY_PVPP_DEF
   9 VR_FET_SW_P12V_STBY_PVPP_DEF VIN<1> @BASEBOARD_FAB2_LIB.BASEBOARD_FAB2(SCH_1):VR_FET_SW_P12V_STBY_PVPP_DEF
   8 VR_FET_SW_P12V_STBY_PVPP_DEF VIN<0> @BASEBOARD_FAB2_LIB.BASEBOARD_FAB2(SCH_1):VR_FET_SW_P12V_STBY_PVPP_DEF
  35 VR_PVPP_DEF_PHASE    VSW @BASEBOARD_FAB2_LIB.BASEBOARD_FAB2(SCH_1):VR_PVPP_DEF_PHASE
  43 VR_PVPP_DEF_PHASE VSWH<7> @BASEBOARD_FAB2_LIB.BASEBOARD_FAB2(SCH_1):VR_PVPP_DEF_PHASE
  34 VR_PVPP_DEF_PHASE VSWH<6> @BASEBOARD_FAB2_LIB.BASEBOARD_FAB2(SCH_1):VR_PVPP_DEF_PHASE
  33 VR_PVPP_DEF_PHASE VSWH<5> @BASEBOARD_FAB2_LIB.BASEBOARD_FAB2(SCH_1):VR_PVPP_DEF_PHASE
  32 VR_PVPP_DEF_PHASE VSWH<4> @BASEBOARD_FAB2_LIB.BASEBOARD_FAB2(SCH_1):VR_PVPP_DEF_PHASE
  31 VR_PVPP_DEF_PHASE VSWH<3> @BASEBOARD_FAB2_LIB.BASEBOARD_FAB2(SCH_1):VR_PVPP_DEF_PHASE
  30 VR_PVPP_DEF_PHASE VSWH<2> @BASEBOARD_FAB2_LIB.BASEBOARD_FAB2(SCH_1):VR_PVPP_DEF_PHASE
  29 VR_PVPP_DEF_PHASE VSWH<1> @BASEBOARD_FAB2_LIB.BASEBOARD_FAB2(SCH_1):VR_PVPP_DEF_PHASE
  15 VR_PVPP_DEF_PHASE VSWH<0> @BASEBOARD_FAB2_LIB.BASEBOARD_FAB2(SCH_1):VR_PVPP_DEF_PHASE

RES_0402-2.2,5%,1/16W,EMPTY,G2A  I218  R7A15
   1 VR_PVPP_DEF_SNUB      A @BASEBOARD_FAB2_LIB.BASEBOARD_FAB2(SCH_1):VR_PVPP_DEF_SNUB
   2    GND      B @BASEBOARD_FAB2_LIB.BASEBOARD_FAB2(SCH_1):GND

CAP_0402LF-3300PF,50V,10%,EMPTA  I220  C7A34
   1 VR_PVPP_DEF_PHASE      A @BASEBOARD_FAB2_LIB.BASEBOARD_FAB2(SCH_1):VR_PVPP_DEF_PHASE
   2 VR_PVPP_DEF_SNUB      B @BASEBOARD_FAB2_LIB.BASEBOARD_FAB2(SCH_1):VR_PVPP_DEF_SNUB

RES_0603-120.0,1%,1/10W,CHIP,GA  I227  R7B10
   1 PVPP_DEF      A @BASEBOARD_FAB2_LIB.BASEBOARD_FAB2(SCH_1):PVPP_DEF
   2    GND      B @BASEBOARD_FAB2_LIB.BASEBOARD_FAB2(SCH_1):GND

CAPP_7343LF-330UF,6.3V,20%,POSA  I229  C6B7
   1 PVPP_DEF      A @BASEBOARD_FAB2_LIB.BASEBOARD_FAB2(SCH_1):PVPP_DEF
   2    GND      B @BASEBOARD_FAB2_LIB.BASEBOARD_FAB2(SCH_1):GND

CAP_0805-47UF,4V,20%,X6S,C9533A  I236  C6B3
   1 PVPP_DEF      A @BASEBOARD_FAB2_LIB.BASEBOARD_FAB2(SCH_1):PVPP_DEF
   2    GND      B @BASEBOARD_FAB2_LIB.BASEBOARD_FAB2(SCH_1):GND

CAP_0805-47UF,4V,20%,X6S,C9533A  I238  C7B7
   1 PVPP_DEF      A @BASEBOARD_FAB2_LIB.BASEBOARD_FAB2(SCH_1):PVPP_DEF
   2    GND      B @BASEBOARD_FAB2_LIB.BASEBOARD_FAB2(SCH_1):GND

INDUCTOR_SM-0.47UH,IND,E13358-A  I239  L7B1
   1 VR_PVPP_DEF_PHASE    INA @BASEBOARD_FAB2_LIB.BASEBOARD_FAB2(SCH_1):VR_PVPP_DEF_PHASE
   2 PVPP_DEF    INB @BASEBOARD_FAB2_LIB.BASEBOARD_FAB2(SCH_1):PVPP_DEF

RES_0402-0.0,5%,1/16W,CHIP,G21A  I240  R7B19
   1 VR_PVPP_DEF_BOOT      A @BASEBOARD_FAB2_LIB.BASEBOARD_FAB2(SCH_1):VR_PVPP_DEF_BOOT
   2 VR_PVPP_DEF_BOOT_R      B @BASEBOARD_FAB2_LIB.BASEBOARD_FAB2(SCH_1):VR_PVPP_DEF_BOOT_R

CAP_0603LF-0.1UF,25V,10%,X7R,6A  I241  C7B30
   1 VR_PVPP_DEF_PHASE      A @BASEBOARD_FAB2_LIB.BASEBOARD_FAB2(SCH_1):VR_PVPP_DEF_PHASE
   2 VR_PVPP_DEF_BOOT_R      B @BASEBOARD_FAB2_LIB.BASEBOARD_FAB2(SCH_1):VR_PVPP_DEF_BOOT_R

CAP_A_0402V-0.1UF,16V,10%,X7R,A  I252  C7B6
   1 VR_FET_SW_P12V_STBY_PVPP_DEF      A @BASEBOARD_FAB2_LIB.BASEBOARD_FAB2(SCH_1):VR_FET_SW_P12V_STBY_PVPP_DEF
   2    GND      B @BASEBOARD_FAB2_LIB.BASEBOARD_FAB2(SCH_1):GND

CAP_0603-4.7UF,6.3V,10%,X6S,E1A  I253  C3M10
   1 VR_VB_PVPP_DEF      A @BASEBOARD_FAB2_LIB.BASEBOARD_FAB2(SCH_1):VR_VB_PVPP_DEF
   2 AGND_PVPP_DEF      B @BASEBOARD_FAB2_LIB.BASEBOARD_FAB2(SCH_1):AGND_PVPP_DEF

RES_0402-22.1,1.0%,1/16W,CHIP,A  I257  R7B12
   1 PWRGD_PVPP_DEF_R      A @BASEBOARD_FAB2_LIB.BASEBOARD_FAB2(SCH_1):PWRGD_PVPP_DEF_R
   2 PWRGD_PVPP_DEF      B @BASEBOARD_FAB2_LIB.BASEBOARD_FAB2(SCH_1):PWRGD_PVPP_DEF

CAP_0805-10UF,16V,10%,X6S,C953A  I259  C3M8
   1 VR_FET_SW_P12V_STBY_PVPP_DEF      A @BASEBOARD_FAB2_LIB.BASEBOARD_FAB2(SCH_1):VR_FET_SW_P12V_STBY_PVPP_DEF
   2    GND      B @BASEBOARD_FAB2_LIB.BASEBOARD_FAB2(SCH_1):GND

CAP_0805-10UF,16V,10%,X6S,C953A  I260  C3M15
   1 VR_FET_SW_P12V_STBY_PVPP_DEF      A @BASEBOARD_FAB2_LIB.BASEBOARD_FAB2(SCH_1):VR_FET_SW_P12V_STBY_PVPP_DEF
   2    GND      B @BASEBOARD_FAB2_LIB.BASEBOARD_FAB2(SCH_1):GND

CAP_0805-10UF,16V,10%,X6S,C953A  I261  C3M16
   1 VR_FET_SW_P12V_STBY_PVPP_DEF      A @BASEBOARD_FAB2_LIB.BASEBOARD_FAB2(SCH_1):VR_FET_SW_P12V_STBY_PVPP_DEF
   2    GND      B @BASEBOARD_FAB2_LIB.BASEBOARD_FAB2(SCH_1):GND

CAP_0805-10UF,16V,10%,X6S,C953A  I262  C7B5
   1 VR_FET_SW_P12V_STBY_PVPP_DEF      A @BASEBOARD_FAB2_LIB.BASEBOARD_FAB2(SCH_1):VR_FET_SW_P12V_STBY_PVPP_DEF
   2    GND      B @BASEBOARD_FAB2_LIB.BASEBOARD_FAB2(SCH_1):GND

CAPP_7343-220UF,4V,20%,POSCAP,A  I267  C4M1
   1 PVPP_DEF      A @BASEBOARD_FAB2_LIB.BASEBOARD_FAB2(SCH_1):PVPP_DEF
   2    GND      B @BASEBOARD_FAB2_LIB.BASEBOARD_FAB2(SCH_1):GND

RES_0402-1.0K,0.1%,1/16W,CHIP,A  I298  R7B18
   1 VSENSE_PVPP_DEF      A @BASEBOARD_FAB2_LIB.BASEBOARD_FAB2(SCH_1):VSENSE_PVPP_DEF
   2 VR_COMP_PVPP_DEF      B @BASEBOARD_FAB2_LIB.BASEBOARD_FAB2(SCH_1):VR_COMP_PVPP_DEF

RES_0402-0.0,5%,1/16W,CHIP,G21A  I299  R7B11
   1 PVPP_DEF      A @BASEBOARD_FAB2_LIB.BASEBOARD_FAB2(SCH_1):PVPP_DEF
   2 VSENSE_PVPP_DEF      B @BASEBOARD_FAB2_LIB.BASEBOARD_FAB2(SCH_1):VSENSE_PVPP_DEF

RES_0402-7.87K,1.0%,1/16W,CHIPA  I300  R7B16
   1 VR_COMP_RC_PVPP_DEF      A @BASEBOARD_FAB2_LIB.BASEBOARD_FAB2(SCH_1):VR_COMP_RC_PVPP_DEF
   2 VR_FB_PVPP_DEF      B @BASEBOARD_FAB2_LIB.BASEBOARD_FAB2(SCH_1):VR_FB_PVPP_DEF

CAP_0402LF-100.0PF,50V,5%,COG,A  I301  C7B10
   1 VR_FB_PVPP_DEF      A @BASEBOARD_FAB2_LIB.BASEBOARD_FAB2(SCH_1):VR_FB_PVPP_DEF
   2 VR_COMP_PVPP_DEF_3      B @BASEBOARD_FAB2_LIB.BASEBOARD_FAB2(SCH_1):VR_COMP_PVPP_DEF_3

CAP_0402LF-2200PF,50V,10%,X7R,A  I302  C7B13
   1 VR_COMP_PVPP_DEF      A @BASEBOARD_FAB2_LIB.BASEBOARD_FAB2(SCH_1):VR_COMP_PVPP_DEF
   2 VR_FB_PVPP_DEF      B @BASEBOARD_FAB2_LIB.BASEBOARD_FAB2(SCH_1):VR_FB_PVPP_DEF

RES_0402-20.0K,1%,1/16W,CHIP,GA  I303  R7B15
   1 VSENSE_PVPP_DEF      A @BASEBOARD_FAB2_LIB.BASEBOARD_FAB2(SCH_1):VSENSE_PVPP_DEF
   2 VR_FB_PVPP_DEF      B @BASEBOARD_FAB2_LIB.BASEBOARD_FAB2(SCH_1):VR_FB_PVPP_DEF

RES_0402-6.34K,1%,1/16W,CHIP,GA  I304  R7B13
   1 VR_FB_PVPP_DEF      A @BASEBOARD_FAB2_LIB.BASEBOARD_FAB2(SCH_1):VR_FB_PVPP_DEF
   2 AGND_PVPP_DEF      B @BASEBOARD_FAB2_LIB.BASEBOARD_FAB2(SCH_1):AGND_PVPP_DEF

CAP_0402LF-2200PF,50V,10%,X7R,A  I306  C7B14
   1 VR_COMP_RC_PVPP_DEF      A @BASEBOARD_FAB2_LIB.BASEBOARD_FAB2(SCH_1):VR_COMP_RC_PVPP_DEF
   2 VR_COMP_PVPP_DEF_3      B @BASEBOARD_FAB2_LIB.BASEBOARD_FAB2(SCH_1):VR_COMP_PVPP_DEF_3

RES_0402-0.0,5%,1/16W,CHIP,G21A  I307  R7B9
   1 FM_PVPP_CPU0_EN      A @BASEBOARD_FAB2_LIB.BASEBOARD_FAB2(SCH_1):FM_PVPP_CPU0_EN
   2 FM_PVPP_PVDDQ_CPU0_EN_DEF      B @BASEBOARD_FAB2_LIB.BASEBOARD_FAB2(SCH_1):FM_PVPP_PVDDQ_CPU0_EN_DEF


DRAWING: @BASEBOARD_FAB2_LIB.BASEBOARD_FAB2(SCH_1):PAGE233 

CAP_0603LF-10UF,4V,20%,X6S,E15A  I109  C7U4
   1 PVPP_GHJ      A @BASEBOARD_FAB2_LIB.BASEBOARD_FAB2(SCH_1):PVPP_GHJ
   2    GND      B @BASEBOARD_FAB2_LIB.BASEBOARD_FAB2(SCH_1):GND

CAP_0603LF-10UF,4V,20%,X6S,E15A  I111  C7U5
   1 PVPP_GHJ      A @BASEBOARD_FAB2_LIB.BASEBOARD_FAB2(SCH_1):PVPP_GHJ
   2    GND      B @BASEBOARD_FAB2_LIB.BASEBOARD_FAB2(SCH_1):GND

CAP_0603LF-10UF,4V,20%,X6S,E15A  I112  C7T2
   1 PVPP_GHJ      A @BASEBOARD_FAB2_LIB.BASEBOARD_FAB2(SCH_1):PVPP_GHJ
   2    GND      B @BASEBOARD_FAB2_LIB.BASEBOARD_FAB2(SCH_1):GND

CAP_0603LF-10UF,4V,20%,X6S,E15A  I113  C7T3
   1 PVPP_GHJ      A @BASEBOARD_FAB2_LIB.BASEBOARD_FAB2(SCH_1):PVPP_GHJ
   2    GND      B @BASEBOARD_FAB2_LIB.BASEBOARD_FAB2(SCH_1):GND

CAP_0603LF-10UF,4V,20%,X6S,E15A  I115  C7U6
   1 PVPP_GHJ      A @BASEBOARD_FAB2_LIB.BASEBOARD_FAB2(SCH_1):PVPP_GHJ
   2    GND      B @BASEBOARD_FAB2_LIB.BASEBOARD_FAB2(SCH_1):GND

CAP_0603LF-10UF,4V,20%,X6S,E15A  I116  C3F3
   1 PVPP_GHJ      A @BASEBOARD_FAB2_LIB.BASEBOARD_FAB2(SCH_1):PVPP_GHJ
   2    GND      B @BASEBOARD_FAB2_LIB.BASEBOARD_FAB2(SCH_1):GND

CAP_0603LF-10UF,4V,20%,X6S,E15A  I117  C3F4
   1 PVPP_GHJ      A @BASEBOARD_FAB2_LIB.BASEBOARD_FAB2(SCH_1):PVPP_GHJ
   2    GND      B @BASEBOARD_FAB2_LIB.BASEBOARD_FAB2(SCH_1):GND

CAP_0603LF-10UF,4V,20%,X6S,E15A  I118  C3G3
   1 PVPP_GHJ      A @BASEBOARD_FAB2_LIB.BASEBOARD_FAB2(SCH_1):PVPP_GHJ
   2    GND      B @BASEBOARD_FAB2_LIB.BASEBOARD_FAB2(SCH_1):GND

CAP_0603LF-10UF,4V,20%,X6S,E15A  I132  C3G7
   1 PVPP_GHJ      A @BASEBOARD_FAB2_LIB.BASEBOARD_FAB2(SCH_1):PVPP_GHJ
   2    GND      B @BASEBOARD_FAB2_LIB.BASEBOARD_FAB2(SCH_1):GND

CAP_0603LF-10UF,4V,20%,X6S,E15A  I133  C3G4
   1 PVPP_GHJ      A @BASEBOARD_FAB2_LIB.BASEBOARD_FAB2(SCH_1):PVPP_GHJ
   2    GND      B @BASEBOARD_FAB2_LIB.BASEBOARD_FAB2(SCH_1):GND

CAP_0603LF-10UF,4V,20%,X6S,E15A  I135  C3G8
   1 PVPP_GHJ      A @BASEBOARD_FAB2_LIB.BASEBOARD_FAB2(SCH_1):PVPP_GHJ
   2    GND      B @BASEBOARD_FAB2_LIB.BASEBOARD_FAB2(SCH_1):GND

CAP_0603LF-10UF,4V,20%,X6S,E15A  I136  C7U3
   1 PVPP_GHJ      A @BASEBOARD_FAB2_LIB.BASEBOARD_FAB2(SCH_1):PVPP_GHJ
   2    GND      B @BASEBOARD_FAB2_LIB.BASEBOARD_FAB2(SCH_1):GND

RES_0402-0.0,5%,1/16W,CHIP,G21A  I157  R4G25
   1    GND      A @BASEBOARD_FAB2_LIB.BASEBOARD_FAB2(SCH_1):GND
   2 AGND_PVPP_GHJ      B @BASEBOARD_FAB2_LIB.BASEBOARD_FAB2(SCH_1):AGND_PVPP_GHJ

RES_0402-10.0K,1%,1/16W,CHIP,GA  I182  R4G5
   1 FM_PVPP_CPU1_EN      A @BASEBOARD_FAB2_LIB.BASEBOARD_FAB2(SCH_1):FM_PVPP_CPU1_EN
   2    GND      B @BASEBOARD_FAB2_LIB.BASEBOARD_FAB2(SCH_1):GND

CAP_0402LF-1000PF,50V,10%,EMPTA  I183  C4G7
   1 FM_PVPP_CPU1_EN      A @BASEBOARD_FAB2_LIB.BASEBOARD_FAB2(SCH_1):FM_PVPP_CPU1_EN
   2 AGND_PVPP_GHJ      B @BASEBOARD_FAB2_LIB.BASEBOARD_FAB2(SCH_1):AGND_PVPP_GHJ

RES_0402-7.87K,1.0%,1/16W,CHIPA  I184  R4G11
   1 VR_PVPP_GHJ_ISET      A @BASEBOARD_FAB2_LIB.BASEBOARD_FAB2(SCH_1):VR_PVPP_GHJ_ISET
   2 AGND_PVPP_GHJ      B @BASEBOARD_FAB2_LIB.BASEBOARD_FAB2(SCH_1):AGND_PVPP_GHJ

RES_0402-1.00K,1%,1/16W,CHIP,GA  I185  R4G14
   1 P3V3_STBY      A @BASEBOARD_FAB2_LIB.BASEBOARD_FAB2(SCH_1):P3V3_STBY
   2 PWRGD_PVPP_GHJ_R      B @BASEBOARD_FAB2_LIB.BASEBOARD_FAB2(SCH_1):PWRGD_PVPP_GHJ_R

CAP_0603-4.7UF,6.3V,10%,X6S,E1A  I187  C6U6
   1 VR_VB_PVPP_GHJ      A @BASEBOARD_FAB2_LIB.BASEBOARD_FAB2(SCH_1):VR_VB_PVPP_GHJ
   2 AGND_PVPP_GHJ      B @BASEBOARD_FAB2_LIB.BASEBOARD_FAB2(SCH_1):AGND_PVPP_GHJ

CAP_1210-47UF,16V,20%,X6S,D384A  I189  C4G5
   1 VR_FET_SW_P12V_STBY_PVPP_GHJ      A @BASEBOARD_FAB2_LIB.BASEBOARD_FAB2(SCH_1):VR_FET_SW_P12V_STBY_PVPP_GHJ
   2    GND      B @BASEBOARD_FAB2_LIB.BASEBOARD_FAB2(SCH_1):GND

CAP_0402-0.027UF,16V,10%,X7R,AA  I194  C4G8
   1 VR_PVPP_GHJ_SS      A @BASEBOARD_FAB2_LIB.BASEBOARD_FAB2(SCH_1):VR_PVPP_GHJ_SS
   2 AGND_PVPP_GHJ      B @BASEBOARD_FAB2_LIB.BASEBOARD_FAB2(SCH_1):AGND_PVPP_GHJ

CAP_0402-1.0UF,16V,10%,X6S,D97A  I196  C4G4
   1 VR_FET_SW_P12V_STBY_PVPP_GHJ      A @BASEBOARD_FAB2_LIB.BASEBOARD_FAB2(SCH_1):VR_FET_SW_P12V_STBY_PVPP_GHJ
   2    GND      B @BASEBOARD_FAB2_LIB.BASEBOARD_FAB2(SCH_1):GND

FERRITE_SM-22,FB,656554-051  I198  FB4G1
   1 P12V_STBY      A @BASEBOARD_FAB2_LIB.BASEBOARD_FAB2(SCH_1):P12V_STBY
   2 VR_FET_SW_P12V_STBY_PVPP_GHJ      B @BASEBOARD_FAB2_LIB.BASEBOARD_FAB2(SCH_1):VR_FET_SW_P12V_STBY_PVPP_GHJ

RES_0402-0.0,5%,1/16W,CHIP,G21A  I199  R4G24
   1 VR_PVPP_GHJ_BOOT      A @BASEBOARD_FAB2_LIB.BASEBOARD_FAB2(SCH_1):VR_PVPP_GHJ_BOOT
   2 VR_PVPP_GHJ_BOOT_R      B @BASEBOARD_FAB2_LIB.BASEBOARD_FAB2(SCH_1):VR_PVPP_GHJ_BOOT_R

CAP_0402LF-1000PF,50V,10%,X7R,A  I201  C4G9
   1 PWRGD_PVPP_GHJ_R      A @BASEBOARD_FAB2_LIB.BASEBOARD_FAB2(SCH_1):PWRGD_PVPP_GHJ_R
   2    GND      B @BASEBOARD_FAB2_LIB.BASEBOARD_FAB2(SCH_1):GND

RES_0402-2.2,5%,1/16W,EMPTY,G2A  I208  R4F6
   1 VR_PVPP_GHJ_SNUB      A @BASEBOARD_FAB2_LIB.BASEBOARD_FAB2(SCH_1):VR_PVPP_GHJ_SNUB
   2    GND      B @BASEBOARD_FAB2_LIB.BASEBOARD_FAB2(SCH_1):GND

CAP_0402LF-3300PF,50V,10%,EMPTA  I209  C4F12
   1 VR_PVPP_GHJ_PHASE      A @BASEBOARD_FAB2_LIB.BASEBOARD_FAB2(SCH_1):VR_PVPP_GHJ_PHASE
   2 VR_PVPP_GHJ_SNUB      B @BASEBOARD_FAB2_LIB.BASEBOARD_FAB2(SCH_1):VR_PVPP_GHJ_SNUB

RES_0603-120.0,1%,1/10W,CHIP,GA  I211  R4G6
   1 PVPP_GHJ      A @BASEBOARD_FAB2_LIB.BASEBOARD_FAB2(SCH_1):PVPP_GHJ
   2    GND      B @BASEBOARD_FAB2_LIB.BASEBOARD_FAB2(SCH_1):GND

CAPP_7343LF-330UF,6.3V,20%,POSA  I217  C4F7
   1 PVPP_GHJ      A @BASEBOARD_FAB2_LIB.BASEBOARD_FAB2(SCH_1):PVPP_GHJ
   2    GND      B @BASEBOARD_FAB2_LIB.BASEBOARD_FAB2(SCH_1):GND

CAP_0805-47UF,4V,20%,X6S,C9533A  I221  C6U3
   1 PVPP_GHJ      A @BASEBOARD_FAB2_LIB.BASEBOARD_FAB2(SCH_1):PVPP_GHJ
   2    GND      B @BASEBOARD_FAB2_LIB.BASEBOARD_FAB2(SCH_1):GND

CAP_0805-47UF,4V,20%,X6S,C9533A  I223  C6U2
   1 PVPP_GHJ      A @BASEBOARD_FAB2_LIB.BASEBOARD_FAB2(SCH_1):PVPP_GHJ
   2    GND      B @BASEBOARD_FAB2_LIB.BASEBOARD_FAB2(SCH_1):GND

CAP_0603LF-0.1UF,25V,10%,X7R,6A  I224  C4G26
   1 VR_PVPP_GHJ_PHASE      A @BASEBOARD_FAB2_LIB.BASEBOARD_FAB2(SCH_1):VR_PVPP_GHJ_PHASE
   2 VR_PVPP_GHJ_BOOT_R      B @BASEBOARD_FAB2_LIB.BASEBOARD_FAB2(SCH_1):VR_PVPP_GHJ_BOOT_R

NCP3232L_SM-IC,H86355-001  I225  EU4G1
   5 AGND_PVPP_GHJ   AGND @BASEBOARD_FAB2_LIB.BASEBOARD_FAB2(SCH_1):AGND_PVPP_GHJ
  36 VR_PVPP_GHJ_BOOT    BST @BASEBOARD_FAB2_LIB.BASEBOARD_FAB2(SCH_1):VR_PVPP_GHJ_BOOT
   3 VR_COMP_PVPP_GHJ_3   COMP @BASEBOARD_FAB2_LIB.BASEBOARD_FAB2(SCH_1):VR_COMP_PVPP_GHJ_3
  40 FM_PVPP_PVDDQ_CPU1_EN_GHJ     EN @BASEBOARD_FAB2_LIB.BASEBOARD_FAB2(SCH_1):FM_PVPP_PVDDQ_CPU1_EN_GHJ
   2 VR_FB_PVPP_GHJ     FB @BASEBOARD_FAB2_LIB.BASEBOARD_FAB2(SCH_1):VR_FB_PVPP_GHJ
  41    GND    GND @BASEBOARD_FAB2_LIB.BASEBOARD_FAB2(SCH_1):GND
   4 VR_PVPP_GHJ_ISET   ISET @BASEBOARD_FAB2_LIB.BASEBOARD_FAB2(SCH_1):VR_PVPP_GHJ_ISET
   6 AGND_PVPP_GHJ    OTS @BASEBOARD_FAB2_LIB.BASEBOARD_FAB2(SCH_1):AGND_PVPP_GHJ
   7 PWRGD_PVPP_GHJ_R     PG @BASEBOARD_FAB2_LIB.BASEBOARD_FAB2(SCH_1):PWRGD_PVPP_GHJ_R
  37    GND PGND<13> @BASEBOARD_FAB2_LIB.BASEBOARD_FAB2(SCH_1):GND
  28    GND PGND<12> @BASEBOARD_FAB2_LIB.BASEBOARD_FAB2(SCH_1):GND
  27    GND PGND<11> @BASEBOARD_FAB2_LIB.BASEBOARD_FAB2(SCH_1):GND
  26    GND PGND<10> @BASEBOARD_FAB2_LIB.BASEBOARD_FAB2(SCH_1):GND
  25    GND PGND<9> @BASEBOARD_FAB2_LIB.BASEBOARD_FAB2(SCH_1):GND
  24    GND PGND<8> @BASEBOARD_FAB2_LIB.BASEBOARD_FAB2(SCH_1):GND
  23    GND PGND<7> @BASEBOARD_FAB2_LIB.BASEBOARD_FAB2(SCH_1):GND
  22    GND PGND<6> @BASEBOARD_FAB2_LIB.BASEBOARD_FAB2(SCH_1):GND
  21    GND PGND<5> @BASEBOARD_FAB2_LIB.BASEBOARD_FAB2(SCH_1):GND
  20    GND PGND<4> @BASEBOARD_FAB2_LIB.BASEBOARD_FAB2(SCH_1):GND
  19    GND PGND<3> @BASEBOARD_FAB2_LIB.BASEBOARD_FAB2(SCH_1):GND
  18    GND PGND<2> @BASEBOARD_FAB2_LIB.BASEBOARD_FAB2(SCH_1):GND
  17    GND PGND<1> @BASEBOARD_FAB2_LIB.BASEBOARD_FAB2(SCH_1):GND
  16    GND PGND<0> @BASEBOARD_FAB2_LIB.BASEBOARD_FAB2(SCH_1):GND
   1 VR_PVPP_GHJ_SS     SS @BASEBOARD_FAB2_LIB.BASEBOARD_FAB2(SCH_1):VR_PVPP_GHJ_SS
  38 VR_VB_PVPP_GHJ     VB @BASEBOARD_FAB2_LIB.BASEBOARD_FAB2(SCH_1):VR_VB_PVPP_GHJ
  39 VR_FET_SW_P12V_STBY_PVPP_GHJ    VCC @BASEBOARD_FAB2_LIB.BASEBOARD_FAB2(SCH_1):VR_FET_SW_P12V_STBY_PVPP_GHJ
  42 VR_FET_SW_P12V_STBY_PVPP_GHJ VIN<7> @BASEBOARD_FAB2_LIB.BASEBOARD_FAB2(SCH_1):VR_FET_SW_P12V_STBY_PVPP_GHJ
  14 VR_FET_SW_P12V_STBY_PVPP_GHJ VIN<6> @BASEBOARD_FAB2_LIB.BASEBOARD_FAB2(SCH_1):VR_FET_SW_P12V_STBY_PVPP_GHJ
  13 VR_FET_SW_P12V_STBY_PVPP_GHJ VIN<5> @BASEBOARD_FAB2_LIB.BASEBOARD_FAB2(SCH_1):VR_FET_SW_P12V_STBY_PVPP_GHJ
  12 VR_FET_SW_P12V_STBY_PVPP_GHJ VIN<4> @BASEBOARD_FAB2_LIB.BASEBOARD_FAB2(SCH_1):VR_FET_SW_P12V_STBY_PVPP_GHJ
  11 VR_FET_SW_P12V_STBY_PVPP_GHJ VIN<3> @BASEBOARD_FAB2_LIB.BASEBOARD_FAB2(SCH_1):VR_FET_SW_P12V_STBY_PVPP_GHJ
  10 VR_FET_SW_P12V_STBY_PVPP_GHJ VIN<2> @BASEBOARD_FAB2_LIB.BASEBOARD_FAB2(SCH_1):VR_FET_SW_P12V_STBY_PVPP_GHJ
   9 VR_FET_SW_P12V_STBY_PVPP_GHJ VIN<1> @BASEBOARD_FAB2_LIB.BASEBOARD_FAB2(SCH_1):VR_FET_SW_P12V_STBY_PVPP_GHJ
   8 VR_FET_SW_P12V_STBY_PVPP_GHJ VIN<0> @BASEBOARD_FAB2_LIB.BASEBOARD_FAB2(SCH_1):VR_FET_SW_P12V_STBY_PVPP_GHJ
  35 VR_PVPP_GHJ_PHASE    VSW @BASEBOARD_FAB2_LIB.BASEBOARD_FAB2(SCH_1):VR_PVPP_GHJ_PHASE
  43 VR_PVPP_GHJ_PHASE VSWH<7> @BASEBOARD_FAB2_LIB.BASEBOARD_FAB2(SCH_1):VR_PVPP_GHJ_PHASE
  34 VR_PVPP_GHJ_PHASE VSWH<6> @BASEBOARD_FAB2_LIB.BASEBOARD_FAB2(SCH_1):VR_PVPP_GHJ_PHASE
  33 VR_PVPP_GHJ_PHASE VSWH<5> @BASEBOARD_FAB2_LIB.BASEBOARD_FAB2(SCH_1):VR_PVPP_GHJ_PHASE
  32 VR_PVPP_GHJ_PHASE VSWH<4> @BASEBOARD_FAB2_LIB.BASEBOARD_FAB2(SCH_1):VR_PVPP_GHJ_PHASE
  31 VR_PVPP_GHJ_PHASE VSWH<3> @BASEBOARD_FAB2_LIB.BASEBOARD_FAB2(SCH_1):VR_PVPP_GHJ_PHASE
  30 VR_PVPP_GHJ_PHASE VSWH<2> @BASEBOARD_FAB2_LIB.BASEBOARD_FAB2(SCH_1):VR_PVPP_GHJ_PHASE
  29 VR_PVPP_GHJ_PHASE VSWH<1> @BASEBOARD_FAB2_LIB.BASEBOARD_FAB2(SCH_1):VR_PVPP_GHJ_PHASE
  15 VR_PVPP_GHJ_PHASE VSWH<0> @BASEBOARD_FAB2_LIB.BASEBOARD_FAB2(SCH_1):VR_PVPP_GHJ_PHASE

CAP_A_0402V-0.1UF,16V,10%,X7R,A  I242  C6U5
   1 VR_FET_SW_P12V_STBY_PVPP_GHJ      A @BASEBOARD_FAB2_LIB.BASEBOARD_FAB2(SCH_1):VR_FET_SW_P12V_STBY_PVPP_GHJ
   2    GND      B @BASEBOARD_FAB2_LIB.BASEBOARD_FAB2(SCH_1):GND

RES_0402-22.1,1.0%,1/16W,CHIP,A  I247  R4G12
   1 PWRGD_PVPP_GHJ_R      A @BASEBOARD_FAB2_LIB.BASEBOARD_FAB2(SCH_1):PWRGD_PVPP_GHJ_R
   2 PWRGD_PVPP_GHJ      B @BASEBOARD_FAB2_LIB.BASEBOARD_FAB2(SCH_1):PWRGD_PVPP_GHJ

CAP_0805-10UF,16V,10%,X6S,C953A  I248  C6U4
   1 VR_FET_SW_P12V_STBY_PVPP_GHJ      A @BASEBOARD_FAB2_LIB.BASEBOARD_FAB2(SCH_1):VR_FET_SW_P12V_STBY_PVPP_GHJ
   2    GND      B @BASEBOARD_FAB2_LIB.BASEBOARD_FAB2(SCH_1):GND

CAP_0805-10UF,16V,10%,X6S,C953A  I253  C4G2
   1 VR_FET_SW_P12V_STBY_PVPP_GHJ      A @BASEBOARD_FAB2_LIB.BASEBOARD_FAB2(SCH_1):VR_FET_SW_P12V_STBY_PVPP_GHJ
   2    GND      B @BASEBOARD_FAB2_LIB.BASEBOARD_FAB2(SCH_1):GND

CAP_0805-10UF,16V,10%,X6S,C953A  I254  C6U7
   1 VR_FET_SW_P12V_STBY_PVPP_GHJ      A @BASEBOARD_FAB2_LIB.BASEBOARD_FAB2(SCH_1):VR_FET_SW_P12V_STBY_PVPP_GHJ
   2    GND      B @BASEBOARD_FAB2_LIB.BASEBOARD_FAB2(SCH_1):GND

CAP_0805-10UF,16V,10%,X6S,C953A  I255  C6U8
   1 VR_FET_SW_P12V_STBY_PVPP_GHJ      A @BASEBOARD_FAB2_LIB.BASEBOARD_FAB2(SCH_1):VR_FET_SW_P12V_STBY_PVPP_GHJ
   2    GND      B @BASEBOARD_FAB2_LIB.BASEBOARD_FAB2(SCH_1):GND

CAPP_7343-220UF,4V,20%,POSCAP,A  I256  C4F11
   1 PVPP_GHJ      A @BASEBOARD_FAB2_LIB.BASEBOARD_FAB2(SCH_1):PVPP_GHJ
   2    GND      B @BASEBOARD_FAB2_LIB.BASEBOARD_FAB2(SCH_1):GND

RES_0402-1.0K,0.1%,1/16W,CHIP,A  I266  R4G10
   1 VSENSE_PVPP_GHJ      A @BASEBOARD_FAB2_LIB.BASEBOARD_FAB2(SCH_1):VSENSE_PVPP_GHJ
   2 VR_COMP_PVPP_GHJ      B @BASEBOARD_FAB2_LIB.BASEBOARD_FAB2(SCH_1):VR_COMP_PVPP_GHJ

CAP_0402LF-2200PF,50V,10%,X7R,A  I267  C4G11
   1 VR_COMP_PVPP_GHJ      A @BASEBOARD_FAB2_LIB.BASEBOARD_FAB2(SCH_1):VR_COMP_PVPP_GHJ
   2 VR_FB_PVPP_GHJ      B @BASEBOARD_FAB2_LIB.BASEBOARD_FAB2(SCH_1):VR_FB_PVPP_GHJ

RES_0402-6.34K,1%,1/16W,CHIP,GA  I269  R4G9
   1 VR_FB_PVPP_GHJ      A @BASEBOARD_FAB2_LIB.BASEBOARD_FAB2(SCH_1):VR_FB_PVPP_GHJ
   2 AGND_PVPP_GHJ      B @BASEBOARD_FAB2_LIB.BASEBOARD_FAB2(SCH_1):AGND_PVPP_GHJ

RES_0402-20.0K,1%,1/16W,CHIP,GA  I270  R4G7
   1 VSENSE_PVPP_GHJ      A @BASEBOARD_FAB2_LIB.BASEBOARD_FAB2(SCH_1):VSENSE_PVPP_GHJ
   2 VR_FB_PVPP_GHJ      B @BASEBOARD_FAB2_LIB.BASEBOARD_FAB2(SCH_1):VR_FB_PVPP_GHJ

RES_0402-0.0,5%,1/16W,CHIP,G21A  I271  R4G8
   1 PVPP_GHJ      A @BASEBOARD_FAB2_LIB.BASEBOARD_FAB2(SCH_1):PVPP_GHJ
   2 VSENSE_PVPP_GHJ      B @BASEBOARD_FAB2_LIB.BASEBOARD_FAB2(SCH_1):VSENSE_PVPP_GHJ

RES_0402-7.87K,1.0%,1/16W,CHIPA  I272  R4G13
   1 VR_COMP_RC_PVPP_GHJ      A @BASEBOARD_FAB2_LIB.BASEBOARD_FAB2(SCH_1):VR_COMP_RC_PVPP_GHJ
   2 VR_FB_PVPP_GHJ      B @BASEBOARD_FAB2_LIB.BASEBOARD_FAB2(SCH_1):VR_FB_PVPP_GHJ

CAP_0402LF-100.0PF,50V,5%,COG,A  I273  C4G6
   1 VR_FB_PVPP_GHJ      A @BASEBOARD_FAB2_LIB.BASEBOARD_FAB2(SCH_1):VR_FB_PVPP_GHJ
   2 VR_COMP_PVPP_GHJ_3      B @BASEBOARD_FAB2_LIB.BASEBOARD_FAB2(SCH_1):VR_COMP_PVPP_GHJ_3

CAP_0402LF-2200PF,50V,10%,X7R,A  I274  C4G10
   1 VR_COMP_RC_PVPP_GHJ      A @BASEBOARD_FAB2_LIB.BASEBOARD_FAB2(SCH_1):VR_COMP_RC_PVPP_GHJ
   2 VR_COMP_PVPP_GHJ_3      B @BASEBOARD_FAB2_LIB.BASEBOARD_FAB2(SCH_1):VR_COMP_PVPP_GHJ_3

RES_0402-0.0,5%,1/16W,CHIP,G21A  I275  R4G4
   1 FM_PVPP_CPU1_EN      A @BASEBOARD_FAB2_LIB.BASEBOARD_FAB2(SCH_1):FM_PVPP_CPU1_EN
   2 FM_PVPP_PVDDQ_CPU1_EN_GHJ      B @BASEBOARD_FAB2_LIB.BASEBOARD_FAB2(SCH_1):FM_PVPP_PVDDQ_CPU1_EN_GHJ

INDUCTOR_SM-0.47UH,IND,E13358-A  I277  L4G1
   1 VR_PVPP_GHJ_PHASE    INA @BASEBOARD_FAB2_LIB.BASEBOARD_FAB2(SCH_1):VR_PVPP_GHJ_PHASE
   2 PVPP_GHJ    INB @BASEBOARD_FAB2_LIB.BASEBOARD_FAB2(SCH_1):PVPP_GHJ


DRAWING: @BASEBOARD_FAB2_LIB.BASEBOARD_FAB2(SCH_1):PAGE234 

RES_0402-0.0,5%,1/16W,CHIP,G21A  I29  R4B14
   1    GND      A @BASEBOARD_FAB2_LIB.BASEBOARD_FAB2(SCH_1):GND
   2 AGND_PVPP_KLM      B @BASEBOARD_FAB2_LIB.BASEBOARD_FAB2(SCH_1):AGND_PVPP_KLM

CAP_0603LF-10UF,4V,20%,X6S,E15A  I84  C3B2
   1 PVPP_KLM      A @BASEBOARD_FAB2_LIB.BASEBOARD_FAB2(SCH_1):PVPP_KLM
   2    GND      B @BASEBOARD_FAB2_LIB.BASEBOARD_FAB2(SCH_1):GND

CAP_0603LF-10UF,4V,20%,X6S,E15A  I86  C3A8
   1 PVPP_KLM      A @BASEBOARD_FAB2_LIB.BASEBOARD_FAB2(SCH_1):PVPP_KLM
   2    GND      B @BASEBOARD_FAB2_LIB.BASEBOARD_FAB2(SCH_1):GND

CAP_0603LF-10UF,4V,20%,X6S,E15A  I87  C7L3
   1 PVPP_KLM      A @BASEBOARD_FAB2_LIB.BASEBOARD_FAB2(SCH_1):PVPP_KLM
   2    GND      B @BASEBOARD_FAB2_LIB.BASEBOARD_FAB2(SCH_1):GND

CAP_0603LF-10UF,4V,20%,X6S,E15A  I88  C7L2
   1 PVPP_KLM      A @BASEBOARD_FAB2_LIB.BASEBOARD_FAB2(SCH_1):PVPP_KLM
   2    GND      B @BASEBOARD_FAB2_LIB.BASEBOARD_FAB2(SCH_1):GND

CAP_0603LF-10UF,4V,20%,X6S,E15A  I89  C7L7
   1 PVPP_KLM      A @BASEBOARD_FAB2_LIB.BASEBOARD_FAB2(SCH_1):PVPP_KLM
   2    GND      B @BASEBOARD_FAB2_LIB.BASEBOARD_FAB2(SCH_1):GND

CAP_0603LF-10UF,4V,20%,X6S,E15A  I90  C7L6
   1 PVPP_KLM      A @BASEBOARD_FAB2_LIB.BASEBOARD_FAB2(SCH_1):PVPP_KLM
   2    GND      B @BASEBOARD_FAB2_LIB.BASEBOARD_FAB2(SCH_1):GND

CAP_0603LF-10UF,4V,20%,X6S,E15A  I91  C7M4
   1 PVPP_KLM      A @BASEBOARD_FAB2_LIB.BASEBOARD_FAB2(SCH_1):PVPP_KLM
   2    GND      B @BASEBOARD_FAB2_LIB.BASEBOARD_FAB2(SCH_1):GND

CAP_0603LF-10UF,4V,20%,X6S,E15A  I92  C7M3
   1 PVPP_KLM      A @BASEBOARD_FAB2_LIB.BASEBOARD_FAB2(SCH_1):PVPP_KLM
   2    GND      B @BASEBOARD_FAB2_LIB.BASEBOARD_FAB2(SCH_1):GND

CAP_0603LF-10UF,4V,20%,X6S,E15A  I93  C3A4
   1 PVPP_KLM      A @BASEBOARD_FAB2_LIB.BASEBOARD_FAB2(SCH_1):PVPP_KLM
   2    GND      B @BASEBOARD_FAB2_LIB.BASEBOARD_FAB2(SCH_1):GND

CAP_0603LF-10UF,4V,20%,X6S,E15A  I94  C3B1
   1 PVPP_KLM      A @BASEBOARD_FAB2_LIB.BASEBOARD_FAB2(SCH_1):PVPP_KLM
   2    GND      B @BASEBOARD_FAB2_LIB.BASEBOARD_FAB2(SCH_1):GND

CAP_0603LF-10UF,4V,20%,X6S,E15A  I95  C3A7
   1 PVPP_KLM      A @BASEBOARD_FAB2_LIB.BASEBOARD_FAB2(SCH_1):PVPP_KLM
   2    GND      B @BASEBOARD_FAB2_LIB.BASEBOARD_FAB2(SCH_1):GND

CAP_0603LF-10UF,4V,20%,X6S,E15A  I97  C3A3
   1 PVPP_KLM      A @BASEBOARD_FAB2_LIB.BASEBOARD_FAB2(SCH_1):PVPP_KLM
   2    GND      B @BASEBOARD_FAB2_LIB.BASEBOARD_FAB2(SCH_1):GND

CAP_0402LF-1000PF,50V,10%,EMPTA  I129  C4B5
   1 FM_PVPP_CPU1_EN      A @BASEBOARD_FAB2_LIB.BASEBOARD_FAB2(SCH_1):FM_PVPP_CPU1_EN
   2 AGND_PVPP_KLM      B @BASEBOARD_FAB2_LIB.BASEBOARD_FAB2(SCH_1):AGND_PVPP_KLM

CAP_1210-47UF,16V,20%,X6S,D384A  I130  C4B1
   1 VR_FET_SW_P12V_STBY_PVPP_KLM      A @BASEBOARD_FAB2_LIB.BASEBOARD_FAB2(SCH_1):VR_FET_SW_P12V_STBY_PVPP_KLM
   2    GND      B @BASEBOARD_FAB2_LIB.BASEBOARD_FAB2(SCH_1):GND

CAP_0402LF-1000PF,50V,10%,X7R,A  I139  C4B8
   1 PWRGD_PVPP_KLM_R      A @BASEBOARD_FAB2_LIB.BASEBOARD_FAB2(SCH_1):PWRGD_PVPP_KLM_R
   2    GND      B @BASEBOARD_FAB2_LIB.BASEBOARD_FAB2(SCH_1):GND

RES_0402-7.87K,1.0%,1/16W,CHIPA  I140  R4B6
   1 VR_PVPP_KLM_ISET      A @BASEBOARD_FAB2_LIB.BASEBOARD_FAB2(SCH_1):VR_PVPP_KLM_ISET
   2 AGND_PVPP_KLM      B @BASEBOARD_FAB2_LIB.BASEBOARD_FAB2(SCH_1):AGND_PVPP_KLM

RES_0402-1.00K,1%,1/16W,CHIP,GA  I143  R4B10
   1 P3V3_STBY      A @BASEBOARD_FAB2_LIB.BASEBOARD_FAB2(SCH_1):P3V3_STBY
   2 PWRGD_PVPP_KLM_R      B @BASEBOARD_FAB2_LIB.BASEBOARD_FAB2(SCH_1):PWRGD_PVPP_KLM_R

CAP_0603-4.7UF,6.3V,10%,X6S,E1A  I144  C6L12
   1 VR_VB_PVPP_KLM      A @BASEBOARD_FAB2_LIB.BASEBOARD_FAB2(SCH_1):VR_VB_PVPP_KLM
   2 AGND_PVPP_KLM      B @BASEBOARD_FAB2_LIB.BASEBOARD_FAB2(SCH_1):AGND_PVPP_KLM

CAP_0402-0.027UF,16V,10%,X7R,AA  I146  C4B6
   1 VR_PVPP_KLM_SS      A @BASEBOARD_FAB2_LIB.BASEBOARD_FAB2(SCH_1):VR_PVPP_KLM_SS
   2 AGND_PVPP_KLM      B @BASEBOARD_FAB2_LIB.BASEBOARD_FAB2(SCH_1):AGND_PVPP_KLM

CAP_0402-1.0UF,16V,10%,X6S,D97A  I152  C6L11
   1 VR_FET_SW_P12V_STBY_PVPP_KLM      A @BASEBOARD_FAB2_LIB.BASEBOARD_FAB2(SCH_1):VR_FET_SW_P12V_STBY_PVPP_KLM
   2    GND      B @BASEBOARD_FAB2_LIB.BASEBOARD_FAB2(SCH_1):GND

FERRITE_SM-22,FB,656554-051  I154  FB4A1
   1 P12V_STBY      A @BASEBOARD_FAB2_LIB.BASEBOARD_FAB2(SCH_1):P12V_STBY
   2 VR_FET_SW_P12V_STBY_PVPP_KLM      B @BASEBOARD_FAB2_LIB.BASEBOARD_FAB2(SCH_1):VR_FET_SW_P12V_STBY_PVPP_KLM

RES_0402-0.0,5%,1/16W,CHIP,G21A  I155  R4B13
   1 VR_PVPP_KLM_BOOT      A @BASEBOARD_FAB2_LIB.BASEBOARD_FAB2(SCH_1):VR_PVPP_KLM_BOOT
   2 VR_PVPP_KLM_BOOT_R      B @BASEBOARD_FAB2_LIB.BASEBOARD_FAB2(SCH_1):VR_PVPP_KLM_BOOT_R

RES_0402-2.2,5%,1/16W,EMPTY,G2A  I162  R4A7
   1 VR_PVPP_KLM_SNUB      A @BASEBOARD_FAB2_LIB.BASEBOARD_FAB2(SCH_1):VR_PVPP_KLM_SNUB
   2    GND      B @BASEBOARD_FAB2_LIB.BASEBOARD_FAB2(SCH_1):GND

CAP_0402LF-3300PF,50V,10%,EMPTA  I163  C4A16
   1 VR_PVPP_KLM_PHASE      A @BASEBOARD_FAB2_LIB.BASEBOARD_FAB2(SCH_1):VR_PVPP_KLM_PHASE
   2 VR_PVPP_KLM_SNUB      B @BASEBOARD_FAB2_LIB.BASEBOARD_FAB2(SCH_1):VR_PVPP_KLM_SNUB

INDUCTOR_SM-0.47UH,IND,E13358-A  I164  L4A1
   1 VR_PVPP_KLM_PHASE    INA @BASEBOARD_FAB2_LIB.BASEBOARD_FAB2(SCH_1):VR_PVPP_KLM_PHASE
   2 PVPP_KLM    INB @BASEBOARD_FAB2_LIB.BASEBOARD_FAB2(SCH_1):PVPP_KLM

CAPP_7343LF-330UF,6.3V,20%,POSA  I167  C3B3
   1 PVPP_KLM      A @BASEBOARD_FAB2_LIB.BASEBOARD_FAB2(SCH_1):PVPP_KLM
   2    GND      B @BASEBOARD_FAB2_LIB.BASEBOARD_FAB2(SCH_1):GND

CAP_0805-47UF,4V,20%,X6S,C9533A  I177  C4B3
   1 PVPP_KLM      A @BASEBOARD_FAB2_LIB.BASEBOARD_FAB2(SCH_1):PVPP_KLM
   2    GND      B @BASEBOARD_FAB2_LIB.BASEBOARD_FAB2(SCH_1):GND

CAP_0805-47UF,4V,20%,X6S,C9533A  I180  C4B2
   1 PVPP_KLM      A @BASEBOARD_FAB2_LIB.BASEBOARD_FAB2(SCH_1):PVPP_KLM
   2    GND      B @BASEBOARD_FAB2_LIB.BASEBOARD_FAB2(SCH_1):GND

CAP_0603LF-0.1UF,25V,10%,X7R,6A  I182  C4B15
   1 VR_PVPP_KLM_PHASE      A @BASEBOARD_FAB2_LIB.BASEBOARD_FAB2(SCH_1):VR_PVPP_KLM_PHASE
   2 VR_PVPP_KLM_BOOT_R      B @BASEBOARD_FAB2_LIB.BASEBOARD_FAB2(SCH_1):VR_PVPP_KLM_BOOT_R

RES_0603-120.0,1%,1/10W,CHIP,GA  I183  R4B2
   1 PVPP_KLM      A @BASEBOARD_FAB2_LIB.BASEBOARD_FAB2(SCH_1):PVPP_KLM
   2    GND      B @BASEBOARD_FAB2_LIB.BASEBOARD_FAB2(SCH_1):GND

NCP3232L_SM-IC,H86355-001  I184  EU4A3
   5 AGND_PVPP_KLM   AGND @BASEBOARD_FAB2_LIB.BASEBOARD_FAB2(SCH_1):AGND_PVPP_KLM
  36 VR_PVPP_KLM_BOOT    BST @BASEBOARD_FAB2_LIB.BASEBOARD_FAB2(SCH_1):VR_PVPP_KLM_BOOT
   3 VR_COMP_PVPP_KLM_3   COMP @BASEBOARD_FAB2_LIB.BASEBOARD_FAB2(SCH_1):VR_COMP_PVPP_KLM_3
  40 FM_PVPP_PVDDQ_CPU1_EN_KLM     EN @BASEBOARD_FAB2_LIB.BASEBOARD_FAB2(SCH_1):FM_PVPP_PVDDQ_CPU1_EN_KLM
   2 VR_FB_PVPP_KLM     FB @BASEBOARD_FAB2_LIB.BASEBOARD_FAB2(SCH_1):VR_FB_PVPP_KLM
  41    GND    GND @BASEBOARD_FAB2_LIB.BASEBOARD_FAB2(SCH_1):GND
   4 VR_PVPP_KLM_ISET   ISET @BASEBOARD_FAB2_LIB.BASEBOARD_FAB2(SCH_1):VR_PVPP_KLM_ISET
   6 AGND_PVPP_KLM    OTS @BASEBOARD_FAB2_LIB.BASEBOARD_FAB2(SCH_1):AGND_PVPP_KLM
   7 PWRGD_PVPP_KLM_R     PG @BASEBOARD_FAB2_LIB.BASEBOARD_FAB2(SCH_1):PWRGD_PVPP_KLM_R
  37    GND PGND<13> @BASEBOARD_FAB2_LIB.BASEBOARD_FAB2(SCH_1):GND
  28    GND PGND<12> @BASEBOARD_FAB2_LIB.BASEBOARD_FAB2(SCH_1):GND
  27    GND PGND<11> @BASEBOARD_FAB2_LIB.BASEBOARD_FAB2(SCH_1):GND
  26    GND PGND<10> @BASEBOARD_FAB2_LIB.BASEBOARD_FAB2(SCH_1):GND
  25    GND PGND<9> @BASEBOARD_FAB2_LIB.BASEBOARD_FAB2(SCH_1):GND
  24    GND PGND<8> @BASEBOARD_FAB2_LIB.BASEBOARD_FAB2(SCH_1):GND
  23    GND PGND<7> @BASEBOARD_FAB2_LIB.BASEBOARD_FAB2(SCH_1):GND
  22    GND PGND<6> @BASEBOARD_FAB2_LIB.BASEBOARD_FAB2(SCH_1):GND
  21    GND PGND<5> @BASEBOARD_FAB2_LIB.BASEBOARD_FAB2(SCH_1):GND
  20    GND PGND<4> @BASEBOARD_FAB2_LIB.BASEBOARD_FAB2(SCH_1):GND
  19    GND PGND<3> @BASEBOARD_FAB2_LIB.BASEBOARD_FAB2(SCH_1):GND
  18    GND PGND<2> @BASEBOARD_FAB2_LIB.BASEBOARD_FAB2(SCH_1):GND
  17    GND PGND<1> @BASEBOARD_FAB2_LIB.BASEBOARD_FAB2(SCH_1):GND
  16    GND PGND<0> @BASEBOARD_FAB2_LIB.BASEBOARD_FAB2(SCH_1):GND
   1 VR_PVPP_KLM_SS     SS @BASEBOARD_FAB2_LIB.BASEBOARD_FAB2(SCH_1):VR_PVPP_KLM_SS
  38 VR_VB_PVPP_KLM     VB @BASEBOARD_FAB2_LIB.BASEBOARD_FAB2(SCH_1):VR_VB_PVPP_KLM
  39 VR_FET_SW_P12V_STBY_PVPP_KLM    VCC @BASEBOARD_FAB2_LIB.BASEBOARD_FAB2(SCH_1):VR_FET_SW_P12V_STBY_PVPP_KLM
  42 VR_FET_SW_P12V_STBY_PVPP_KLM VIN<7> @BASEBOARD_FAB2_LIB.BASEBOARD_FAB2(SCH_1):VR_FET_SW_P12V_STBY_PVPP_KLM
  14 VR_FET_SW_P12V_STBY_PVPP_KLM VIN<6> @BASEBOARD_FAB2_LIB.BASEBOARD_FAB2(SCH_1):VR_FET_SW_P12V_STBY_PVPP_KLM
  13 VR_FET_SW_P12V_STBY_PVPP_KLM VIN<5> @BASEBOARD_FAB2_LIB.BASEBOARD_FAB2(SCH_1):VR_FET_SW_P12V_STBY_PVPP_KLM
  12 VR_FET_SW_P12V_STBY_PVPP_KLM VIN<4> @BASEBOARD_FAB2_LIB.BASEBOARD_FAB2(SCH_1):VR_FET_SW_P12V_STBY_PVPP_KLM
  11 VR_FET_SW_P12V_STBY_PVPP_KLM VIN<3> @BASEBOARD_FAB2_LIB.BASEBOARD_FAB2(SCH_1):VR_FET_SW_P12V_STBY_PVPP_KLM
  10 VR_FET_SW_P12V_STBY_PVPP_KLM VIN<2> @BASEBOARD_FAB2_LIB.BASEBOARD_FAB2(SCH_1):VR_FET_SW_P12V_STBY_PVPP_KLM
   9 VR_FET_SW_P12V_STBY_PVPP_KLM VIN<1> @BASEBOARD_FAB2_LIB.BASEBOARD_FAB2(SCH_1):VR_FET_SW_P12V_STBY_PVPP_KLM
   8 VR_FET_SW_P12V_STBY_PVPP_KLM VIN<0> @BASEBOARD_FAB2_LIB.BASEBOARD_FAB2(SCH_1):VR_FET_SW_P12V_STBY_PVPP_KLM
  35 VR_PVPP_KLM_PHASE    VSW @BASEBOARD_FAB2_LIB.BASEBOARD_FAB2(SCH_1):VR_PVPP_KLM_PHASE
  43 VR_PVPP_KLM_PHASE VSWH<7> @BASEBOARD_FAB2_LIB.BASEBOARD_FAB2(SCH_1):VR_PVPP_KLM_PHASE
  34 VR_PVPP_KLM_PHASE VSWH<6> @BASEBOARD_FAB2_LIB.BASEBOARD_FAB2(SCH_1):VR_PVPP_KLM_PHASE
  33 VR_PVPP_KLM_PHASE VSWH<5> @BASEBOARD_FAB2_LIB.BASEBOARD_FAB2(SCH_1):VR_PVPP_KLM_PHASE
  32 VR_PVPP_KLM_PHASE VSWH<4> @BASEBOARD_FAB2_LIB.BASEBOARD_FAB2(SCH_1):VR_PVPP_KLM_PHASE
  31 VR_PVPP_KLM_PHASE VSWH<3> @BASEBOARD_FAB2_LIB.BASEBOARD_FAB2(SCH_1):VR_PVPP_KLM_PHASE
  30 VR_PVPP_KLM_PHASE VSWH<2> @BASEBOARD_FAB2_LIB.BASEBOARD_FAB2(SCH_1):VR_PVPP_KLM_PHASE
  29 VR_PVPP_KLM_PHASE VSWH<1> @BASEBOARD_FAB2_LIB.BASEBOARD_FAB2(SCH_1):VR_PVPP_KLM_PHASE
  15 VR_PVPP_KLM_PHASE VSWH<0> @BASEBOARD_FAB2_LIB.BASEBOARD_FAB2(SCH_1):VR_PVPP_KLM_PHASE

CAP_A_0402V-0.1UF,16V,10%,X7R,A  I199  C4A20
   1 VR_FET_SW_P12V_STBY_PVPP_KLM      A @BASEBOARD_FAB2_LIB.BASEBOARD_FAB2(SCH_1):VR_FET_SW_P12V_STBY_PVPP_KLM
   2    GND      B @BASEBOARD_FAB2_LIB.BASEBOARD_FAB2(SCH_1):GND

RES_0402-22.1,1.0%,1/16W,CHIP,A  I201  R4B7
   1 PWRGD_PVPP_KLM_R      A @BASEBOARD_FAB2_LIB.BASEBOARD_FAB2(SCH_1):PWRGD_PVPP_KLM_R
   2 PWRGD_PVPP_KLM      B @BASEBOARD_FAB2_LIB.BASEBOARD_FAB2(SCH_1):PWRGD_PVPP_KLM

CAP_0805-10UF,16V,10%,X6S,C953A  I202  C6L10
   1 VR_FET_SW_P12V_STBY_PVPP_KLM      A @BASEBOARD_FAB2_LIB.BASEBOARD_FAB2(SCH_1):VR_FET_SW_P12V_STBY_PVPP_KLM
   2    GND      B @BASEBOARD_FAB2_LIB.BASEBOARD_FAB2(SCH_1):GND

CAP_0805-10UF,16V,10%,X6S,C953A  I203  C6M3
   1 VR_FET_SW_P12V_STBY_PVPP_KLM      A @BASEBOARD_FAB2_LIB.BASEBOARD_FAB2(SCH_1):VR_FET_SW_P12V_STBY_PVPP_KLM
   2    GND      B @BASEBOARD_FAB2_LIB.BASEBOARD_FAB2(SCH_1):GND

CAP_0805-10UF,16V,10%,X6S,C953A  I204  C6M5
   1 VR_FET_SW_P12V_STBY_PVPP_KLM      A @BASEBOARD_FAB2_LIB.BASEBOARD_FAB2(SCH_1):VR_FET_SW_P12V_STBY_PVPP_KLM
   2    GND      B @BASEBOARD_FAB2_LIB.BASEBOARD_FAB2(SCH_1):GND

CAP_0805-10UF,16V,10%,X6S,C953A  I205  C4A19
   1 VR_FET_SW_P12V_STBY_PVPP_KLM      A @BASEBOARD_FAB2_LIB.BASEBOARD_FAB2(SCH_1):VR_FET_SW_P12V_STBY_PVPP_KLM
   2    GND      B @BASEBOARD_FAB2_LIB.BASEBOARD_FAB2(SCH_1):GND

CAPP_7343-220UF,4V,20%,POSCAP,A  I210  C6L8
   1 PVPP_KLM      A @BASEBOARD_FAB2_LIB.BASEBOARD_FAB2(SCH_1):PVPP_KLM
   2    GND      B @BASEBOARD_FAB2_LIB.BASEBOARD_FAB2(SCH_1):GND

CAP_0402LF-2200PF,50V,10%,X7R,A  I211  C4B9
   1 VR_COMP_RC_PVPP_KLM      A @BASEBOARD_FAB2_LIB.BASEBOARD_FAB2(SCH_1):VR_COMP_RC_PVPP_KLM
   2 VR_COMP_PVPP_KLM_3      B @BASEBOARD_FAB2_LIB.BASEBOARD_FAB2(SCH_1):VR_COMP_PVPP_KLM_3

CAP_0402LF-100.0PF,50V,5%,COG,A  I212  C4B4
   1 VR_FB_PVPP_KLM      A @BASEBOARD_FAB2_LIB.BASEBOARD_FAB2(SCH_1):VR_FB_PVPP_KLM
   2 VR_COMP_PVPP_KLM_3      B @BASEBOARD_FAB2_LIB.BASEBOARD_FAB2(SCH_1):VR_COMP_PVPP_KLM_3

RES_0402-7.87K,1.0%,1/16W,CHIPA  I213  R4B8
   1 VR_COMP_RC_PVPP_KLM      A @BASEBOARD_FAB2_LIB.BASEBOARD_FAB2(SCH_1):VR_COMP_RC_PVPP_KLM
   2 VR_FB_PVPP_KLM      B @BASEBOARD_FAB2_LIB.BASEBOARD_FAB2(SCH_1):VR_FB_PVPP_KLM

RES_0402-0.0,5%,1/16W,CHIP,G21A  I214  R4B3
   1 PVPP_KLM      A @BASEBOARD_FAB2_LIB.BASEBOARD_FAB2(SCH_1):PVPP_KLM
   2 VSENSE_PVPP_KLM      B @BASEBOARD_FAB2_LIB.BASEBOARD_FAB2(SCH_1):VSENSE_PVPP_KLM

RES_0402-20.0K,1%,1/16W,CHIP,GA  I215  R4B5
   1 VSENSE_PVPP_KLM      A @BASEBOARD_FAB2_LIB.BASEBOARD_FAB2(SCH_1):VSENSE_PVPP_KLM
   2 VR_FB_PVPP_KLM      B @BASEBOARD_FAB2_LIB.BASEBOARD_FAB2(SCH_1):VR_FB_PVPP_KLM

RES_0402-6.34K,1%,1/16W,CHIP,GA  I216  R4B4
   1 VR_FB_PVPP_KLM      A @BASEBOARD_FAB2_LIB.BASEBOARD_FAB2(SCH_1):VR_FB_PVPP_KLM
   2 AGND_PVPP_KLM      B @BASEBOARD_FAB2_LIB.BASEBOARD_FAB2(SCH_1):AGND_PVPP_KLM

CAP_0402LF-2200PF,50V,10%,X7R,A  I218  C4B7
   1 VR_COMP_PVPP_KLM      A @BASEBOARD_FAB2_LIB.BASEBOARD_FAB2(SCH_1):VR_COMP_PVPP_KLM
   2 VR_FB_PVPP_KLM      B @BASEBOARD_FAB2_LIB.BASEBOARD_FAB2(SCH_1):VR_FB_PVPP_KLM

RES_0402-1.0K,0.1%,1/16W,CHIP,A  I219  R4B9
   1 VSENSE_PVPP_KLM      A @BASEBOARD_FAB2_LIB.BASEBOARD_FAB2(SCH_1):VSENSE_PVPP_KLM
   2 VR_COMP_PVPP_KLM      B @BASEBOARD_FAB2_LIB.BASEBOARD_FAB2(SCH_1):VR_COMP_PVPP_KLM

RES_0402-0.0,5%,1/16W,CHIP,G21A  I220  R4B1
   1 FM_PVPP_CPU1_EN      A @BASEBOARD_FAB2_LIB.BASEBOARD_FAB2(SCH_1):FM_PVPP_CPU1_EN
   2 FM_PVPP_PVDDQ_CPU1_EN_KLM      B @BASEBOARD_FAB2_LIB.BASEBOARD_FAB2(SCH_1):FM_PVPP_PVDDQ_CPU1_EN_KLM


DRAWING: @BASEBOARD_FAB2_LIB.BASEBOARD_FAB2(SCH_1):PAGE235 

CAP_A_0402V-1.0UF,6.3V,10%,X6SA  I143  C8A7
   1 VR_PVNN_P1V05_PCH_VD12      A @BASEBOARD_FAB2_LIB.BASEBOARD_FAB2(SCH_1):VR_PVNN_P1V05_PCH_VD12
   2    GND      B @BASEBOARD_FAB2_LIB.BASEBOARD_FAB2(SCH_1):GND

CAP_A_0402V-0.1UF,16V,10%,X7R,A  I145  C8A8
   1 VR_PVNN_P1V05_PCH_VD12      A @BASEBOARD_FAB2_LIB.BASEBOARD_FAB2(SCH_1):VR_PVNN_P1V05_PCH_VD12
   2    GND      B @BASEBOARD_FAB2_LIB.BASEBOARD_FAB2(SCH_1):GND

RES_0402-22.1,1.0%,1/16W,CHIP,A  I147  R2L16
   1 PWRGD_PVNN_PCH_R      A @BASEBOARD_FAB2_LIB.BASEBOARD_FAB2(SCH_1):PWRGD_PVNN_PCH_R
   2 PWRGD_PVNN_P1V05_PCH      B @BASEBOARD_FAB2_LIB.BASEBOARD_FAB2(SCH_1):PWRGD_PVNN_P1V05_PCH

RES_0402-2.26K,1.0%,1/16W,EMPTA  I148  R2L24
   1 P3V3_STBY      A @BASEBOARD_FAB2_LIB.BASEBOARD_FAB2(SCH_1):P3V3_STBY
   2 PU_VR_PVNN_PCH_FAULT1      B @BASEBOARD_FAB2_LIB.BASEBOARD_FAB2(SCH_1):PU_VR_PVNN_PCH_FAULT1

RES_0402-1.00K,1%,1/16W,CHIP,GA  I149  R8A6
   1 P3V3_STBY      A @BASEBOARD_FAB2_LIB.BASEBOARD_FAB2(SCH_1):P3V3_STBY
   2 PWRGD_PVNN_PCH_R      B @BASEBOARD_FAB2_LIB.BASEBOARD_FAB2(SCH_1):PWRGD_PVNN_PCH_R

CAP_A_0402V-1.0UF,6.3V,10%,X6SA  I151  C2L8
   1 VR_PVNN_PCH_VDD      A @BASEBOARD_FAB2_LIB.BASEBOARD_FAB2(SCH_1):VR_PVNN_PCH_VDD
   2    GND      B @BASEBOARD_FAB2_LIB.BASEBOARD_FAB2(SCH_1):GND

CAP_0402LF-220PF,50V,10%,X7R,AA  I153  C2L2
   1 VR_P1V05_PCH_STBY_AVSP      A @BASEBOARD_FAB2_LIB.BASEBOARD_FAB2(SCH_1):VR_P1V05_PCH_STBY_AVSP
   2 VSENSE_P1V05_PCH_STBY_AVSN      B @BASEBOARD_FAB2_LIB.BASEBOARD_FAB2(SCH_1):VSENSE_P1V05_PCH_STBY_AVSN

RES_0603-10.0,1%,1/10W,CHIP,G2A  I154  R2L8
   1 VSENSE_P1V05_PCH_STBY_AVSP      A @BASEBOARD_FAB2_LIB.BASEBOARD_FAB2(SCH_1):VSENSE_P1V05_PCH_STBY_AVSP
   2 VR_P1V05_PCH_STBY_AVSP      B @BASEBOARD_FAB2_LIB.BASEBOARD_FAB2(SCH_1):VR_P1V05_PCH_STBY_AVSP

RES_0402-0.0,5%,1/16W,CHIP,G21A  I159  R2L14
   1 P3V3_STBY      A @BASEBOARD_FAB2_LIB.BASEBOARD_FAB2(SCH_1):P3V3_STBY
   2 VR_PVNN_PCH_VDD      B @BASEBOARD_FAB2_LIB.BASEBOARD_FAB2(SCH_1):VR_PVNN_PCH_VDD

RES_0402-100.0K,1%,1/16W,CHIP,B  I165  R8A4
   1 VR_FET_SW_P12V_STBY_PVDDQ_DEF      A @BASEBOARD_FAB2_LIB.BASEBOARD_FAB2(SCH_1):VR_FET_SW_P12V_STBY_PVDDQ_DEF
   2 VR_PVNN_PCH_VINSEN      B @BASEBOARD_FAB2_LIB.BASEBOARD_FAB2(SCH_1):VR_PVNN_PCH_VINSEN

RES_0402-1.5K,1%,1/16W,CHIP,G2A  I166  R2L10
   1 VR_PVNN_PCH_VINSEN      A @BASEBOARD_FAB2_LIB.BASEBOARD_FAB2(SCH_1):VR_PVNN_PCH_VINSEN
   2    GND      B @BASEBOARD_FAB2_LIB.BASEBOARD_FAB2(SCH_1):GND

CAP_0402LF-1000PF,50V,10%,X7R,A  I167  C8A3
   1 VR_PVNN_PCH_VINSEN      A @BASEBOARD_FAB2_LIB.BASEBOARD_FAB2(SCH_1):VR_PVNN_PCH_VINSEN
   2    GND      B @BASEBOARD_FAB2_LIB.BASEBOARD_FAB2(SCH_1):GND

CAP_A_0402V-0.1UF,16V,10%,X7R,A  I169  C2L11
   1 VR_PVNN_PCH_VDD      A @BASEBOARD_FAB2_LIB.BASEBOARD_FAB2(SCH_1):VR_PVNN_PCH_VDD
   2    GND      B @BASEBOARD_FAB2_LIB.BASEBOARD_FAB2(SCH_1):GND

RES_0402-20.0,1%,1/16W,CHIP,G2A  I172  R8A8
   1 SMB_VR_STBY_LVC3_SDA      A @BASEBOARD_FAB2_LIB.BASEBOARD_FAB2(SCH_1):SMB_VR_STBY_LVC3_SDA
   2 SMB_VR_SDA_PVNN_PCH      B @BASEBOARD_FAB2_LIB.BASEBOARD_FAB2(SCH_1):SMB_VR_SDA_PVNN_PCH

RES_0402-20.0,1%,1/16W,CHIP,G2A  I173  R8A9
   1 SMB_VR_STBY_LVC3_SCL      A @BASEBOARD_FAB2_LIB.BASEBOARD_FAB2(SCH_1):SMB_VR_STBY_LVC3_SCL
   2 SMB_VR_SCL_PVNN_PCH      B @BASEBOARD_FAB2_LIB.BASEBOARD_FAB2(SCH_1):SMB_VR_SCL_PVNN_PCH

RES_0402-4.02K,1%,1/16W,CHIP,GA  I176  R2L9
   1 VR_PVNN_PCH_XADDR1      A @BASEBOARD_FAB2_LIB.BASEBOARD_FAB2(SCH_1):VR_PVNN_PCH_XADDR1
   2    GND      B @BASEBOARD_FAB2_LIB.BASEBOARD_FAB2(SCH_1):GND

CAP_0402LF-220PF,50V,10%,X7R,AA  I209  C8A2
   1 VR_PVNN_PCH_AVSP      A @BASEBOARD_FAB2_LIB.BASEBOARD_FAB2(SCH_1):VR_PVNN_PCH_AVSP
   2 VSENSE_PVNN_PCH_STBY_AVSN      B @BASEBOARD_FAB2_LIB.BASEBOARD_FAB2(SCH_1):VSENSE_PVNN_PCH_STBY_AVSN

RES_0402-10.0,1%,1/16W,CHIP,G2A  I210  R8A1
   1 VSENSE_PVNN_PCH_STBY_AVSP      A @BASEBOARD_FAB2_LIB.BASEBOARD_FAB2(SCH_1):VSENSE_PVNN_PCH_STBY_AVSP
   2 VR_PVNN_PCH_AVSP      B @BASEBOARD_FAB2_LIB.BASEBOARD_FAB2(SCH_1):VR_PVNN_PCH_AVSP

RES_0402-1.00K,1%,1/16W,CHIP,GA  I216  R8A5
   1 P3V3_STBY      A @BASEBOARD_FAB2_LIB.BASEBOARD_FAB2(SCH_1):P3V3_STBY
   2 IRQ_PVNN_PCH_VRHOT_N      B @BASEBOARD_FAB2_LIB.BASEBOARD_FAB2(SCH_1):IRQ_PVNN_PCH_VRHOT_N

RES_0402-2.67K,1%,1/16W,CHIP,GA  I217  R8A2
   1 VR_PVNN_PCH_XADDR2      A @BASEBOARD_FAB2_LIB.BASEBOARD_FAB2(SCH_1):VR_PVNN_PCH_XADDR2
   2    GND      B @BASEBOARD_FAB2_LIB.BASEBOARD_FAB2(SCH_1):GND

CAP_0402LF-1000PF,50V,10%,X7R,A  I218  C8A9
   1 PWRGD_PVNN_PCH_R      A @BASEBOARD_FAB2_LIB.BASEBOARD_FAB2(SCH_1):PWRGD_PVNN_PCH_R
   2    GND      B @BASEBOARD_FAB2_LIB.BASEBOARD_FAB2(SCH_1):GND

RES_0402-0.0,5%,1/16W,CHIP,G21A  I221  R2L17
   1 PWRGD_P1V8_PCH_STBY      A @BASEBOARD_FAB2_LIB.BASEBOARD_FAB2(SCH_1):PWRGD_P1V8_PCH_STBY
   2 VR_PVNN_PCH_VREN      B @BASEBOARD_FAB2_LIB.BASEBOARD_FAB2(SCH_1):VR_PVNN_PCH_VREN

RES_0402-100.0K,1%,1/16W,EMPTYA  I222  R8A7
   1 P3V3_STBY      A @BASEBOARD_FAB2_LIB.BASEBOARD_FAB2(SCH_1):P3V3_STBY
   2 VR_PVNN_PCH_VREN      B @BASEBOARD_FAB2_LIB.BASEBOARD_FAB2(SCH_1):VR_PVNN_PCH_VREN

RES_0402-0.0,5%,1/16W,CHIP,G21A  I224  R2L1
   1 VR_PVNN_P1V05_PCH_VD12      A @BASEBOARD_FAB2_LIB.BASEBOARD_FAB2(SCH_1):VR_PVNN_P1V05_PCH_VD12
   2 VR_PVNN_PCH_AIREF1      B @BASEBOARD_FAB2_LIB.BASEBOARD_FAB2(SCH_1):VR_PVNN_PCH_AIREF1

RES_0402-0.0,5%,1/16W,CHIP,G21A  I225  R2L7
   1 VR_PVNN_P1V05_PCH_VD12      A @BASEBOARD_FAB2_LIB.BASEBOARD_FAB2(SCH_1):VR_PVNN_P1V05_PCH_VD12
   2 VR_P1V05_PCH_BIREF1      B @BASEBOARD_FAB2_LIB.BASEBOARD_FAB2(SCH_1):VR_P1V05_PCH_BIREF1

PXE1110B_QFN-IC,H89187-001  I229  EU8A1
   1 NC_PVNN_PCH_DNC0 DNC<0> @BASEBOARD_FAB2_LIB.BASEBOARD_FAB2(SCH_1):NC_PVNN_PCH_DNC0
   2 NC_PVNN_PCH_DNC1 DNC<1> @BASEBOARD_FAB2_LIB.BASEBOARD_FAB2(SCH_1):NC_PVNN_PCH_DNC1
   3 VR_P1V05_PCH_STBY_PWM1  BPWM1 @BASEBOARD_FAB2_LIB.BASEBOARD_FAB2(SCH_1):VR_P1V05_PCH_STBY_PWM1
   4 NC_PVNN_PCH_DNC2 DNC<2> @BASEBOARD_FAB2_LIB.BASEBOARD_FAB2(SCH_1):NC_PVNN_PCH_DNC2
   5 VR_PVNN_PCH_PWM1  APWM1 @BASEBOARD_FAB2_LIB.BASEBOARD_FAB2(SCH_1):VR_PVNN_PCH_PWM1
   6 SMB_VR_SDA_PVNN_PCH    SDA @BASEBOARD_FAB2_LIB.BASEBOARD_FAB2(SCH_1):SMB_VR_SDA_PVNN_PCH
   7 SMB_VR_SCL_PVNN_PCH    SCL @BASEBOARD_FAB2_LIB.BASEBOARD_FAB2(SCH_1):SMB_VR_SCL_PVNN_PCH
   8 TP_PVNN_PCH_RESET_N RESET_N @BASEBOARD_FAB2_LIB.BASEBOARD_FAB2(SCH_1):TP_PVNN_PCH_RESET_N
   9 PWRGD_PVNN_PCH_R AVRRDY @BASEBOARD_FAB2_LIB.BASEBOARD_FAB2(SCH_1):PWRGD_PVNN_PCH_R
  10 VR_PVNN_PCH_VREN  AVREN @BASEBOARD_FAB2_LIB.BASEBOARD_FAB2(SCH_1):VR_PVNN_PCH_VREN
  11 IRQ_PVNN_PCH_VRHOT_N VRHOT_N @BASEBOARD_FAB2_LIB.BASEBOARD_FAB2(SCH_1):IRQ_PVNN_PCH_VRHOT_N
  12 TP_PVNN_PCH_PINALRT_N PINALRT_N @BASEBOARD_FAB2_LIB.BASEBOARD_FAB2(SCH_1):TP_PVNN_PCH_PINALRT_N
  13 VID_PCH_CORE_PVNN_AUX_VID_0    MP0 @BASEBOARD_FAB2_LIB.BASEBOARD_FAB2(SCH_1):VID_PCH_CORE_PVNN_AUX_VID_0
  14 VID_PCH_CORE_PVNN_AUX_VID_1    MP1 @BASEBOARD_FAB2_LIB.BASEBOARD_FAB2(SCH_1):VID_PCH_CORE_PVNN_AUX_VID_1
  15 TP_PVNN_PCH_VCLK   VCLK @BASEBOARD_FAB2_LIB.BASEBOARD_FAB2(SCH_1):TP_PVNN_PCH_VCLK
  16 TP_PVNN_PCH_VDIO   VDIO @BASEBOARD_FAB2_LIB.BASEBOARD_FAB2(SCH_1):TP_PVNN_PCH_VDIO
  17 TP_PVNN_PCH_SVID_ALERT VALRT_N @BASEBOARD_FAB2_LIB.BASEBOARD_FAB2(SCH_1):TP_PVNN_PCH_SVID_ALERT
  18 TP_PVNN_PCH_MP2    MP2 @BASEBOARD_FAB2_LIB.BASEBOARD_FAB2(SCH_1):TP_PVNN_PCH_MP2
  19 VR_PVNN_PCH_AVSP  AVSEN @BASEBOARD_FAB2_LIB.BASEBOARD_FAB2(SCH_1):VR_PVNN_PCH_AVSP
  20 VSENSE_PVNN_PCH_STBY_AVSN  AVREF @BASEBOARD_FAB2_LIB.BASEBOARD_FAB2(SCH_1):VSENSE_PVNN_PCH_STBY_AVSN
  21 VR_PVNN_PCH_AIREF1 AIREF1 @BASEBOARD_FAB2_LIB.BASEBOARD_FAB2(SCH_1):VR_PVNN_PCH_AIREF1
  22 ISENSE_PVNN_PCH_PH1_IMON AISEN1 @BASEBOARD_FAB2_LIB.BASEBOARD_FAB2(SCH_1):ISENSE_PVNN_PCH_PH1_IMON
  23    GND GND<1> @BASEBOARD_FAB2_LIB.BASEBOARD_FAB2(SCH_1):GND
  24 NC_PVNN_PCH_DNC3 DNC<3> @BASEBOARD_FAB2_LIB.BASEBOARD_FAB2(SCH_1):NC_PVNN_PCH_DNC3
  25 VR_P1V05_PCH_BIREF1 BIREF1 @BASEBOARD_FAB2_LIB.BASEBOARD_FAB2(SCH_1):VR_P1V05_PCH_BIREF1
  26 ISENSE_P1V05_PCH_STBY_PH1_IMON BISEN1 @BASEBOARD_FAB2_LIB.BASEBOARD_FAB2(SCH_1):ISENSE_P1V05_PCH_STBY_PH1_IMON
  27    GND GND<0> @BASEBOARD_FAB2_LIB.BASEBOARD_FAB2(SCH_1):GND
  28 NC_PVNN_PCH_DNC4 DNC<4> @BASEBOARD_FAB2_LIB.BASEBOARD_FAB2(SCH_1):NC_PVNN_PCH_DNC4
  29 VR_P1V05_PCH_STBY_AVSP  BVSEN @BASEBOARD_FAB2_LIB.BASEBOARD_FAB2(SCH_1):VR_P1V05_PCH_STBY_AVSP
  30 VSENSE_P1V05_PCH_STBY_AVSN  BVREF @BASEBOARD_FAB2_LIB.BASEBOARD_FAB2(SCH_1):VSENSE_P1V05_PCH_STBY_AVSN
  31 TP_PVNN_PCH_MP3    MP3 @BASEBOARD_FAB2_LIB.BASEBOARD_FAB2(SCH_1):TP_PVNN_PCH_MP3
  32 PU_VR_PVNN_PCH_FAULT1    MP4 @BASEBOARD_FAB2_LIB.BASEBOARD_FAB2(SCH_1):PU_VR_PVNN_PCH_FAULT1
  33 VR_PVNN_PCH_XADDR2 XADDR2 @BASEBOARD_FAB2_LIB.BASEBOARD_FAB2(SCH_1):VR_PVNN_PCH_XADDR2
  34 A_TSENSE_P1V05_PCH_STBY_TMON  BTSEN @BASEBOARD_FAB2_LIB.BASEBOARD_FAB2(SCH_1):A_TSENSE_P1V05_PCH_STBY_TMON
  35 A_TSENSE_PVNN_PCH_TMON  ATSEN @BASEBOARD_FAB2_LIB.BASEBOARD_FAB2(SCH_1):A_TSENSE_PVNN_PCH_TMON
  36 VR_PVNN_PCH_XADDR1 XADDR1 @BASEBOARD_FAB2_LIB.BASEBOARD_FAB2(SCH_1):VR_PVNN_PCH_XADDR1
  37 VR_PVNN_PCH_VINSEN VINSEN @BASEBOARD_FAB2_LIB.BASEBOARD_FAB2(SCH_1):VR_PVNN_PCH_VINSEN
  38 TP_VR_PVNN_PCH_AIINSEN IINSEN @BASEBOARD_FAB2_LIB.BASEBOARD_FAB2(SCH_1):TP_VR_PVNN_PCH_AIINSEN
  39 VR_PVNN_PCH_VDD    VDD @BASEBOARD_FAB2_LIB.BASEBOARD_FAB2(SCH_1):VR_PVNN_PCH_VDD
  40 VR_PVNN_P1V05_PCH_VD12   VD12 @BASEBOARD_FAB2_LIB.BASEBOARD_FAB2(SCH_1):VR_PVNN_P1V05_PCH_VD12
  41    GND  THPAD @BASEBOARD_FAB2_LIB.BASEBOARD_FAB2(SCH_1):GND

RES_0402-100.0K,1%,1/16W,EMPTYA  I235  R2L25
   1 P3V3_STBY      A @BASEBOARD_FAB2_LIB.BASEBOARD_FAB2(SCH_1):P3V3_STBY
   2 VID_PCH_CORE_PVNN_AUX_VID_1      B @BASEBOARD_FAB2_LIB.BASEBOARD_FAB2(SCH_1):VID_PCH_CORE_PVNN_AUX_VID_1

RES_0402-100.0K,1%,1/16W,EMPTYA  I236  R2L26
   1 P3V3_STBY      A @BASEBOARD_FAB2_LIB.BASEBOARD_FAB2(SCH_1):P3V3_STBY
   2 VID_PCH_CORE_PVNN_AUX_VID_0      B @BASEBOARD_FAB2_LIB.BASEBOARD_FAB2(SCH_1):VID_PCH_CORE_PVNN_AUX_VID_0


DRAWING: @BASEBOARD_FAB2_LIB.BASEBOARD_FAB2(SCH_1):PAGE237 

RES_0402-5.11K,1%,1/16W,CHIP,GA  I3  R8A10
   1 P3V3_STBY      A @BASEBOARD_FAB2_LIB.BASEBOARD_FAB2(SCH_1):P3V3_STBY
   2 PWRGD_P1V8_PCH_STBY_R      B @BASEBOARD_FAB2_LIB.BASEBOARD_FAB2(SCH_1):PWRGD_P1V8_PCH_STBY_R

CAP_0402LF-1000PF,50V,10%,X7R,A  I5  C8A11
   1 PWRGD_P1V8_PCH_STBY_R      A @BASEBOARD_FAB2_LIB.BASEBOARD_FAB2(SCH_1):PWRGD_P1V8_PCH_STBY_R
   2    GND      B @BASEBOARD_FAB2_LIB.BASEBOARD_FAB2(SCH_1):GND

CAP_0805-22UF,6.3V,20%,X6S,C95A  I12  C2L45
   1 P1V8_PCH_STBY      A @BASEBOARD_FAB2_LIB.BASEBOARD_FAB2(SCH_1):P1V8_PCH_STBY
   2    GND      B @BASEBOARD_FAB2_LIB.BASEBOARD_FAB2(SCH_1):GND

CAP_0805-22UF,6.3V,20%,X6S,C95A  I13  C8A14
   1 P1V8_PCH_STBY      A @BASEBOARD_FAB2_LIB.BASEBOARD_FAB2(SCH_1):P1V8_PCH_STBY
   2    GND      B @BASEBOARD_FAB2_LIB.BASEBOARD_FAB2(SCH_1):GND

RES_0603-475.0,1%,1/10W,CHIP,GA  I15  R8A12
   1 P1V8_PCH_STBY      A @BASEBOARD_FAB2_LIB.BASEBOARD_FAB2(SCH_1):P1V8_PCH_STBY
   2    GND      B @BASEBOARD_FAB2_LIB.BASEBOARD_FAB2(SCH_1):GND

CAP_0603-10UF,6.3V,20%,X6S,E15A  I29  C8A6
   1 P3V3_STBY      A @BASEBOARD_FAB2_LIB.BASEBOARD_FAB2(SCH_1):P3V3_STBY
   2    GND      B @BASEBOARD_FAB2_LIB.BASEBOARD_FAB2(SCH_1):GND

CAP_0603LF-0.1UF,25V,10%,X7R,6A  I31  C8A4
   1 P3V3_STBY      A @BASEBOARD_FAB2_LIB.BASEBOARD_FAB2(SCH_1):P3V3_STBY
   2    GND      B @BASEBOARD_FAB2_LIB.BASEBOARD_FAB2(SCH_1):GND

CAP_0402LF-1000PF,50V,10%,EMPTA  I55  C8A10
   1 PWRGD_P3V3_STBY      A @BASEBOARD_FAB2_LIB.BASEBOARD_FAB2(SCH_1):PWRGD_P3V3_STBY
   2    GND      B @BASEBOARD_FAB2_LIB.BASEBOARD_FAB2(SCH_1):GND

CAP_0805-47UF,4V,20%,X6S,C9533A  I77  C8A12
   1 P1V8_PCH_STBY      A @BASEBOARD_FAB2_LIB.BASEBOARD_FAB2(SCH_1):P1V8_PCH_STBY
   2    GND      B @BASEBOARD_FAB2_LIB.BASEBOARD_FAB2(SCH_1):GND

CAP_0805-47UF,4V,20%,X6S,C9533A  I79  C2L32
   1 P1V8_PCH_STBY      A @BASEBOARD_FAB2_LIB.BASEBOARD_FAB2(SCH_1):P1V8_PCH_STBY
   2    GND      B @BASEBOARD_FAB2_LIB.BASEBOARD_FAB2(SCH_1):GND

RES_0402-49.9K,1%,1/16W,CHIP,GA  I80  R2L19
   1 VR_P1V8_PCH_STBY_FB      A @BASEBOARD_FAB2_LIB.BASEBOARD_FAB2(SCH_1):VR_P1V8_PCH_STBY_FB
   2    GND      B @BASEBOARD_FAB2_LIB.BASEBOARD_FAB2(SCH_1):GND

RES_0402-63.4K,1.0%,1/16W,CHIPA  I81  R2L20
   1 P1V8_PCH_STBY      A @BASEBOARD_FAB2_LIB.BASEBOARD_FAB2(SCH_1):P1V8_PCH_STBY
   2 VR_P1V8_PCH_STBY_FB      B @BASEBOARD_FAB2_LIB.BASEBOARD_FAB2(SCH_1):VR_P1V8_PCH_STBY_FB

RT9059_DFN-IC,H65765-001  I86  EU8A2
   4 VR_P1V8_PCH_STBY_FB ADJ_NC @BASEBOARD_FAB2_LIB.BASEBOARD_FAB2(SCH_1):VR_P1V8_PCH_STBY_FB
   6 PWRGD_P3V3_STBY     EN @BASEBOARD_FAB2_LIB.BASEBOARD_FAB2(SCH_1):PWRGD_P3V3_STBY
  11    GND    GND @BASEBOARD_FAB2_LIB.BASEBOARD_FAB2(SCH_1):GND
   5 PWRGD_P1V8_PCH_STBY_R  PGOOD @BASEBOARD_FAB2_LIB.BASEBOARD_FAB2(SCH_1):PWRGD_P1V8_PCH_STBY_R
  10 P3V3_STBY    VDD @BASEBOARD_FAB2_LIB.BASEBOARD_FAB2(SCH_1):P3V3_STBY
   9 P3V3_STBY VIN<2> @BASEBOARD_FAB2_LIB.BASEBOARD_FAB2(SCH_1):P3V3_STBY
   8 P3V3_STBY VIN<1> @BASEBOARD_FAB2_LIB.BASEBOARD_FAB2(SCH_1):P3V3_STBY
   7 P3V3_STBY VIN<0> @BASEBOARD_FAB2_LIB.BASEBOARD_FAB2(SCH_1):P3V3_STBY
   3 P1V8_PCH_STBY VOUT<2> @BASEBOARD_FAB2_LIB.BASEBOARD_FAB2(SCH_1):P1V8_PCH_STBY
   2 P1V8_PCH_STBY VOUT<1> @BASEBOARD_FAB2_LIB.BASEBOARD_FAB2(SCH_1):P1V8_PCH_STBY
   1 P1V8_PCH_STBY VOUT<0> @BASEBOARD_FAB2_LIB.BASEBOARD_FAB2(SCH_1):P1V8_PCH_STBY

RES_0402-22.1,1.0%,1/16W,CHIP,A  I90  R8A11
   1 PWRGD_P1V8_PCH_STBY_R      A @BASEBOARD_FAB2_LIB.BASEBOARD_FAB2(SCH_1):PWRGD_P1V8_PCH_STBY_R
   2 PWRGD_P1V8_PCH_STBY      B @BASEBOARD_FAB2_LIB.BASEBOARD_FAB2(SCH_1):PWRGD_P1V8_PCH_STBY


DRAWING: @BASEBOARD_FAB2_LIB.BASEBOARD_FAB2(SCH_1):PAGE238 

CAP_0402LF-1000PF,50V,10%,EMPTA  I5  C9F9
   1 PWRGD_P1V538_BMC_STBY      A @BASEBOARD_FAB2_LIB.BASEBOARD_FAB2(SCH_1):PWRGD_P1V538_BMC_STBY
   2    GND      B @BASEBOARD_FAB2_LIB.BASEBOARD_FAB2(SCH_1):GND

CAP_0603-10UF,6.3V,20%,X6S,E15A  I7  C9F3
   1 P3V3_STBY      A @BASEBOARD_FAB2_LIB.BASEBOARD_FAB2(SCH_1):P3V3_STBY
   2    GND      B @BASEBOARD_FAB2_LIB.BASEBOARD_FAB2(SCH_1):GND

RES_0402-10.0K,1%,1/16W,CHIP,GA  I14  R9F8
   1    GND      A @BASEBOARD_FAB2_LIB.BASEBOARD_FAB2(SCH_1):GND
   2 VR_P1V26_BMC_STBY_FB      B @BASEBOARD_FAB2_LIB.BASEBOARD_FAB2(SCH_1):VR_P1V26_BMC_STBY_FB

CAP_0402LF-1000PF,50V,10%,X7R,A  I19  C9F8
   1 PWRGD_P1V26_BMC_STBY_R      A @BASEBOARD_FAB2_LIB.BASEBOARD_FAB2(SCH_1):PWRGD_P1V26_BMC_STBY_R
   2    GND      B @BASEBOARD_FAB2_LIB.BASEBOARD_FAB2(SCH_1):GND

RES_0402-10.0K,1%,1/16W,CHIP,GA  I21  R9F13
   1 P3V3_STBY      A @BASEBOARD_FAB2_LIB.BASEBOARD_FAB2(SCH_1):P3V3_STBY
   2 PWRGD_P1V26_BMC_STBY_R      B @BASEBOARD_FAB2_LIB.BASEBOARD_FAB2(SCH_1):PWRGD_P1V26_BMC_STBY_R

CAP_0603-10UF,6.3V,20%,X6S,E15A  I23  C9E10
   1 P1V15_AUX_BMC      A @BASEBOARD_FAB2_LIB.BASEBOARD_FAB2(SCH_1):P1V15_AUX_BMC
   2    GND      B @BASEBOARD_FAB2_LIB.BASEBOARD_FAB2(SCH_1):GND

CAP_0805LF-22UF,4V,20%,X6S,C95A  I30  C9F4
   1 P1V15_AUX_BMC      A @BASEBOARD_FAB2_LIB.BASEBOARD_FAB2(SCH_1):P1V15_AUX_BMC
   2    GND      B @BASEBOARD_FAB2_LIB.BASEBOARD_FAB2(SCH_1):GND

CAP_0402-1.0UF,16V,10%,X6S,D97A  I39  C9E11
   1 P3V3_STBY      A @BASEBOARD_FAB2_LIB.BASEBOARD_FAB2(SCH_1):P3V3_STBY
   2    GND      B @BASEBOARD_FAB2_LIB.BASEBOARD_FAB2(SCH_1):GND

RT9059_DFN-IC,H65765-001  I40  EU9F1
   4 VR_P1V26_BMC_STBY_FB ADJ_NC @BASEBOARD_FAB2_LIB.BASEBOARD_FAB2(SCH_1):VR_P1V26_BMC_STBY_FB
   6 PWRGD_P1V538_BMC_STBY     EN @BASEBOARD_FAB2_LIB.BASEBOARD_FAB2(SCH_1):PWRGD_P1V538_BMC_STBY
  11    GND    GND @BASEBOARD_FAB2_LIB.BASEBOARD_FAB2(SCH_1):GND
   5 PWRGD_P1V26_BMC_STBY_R  PGOOD @BASEBOARD_FAB2_LIB.BASEBOARD_FAB2(SCH_1):PWRGD_P1V26_BMC_STBY_R
  10 P3V3_STBY    VDD @BASEBOARD_FAB2_LIB.BASEBOARD_FAB2(SCH_1):P3V3_STBY
   9 P3V3_STBY VIN<2> @BASEBOARD_FAB2_LIB.BASEBOARD_FAB2(SCH_1):P3V3_STBY
   8 P3V3_STBY VIN<1> @BASEBOARD_FAB2_LIB.BASEBOARD_FAB2(SCH_1):P3V3_STBY
   7 P3V3_STBY VIN<0> @BASEBOARD_FAB2_LIB.BASEBOARD_FAB2(SCH_1):P3V3_STBY
   3 P1V15_AUX_BMC VOUT<2> @BASEBOARD_FAB2_LIB.BASEBOARD_FAB2(SCH_1):P1V15_AUX_BMC
   2 P1V15_AUX_BMC VOUT<1> @BASEBOARD_FAB2_LIB.BASEBOARD_FAB2(SCH_1):P1V15_AUX_BMC
   1 P1V15_AUX_BMC VOUT<0> @BASEBOARD_FAB2_LIB.BASEBOARD_FAB2(SCH_1):P1V15_AUX_BMC

RES_0402-22.1,1.0%,1/16W,CHIP,A  I41  R9F11
   1 PWRGD_P1V26_BMC_STBY_R      A @BASEBOARD_FAB2_LIB.BASEBOARD_FAB2(SCH_1):PWRGD_P1V26_BMC_STBY_R
   2 PWRGD_P1V26_BMC_STBY      B @BASEBOARD_FAB2_LIB.BASEBOARD_FAB2(SCH_1):PWRGD_P1V26_BMC_STBY

4K42R2F-GP_SMD-RG-4K42R2F-GP,6A  I45  R9F6
   1 P1V15_AUX_BMC      1 @BASEBOARD_FAB2_LIB.BASEBOARD_FAB2(SCH_1):P1V15_AUX_BMC
   2 VR_P1V26_BMC_STBY_FB      2 @BASEBOARD_FAB2_LIB.BASEBOARD_FAB2(SCH_1):VR_P1V26_BMC_STBY_FB


DRAWING: @BASEBOARD_FAB2_LIB.BASEBOARD_FAB2(SCH_1):PAGE240 

RES_0402-64.9K,1%,1/16W,CHIP,GA  I106  R8F9
   1 VR_P3V3_STBY_OCSELECT      A @BASEBOARD_FAB2_LIB.BASEBOARD_FAB2(SCH_1):VR_P3V3_STBY_OCSELECT
   2 AGND_P3V3_STBY      B @BASEBOARD_FAB2_LIB.BASEBOARD_FAB2(SCH_1):AGND_P3V3_STBY

CAP_0603-4.7UF,6.3V,10%,X6S,E1A  I109  C2R11
   1 P5V_STBY      A @BASEBOARD_FAB2_LIB.BASEBOARD_FAB2(SCH_1):P5V_STBY
   2 AGND_P3V3_STBY      B @BASEBOARD_FAB2_LIB.BASEBOARD_FAB2(SCH_1):AGND_P3V3_STBY

RES_0402-10.0K,1%,1/16W,EMPTY,A  I111  R8F1
   1 PWRGD_P5V_STBY      A @BASEBOARD_FAB2_LIB.BASEBOARD_FAB2(SCH_1):PWRGD_P5V_STBY
   2    GND      B @BASEBOARD_FAB2_LIB.BASEBOARD_FAB2(SCH_1):GND

CAP_0402LF-1000PF,50V,10%,EMPTA  I113  C8E17
   1 PWRGD_P5V_STBY      A @BASEBOARD_FAB2_LIB.BASEBOARD_FAB2(SCH_1):PWRGD_P5V_STBY
   2 AGND_P3V3_STBY      B @BASEBOARD_FAB2_LIB.BASEBOARD_FAB2(SCH_1):AGND_P3V3_STBY

CAP_0402LF-1000PF,50V,10%,X7R,A  I116  C8F2
   1 PWRGD_P3V3_STBY_R      A @BASEBOARD_FAB2_LIB.BASEBOARD_FAB2(SCH_1):PWRGD_P3V3_STBY_R
   2    GND      B @BASEBOARD_FAB2_LIB.BASEBOARD_FAB2(SCH_1):GND

RES_0402-1.00K,1%,1/16W,CHIP,GA  I117  R8F5
   1 P3V3_STBY      A @BASEBOARD_FAB2_LIB.BASEBOARD_FAB2(SCH_1):P3V3_STBY
   2 PWRGD_P3V3_STBY_R      B @BASEBOARD_FAB2_LIB.BASEBOARD_FAB2(SCH_1):PWRGD_P3V3_STBY_R

RT8240_QFN-IC,H66262-001  I125  EU8F1
   4 VR_P3V3_STBY_BOOT   BOOT @BASEBOARD_FAB2_LIB.BASEBOARD_FAB2(SCH_1):VR_P3V3_STBY_BOOT
  10 VR_P3V3_STBY_OCSELECT     CS @BASEBOARD_FAB2_LIB.BASEBOARD_FAB2(SCH_1):VR_P3V3_STBY_OCSELECT
   8 VR_P3V3_STBY_EN     EN @BASEBOARD_FAB2_LIB.BASEBOARD_FAB2(SCH_1):VR_P3V3_STBY_EN
  11 AGND_P3V3_STBY     G0 @BASEBOARD_FAB2_LIB.BASEBOARD_FAB2(SCH_1):AGND_P3V3_STBY
  13 AGND_P3V3_STBY GND<1> @BASEBOARD_FAB2_LIB.BASEBOARD_FAB2(SCH_1):AGND_P3V3_STBY
  12 AGND_P3V3_STBY GND<0> @BASEBOARD_FAB2_LIB.BASEBOARD_FAB2(SCH_1):AGND_P3V3_STBY
   1 VR_P3V3_STBY_LGATE  LGATE @BASEBOARD_FAB2_LIB.BASEBOARD_FAB2(SCH_1):VR_P3V3_STBY_LGATE
   9 PWRGD_P3V3_STBY_R  PGOOD @BASEBOARD_FAB2_LIB.BASEBOARD_FAB2(SCH_1):PWRGD_P3V3_STBY_R
   2 VR_P3V3_STBY_PHASE  PHASE @BASEBOARD_FAB2_LIB.BASEBOARD_FAB2(SCH_1):VR_P3V3_STBY_PHASE
   7 VSENSE_RGND_P3V3_STBY   RGND @BASEBOARD_FAB2_LIB.BASEBOARD_FAB2(SCH_1):VSENSE_RGND_P3V3_STBY
   3 VR_P3V3_STBY_UGATE  UGATE @BASEBOARD_FAB2_LIB.BASEBOARD_FAB2(SCH_1):VR_P3V3_STBY_UGATE
   5 P5V_STBY    VCC @BASEBOARD_FAB2_LIB.BASEBOARD_FAB2(SCH_1):P5V_STBY
   6 VSENSE_VOUT_P3V3_STBY   VOUT @BASEBOARD_FAB2_LIB.BASEBOARD_FAB2(SCH_1):VSENSE_VOUT_P3V3_STBY

RES_0402-0.0,5%,1/16W,CHIP,G21A  I127  R8E35
   1 VR_P3V3_STBY_BOOT      A @BASEBOARD_FAB2_LIB.BASEBOARD_FAB2(SCH_1):VR_P3V3_STBY_BOOT
   2 VR_P3V3_STBY_BOOT_R      B @BASEBOARD_FAB2_LIB.BASEBOARD_FAB2(SCH_1):VR_P3V3_STBY_BOOT_R

CAP_0603LF-0.1UF,25V,10%,X7R,6A  I129  C8E12
   1 VR_P3V3_STBY_PHASE      A @BASEBOARD_FAB2_LIB.BASEBOARD_FAB2(SCH_1):VR_P3V3_STBY_PHASE
   2 VR_P3V3_STBY_BOOT_R      B @BASEBOARD_FAB2_LIB.BASEBOARD_FAB2(SCH_1):VR_P3V3_STBY_BOOT_R

FERRITE_SM-22,FB,656554-051  I132  FB9E1
   1 P12V_STBY      A @BASEBOARD_FAB2_LIB.BASEBOARD_FAB2(SCH_1):P12V_STBY
   2 VR_FET_SW_P12V_STBY_P3V3_STBY      B @BASEBOARD_FAB2_LIB.BASEBOARD_FAB2(SCH_1):VR_FET_SW_P12V_STBY_P3V3_STBY

CAP_1210-47UF,16V,20%,X6S,D384A  I134  C9F1
   1 VR_FET_SW_P12V_STBY_P3V3_STBY      A @BASEBOARD_FAB2_LIB.BASEBOARD_FAB2(SCH_1):VR_FET_SW_P12V_STBY_P3V3_STBY
   2    GND      B @BASEBOARD_FAB2_LIB.BASEBOARD_FAB2(SCH_1):GND

CAP_1210-47UF,16V,20%,X6S,D384A  I135  C8E11
   1 VR_FET_SW_P12V_STBY_P3V3_STBY      A @BASEBOARD_FAB2_LIB.BASEBOARD_FAB2(SCH_1):VR_FET_SW_P12V_STBY_P3V3_STBY
   2    GND      B @BASEBOARD_FAB2_LIB.BASEBOARD_FAB2(SCH_1):GND

CAP_1206LF-22UF,16V,10%,X6S,D3A  I137  C8E10
   1 VR_FET_SW_P12V_STBY_P3V3_STBY      A @BASEBOARD_FAB2_LIB.BASEBOARD_FAB2(SCH_1):VR_FET_SW_P12V_STBY_P3V3_STBY
   2    GND      B @BASEBOARD_FAB2_LIB.BASEBOARD_FAB2(SCH_1):GND

CAP_0402-1.0UF,16V,10%,X6S,D97A  I139  C8E14
   1 VR_FET_SW_P12V_STBY_P3V3_STBY      A @BASEBOARD_FAB2_LIB.BASEBOARD_FAB2(SCH_1):VR_FET_SW_P12V_STBY_P3V3_STBY
   2    GND      B @BASEBOARD_FAB2_LIB.BASEBOARD_FAB2(SCH_1):GND

RES_0402-0.0,5%,1/16W,CHIP,G21A  I140  R8E38
   1 VSENSE_RGND_P3V3_STBY      A @BASEBOARD_FAB2_LIB.BASEBOARD_FAB2(SCH_1):VSENSE_RGND_P3V3_STBY
   2 AGND_P3V3_STBY      B @BASEBOARD_FAB2_LIB.BASEBOARD_FAB2(SCH_1):AGND_P3V3_STBY

RES_0402-10.0K,1%,1/16W,CHIP,GA  I142  R8E34
   1 VSENSE_VOUT_P3V3_STBY      A @BASEBOARD_FAB2_LIB.BASEBOARD_FAB2(SCH_1):VSENSE_VOUT_P3V3_STBY
   2 AGND_P3V3_STBY      B @BASEBOARD_FAB2_LIB.BASEBOARD_FAB2(SCH_1):AGND_P3V3_STBY

RES_0402-23.2K,1%,1/16W,CHIP,GA  I143  R8E31
   1 VSENSE_P3V3_STBY      A @BASEBOARD_FAB2_LIB.BASEBOARD_FAB2(SCH_1):VSENSE_P3V3_STBY
   2 VSENSE_VOUT_P3V3_STBY      B @BASEBOARD_FAB2_LIB.BASEBOARD_FAB2(SCH_1):VSENSE_VOUT_P3V3_STBY

RES_0402-0.0,5%,1/16W,CHIP,G21A  I144  R8E25
   1 P3V3_STBY      A @BASEBOARD_FAB2_LIB.BASEBOARD_FAB2(SCH_1):P3V3_STBY
   2 VSENSE_P3V3_STBY      B @BASEBOARD_FAB2_LIB.BASEBOARD_FAB2(SCH_1):VSENSE_P3V3_STBY

RES_0402-0.0,5%,1/16W,CHIP,G21A  I146  R8F11
   1    GND      A @BASEBOARD_FAB2_LIB.BASEBOARD_FAB2(SCH_1):GND
   2 AGND_P3V3_STBY      B @BASEBOARD_FAB2_LIB.BASEBOARD_FAB2(SCH_1):AGND_P3V3_STBY

RES_0402-2.2,5%,1/16W,EMPTY,G2A  I148  R8F3
   1 VR_P3V3_STBY_SNUB      A @BASEBOARD_FAB2_LIB.BASEBOARD_FAB2(SCH_1):VR_P3V3_STBY_SNUB
   2    GND      B @BASEBOARD_FAB2_LIB.BASEBOARD_FAB2(SCH_1):GND

RES_0402-1.0K,0.1%,1/16W,CHIP,A  I152  R2T4
   1 P3V3_STBY      A @BASEBOARD_FAB2_LIB.BASEBOARD_FAB2(SCH_1):P3V3_STBY
   2    GND      B @BASEBOARD_FAB2_LIB.BASEBOARD_FAB2(SCH_1):GND

CAPP_3018-470UF,6.3V,20%,POSCAA  I154  C8F14
   1 P3V3_STBY      A @BASEBOARD_FAB2_LIB.BASEBOARD_FAB2(SCH_1):P3V3_STBY
   2    GND      B @BASEBOARD_FAB2_LIB.BASEBOARD_FAB2(SCH_1):GND

CAPP_3018-470UF,6.3V,20%,POSCAA  I155  C8F8
   1 P3V3_STBY      A @BASEBOARD_FAB2_LIB.BASEBOARD_FAB2(SCH_1):P3V3_STBY
   2    GND      B @BASEBOARD_FAB2_LIB.BASEBOARD_FAB2(SCH_1):GND

CAP_0805-22UF,6.3V,20%,X6S,C95A  I158  C2T7
   1 P3V3_STBY      A @BASEBOARD_FAB2_LIB.BASEBOARD_FAB2(SCH_1):P3V3_STBY
   2    GND      B @BASEBOARD_FAB2_LIB.BASEBOARD_FAB2(SCH_1):GND

CAP_0805-22UF,6.3V,20%,X6S,C95A  I160  C2T6
   1 P3V3_STBY      A @BASEBOARD_FAB2_LIB.BASEBOARD_FAB2(SCH_1):P3V3_STBY
   2    GND      B @BASEBOARD_FAB2_LIB.BASEBOARD_FAB2(SCH_1):GND

CAP_0402LF-3300PF,50V,10%,EMPTA  I163  C8F3
   1 VR_P3V3_STBY_PHASE      A @BASEBOARD_FAB2_LIB.BASEBOARD_FAB2(SCH_1):VR_P3V3_STBY_PHASE
   2 VR_P3V3_STBY_SNUB      B @BASEBOARD_FAB2_LIB.BASEBOARD_FAB2(SCH_1):VR_P3V3_STBY_SNUB

CSD87384M_SM-IC,H66258-001  I170  EU8E1
   4 VR_P3V3_STBY_LGATE     BG @BASEBOARD_FAB2_LIB.BASEBOARD_FAB2(SCH_1):VR_P3V3_STBY_LGATE
   3    GND   PGND @BASEBOARD_FAB2_LIB.BASEBOARD_FAB2(SCH_1):GND
   1 VR_P3V3_STBY_UGATE     TG @BASEBOARD_FAB2_LIB.BASEBOARD_FAB2(SCH_1):VR_P3V3_STBY_UGATE
   2 VR_FET_SW_P12V_STBY_P3V3_STBY    VIN @BASEBOARD_FAB2_LIB.BASEBOARD_FAB2(SCH_1):VR_FET_SW_P12V_STBY_P3V3_STBY
   5 VR_P3V3_STBY_PHASE    VSW @BASEBOARD_FAB2_LIB.BASEBOARD_FAB2(SCH_1):VR_P3V3_STBY_PHASE

RES_0402-22.1,1.0%,1/16W,CHIP,A  I171  R8F10
   1 PWRGD_P3V3_STBY_R      A @BASEBOARD_FAB2_LIB.BASEBOARD_FAB2(SCH_1):PWRGD_P3V3_STBY_R
   2 PWRGD_P3V3_STBY      B @BASEBOARD_FAB2_LIB.BASEBOARD_FAB2(SCH_1):PWRGD_P3V3_STBY

INDUCTOR_SM-1.00UH,IND,E98679-A  I173  L8F1
   1 VR_P3V3_STBY_PHASE    INA @BASEBOARD_FAB2_LIB.BASEBOARD_FAB2(SCH_1):VR_P3V3_STBY_PHASE
   2 P3V3_STBY    INB @BASEBOARD_FAB2_LIB.BASEBOARD_FAB2(SCH_1):P3V3_STBY

CAP_0805-22UF,6.3V,20%,X6S,C95A  I174  C2T9
   1 P3V3_STBY      A @BASEBOARD_FAB2_LIB.BASEBOARD_FAB2(SCH_1):P3V3_STBY
   2    GND      B @BASEBOARD_FAB2_LIB.BASEBOARD_FAB2(SCH_1):GND

RES_0402-0.0,5%,1/16W,CHIP,G21A  I176  R8F2
   1 PWRGD_P5V_STBY      A @BASEBOARD_FAB2_LIB.BASEBOARD_FAB2(SCH_1):PWRGD_P5V_STBY
   2 VR_P3V3_STBY_EN      B @BASEBOARD_FAB2_LIB.BASEBOARD_FAB2(SCH_1):VR_P3V3_STBY_EN

RES_0402-100.0K,1%,1/16W,EMPTYA  I177  R8E40
   1 P3V3_STBY      A @BASEBOARD_FAB2_LIB.BASEBOARD_FAB2(SCH_1):P3V3_STBY
   2 VR_P3V3_STBY_EN      B @BASEBOARD_FAB2_LIB.BASEBOARD_FAB2(SCH_1):VR_P3V3_STBY_EN


DRAWING: @BASEBOARD_FAB2_LIB.BASEBOARD_FAB2(SCH_1):PAGE241 

CAP_0805-22UF,6.3V,20%,X6S,C95A  I2  C8E9
   1 P5V_STBY      A @BASEBOARD_FAB2_LIB.BASEBOARD_FAB2(SCH_1):P5V_STBY
   2    GND      B @BASEBOARD_FAB2_LIB.BASEBOARD_FAB2(SCH_1):GND

CAP_0805-22UF,6.3V,20%,X6S,C95A  I3  C8E7
   1 P5V_STBY      A @BASEBOARD_FAB2_LIB.BASEBOARD_FAB2(SCH_1):P5V_STBY
   2    GND      B @BASEBOARD_FAB2_LIB.BASEBOARD_FAB2(SCH_1):GND

CAPP_3018-470UF,6.3V,20%,POSCAA  I8  C8E4
   1 P5V_STBY      A @BASEBOARD_FAB2_LIB.BASEBOARD_FAB2(SCH_1):P5V_STBY
   2    GND      B @BASEBOARD_FAB2_LIB.BASEBOARD_FAB2(SCH_1):GND

RES_0402-1.0K,0.1%,1/16W,CHIP,A  I9  R8E18
   1 P5V_STBY      A @BASEBOARD_FAB2_LIB.BASEBOARD_FAB2(SCH_1):P5V_STBY
   2    GND      B @BASEBOARD_FAB2_LIB.BASEBOARD_FAB2(SCH_1):GND

RES_0402-1.00K,1%,1/16W,CHIP,GA  I11  R7E12
   1 P5V_STBY      A @BASEBOARD_FAB2_LIB.BASEBOARD_FAB2(SCH_1):P5V_STBY
   2 PWRGD_P5V_STBY_R      B @BASEBOARD_FAB2_LIB.BASEBOARD_FAB2(SCH_1):PWRGD_P5V_STBY_R

CAP_0603LF-0.1UF,25V,10%,X7R,6A  I12  C8E6
   1 VR_P5V_STBY_BOOT      A @BASEBOARD_FAB2_LIB.BASEBOARD_FAB2(SCH_1):VR_P5V_STBY_BOOT
   2 VR_P5V_STBY_PHASE      B @BASEBOARD_FAB2_LIB.BASEBOARD_FAB2(SCH_1):VR_P5V_STBY_PHASE

CAP_0402LF-1000PF,50V,10%,X7R,A  I14  C7E10
   1 PWRGD_P5V_STBY_R      A @BASEBOARD_FAB2_LIB.BASEBOARD_FAB2(SCH_1):PWRGD_P5V_STBY_R
   2    GND      B @BASEBOARD_FAB2_LIB.BASEBOARD_FAB2(SCH_1):GND

RES_0402-75K,1%,1/16W,CHIP,G21A  I18  R7E14
   1 VR_P5V_STBY_RT      A @BASEBOARD_FAB2_LIB.BASEBOARD_FAB2(SCH_1):VR_P5V_STBY_RT
   2 AGND_P5V_STBY      B @BASEBOARD_FAB2_LIB.BASEBOARD_FAB2(SCH_1):AGND_P5V_STBY

CAP_0402-1.0UF,16V,10%,X6S,D97A  I30  C7E14
   1 VR_P5V_STBY_VIN      A @BASEBOARD_FAB2_LIB.BASEBOARD_FAB2(SCH_1):VR_P5V_STBY_VIN
   2    GND      B @BASEBOARD_FAB2_LIB.BASEBOARD_FAB2(SCH_1):GND

RES_0402-0.0,5%,1/16W,CHIP,G21A  I37  R7E17
   1 VR_FET_SW_P5V_STBY_PVIN      A @BASEBOARD_FAB2_LIB.BASEBOARD_FAB2(SCH_1):VR_FET_SW_P5V_STBY_PVIN
   2 VR_P5V_STBY_VIN      B @BASEBOARD_FAB2_LIB.BASEBOARD_FAB2(SCH_1):VR_P5V_STBY_VIN

CAP_1206LF-22UF,16V,10%,X6S,D3A  I39  C7E11
   1 VR_FET_SW_P5V_STBY_PVIN      A @BASEBOARD_FAB2_LIB.BASEBOARD_FAB2(SCH_1):VR_FET_SW_P5V_STBY_PVIN
   2    GND      B @BASEBOARD_FAB2_LIB.BASEBOARD_FAB2(SCH_1):GND

CAP_0402LF-1000PF,50V,10%,EMPTA  I41  C8E13
   1 PWRGD_P12V_HSC_DLY      A @BASEBOARD_FAB2_LIB.BASEBOARD_FAB2(SCH_1):PWRGD_P12V_HSC_DLY
   2 AGND_P5V_STBY      B @BASEBOARD_FAB2_LIB.BASEBOARD_FAB2(SCH_1):AGND_P5V_STBY

CAP_1210-47UF,16V,20%,X6S,D384A  I45  C7E13
   1 VR_FET_SW_P5V_STBY_PVIN      A @BASEBOARD_FAB2_LIB.BASEBOARD_FAB2(SCH_1):VR_FET_SW_P5V_STBY_PVIN
   2    GND      B @BASEBOARD_FAB2_LIB.BASEBOARD_FAB2(SCH_1):GND

CAP_1210-47UF,16V,20%,X6S,D384A  I47  C7E12
   1 VR_FET_SW_P5V_STBY_PVIN      A @BASEBOARD_FAB2_LIB.BASEBOARD_FAB2(SCH_1):VR_FET_SW_P5V_STBY_PVIN
   2    GND      B @BASEBOARD_FAB2_LIB.BASEBOARD_FAB2(SCH_1):GND

RES_0402-10.0K,1%,1/16W,CHIP,GA  I50  R7F1
   1 VR_P5V_STBY_VSENSE_R      A @BASEBOARD_FAB2_LIB.BASEBOARD_FAB2(SCH_1):VR_P5V_STBY_VSENSE_R
   2 VR_P5V_STBY_VSENSE      B @BASEBOARD_FAB2_LIB.BASEBOARD_FAB2(SCH_1):VR_P5V_STBY_VSENSE

RES_0402-1.37K,1%,1/16W,CHIP,GA  I51  R7E16
   1 VR_P5V_STBY_VSENSE      A @BASEBOARD_FAB2_LIB.BASEBOARD_FAB2(SCH_1):VR_P5V_STBY_VSENSE
   2 AGND_P5V_STBY      B @BASEBOARD_FAB2_LIB.BASEBOARD_FAB2(SCH_1):AGND_P5V_STBY

CAP_0402LF-270PF,50V,10%,X7R,AA  I53  C8E16
   1 VR_P5V_STBY_COMP      A @BASEBOARD_FAB2_LIB.BASEBOARD_FAB2(SCH_1):VR_P5V_STBY_COMP
   2 AGND_P5V_STBY      B @BASEBOARD_FAB2_LIB.BASEBOARD_FAB2(SCH_1):AGND_P5V_STBY

RES_0402-24.9K,1%,1/16W,CHIP,GA  I54  R8E39
   1 VR_P5V_STBY_COMP      A @BASEBOARD_FAB2_LIB.BASEBOARD_FAB2(SCH_1):VR_P5V_STBY_COMP
   2 VR_P5V_STBY_RC_COMP      B @BASEBOARD_FAB2_LIB.BASEBOARD_FAB2(SCH_1):VR_P5V_STBY_RC_COMP

CAP_0402LF-2200PF,50V,10%,X7R,A  I57  C8F1
   1 VR_P5V_STBY_RC_COMP      A @BASEBOARD_FAB2_LIB.BASEBOARD_FAB2(SCH_1):VR_P5V_STBY_RC_COMP
   2 AGND_P5V_STBY      B @BASEBOARD_FAB2_LIB.BASEBOARD_FAB2(SCH_1):AGND_P5V_STBY

RES_0402-0.0,5%,1/16W,CHIP,G21A  I58  R7E13
   1    GND      A @BASEBOARD_FAB2_LIB.BASEBOARD_FAB2(SCH_1):GND
   2 AGND_P5V_STBY      B @BASEBOARD_FAB2_LIB.BASEBOARD_FAB2(SCH_1):AGND_P5V_STBY

CAP_0402LF-0.022UF,16V,10%,X7RA  I63  C8E15
   1 VR_P5V_STBY_SS      A @BASEBOARD_FAB2_LIB.BASEBOARD_FAB2(SCH_1):VR_P5V_STBY_SS
   2 AGND_P5V_STBY      B @BASEBOARD_FAB2_LIB.BASEBOARD_FAB2(SCH_1):AGND_P5V_STBY

RES_0402-0.0,5%,1/16W,CHIP,G21A  I78  R8E37
   1 VR_P5V_STBY_VSENSE_R      A @BASEBOARD_FAB2_LIB.BASEBOARD_FAB2(SCH_1):VR_P5V_STBY_VSENSE_R
   2 P5V_STBY      B @BASEBOARD_FAB2_LIB.BASEBOARD_FAB2(SCH_1):P5V_STBY

FERRITE_SM-22,FB,656554-051  I82  FB7E1
   1 P12V_STBY      A @BASEBOARD_FAB2_LIB.BASEBOARD_FAB2(SCH_1):P12V_STBY
   2 VR_FET_SW_P5V_STBY_PVIN      B @BASEBOARD_FAB2_LIB.BASEBOARD_FAB2(SCH_1):VR_FET_SW_P5V_STBY_PVIN

TPS54821_LCC-IC,H63269-001  I83  EU7E2
  13 VR_P5V_STBY_BOOT   BOOT @BASEBOARD_FAB2_LIB.BASEBOARD_FAB2(SCH_1):VR_P5V_STBY_BOOT
   8 VR_P5V_STBY_COMP   COMP @BASEBOARD_FAB2_LIB.BASEBOARD_FAB2(SCH_1):VR_P5V_STBY_COMP
  10 VR_P5V_STBY_EN     EN @BASEBOARD_FAB2_LIB.BASEBOARD_FAB2(SCH_1):VR_P5V_STBY_EN
   3    GND GND<1> @BASEBOARD_FAB2_LIB.BASEBOARD_FAB2(SCH_1):GND
   2    GND GND<0> @BASEBOARD_FAB2_LIB.BASEBOARD_FAB2(SCH_1):GND
  12 VR_P5V_STBY_PHASE  PH<1> @BASEBOARD_FAB2_LIB.BASEBOARD_FAB2(SCH_1):VR_P5V_STBY_PHASE
  11 VR_P5V_STBY_PHASE  PH<0> @BASEBOARD_FAB2_LIB.BASEBOARD_FAB2(SCH_1):VR_P5V_STBY_PHASE
   5 VR_FET_SW_P5V_STBY_PVIN PVIN<1> @BASEBOARD_FAB2_LIB.BASEBOARD_FAB2(SCH_1):VR_FET_SW_P5V_STBY_PVIN
   4 VR_FET_SW_P5V_STBY_PVIN PVIN<0> @BASEBOARD_FAB2_LIB.BASEBOARD_FAB2(SCH_1):VR_FET_SW_P5V_STBY_PVIN
  14 PWRGD_P5V_STBY_R  PWRGD @BASEBOARD_FAB2_LIB.BASEBOARD_FAB2(SCH_1):PWRGD_P5V_STBY_R
   1 VR_P5V_STBY_RT RT_CLK @BASEBOARD_FAB2_LIB.BASEBOARD_FAB2(SCH_1):VR_P5V_STBY_RT
   9 VR_P5V_STBY_SS  SS_TR @BASEBOARD_FAB2_LIB.BASEBOARD_FAB2(SCH_1):VR_P5V_STBY_SS
  15    GND  THPAD @BASEBOARD_FAB2_LIB.BASEBOARD_FAB2(SCH_1):GND
   6 VR_P5V_STBY_VIN    VIN @BASEBOARD_FAB2_LIB.BASEBOARD_FAB2(SCH_1):VR_P5V_STBY_VIN
   7 VR_P5V_STBY_VSENSE VSENSE @BASEBOARD_FAB2_LIB.BASEBOARD_FAB2(SCH_1):VR_P5V_STBY_VSENSE

RES_0402-22.1,1.0%,1/16W,CHIP,A  I89  R7E15
   1 PWRGD_P5V_STBY_R      A @BASEBOARD_FAB2_LIB.BASEBOARD_FAB2(SCH_1):PWRGD_P5V_STBY_R
   2 PWRGD_P5V_STBY      B @BASEBOARD_FAB2_LIB.BASEBOARD_FAB2(SCH_1):PWRGD_P5V_STBY

INDUCTOR_SM-2.2UH,IND,E98761-0A  I90  L8E1
   1 VR_P5V_STBY_PHASE    INA @BASEBOARD_FAB2_LIB.BASEBOARD_FAB2(SCH_1):VR_P5V_STBY_PHASE
   2 P5V_STBY    INB @BASEBOARD_FAB2_LIB.BASEBOARD_FAB2(SCH_1):P5V_STBY

RES_0402-0.0,5%,1/16W,CHIP,G21A  I91  R8E33
   1 PWRGD_P12V_HSC_DLY      A @BASEBOARD_FAB2_LIB.BASEBOARD_FAB2(SCH_1):PWRGD_P12V_HSC_DLY
   2 VR_P5V_STBY_EN      B @BASEBOARD_FAB2_LIB.BASEBOARD_FAB2(SCH_1):VR_P5V_STBY_EN


DRAWING: @BASEBOARD_FAB2_LIB.BASEBOARD_FAB2(SCH_1):PAGE242 

CAP_0805-100UF,4V,20%,X5R,6024A  I11  C5G21
   1 PVDDQ_ABC      A @BASEBOARD_FAB2_LIB.BASEBOARD_FAB2(SCH_1):PVDDQ_ABC
   2    GND      B @BASEBOARD_FAB2_LIB.BASEBOARD_FAB2(SCH_1):GND

CAP_0805-100UF,4V,20%,X5R,6024A  I15  C5G22
   1 PVDDQ_ABC      A @BASEBOARD_FAB2_LIB.BASEBOARD_FAB2(SCH_1):PVDDQ_ABC
   2    GND      B @BASEBOARD_FAB2_LIB.BASEBOARD_FAB2(SCH_1):GND

CAP_0805-100UF,4V,20%,X5R,6024A  I37  C5G77
   1 PVDDQ_DEF      A @BASEBOARD_FAB2_LIB.BASEBOARD_FAB2(SCH_1):PVDDQ_DEF
   2    GND      B @BASEBOARD_FAB2_LIB.BASEBOARD_FAB2(SCH_1):GND

CAP_0805-100UF,4V,20%,X5R,6024A  I41  C5G78
   1 PVDDQ_DEF      A @BASEBOARD_FAB2_LIB.BASEBOARD_FAB2(SCH_1):PVDDQ_DEF
   2    GND      B @BASEBOARD_FAB2_LIB.BASEBOARD_FAB2(SCH_1):GND

CAP_A_0603V-22.0UF,4V,20%,X6S,A  I53  C5G41
   1 PVDDQ_ABC      A @BASEBOARD_FAB2_LIB.BASEBOARD_FAB2(SCH_1):PVDDQ_ABC
   2    GND      B @BASEBOARD_FAB2_LIB.BASEBOARD_FAB2(SCH_1):GND

CAP_A_0603V-22.0UF,4V,20%,X6S,A  I54  C5G42
   1 PVDDQ_ABC      A @BASEBOARD_FAB2_LIB.BASEBOARD_FAB2(SCH_1):PVDDQ_ABC
   2    GND      B @BASEBOARD_FAB2_LIB.BASEBOARD_FAB2(SCH_1):GND

CAP_A_0603V-22.0UF,4V,20%,X6S,A  I55  C5G44
   1 PVDDQ_ABC      A @BASEBOARD_FAB2_LIB.BASEBOARD_FAB2(SCH_1):PVDDQ_ABC
   2    GND      B @BASEBOARD_FAB2_LIB.BASEBOARD_FAB2(SCH_1):GND

CAP_A_0603V-22.0UF,4V,20%,X6S,A  I56  C5G43
   1 PVDDQ_ABC      A @BASEBOARD_FAB2_LIB.BASEBOARD_FAB2(SCH_1):PVDDQ_ABC
   2    GND      B @BASEBOARD_FAB2_LIB.BASEBOARD_FAB2(SCH_1):GND

CAP_A_0603V-22.0UF,4V,20%,X6S,A  I57  C5G48
   1 PVDDQ_ABC      A @BASEBOARD_FAB2_LIB.BASEBOARD_FAB2(SCH_1):PVDDQ_ABC
   2    GND      B @BASEBOARD_FAB2_LIB.BASEBOARD_FAB2(SCH_1):GND

CAP_A_0603V-22.0UF,4V,20%,X6S,A  I58  C5G47
   1 PVDDQ_ABC      A @BASEBOARD_FAB2_LIB.BASEBOARD_FAB2(SCH_1):PVDDQ_ABC
   2    GND      B @BASEBOARD_FAB2_LIB.BASEBOARD_FAB2(SCH_1):GND

CAP_A_0603V-22.0UF,4V,20%,X6S,A  I59  C5G46
   1 PVDDQ_ABC      A @BASEBOARD_FAB2_LIB.BASEBOARD_FAB2(SCH_1):PVDDQ_ABC
   2    GND      B @BASEBOARD_FAB2_LIB.BASEBOARD_FAB2(SCH_1):GND

CAP_A_0603V-22.0UF,4V,20%,X6S,A  I60  C5G45
   1 PVDDQ_ABC      A @BASEBOARD_FAB2_LIB.BASEBOARD_FAB2(SCH_1):PVDDQ_ABC
   2    GND      B @BASEBOARD_FAB2_LIB.BASEBOARD_FAB2(SCH_1):GND

CAP_A_0603V-22.0UF,4V,20%,X6S,A  I61  C5G49
   1 PVDDQ_ABC      A @BASEBOARD_FAB2_LIB.BASEBOARD_FAB2(SCH_1):PVDDQ_ABC
   2    GND      B @BASEBOARD_FAB2_LIB.BASEBOARD_FAB2(SCH_1):GND

CAP_A_0603V-22.0UF,4V,20%,X6S,A  I62  C5G54
   1 PVDDQ_ABC      A @BASEBOARD_FAB2_LIB.BASEBOARD_FAB2(SCH_1):PVDDQ_ABC
   2    GND      B @BASEBOARD_FAB2_LIB.BASEBOARD_FAB2(SCH_1):GND

CAP_A_0603V-22.0UF,4V,20%,X6S,A  I63  C5G58
   1 PVDDQ_ABC      A @BASEBOARD_FAB2_LIB.BASEBOARD_FAB2(SCH_1):PVDDQ_ABC
   2    GND      B @BASEBOARD_FAB2_LIB.BASEBOARD_FAB2(SCH_1):GND

CAP_A_0603V-22.0UF,4V,20%,X6S,A  I64  C5G57
   1 PVDDQ_ABC      A @BASEBOARD_FAB2_LIB.BASEBOARD_FAB2(SCH_1):PVDDQ_ABC
   2    GND      B @BASEBOARD_FAB2_LIB.BASEBOARD_FAB2(SCH_1):GND

CAP_A_0603V-22.0UF,4V,20%,X6S,A  I65  C5G56
   1 PVDDQ_ABC      A @BASEBOARD_FAB2_LIB.BASEBOARD_FAB2(SCH_1):PVDDQ_ABC
   2    GND      B @BASEBOARD_FAB2_LIB.BASEBOARD_FAB2(SCH_1):GND

CAP_A_0603V-22.0UF,4V,20%,X6S,A  I66  C5G55
   1 PVDDQ_ABC      A @BASEBOARD_FAB2_LIB.BASEBOARD_FAB2(SCH_1):PVDDQ_ABC
   2    GND      B @BASEBOARD_FAB2_LIB.BASEBOARD_FAB2(SCH_1):GND

CAP_A_0603V-22.0UF,4V,20%,X6S,A  I67  C5G53
   1 PVDDQ_ABC      A @BASEBOARD_FAB2_LIB.BASEBOARD_FAB2(SCH_1):PVDDQ_ABC
   2    GND      B @BASEBOARD_FAB2_LIB.BASEBOARD_FAB2(SCH_1):GND

CAP_A_0603V-22.0UF,4V,20%,X6S,A  I68  C5G52
   1 PVDDQ_ABC      A @BASEBOARD_FAB2_LIB.BASEBOARD_FAB2(SCH_1):PVDDQ_ABC
   2    GND      B @BASEBOARD_FAB2_LIB.BASEBOARD_FAB2(SCH_1):GND

CAP_A_0603V-22.0UF,4V,20%,X6S,A  I69  C5G51
   1 PVDDQ_ABC      A @BASEBOARD_FAB2_LIB.BASEBOARD_FAB2(SCH_1):PVDDQ_ABC
   2    GND      B @BASEBOARD_FAB2_LIB.BASEBOARD_FAB2(SCH_1):GND

CAP_A_0603V-22.0UF,4V,20%,X6S,A  I70  C5G50
   1 PVDDQ_ABC      A @BASEBOARD_FAB2_LIB.BASEBOARD_FAB2(SCH_1):PVDDQ_ABC
   2    GND      B @BASEBOARD_FAB2_LIB.BASEBOARD_FAB2(SCH_1):GND

CAP_A_0603V-22.0UF,4V,20%,X6S,A  I71  C5G67
   1 PVDDQ_DEF      A @BASEBOARD_FAB2_LIB.BASEBOARD_FAB2(SCH_1):PVDDQ_DEF
   2    GND      B @BASEBOARD_FAB2_LIB.BASEBOARD_FAB2(SCH_1):GND

CAP_A_0603V-22.0UF,4V,20%,X6S,A  I72  C5G66
   1 PVDDQ_DEF      A @BASEBOARD_FAB2_LIB.BASEBOARD_FAB2(SCH_1):PVDDQ_DEF
   2    GND      B @BASEBOARD_FAB2_LIB.BASEBOARD_FAB2(SCH_1):GND

CAP_A_0603V-22.0UF,4V,20%,X6S,A  I73  C5G65
   1 PVDDQ_DEF      A @BASEBOARD_FAB2_LIB.BASEBOARD_FAB2(SCH_1):PVDDQ_DEF
   2    GND      B @BASEBOARD_FAB2_LIB.BASEBOARD_FAB2(SCH_1):GND

CAP_A_0603V-22.0UF,4V,20%,X6S,A  I74  C5G64
   1 PVDDQ_DEF      A @BASEBOARD_FAB2_LIB.BASEBOARD_FAB2(SCH_1):PVDDQ_DEF
   2    GND      B @BASEBOARD_FAB2_LIB.BASEBOARD_FAB2(SCH_1):GND

CAP_A_0603V-22.0UF,4V,20%,X6S,A  I75  C5G63
   1 PVDDQ_DEF      A @BASEBOARD_FAB2_LIB.BASEBOARD_FAB2(SCH_1):PVDDQ_DEF
   2    GND      B @BASEBOARD_FAB2_LIB.BASEBOARD_FAB2(SCH_1):GND

CAP_A_0603V-22.0UF,4V,20%,X6S,A  I76  C5G62
   1 PVDDQ_DEF      A @BASEBOARD_FAB2_LIB.BASEBOARD_FAB2(SCH_1):PVDDQ_DEF
   2    GND      B @BASEBOARD_FAB2_LIB.BASEBOARD_FAB2(SCH_1):GND

CAP_A_0603V-22.0UF,4V,20%,X6S,A  I77  C5G61
   1 PVDDQ_DEF      A @BASEBOARD_FAB2_LIB.BASEBOARD_FAB2(SCH_1):PVDDQ_DEF
   2    GND      B @BASEBOARD_FAB2_LIB.BASEBOARD_FAB2(SCH_1):GND

CAP_A_0603V-22.0UF,4V,20%,X6S,A  I78  C5G60
   1 PVDDQ_DEF      A @BASEBOARD_FAB2_LIB.BASEBOARD_FAB2(SCH_1):PVDDQ_DEF
   2    GND      B @BASEBOARD_FAB2_LIB.BASEBOARD_FAB2(SCH_1):GND

CAP_A_0603V-22.0UF,4V,20%,X6S,A  I79  C5G59
   1 PVDDQ_DEF      A @BASEBOARD_FAB2_LIB.BASEBOARD_FAB2(SCH_1):PVDDQ_DEF
   2    GND      B @BASEBOARD_FAB2_LIB.BASEBOARD_FAB2(SCH_1):GND

CAP_A_0603V-22.0UF,4V,20%,X6S,A  I80  C5G76
   1 PVDDQ_DEF      A @BASEBOARD_FAB2_LIB.BASEBOARD_FAB2(SCH_1):PVDDQ_DEF
   2    GND      B @BASEBOARD_FAB2_LIB.BASEBOARD_FAB2(SCH_1):GND

CAP_A_0603V-22.0UF,4V,20%,X6S,A  I81  C5G75
   1 PVDDQ_DEF      A @BASEBOARD_FAB2_LIB.BASEBOARD_FAB2(SCH_1):PVDDQ_DEF
   2    GND      B @BASEBOARD_FAB2_LIB.BASEBOARD_FAB2(SCH_1):GND

CAP_A_0603V-22.0UF,4V,20%,X6S,A  I82  C5G74
   1 PVDDQ_DEF      A @BASEBOARD_FAB2_LIB.BASEBOARD_FAB2(SCH_1):PVDDQ_DEF
   2    GND      B @BASEBOARD_FAB2_LIB.BASEBOARD_FAB2(SCH_1):GND

CAP_A_0603V-22.0UF,4V,20%,X6S,A  I83  C5G73
   1 PVDDQ_DEF      A @BASEBOARD_FAB2_LIB.BASEBOARD_FAB2(SCH_1):PVDDQ_DEF
   2    GND      B @BASEBOARD_FAB2_LIB.BASEBOARD_FAB2(SCH_1):GND

CAP_A_0603V-22.0UF,4V,20%,X6S,A  I84  C5G72
   1 PVDDQ_DEF      A @BASEBOARD_FAB2_LIB.BASEBOARD_FAB2(SCH_1):PVDDQ_DEF
   2    GND      B @BASEBOARD_FAB2_LIB.BASEBOARD_FAB2(SCH_1):GND

CAP_A_0603V-22.0UF,4V,20%,X6S,A  I85  C5G71
   1 PVDDQ_DEF      A @BASEBOARD_FAB2_LIB.BASEBOARD_FAB2(SCH_1):PVDDQ_DEF
   2    GND      B @BASEBOARD_FAB2_LIB.BASEBOARD_FAB2(SCH_1):GND

CAP_A_0603V-22.0UF,4V,20%,X6S,A  I86  C5G70
   1 PVDDQ_DEF      A @BASEBOARD_FAB2_LIB.BASEBOARD_FAB2(SCH_1):PVDDQ_DEF
   2    GND      B @BASEBOARD_FAB2_LIB.BASEBOARD_FAB2(SCH_1):GND

CAP_A_0603V-22.0UF,4V,20%,X6S,A  I87  C5G69
   1 PVDDQ_DEF      A @BASEBOARD_FAB2_LIB.BASEBOARD_FAB2(SCH_1):PVDDQ_DEF
   2    GND      B @BASEBOARD_FAB2_LIB.BASEBOARD_FAB2(SCH_1):GND

CAP_A_0603V-22.0UF,4V,20%,X6S,A  I88  C5G68
   1 PVDDQ_DEF      A @BASEBOARD_FAB2_LIB.BASEBOARD_FAB2(SCH_1):PVDDQ_DEF
   2    GND      B @BASEBOARD_FAB2_LIB.BASEBOARD_FAB2(SCH_1):GND


DRAWING: @BASEBOARD_FAB2_LIB.BASEBOARD_FAB2(SCH_1):PAGE243 

CAP_0805-100UF,4V,20%,X5R,6024A  I12  C5G117
   1 PVDDQ_GHJ      A @BASEBOARD_FAB2_LIB.BASEBOARD_FAB2(SCH_1):PVDDQ_GHJ
   2    GND      B @BASEBOARD_FAB2_LIB.BASEBOARD_FAB2(SCH_1):GND

CAP_0805-100UF,4V,20%,X5R,6024A  I13  C5G118
   1 PVDDQ_GHJ      A @BASEBOARD_FAB2_LIB.BASEBOARD_FAB2(SCH_1):PVDDQ_GHJ
   2    GND      B @BASEBOARD_FAB2_LIB.BASEBOARD_FAB2(SCH_1):GND

CAP_0805-100UF,4V,20%,X5R,6024A  I39  C5G115
   1 PVDDQ_KLM      A @BASEBOARD_FAB2_LIB.BASEBOARD_FAB2(SCH_1):PVDDQ_KLM
   2    GND      B @BASEBOARD_FAB2_LIB.BASEBOARD_FAB2(SCH_1):GND

CAP_0805-100UF,4V,20%,X5R,6024A  I43  C5G116
   1 PVDDQ_KLM      A @BASEBOARD_FAB2_LIB.BASEBOARD_FAB2(SCH_1):PVDDQ_KLM
   2    GND      B @BASEBOARD_FAB2_LIB.BASEBOARD_FAB2(SCH_1):GND

CAP_A_0603V-22.0UF,4V,20%,X6S,A  I53  C5G79
   1 PVDDQ_GHJ      A @BASEBOARD_FAB2_LIB.BASEBOARD_FAB2(SCH_1):PVDDQ_GHJ
   2    GND      B @BASEBOARD_FAB2_LIB.BASEBOARD_FAB2(SCH_1):GND

CAP_A_0603V-22.0UF,4V,20%,X6S,A  I54  C5G87
   1 PVDDQ_GHJ      A @BASEBOARD_FAB2_LIB.BASEBOARD_FAB2(SCH_1):PVDDQ_GHJ
   2    GND      B @BASEBOARD_FAB2_LIB.BASEBOARD_FAB2(SCH_1):GND

CAP_A_0603V-22.0UF,4V,20%,X6S,A  I55  C5G86
   1 PVDDQ_GHJ      A @BASEBOARD_FAB2_LIB.BASEBOARD_FAB2(SCH_1):PVDDQ_GHJ
   2    GND      B @BASEBOARD_FAB2_LIB.BASEBOARD_FAB2(SCH_1):GND

CAP_A_0603V-22.0UF,4V,20%,X6S,A  I56  C5G85
   1 PVDDQ_GHJ      A @BASEBOARD_FAB2_LIB.BASEBOARD_FAB2(SCH_1):PVDDQ_GHJ
   2    GND      B @BASEBOARD_FAB2_LIB.BASEBOARD_FAB2(SCH_1):GND

CAP_A_0603V-22.0UF,4V,20%,X6S,A  I57  C5G84
   1 PVDDQ_GHJ      A @BASEBOARD_FAB2_LIB.BASEBOARD_FAB2(SCH_1):PVDDQ_GHJ
   2    GND      B @BASEBOARD_FAB2_LIB.BASEBOARD_FAB2(SCH_1):GND

CAP_A_0603V-22.0UF,4V,20%,X6S,A  I58  C5G83
   1 PVDDQ_GHJ      A @BASEBOARD_FAB2_LIB.BASEBOARD_FAB2(SCH_1):PVDDQ_GHJ
   2    GND      B @BASEBOARD_FAB2_LIB.BASEBOARD_FAB2(SCH_1):GND

CAP_A_0603V-22.0UF,4V,20%,X6S,A  I59  C5G82
   1 PVDDQ_GHJ      A @BASEBOARD_FAB2_LIB.BASEBOARD_FAB2(SCH_1):PVDDQ_GHJ
   2    GND      B @BASEBOARD_FAB2_LIB.BASEBOARD_FAB2(SCH_1):GND

CAP_A_0603V-22.0UF,4V,20%,X6S,A  I60  C5G81
   1 PVDDQ_GHJ      A @BASEBOARD_FAB2_LIB.BASEBOARD_FAB2(SCH_1):PVDDQ_GHJ
   2    GND      B @BASEBOARD_FAB2_LIB.BASEBOARD_FAB2(SCH_1):GND

CAP_A_0603V-22.0UF,4V,20%,X6S,A  I61  C5G80
   1 PVDDQ_GHJ      A @BASEBOARD_FAB2_LIB.BASEBOARD_FAB2(SCH_1):PVDDQ_GHJ
   2    GND      B @BASEBOARD_FAB2_LIB.BASEBOARD_FAB2(SCH_1):GND

CAP_A_0603V-22.0UF,4V,20%,X6S,A  I62  C5G96
   1 PVDDQ_GHJ      A @BASEBOARD_FAB2_LIB.BASEBOARD_FAB2(SCH_1):PVDDQ_GHJ
   2    GND      B @BASEBOARD_FAB2_LIB.BASEBOARD_FAB2(SCH_1):GND

CAP_A_0603V-22.0UF,4V,20%,X6S,A  I63  C5G95
   1 PVDDQ_GHJ      A @BASEBOARD_FAB2_LIB.BASEBOARD_FAB2(SCH_1):PVDDQ_GHJ
   2    GND      B @BASEBOARD_FAB2_LIB.BASEBOARD_FAB2(SCH_1):GND

CAP_A_0603V-22.0UF,4V,20%,X6S,A  I64  C5G94
   1 PVDDQ_GHJ      A @BASEBOARD_FAB2_LIB.BASEBOARD_FAB2(SCH_1):PVDDQ_GHJ
   2    GND      B @BASEBOARD_FAB2_LIB.BASEBOARD_FAB2(SCH_1):GND

CAP_A_0603V-22.0UF,4V,20%,X6S,A  I65  C5G93
   1 PVDDQ_GHJ      A @BASEBOARD_FAB2_LIB.BASEBOARD_FAB2(SCH_1):PVDDQ_GHJ
   2    GND      B @BASEBOARD_FAB2_LIB.BASEBOARD_FAB2(SCH_1):GND

CAP_A_0603V-22.0UF,4V,20%,X6S,A  I66  C5G92
   1 PVDDQ_GHJ      A @BASEBOARD_FAB2_LIB.BASEBOARD_FAB2(SCH_1):PVDDQ_GHJ
   2    GND      B @BASEBOARD_FAB2_LIB.BASEBOARD_FAB2(SCH_1):GND

CAP_A_0603V-22.0UF,4V,20%,X6S,A  I67  C5G91
   1 PVDDQ_GHJ      A @BASEBOARD_FAB2_LIB.BASEBOARD_FAB2(SCH_1):PVDDQ_GHJ
   2    GND      B @BASEBOARD_FAB2_LIB.BASEBOARD_FAB2(SCH_1):GND

CAP_A_0603V-22.0UF,4V,20%,X6S,A  I68  C5G90
   1 PVDDQ_GHJ      A @BASEBOARD_FAB2_LIB.BASEBOARD_FAB2(SCH_1):PVDDQ_GHJ
   2    GND      B @BASEBOARD_FAB2_LIB.BASEBOARD_FAB2(SCH_1):GND

CAP_A_0603V-22.0UF,4V,20%,X6S,A  I69  C5G89
   1 PVDDQ_GHJ      A @BASEBOARD_FAB2_LIB.BASEBOARD_FAB2(SCH_1):PVDDQ_GHJ
   2    GND      B @BASEBOARD_FAB2_LIB.BASEBOARD_FAB2(SCH_1):GND

CAP_A_0603V-22.0UF,4V,20%,X6S,A  I70  C5G88
   1 PVDDQ_GHJ      A @BASEBOARD_FAB2_LIB.BASEBOARD_FAB2(SCH_1):PVDDQ_GHJ
   2    GND      B @BASEBOARD_FAB2_LIB.BASEBOARD_FAB2(SCH_1):GND

CAP_A_0603V-22.0UF,4V,20%,X6S,A  I71  C5G103
   1 PVDDQ_KLM      A @BASEBOARD_FAB2_LIB.BASEBOARD_FAB2(SCH_1):PVDDQ_KLM
   2    GND      B @BASEBOARD_FAB2_LIB.BASEBOARD_FAB2(SCH_1):GND

CAP_A_0603V-22.0UF,4V,20%,X6S,A  I72  C5G104
   1 PVDDQ_KLM      A @BASEBOARD_FAB2_LIB.BASEBOARD_FAB2(SCH_1):PVDDQ_KLM
   2    GND      B @BASEBOARD_FAB2_LIB.BASEBOARD_FAB2(SCH_1):GND

CAP_A_0603V-22.0UF,4V,20%,X6S,A  I73  C5G105
   1 PVDDQ_KLM      A @BASEBOARD_FAB2_LIB.BASEBOARD_FAB2(SCH_1):PVDDQ_KLM
   2    GND      B @BASEBOARD_FAB2_LIB.BASEBOARD_FAB2(SCH_1):GND

CAP_A_0603V-22.0UF,4V,20%,X6S,A  I74  C5G102
   1 PVDDQ_KLM      A @BASEBOARD_FAB2_LIB.BASEBOARD_FAB2(SCH_1):PVDDQ_KLM
   2    GND      B @BASEBOARD_FAB2_LIB.BASEBOARD_FAB2(SCH_1):GND

CAP_A_0603V-22.0UF,4V,20%,X6S,A  I75  C5G101
   1 PVDDQ_KLM      A @BASEBOARD_FAB2_LIB.BASEBOARD_FAB2(SCH_1):PVDDQ_KLM
   2    GND      B @BASEBOARD_FAB2_LIB.BASEBOARD_FAB2(SCH_1):GND

CAP_A_0603V-22.0UF,4V,20%,X6S,A  I76  C5G100
   1 PVDDQ_KLM      A @BASEBOARD_FAB2_LIB.BASEBOARD_FAB2(SCH_1):PVDDQ_KLM
   2    GND      B @BASEBOARD_FAB2_LIB.BASEBOARD_FAB2(SCH_1):GND

CAP_A_0603V-22.0UF,4V,20%,X6S,A  I77  C5G99
   1 PVDDQ_KLM      A @BASEBOARD_FAB2_LIB.BASEBOARD_FAB2(SCH_1):PVDDQ_KLM
   2    GND      B @BASEBOARD_FAB2_LIB.BASEBOARD_FAB2(SCH_1):GND

CAP_A_0603V-22.0UF,4V,20%,X6S,A  I78  C5G98
   1 PVDDQ_KLM      A @BASEBOARD_FAB2_LIB.BASEBOARD_FAB2(SCH_1):PVDDQ_KLM
   2    GND      B @BASEBOARD_FAB2_LIB.BASEBOARD_FAB2(SCH_1):GND

CAP_A_0603V-22.0UF,4V,20%,X6S,A  I79  C5G97
   1 PVDDQ_KLM      A @BASEBOARD_FAB2_LIB.BASEBOARD_FAB2(SCH_1):PVDDQ_KLM
   2    GND      B @BASEBOARD_FAB2_LIB.BASEBOARD_FAB2(SCH_1):GND

CAP_A_0603V-22.0UF,4V,20%,X6S,A  I80  C5G114
   1 PVDDQ_KLM      A @BASEBOARD_FAB2_LIB.BASEBOARD_FAB2(SCH_1):PVDDQ_KLM
   2    GND      B @BASEBOARD_FAB2_LIB.BASEBOARD_FAB2(SCH_1):GND

CAP_A_0603V-22.0UF,4V,20%,X6S,A  I81  C5G113
   1 PVDDQ_KLM      A @BASEBOARD_FAB2_LIB.BASEBOARD_FAB2(SCH_1):PVDDQ_KLM
   2    GND      B @BASEBOARD_FAB2_LIB.BASEBOARD_FAB2(SCH_1):GND

CAP_A_0603V-22.0UF,4V,20%,X6S,A  I82  C5G112
   1 PVDDQ_KLM      A @BASEBOARD_FAB2_LIB.BASEBOARD_FAB2(SCH_1):PVDDQ_KLM
   2    GND      B @BASEBOARD_FAB2_LIB.BASEBOARD_FAB2(SCH_1):GND

CAP_A_0603V-22.0UF,4V,20%,X6S,A  I83  C5G111
   1 PVDDQ_KLM      A @BASEBOARD_FAB2_LIB.BASEBOARD_FAB2(SCH_1):PVDDQ_KLM
   2    GND      B @BASEBOARD_FAB2_LIB.BASEBOARD_FAB2(SCH_1):GND

CAP_A_0603V-22.0UF,4V,20%,X6S,A  I84  C5G110
   1 PVDDQ_KLM      A @BASEBOARD_FAB2_LIB.BASEBOARD_FAB2(SCH_1):PVDDQ_KLM
   2    GND      B @BASEBOARD_FAB2_LIB.BASEBOARD_FAB2(SCH_1):GND

CAP_A_0603V-22.0UF,4V,20%,X6S,A  I85  C5G109
   1 PVDDQ_KLM      A @BASEBOARD_FAB2_LIB.BASEBOARD_FAB2(SCH_1):PVDDQ_KLM
   2    GND      B @BASEBOARD_FAB2_LIB.BASEBOARD_FAB2(SCH_1):GND

CAP_A_0603V-22.0UF,4V,20%,X6S,A  I86  C5G108
   1 PVDDQ_KLM      A @BASEBOARD_FAB2_LIB.BASEBOARD_FAB2(SCH_1):PVDDQ_KLM
   2    GND      B @BASEBOARD_FAB2_LIB.BASEBOARD_FAB2(SCH_1):GND

CAP_A_0603V-22.0UF,4V,20%,X6S,A  I87  C5G107
   1 PVDDQ_KLM      A @BASEBOARD_FAB2_LIB.BASEBOARD_FAB2(SCH_1):PVDDQ_KLM
   2    GND      B @BASEBOARD_FAB2_LIB.BASEBOARD_FAB2(SCH_1):GND

CAP_A_0603V-22.0UF,4V,20%,X6S,A  I88  C5G106
   1 PVDDQ_KLM      A @BASEBOARD_FAB2_LIB.BASEBOARD_FAB2(SCH_1):PVDDQ_KLM
   2    GND      B @BASEBOARD_FAB2_LIB.BASEBOARD_FAB2(SCH_1):GND


DRAWING: @BASEBOARD_FAB2_LIB.BASEBOARD_FAB2(SCH_1):PAGE244 

CAP_0402-0.22UF,16V,10%,X7R,A3A  I2  C831
   1 P3E_CPU0_PE1_PCH_TXP<15>      A @BASEBOARD_FAB2_LIB.BASEBOARD_FAB2(SCH_1):P3E_CPU0_PE1_PCH_TXP(15)
   2 P3E_CPU0_PE1_PCH_CON_TXP<15>      B @BASEBOARD_FAB2_LIB.BASEBOARD_FAB2(SCH_1):P3E_CPU0_PE1_PCH_CON_TXP(15)

CAP_0402-0.22UF,16V,10%,X7R,A3A  I5  C829
   1 P3E_CPU0_PE1_PCH_TXP<13>      A @BASEBOARD_FAB2_LIB.BASEBOARD_FAB2(SCH_1):P3E_CPU0_PE1_PCH_TXP(13)
   2 P3E_CPU0_PE1_PCH_CON_TXP<13>      B @BASEBOARD_FAB2_LIB.BASEBOARD_FAB2(SCH_1):P3E_CPU0_PE1_PCH_CON_TXP(13)

CAP_0402-0.22UF,16V,10%,X7R,A3A  I8  C833
   1 P3E_CPU0_PE1_PCH_TXP<11>      A @BASEBOARD_FAB2_LIB.BASEBOARD_FAB2(SCH_1):P3E_CPU0_PE1_PCH_TXP(11)
   2 P3E_CPU0_PE1_PCH_CON_TXP<11>      B @BASEBOARD_FAB2_LIB.BASEBOARD_FAB2(SCH_1):P3E_CPU0_PE1_PCH_CON_TXP(11)

CAP_0402-0.22UF,16V,10%,X7R,A3A  I12  C827
   1 P3E_CPU0_PE1_PCH_TXP<14>      A @BASEBOARD_FAB2_LIB.BASEBOARD_FAB2(SCH_1):P3E_CPU0_PE1_PCH_TXP(14)
   2 P3E_CPU0_PE1_PCH_CON_TXP<14>      B @BASEBOARD_FAB2_LIB.BASEBOARD_FAB2(SCH_1):P3E_CPU0_PE1_PCH_CON_TXP(14)

CAP_0402-0.22UF,16V,10%,X7R,A3A  I17  C841
   1 P3E_CPU0_PE1_PCH_TXP<12>      A @BASEBOARD_FAB2_LIB.BASEBOARD_FAB2(SCH_1):P3E_CPU0_PE1_PCH_TXP(12)
   2 P3E_CPU0_PE1_PCH_CON_TXP<12>      B @BASEBOARD_FAB2_LIB.BASEBOARD_FAB2(SCH_1):P3E_CPU0_PE1_PCH_CON_TXP(12)

CAP_0402-0.22UF,16V,10%,X7R,A3A  I23  C830
   1 P3E_CPU0_PE1_PCH_TXN<15>      A @BASEBOARD_FAB2_LIB.BASEBOARD_FAB2(SCH_1):P3E_CPU0_PE1_PCH_TXN(15)
   2 P3E_CPU0_PE1_PCH_CON_TXN<15>      B @BASEBOARD_FAB2_LIB.BASEBOARD_FAB2(SCH_1):P3E_CPU0_PE1_PCH_CON_TXN(15)

CAP_0402-0.22UF,16V,10%,X7R,A3A  I24  C826
   1 P3E_CPU0_PE1_PCH_TXN<14>      A @BASEBOARD_FAB2_LIB.BASEBOARD_FAB2(SCH_1):P3E_CPU0_PE1_PCH_TXN(14)
   2 P3E_CPU0_PE1_PCH_CON_TXN<14>      B @BASEBOARD_FAB2_LIB.BASEBOARD_FAB2(SCH_1):P3E_CPU0_PE1_PCH_CON_TXN(14)

CAP_0402-0.22UF,16V,10%,X7R,A3A  I28  C828
   1 P3E_CPU0_PE1_PCH_TXN<13>      A @BASEBOARD_FAB2_LIB.BASEBOARD_FAB2(SCH_1):P3E_CPU0_PE1_PCH_TXN(13)
   2 P3E_CPU0_PE1_PCH_CON_TXN<13>      B @BASEBOARD_FAB2_LIB.BASEBOARD_FAB2(SCH_1):P3E_CPU0_PE1_PCH_CON_TXN(13)

CAP_0402-0.22UF,16V,10%,X7R,A3A  I29  C840
   1 P3E_CPU0_PE1_PCH_TXN<12>      A @BASEBOARD_FAB2_LIB.BASEBOARD_FAB2(SCH_1):P3E_CPU0_PE1_PCH_TXN(12)
   2 P3E_CPU0_PE1_PCH_CON_TXN<12>      B @BASEBOARD_FAB2_LIB.BASEBOARD_FAB2(SCH_1):P3E_CPU0_PE1_PCH_CON_TXN(12)

CAP_0402-0.22UF,16V,10%,X7R,A3A  I30  C832
   1 P3E_CPU0_PE1_PCH_TXN<11>      A @BASEBOARD_FAB2_LIB.BASEBOARD_FAB2(SCH_1):P3E_CPU0_PE1_PCH_TXN(11)
   2 P3E_CPU0_PE1_PCH_CON_TXN<11>      B @BASEBOARD_FAB2_LIB.BASEBOARD_FAB2(SCH_1):P3E_CPU0_PE1_PCH_CON_TXN(11)

CAP_0402-0.22UF,16V,10%,X7R,A3A  I35  C845
   1 P3E_CPU0_PE1_PCH_TXP<9>      A @BASEBOARD_FAB2_LIB.BASEBOARD_FAB2(SCH_1):P3E_CPU0_PE1_PCH_TXP(9)
   2 P3E_CPU0_PE1_PCH_CON_TXP<9>      B @BASEBOARD_FAB2_LIB.BASEBOARD_FAB2(SCH_1):P3E_CPU0_PE1_PCH_CON_TXP(9)

RES_0402-0.0,5%,1/16W,CHIP,G21A  I39  R767
   1 P3E_CPU0_PE1_PCH_RXP<15>      A @BASEBOARD_FAB2_LIB.BASEBOARD_FAB2(SCH_1):P3E_CPU0_PE1_PCH_RXP(15)
   2 P3E_CPU0_PE1_PCH_CON_RXP<15>      B @BASEBOARD_FAB2_LIB.BASEBOARD_FAB2(SCH_1):P3E_CPU0_PE1_PCH_CON_RXP(15)

CAP_0402-0.22UF,16V,10%,X7R,A3A  I41  C835
   1 P3E_CPU0_PE1_PCH_TXP<10>      A @BASEBOARD_FAB2_LIB.BASEBOARD_FAB2(SCH_1):P3E_CPU0_PE1_PCH_TXP(10)
   2 P3E_CPU0_PE1_PCH_CON_TXP<10>      B @BASEBOARD_FAB2_LIB.BASEBOARD_FAB2(SCH_1):P3E_CPU0_PE1_PCH_CON_TXP(10)

CAP_0402-0.22UF,16V,10%,X7R,A3A  I47  C843
   1 P3E_CPU0_PE1_PCH_TXP<8>      A @BASEBOARD_FAB2_LIB.BASEBOARD_FAB2(SCH_1):P3E_CPU0_PE1_PCH_TXP(8)
   2 P3E_CPU0_PE1_PCH_CON_TXP<8>      B @BASEBOARD_FAB2_LIB.BASEBOARD_FAB2(SCH_1):P3E_CPU0_PE1_PCH_CON_TXP(8)

CAP_0402-0.22UF,16V,10%,X7R,A3A  I50  C834
   1 P3E_CPU0_PE1_PCH_TXN<10>      A @BASEBOARD_FAB2_LIB.BASEBOARD_FAB2(SCH_1):P3E_CPU0_PE1_PCH_TXN(10)
   2 P3E_CPU0_PE1_PCH_CON_TXN<10>      B @BASEBOARD_FAB2_LIB.BASEBOARD_FAB2(SCH_1):P3E_CPU0_PE1_PCH_CON_TXN(10)

CAP_0402-0.22UF,16V,10%,X7R,A3A  I51  C844
   1 P3E_CPU0_PE1_PCH_TXN<9>      A @BASEBOARD_FAB2_LIB.BASEBOARD_FAB2(SCH_1):P3E_CPU0_PE1_PCH_TXN(9)
   2 P3E_CPU0_PE1_PCH_CON_TXN<9>      B @BASEBOARD_FAB2_LIB.BASEBOARD_FAB2(SCH_1):P3E_CPU0_PE1_PCH_CON_TXN(9)

CAP_0402-0.22UF,16V,10%,X7R,A3A  I52  C842
   1 P3E_CPU0_PE1_PCH_TXN<8>      A @BASEBOARD_FAB2_LIB.BASEBOARD_FAB2(SCH_1):P3E_CPU0_PE1_PCH_TXN(8)
   2 P3E_CPU0_PE1_PCH_CON_TXN<8>      B @BASEBOARD_FAB2_LIB.BASEBOARD_FAB2(SCH_1):P3E_CPU0_PE1_PCH_CON_TXN(8)

RES_0402-0.0,5%,1/16W,CHIP,G21A  I58  R769
   1 P3E_CPU0_PE1_PCH_RXP<14>      A @BASEBOARD_FAB2_LIB.BASEBOARD_FAB2(SCH_1):P3E_CPU0_PE1_PCH_RXP(14)
   2 P3E_CPU0_PE1_PCH_CON_RXP<14>      B @BASEBOARD_FAB2_LIB.BASEBOARD_FAB2(SCH_1):P3E_CPU0_PE1_PCH_CON_RXP(14)

RES_0402-0.0,5%,1/16W,CHIP,G21A  I64  R760
   1 P3E_CPU0_PE1_PCH_RXN<15>      A @BASEBOARD_FAB2_LIB.BASEBOARD_FAB2(SCH_1):P3E_CPU0_PE1_PCH_RXN(15)
   2 P3E_CPU0_PE1_PCH_CON_RXN<15>      B @BASEBOARD_FAB2_LIB.BASEBOARD_FAB2(SCH_1):P3E_CPU0_PE1_PCH_CON_RXN(15)

RES_0402-0.0,5%,1/16W,CHIP,G21A  I65  R771
   1 P3E_CPU0_PE1_PCH_RXN<13>      A @BASEBOARD_FAB2_LIB.BASEBOARD_FAB2(SCH_1):P3E_CPU0_PE1_PCH_RXN(13)
   2 P3E_CPU0_PE1_PCH_CON_RXN<13>      B @BASEBOARD_FAB2_LIB.BASEBOARD_FAB2(SCH_1):P3E_CPU0_PE1_PCH_CON_RXN(13)

RES_0402-0.0,5%,1/16W,CHIP,G21A  I66  R768
   1 P3E_CPU0_PE1_PCH_RXN<14>      A @BASEBOARD_FAB2_LIB.BASEBOARD_FAB2(SCH_1):P3E_CPU0_PE1_PCH_RXN(14)
   2 P3E_CPU0_PE1_PCH_CON_RXN<14>      B @BASEBOARD_FAB2_LIB.BASEBOARD_FAB2(SCH_1):P3E_CPU0_PE1_PCH_CON_RXN(14)

RES_0402-0.0,5%,1/16W,CHIP,G21A  I72  R774
   1 P3E_CPU0_PE1_PCH_RXP<13>      A @BASEBOARD_FAB2_LIB.BASEBOARD_FAB2(SCH_1):P3E_CPU0_PE1_PCH_RXP(13)
   2 P3E_CPU0_PE1_PCH_CON_RXP<13>      B @BASEBOARD_FAB2_LIB.BASEBOARD_FAB2(SCH_1):P3E_CPU0_PE1_PCH_CON_RXP(13)

RES_0402-0.0,5%,1/16W,CHIP,G21A  I74  R779
   1 P3E_CPU0_PE1_PCH_RXP<11>      A @BASEBOARD_FAB2_LIB.BASEBOARD_FAB2(SCH_1):P3E_CPU0_PE1_PCH_RXP(11)
   2 P3E_CPU0_PE1_PCH_CON_RXP<11>      B @BASEBOARD_FAB2_LIB.BASEBOARD_FAB2(SCH_1):P3E_CPU0_PE1_PCH_CON_RXP(11)

RES_0402-0.0,5%,1/16W,CHIP,G21A  I77  R783
   1 P3E_CPU0_PE1_PCH_RXP<9>      A @BASEBOARD_FAB2_LIB.BASEBOARD_FAB2(SCH_1):P3E_CPU0_PE1_PCH_RXP(9)
   2 P3E_CPU0_PE1_PCH_CON_RXP<9>      B @BASEBOARD_FAB2_LIB.BASEBOARD_FAB2(SCH_1):P3E_CPU0_PE1_PCH_CON_RXP(9)

RES_0402-0.0,5%,1/16W,CHIP,G21A  I80  R777
   1 P3E_CPU0_PE1_PCH_RXP<12>      A @BASEBOARD_FAB2_LIB.BASEBOARD_FAB2(SCH_1):P3E_CPU0_PE1_PCH_RXP(12)
   2 P3E_CPU0_PE1_PCH_CON_RXP<12>      B @BASEBOARD_FAB2_LIB.BASEBOARD_FAB2(SCH_1):P3E_CPU0_PE1_PCH_CON_RXP(12)

RES_0402-0.0,5%,1/16W,CHIP,G21A  I86  R781
   1 P3E_CPU0_PE1_PCH_RXP<10>      A @BASEBOARD_FAB2_LIB.BASEBOARD_FAB2(SCH_1):P3E_CPU0_PE1_PCH_RXP(10)
   2 P3E_CPU0_PE1_PCH_CON_RXP<10>      B @BASEBOARD_FAB2_LIB.BASEBOARD_FAB2(SCH_1):P3E_CPU0_PE1_PCH_CON_RXP(10)

RES_0402-0.0,5%,1/16W,CHIP,G21A  I93  R775
   1 P3E_CPU0_PE1_PCH_RXN<12>      A @BASEBOARD_FAB2_LIB.BASEBOARD_FAB2(SCH_1):P3E_CPU0_PE1_PCH_RXN(12)
   2 P3E_CPU0_PE1_PCH_CON_RXN<12>      B @BASEBOARD_FAB2_LIB.BASEBOARD_FAB2(SCH_1):P3E_CPU0_PE1_PCH_CON_RXN(12)

RES_0402-0.0,5%,1/16W,CHIP,G21A  I94  R778
   1 P3E_CPU0_PE1_PCH_RXN<11>      A @BASEBOARD_FAB2_LIB.BASEBOARD_FAB2(SCH_1):P3E_CPU0_PE1_PCH_RXN(11)
   2 P3E_CPU0_PE1_PCH_CON_RXN<11>      B @BASEBOARD_FAB2_LIB.BASEBOARD_FAB2(SCH_1):P3E_CPU0_PE1_PCH_CON_RXN(11)

RES_0402-0.0,5%,1/16W,CHIP,G21A  I97  R780
   1 P3E_CPU0_PE1_PCH_RXN<10>      A @BASEBOARD_FAB2_LIB.BASEBOARD_FAB2(SCH_1):P3E_CPU0_PE1_PCH_RXN(10)
   2 P3E_CPU0_PE1_PCH_CON_RXN<10>      B @BASEBOARD_FAB2_LIB.BASEBOARD_FAB2(SCH_1):P3E_CPU0_PE1_PCH_CON_RXN(10)

RES_0402-0.0,5%,1/16W,CHIP,G21A  I98  R782
   1 P3E_CPU0_PE1_PCH_RXN<9>      A @BASEBOARD_FAB2_LIB.BASEBOARD_FAB2(SCH_1):P3E_CPU0_PE1_PCH_RXN(9)
   2 P3E_CPU0_PE1_PCH_CON_RXN<9>      B @BASEBOARD_FAB2_LIB.BASEBOARD_FAB2(SCH_1):P3E_CPU0_PE1_PCH_CON_RXN(9)

RES_0402-0.0,5%,1/16W,CHIP,G21A  I99  R784
   1 P3E_CPU0_PE1_PCH_RXN<8>      A @BASEBOARD_FAB2_LIB.BASEBOARD_FAB2(SCH_1):P3E_CPU0_PE1_PCH_RXN(8)
   2 P3E_CPU0_PE1_PCH_CON_RXN<8>      B @BASEBOARD_FAB2_LIB.BASEBOARD_FAB2(SCH_1):P3E_CPU0_PE1_PCH_CON_RXN(8)

RES_0402-0.0,5%,1/16W,CHIP,G21A  I103  R785
   1 P3E_CPU0_PE1_PCH_RXP<8>      A @BASEBOARD_FAB2_LIB.BASEBOARD_FAB2(SCH_1):P3E_CPU0_PE1_PCH_RXP(8)
   2 P3E_CPU0_PE1_PCH_CON_RXP<8>      B @BASEBOARD_FAB2_LIB.BASEBOARD_FAB2(SCH_1):P3E_CPU0_PE1_PCH_CON_RXP(8)


DRAWING: @BASEBOARD_FAB2_LIB.BASEBOARD_FAB2(SCH_1):PAGE245 

SMC-CONN60A-22-GP_CONN-G7-SMC-A  I48  CONX8
   1    GND      1 @BASEBOARD_FAB2_LIB.BASEBOARD_FAB2(SCH_1):GND
   3 P3E_CPU0_PE2_SS_C_TXP<8>      3 @BASEBOARD_FAB2_LIB.BASEBOARD_FAB2(SCH_1):P3E_CPU0_PE2_SS_C_TXP(8)
   5 P3E_CPU0_PE2_SS_C_TXN<8>      5 @BASEBOARD_FAB2_LIB.BASEBOARD_FAB2(SCH_1):P3E_CPU0_PE2_SS_C_TXN(8)
   7    GND      7 @BASEBOARD_FAB2_LIB.BASEBOARD_FAB2(SCH_1):GND
   2     NC      2     NC
   4    GND      4 @BASEBOARD_FAB2_LIB.BASEBOARD_FAB2(SCH_1):GND
   6 P3E_CPU0_PE2_SS_RXN<8>      6 @BASEBOARD_FAB2_LIB.BASEBOARD_FAB2(SCH_1):P3E_CPU0_PE2_SS_RXN(8)
   8 P3E_CPU0_PE2_SS_RXP<8>      8 @BASEBOARD_FAB2_LIB.BASEBOARD_FAB2(SCH_1):P3E_CPU0_PE2_SS_RXP(8)
   9 P3E_CPU0_PE2_SS_C_TXN<9>      9 @BASEBOARD_FAB2_LIB.BASEBOARD_FAB2(SCH_1):P3E_CPU0_PE2_SS_C_TXN(9)
  11 P3E_CPU0_PE2_SS_C_TXP<9>     11 @BASEBOARD_FAB2_LIB.BASEBOARD_FAB2(SCH_1):P3E_CPU0_PE2_SS_C_TXP(9)
  13    GND     13 @BASEBOARD_FAB2_LIB.BASEBOARD_FAB2(SCH_1):GND
  15 P3E_CPU0_PE2_SS_C_TXN<10>     15 @BASEBOARD_FAB2_LIB.BASEBOARD_FAB2(SCH_1):P3E_CPU0_PE2_SS_C_TXN(10)
  17 P3E_CPU0_PE2_SS_C_TXP<10>     17 @BASEBOARD_FAB2_LIB.BASEBOARD_FAB2(SCH_1):P3E_CPU0_PE2_SS_C_TXP(10)
  19    GND     19 @BASEBOARD_FAB2_LIB.BASEBOARD_FAB2(SCH_1):GND
  21 P3E_CPU0_PE2_SS_C_TXP<11>     21 @BASEBOARD_FAB2_LIB.BASEBOARD_FAB2(SCH_1):P3E_CPU0_PE2_SS_C_TXP(11)
  23 P3E_CPU0_PE2_SS_C_TXN<11>     23 @BASEBOARD_FAB2_LIB.BASEBOARD_FAB2(SCH_1):P3E_CPU0_PE2_SS_C_TXN(11)
  25    GND     25 @BASEBOARD_FAB2_LIB.BASEBOARD_FAB2(SCH_1):GND
  27 P3E_CPU0_PE2_SS_C_TXN<12>     27 @BASEBOARD_FAB2_LIB.BASEBOARD_FAB2(SCH_1):P3E_CPU0_PE2_SS_C_TXN(12)
  29 P3E_CPU0_PE2_SS_C_TXP<12>     29 @BASEBOARD_FAB2_LIB.BASEBOARD_FAB2(SCH_1):P3E_CPU0_PE2_SS_C_TXP(12)
  31    GND     31 @BASEBOARD_FAB2_LIB.BASEBOARD_FAB2(SCH_1):GND
  33 P3E_CPU0_PE2_SS_C_TXN<13>     33 @BASEBOARD_FAB2_LIB.BASEBOARD_FAB2(SCH_1):P3E_CPU0_PE2_SS_C_TXN(13)
  35 P3E_CPU0_PE2_SS_C_TXP<13>     35 @BASEBOARD_FAB2_LIB.BASEBOARD_FAB2(SCH_1):P3E_CPU0_PE2_SS_C_TXP(13)
  37    GND     37 @BASEBOARD_FAB2_LIB.BASEBOARD_FAB2(SCH_1):GND
  39 P3E_CPU0_PE2_SS_C_TXP<14>     39 @BASEBOARD_FAB2_LIB.BASEBOARD_FAB2(SCH_1):P3E_CPU0_PE2_SS_C_TXP(14)
  41 P3E_CPU0_PE2_SS_C_TXN<14>     41 @BASEBOARD_FAB2_LIB.BASEBOARD_FAB2(SCH_1):P3E_CPU0_PE2_SS_C_TXN(14)
  43    GND     43 @BASEBOARD_FAB2_LIB.BASEBOARD_FAB2(SCH_1):GND
  45 P3E_CPU0_PE2_SS_C_TXN<15>     45 @BASEBOARD_FAB2_LIB.BASEBOARD_FAB2(SCH_1):P3E_CPU0_PE2_SS_C_TXN(15)
  47 P3E_CPU0_PE2_SS_C_TXP<15>     47 @BASEBOARD_FAB2_LIB.BASEBOARD_FAB2(SCH_1):P3E_CPU0_PE2_SS_C_TXP(15)
  49    GND     49 @BASEBOARD_FAB2_LIB.BASEBOARD_FAB2(SCH_1):GND
  51 CLK_100M_SRC12_DP     51 @BASEBOARD_FAB2_LIB.BASEBOARD_FAB2(SCH_1):CLK_100M_SRC12_DP
  53 CLK_100M_SRC12_DN     53 @BASEBOARD_FAB2_LIB.BASEBOARD_FAB2(SCH_1):CLK_100M_SRC12_DN
  55    GND     55 @BASEBOARD_FAB2_LIB.BASEBOARD_FAB2(SCH_1):GND
  57 USB2_P02_DP     57 @BASEBOARD_FAB2_LIB.BASEBOARD_FAB2(SCH_1):USB2_P02_DP
  59 USB2_P02_DN     59 @BASEBOARD_FAB2_LIB.BASEBOARD_FAB2(SCH_1):USB2_P02_DN
  10    GND     10 @BASEBOARD_FAB2_LIB.BASEBOARD_FAB2(SCH_1):GND
  12 P3E_CPU0_PE2_SS_RXN<9>     12 @BASEBOARD_FAB2_LIB.BASEBOARD_FAB2(SCH_1):P3E_CPU0_PE2_SS_RXN(9)
  14 P3E_CPU0_PE2_SS_RXP<9>     14 @BASEBOARD_FAB2_LIB.BASEBOARD_FAB2(SCH_1):P3E_CPU0_PE2_SS_RXP(9)
  16    GND     16 @BASEBOARD_FAB2_LIB.BASEBOARD_FAB2(SCH_1):GND
  18 P3E_CPU0_PE2_SS_RXN<10>     18 @BASEBOARD_FAB2_LIB.BASEBOARD_FAB2(SCH_1):P3E_CPU0_PE2_SS_RXN(10)
  20 P3E_CPU0_PE2_SS_RXP<10>     20 @BASEBOARD_FAB2_LIB.BASEBOARD_FAB2(SCH_1):P3E_CPU0_PE2_SS_RXP(10)
  22    GND     22 @BASEBOARD_FAB2_LIB.BASEBOARD_FAB2(SCH_1):GND
  24 P3E_CPU0_PE2_SS_RXN<11>     24 @BASEBOARD_FAB2_LIB.BASEBOARD_FAB2(SCH_1):P3E_CPU0_PE2_SS_RXN(11)
  26 P3E_CPU0_PE2_SS_RXP<11>     26 @BASEBOARD_FAB2_LIB.BASEBOARD_FAB2(SCH_1):P3E_CPU0_PE2_SS_RXP(11)
  28    GND     28 @BASEBOARD_FAB2_LIB.BASEBOARD_FAB2(SCH_1):GND
  30 P3E_CPU0_PE2_SS_RXN<12>     30 @BASEBOARD_FAB2_LIB.BASEBOARD_FAB2(SCH_1):P3E_CPU0_PE2_SS_RXN(12)
  32 P3E_CPU0_PE2_SS_RXP<12>     32 @BASEBOARD_FAB2_LIB.BASEBOARD_FAB2(SCH_1):P3E_CPU0_PE2_SS_RXP(12)
  34    GND     34 @BASEBOARD_FAB2_LIB.BASEBOARD_FAB2(SCH_1):GND
  36 P3E_CPU0_PE2_SS_RXP<13>     36 @BASEBOARD_FAB2_LIB.BASEBOARD_FAB2(SCH_1):P3E_CPU0_PE2_SS_RXP(13)
  38 P3E_CPU0_PE2_SS_RXN<13>     38 @BASEBOARD_FAB2_LIB.BASEBOARD_FAB2(SCH_1):P3E_CPU0_PE2_SS_RXN(13)
  40    GND     40 @BASEBOARD_FAB2_LIB.BASEBOARD_FAB2(SCH_1):GND
  42 P3E_CPU0_PE2_SS_RXN<14>     42 @BASEBOARD_FAB2_LIB.BASEBOARD_FAB2(SCH_1):P3E_CPU0_PE2_SS_RXN(14)
  44 P3E_CPU0_PE2_SS_RXP<14>     44 @BASEBOARD_FAB2_LIB.BASEBOARD_FAB2(SCH_1):P3E_CPU0_PE2_SS_RXP(14)
  46    GND     46 @BASEBOARD_FAB2_LIB.BASEBOARD_FAB2(SCH_1):GND
  48 P3E_CPU0_PE2_SS_RXN<15>     48 @BASEBOARD_FAB2_LIB.BASEBOARD_FAB2(SCH_1):P3E_CPU0_PE2_SS_RXN(15)
  50 P3E_CPU0_PE2_SS_RXP<15>     50 @BASEBOARD_FAB2_LIB.BASEBOARD_FAB2(SCH_1):P3E_CPU0_PE2_SS_RXP(15)
  52    GND     52 @BASEBOARD_FAB2_LIB.BASEBOARD_FAB2(SCH_1):GND
  54 CLK_100M_SRC13_DP     54 @BASEBOARD_FAB2_LIB.BASEBOARD_FAB2(SCH_1):CLK_100M_SRC13_DP
  56 CLK_100M_SRC13_DN     56 @BASEBOARD_FAB2_LIB.BASEBOARD_FAB2(SCH_1):CLK_100M_SRC13_DN
  58    GND     58 @BASEBOARD_FAB2_LIB.BASEBOARD_FAB2(SCH_1):GND
  60     NC     60     NC
 NP1    GND    NP1 @BASEBOARD_FAB2_LIB.BASEBOARD_FAB2(SCH_1):GND
 NP2    GND    NP2 @BASEBOARD_FAB2_LIB.BASEBOARD_FAB2(SCH_1):GND
PTH1    GND   PTH1 @BASEBOARD_FAB2_LIB.BASEBOARD_FAB2(SCH_1):GND
PTH2    GND   PTH2 @BASEBOARD_FAB2_LIB.BASEBOARD_FAB2(SCH_1):GND


DRAWING: @BASEBOARD_FAB2_LIB.BASEBOARD_FAB2(SCH_1):PAGE109 

SCONN200_H68296001_SM-CONN,H68A  I78  J8G1
 101    GND  IO101 @BASEBOARD_FAB2_LIB.BASEBOARD_FAB2(SCH_1):GND
 102 P3E_CPU0_PE1_PCH_CON_RXP<8>  IO102 @BASEBOARD_FAB2_LIB.BASEBOARD_FAB2(SCH_1):P3E_CPU0_PE1_PCH_CON_RXP(8)
 103 P3E_CPU0_PE1_SS_C_TXN<7>  IO103 @BASEBOARD_FAB2_LIB.BASEBOARD_FAB2(SCH_1):P3E_CPU0_PE1_SS_C_TXN(7)
 104    GND  IO104 @BASEBOARD_FAB2_LIB.BASEBOARD_FAB2(SCH_1):GND
 105 P3E_CPU0_PE1_SS_C_TXP<7>  IO105 @BASEBOARD_FAB2_LIB.BASEBOARD_FAB2(SCH_1):P3E_CPU0_PE1_SS_C_TXP(7)
 106 P3E_CPU0_PE1_SS_R_RXN<7>  IO106 @BASEBOARD_FAB2_LIB.BASEBOARD_FAB2(SCH_1):P3E_CPU0_PE1_SS_R_RXN(7)
 107    GND  IO107 @BASEBOARD_FAB2_LIB.BASEBOARD_FAB2(SCH_1):GND
 108 P3E_CPU0_PE1_SS_R_RXP<7>  IO108 @BASEBOARD_FAB2_LIB.BASEBOARD_FAB2(SCH_1):P3E_CPU0_PE1_SS_R_RXP(7)
 109 P3E_CPU0_PE1_SS_C_TXN<6>  IO109 @BASEBOARD_FAB2_LIB.BASEBOARD_FAB2(SCH_1):P3E_CPU0_PE1_SS_C_TXN(6)
 110    GND  IO110 @BASEBOARD_FAB2_LIB.BASEBOARD_FAB2(SCH_1):GND
 111 P3E_CPU0_PE1_SS_C_TXP<6>  IO111 @BASEBOARD_FAB2_LIB.BASEBOARD_FAB2(SCH_1):P3E_CPU0_PE1_SS_C_TXP(6)
 112 P3E_CPU0_PE1_SS_R_RXN<6>  IO112 @BASEBOARD_FAB2_LIB.BASEBOARD_FAB2(SCH_1):P3E_CPU0_PE1_SS_R_RXN(6)
 113    GND  IO113 @BASEBOARD_FAB2_LIB.BASEBOARD_FAB2(SCH_1):GND
 114 P3E_CPU0_PE1_SS_R_RXP<6>  IO114 @BASEBOARD_FAB2_LIB.BASEBOARD_FAB2(SCH_1):P3E_CPU0_PE1_SS_R_RXP(6)
 115 P3E_CPU0_PE1_SS_C_TXN<5>  IO115 @BASEBOARD_FAB2_LIB.BASEBOARD_FAB2(SCH_1):P3E_CPU0_PE1_SS_C_TXN(5)
 116    GND  IO116 @BASEBOARD_FAB2_LIB.BASEBOARD_FAB2(SCH_1):GND
 117 P3E_CPU0_PE1_SS_C_TXP<5>  IO117 @BASEBOARD_FAB2_LIB.BASEBOARD_FAB2(SCH_1):P3E_CPU0_PE1_SS_C_TXP(5)
 118 P3E_CPU0_PE1_SS_R_RXN<5>  IO118 @BASEBOARD_FAB2_LIB.BASEBOARD_FAB2(SCH_1):P3E_CPU0_PE1_SS_R_RXN(5)
 119    GND  IO119 @BASEBOARD_FAB2_LIB.BASEBOARD_FAB2(SCH_1):GND
 120 P3E_CPU0_PE1_SS_R_RXP<5>  IO120 @BASEBOARD_FAB2_LIB.BASEBOARD_FAB2(SCH_1):P3E_CPU0_PE1_SS_R_RXP(5)
 121 P3E_CPU0_PE1_SS_C_TXP<4>  IO121 @BASEBOARD_FAB2_LIB.BASEBOARD_FAB2(SCH_1):P3E_CPU0_PE1_SS_C_TXP(4)
 122    GND  IO122 @BASEBOARD_FAB2_LIB.BASEBOARD_FAB2(SCH_1):GND
 123 P3E_CPU0_PE1_SS_C_TXN<4>  IO123 @BASEBOARD_FAB2_LIB.BASEBOARD_FAB2(SCH_1):P3E_CPU0_PE1_SS_C_TXN(4)
 124 P3E_CPU0_PE1_SS_R_RXN<4>  IO124 @BASEBOARD_FAB2_LIB.BASEBOARD_FAB2(SCH_1):P3E_CPU0_PE1_SS_R_RXN(4)
 125    GND  IO125 @BASEBOARD_FAB2_LIB.BASEBOARD_FAB2(SCH_1):GND
 126 P3E_CPU0_PE1_SS_R_RXP<4>  IO126 @BASEBOARD_FAB2_LIB.BASEBOARD_FAB2(SCH_1):P3E_CPU0_PE1_SS_R_RXP(4)
 127 P3E_CPU0_PE1_SS_C_TXN<3>  IO127 @BASEBOARD_FAB2_LIB.BASEBOARD_FAB2(SCH_1):P3E_CPU0_PE1_SS_C_TXN(3)
 128    GND  IO128 @BASEBOARD_FAB2_LIB.BASEBOARD_FAB2(SCH_1):GND
 129 P3E_CPU0_PE1_SS_C_TXP<3>  IO129 @BASEBOARD_FAB2_LIB.BASEBOARD_FAB2(SCH_1):P3E_CPU0_PE1_SS_C_TXP(3)
 130 P3E_CPU0_PE1_SS_R_RXN<3>  IO130 @BASEBOARD_FAB2_LIB.BASEBOARD_FAB2(SCH_1):P3E_CPU0_PE1_SS_R_RXN(3)
 131    GND  IO131 @BASEBOARD_FAB2_LIB.BASEBOARD_FAB2(SCH_1):GND
 132 P3E_CPU0_PE1_SS_R_RXP<3>  IO132 @BASEBOARD_FAB2_LIB.BASEBOARD_FAB2(SCH_1):P3E_CPU0_PE1_SS_R_RXP(3)
 133 P3E_CPU0_PE1_SS_C_TXN<2>  IO133 @BASEBOARD_FAB2_LIB.BASEBOARD_FAB2(SCH_1):P3E_CPU0_PE1_SS_C_TXN(2)
 134    GND  IO134 @BASEBOARD_FAB2_LIB.BASEBOARD_FAB2(SCH_1):GND
 135 P3E_CPU0_PE1_SS_C_TXP<2>  IO135 @BASEBOARD_FAB2_LIB.BASEBOARD_FAB2(SCH_1):P3E_CPU0_PE1_SS_C_TXP(2)
 136 P3E_CPU0_PE1_SS_R_RXP<2>  IO136 @BASEBOARD_FAB2_LIB.BASEBOARD_FAB2(SCH_1):P3E_CPU0_PE1_SS_R_RXP(2)
 137    GND  IO137 @BASEBOARD_FAB2_LIB.BASEBOARD_FAB2(SCH_1):GND
 138 P3E_CPU0_PE1_SS_R_RXN<2>  IO138 @BASEBOARD_FAB2_LIB.BASEBOARD_FAB2(SCH_1):P3E_CPU0_PE1_SS_R_RXN(2)
 139 P3E_CPU0_PE1_SS_C_TXP<1>  IO139 @BASEBOARD_FAB2_LIB.BASEBOARD_FAB2(SCH_1):P3E_CPU0_PE1_SS_C_TXP(1)
 140    GND  IO140 @BASEBOARD_FAB2_LIB.BASEBOARD_FAB2(SCH_1):GND
 141 P3E_CPU0_PE1_SS_C_TXN<1>  IO141 @BASEBOARD_FAB2_LIB.BASEBOARD_FAB2(SCH_1):P3E_CPU0_PE1_SS_C_TXN(1)
 142 P3E_CPU0_PE1_SS_R_RXN<1>  IO142 @BASEBOARD_FAB2_LIB.BASEBOARD_FAB2(SCH_1):P3E_CPU0_PE1_SS_R_RXN(1)
 143    GND  IO143 @BASEBOARD_FAB2_LIB.BASEBOARD_FAB2(SCH_1):GND
 144 P3E_CPU0_PE1_SS_R_RXP<1>  IO144 @BASEBOARD_FAB2_LIB.BASEBOARD_FAB2(SCH_1):P3E_CPU0_PE1_SS_R_RXP(1)
 145 P3E_CPU0_PE1_SS_C_TXN<0>  IO145 @BASEBOARD_FAB2_LIB.BASEBOARD_FAB2(SCH_1):P3E_CPU0_PE1_SS_C_TXN(0)
 146    GND  IO146 @BASEBOARD_FAB2_LIB.BASEBOARD_FAB2(SCH_1):GND
 147 P3E_CPU0_PE1_SS_C_TXP<0>  IO147 @BASEBOARD_FAB2_LIB.BASEBOARD_FAB2(SCH_1):P3E_CPU0_PE1_SS_C_TXP(0)
 148 P3E_CPU0_PE1_SS_R_RXN<0>  IO148 @BASEBOARD_FAB2_LIB.BASEBOARD_FAB2(SCH_1):P3E_CPU0_PE1_SS_R_RXN(0)
 149    GND  IO149 @BASEBOARD_FAB2_LIB.BASEBOARD_FAB2(SCH_1):GND
 150 P3E_CPU0_PE1_SS_R_RXP<0>  IO150 @BASEBOARD_FAB2_LIB.BASEBOARD_FAB2(SCH_1):P3E_CPU0_PE1_SS_R_RXP(0)
 151 P3E_CPU0_PE2_SS_C_TXN<0>  IO151 @BASEBOARD_FAB2_LIB.BASEBOARD_FAB2(SCH_1):P3E_CPU0_PE2_SS_C_TXN(0)
 152    GND  IO152 @BASEBOARD_FAB2_LIB.BASEBOARD_FAB2(SCH_1):GND
 153 P3E_CPU0_PE2_SS_C_TXP<0>  IO153 @BASEBOARD_FAB2_LIB.BASEBOARD_FAB2(SCH_1):P3E_CPU0_PE2_SS_C_TXP(0)
 154 P3E_CPU0_PE2_SS_RXN<0>  IO154 @BASEBOARD_FAB2_LIB.BASEBOARD_FAB2(SCH_1):P3E_CPU0_PE2_SS_RXN(0)
 155    GND  IO155 @BASEBOARD_FAB2_LIB.BASEBOARD_FAB2(SCH_1):GND
 156 P3E_CPU0_PE2_SS_RXP<0>  IO156 @BASEBOARD_FAB2_LIB.BASEBOARD_FAB2(SCH_1):P3E_CPU0_PE2_SS_RXP(0)
 157 P3E_CPU0_PE2_SS_C_TXP<1>  IO157 @BASEBOARD_FAB2_LIB.BASEBOARD_FAB2(SCH_1):P3E_CPU0_PE2_SS_C_TXP(1)
 158    GND  IO158 @BASEBOARD_FAB2_LIB.BASEBOARD_FAB2(SCH_1):GND
 159 P3E_CPU0_PE2_SS_C_TXN<1>  IO159 @BASEBOARD_FAB2_LIB.BASEBOARD_FAB2(SCH_1):P3E_CPU0_PE2_SS_C_TXN(1)
 160 P3E_CPU0_PE2_SS_RXN<1>  IO160 @BASEBOARD_FAB2_LIB.BASEBOARD_FAB2(SCH_1):P3E_CPU0_PE2_SS_RXN(1)
 161    GND  IO161 @BASEBOARD_FAB2_LIB.BASEBOARD_FAB2(SCH_1):GND
 162 P3E_CPU0_PE2_SS_RXP<1>  IO162 @BASEBOARD_FAB2_LIB.BASEBOARD_FAB2(SCH_1):P3E_CPU0_PE2_SS_RXP(1)
 163 P3E_CPU0_PE2_SS_C_TXN<2>  IO163 @BASEBOARD_FAB2_LIB.BASEBOARD_FAB2(SCH_1):P3E_CPU0_PE2_SS_C_TXN(2)
 164    GND  IO164 @BASEBOARD_FAB2_LIB.BASEBOARD_FAB2(SCH_1):GND
 165 P3E_CPU0_PE2_SS_C_TXP<2>  IO165 @BASEBOARD_FAB2_LIB.BASEBOARD_FAB2(SCH_1):P3E_CPU0_PE2_SS_C_TXP(2)
 166 P3E_CPU0_PE2_SS_RXP<2>  IO166 @BASEBOARD_FAB2_LIB.BASEBOARD_FAB2(SCH_1):P3E_CPU0_PE2_SS_RXP(2)
 167    GND  IO167 @BASEBOARD_FAB2_LIB.BASEBOARD_FAB2(SCH_1):GND
 168 P3E_CPU0_PE2_SS_RXN<2>  IO168 @BASEBOARD_FAB2_LIB.BASEBOARD_FAB2(SCH_1):P3E_CPU0_PE2_SS_RXN(2)
 169 P3E_CPU0_PE2_SS_C_TXN<3>  IO169 @BASEBOARD_FAB2_LIB.BASEBOARD_FAB2(SCH_1):P3E_CPU0_PE2_SS_C_TXN(3)
 170    GND  IO170 @BASEBOARD_FAB2_LIB.BASEBOARD_FAB2(SCH_1):GND
 171 P3E_CPU0_PE2_SS_C_TXP<3>  IO171 @BASEBOARD_FAB2_LIB.BASEBOARD_FAB2(SCH_1):P3E_CPU0_PE2_SS_C_TXP(3)
 172 P3E_CPU0_PE2_SS_RXN<3>  IO172 @BASEBOARD_FAB2_LIB.BASEBOARD_FAB2(SCH_1):P3E_CPU0_PE2_SS_RXN(3)
 173    GND  IO173 @BASEBOARD_FAB2_LIB.BASEBOARD_FAB2(SCH_1):GND
 174 P3E_CPU0_PE2_SS_RXP<3>  IO174 @BASEBOARD_FAB2_LIB.BASEBOARD_FAB2(SCH_1):P3E_CPU0_PE2_SS_RXP(3)
 175 P3E_CPU0_PE2_SS_C_TXN<4>  IO175 @BASEBOARD_FAB2_LIB.BASEBOARD_FAB2(SCH_1):P3E_CPU0_PE2_SS_C_TXN(4)
 176    GND  IO176 @BASEBOARD_FAB2_LIB.BASEBOARD_FAB2(SCH_1):GND
 177 P3E_CPU0_PE2_SS_C_TXP<4>  IO177 @BASEBOARD_FAB2_LIB.BASEBOARD_FAB2(SCH_1):P3E_CPU0_PE2_SS_C_TXP(4)
 178 P3E_CPU0_PE2_SS_RXN<4>  IO178 @BASEBOARD_FAB2_LIB.BASEBOARD_FAB2(SCH_1):P3E_CPU0_PE2_SS_RXN(4)
 179    GND  IO179 @BASEBOARD_FAB2_LIB.BASEBOARD_FAB2(SCH_1):GND
 180 P3E_CPU0_PE2_SS_RXP<4>  IO180 @BASEBOARD_FAB2_LIB.BASEBOARD_FAB2(SCH_1):P3E_CPU0_PE2_SS_RXP(4)
 181 P3E_CPU0_PE2_SS_C_TXN<5>  IO181 @BASEBOARD_FAB2_LIB.BASEBOARD_FAB2(SCH_1):P3E_CPU0_PE2_SS_C_TXN(5)
 182    GND  IO182 @BASEBOARD_FAB2_LIB.BASEBOARD_FAB2(SCH_1):GND
 183 P3E_CPU0_PE2_SS_C_TXP<5>  IO183 @BASEBOARD_FAB2_LIB.BASEBOARD_FAB2(SCH_1):P3E_CPU0_PE2_SS_C_TXP(5)
 184 P3E_CPU0_PE2_SS_RXN<5>  IO184 @BASEBOARD_FAB2_LIB.BASEBOARD_FAB2(SCH_1):P3E_CPU0_PE2_SS_RXN(5)
 185    GND  IO185 @BASEBOARD_FAB2_LIB.BASEBOARD_FAB2(SCH_1):GND
 186 P3E_CPU0_PE2_SS_RXP<5>  IO186 @BASEBOARD_FAB2_LIB.BASEBOARD_FAB2(SCH_1):P3E_CPU0_PE2_SS_RXP(5)
 187 P3E_CPU0_PE2_SS_C_TXN<6>  IO187 @BASEBOARD_FAB2_LIB.BASEBOARD_FAB2(SCH_1):P3E_CPU0_PE2_SS_C_TXN(6)
 188    GND  IO188 @BASEBOARD_FAB2_LIB.BASEBOARD_FAB2(SCH_1):GND
 189 P3E_CPU0_PE2_SS_C_TXP<6>  IO189 @BASEBOARD_FAB2_LIB.BASEBOARD_FAB2(SCH_1):P3E_CPU0_PE2_SS_C_TXP(6)
 190 P3E_CPU0_PE2_SS_RXP<6>  IO190 @BASEBOARD_FAB2_LIB.BASEBOARD_FAB2(SCH_1):P3E_CPU0_PE2_SS_RXP(6)
 191    GND  IO191 @BASEBOARD_FAB2_LIB.BASEBOARD_FAB2(SCH_1):GND
 192 P3E_CPU0_PE2_SS_RXN<6>  IO192 @BASEBOARD_FAB2_LIB.BASEBOARD_FAB2(SCH_1):P3E_CPU0_PE2_SS_RXN(6)
 193 P3E_CPU0_PE2_SS_C_TXN<7>  IO193 @BASEBOARD_FAB2_LIB.BASEBOARD_FAB2(SCH_1):P3E_CPU0_PE2_SS_C_TXN(7)
 194    GND  IO194 @BASEBOARD_FAB2_LIB.BASEBOARD_FAB2(SCH_1):GND
 195 P3E_CPU0_PE2_SS_C_TXP<7>  IO195 @BASEBOARD_FAB2_LIB.BASEBOARD_FAB2(SCH_1):P3E_CPU0_PE2_SS_C_TXP(7)
 196 P3E_CPU0_PE2_SS_RXN<7>  IO196 @BASEBOARD_FAB2_LIB.BASEBOARD_FAB2(SCH_1):P3E_CPU0_PE2_SS_RXN(7)
 197    GND  IO197 @BASEBOARD_FAB2_LIB.BASEBOARD_FAB2(SCH_1):GND
 198 P3E_CPU0_PE2_SS_RXP<7>  IO198 @BASEBOARD_FAB2_LIB.BASEBOARD_FAB2(SCH_1):P3E_CPU0_PE2_SS_RXP(7)
 199 FM_PRSNT_2_6_N  IO199 @BASEBOARD_FAB2_LIB.BASEBOARD_FAB2(SCH_1):FM_PRSNT_2_6_N
 200    GND  IO200 @BASEBOARD_FAB2_LIB.BASEBOARD_FAB2(SCH_1):GND


DRAWING: @BASEBOARD_FAB2_LIB.BASEBOARD_FAB2(SCH_1):PAGE246 

RES_0402-4.75K,1%,1/16W,CHIP,GA  I5  RN8F1
   1 P3V3_STBY      A @BASEBOARD_FAB2_LIB.BASEBOARD_FAB2(SCH_1):P3V3_STBY
   2 SPI_BMC_BT_CS1_N      B @BASEBOARD_FAB2_LIB.BASEBOARD_FAB2(SCH_1):SPI_BMC_BT_CS1_N

RES_0402-1.00K,1%,1/16W,EMPTY,A  I8  RN8F6
   1 PU_TPM_SPI_BMC_WP_N      A @BASEBOARD_FAB2_LIB.BASEBOARD_FAB2(SCH_1):PU_TPM_SPI_BMC_WP_N
   2    GND      B @BASEBOARD_FAB2_LIB.BASEBOARD_FAB2(SCH_1):GND

RES_0402-33.2,1%,1/16W,CHIP,G2A  I9  RN8F5
   1 SPI_BMC_BT_DI      A @BASEBOARD_FAB2_LIB.BASEBOARD_FAB2(SCH_1):SPI_BMC_BT_DI
   2 SPI_TPM_BMC_DI_R_      B @BASEBOARD_FAB2_LIB.BASEBOARD_FAB2(SCH_1):SPI_TPM_BMC_DI_R_

RES_0402-4.75K,1%,1/16W,CHIP,GA  I10  RN8F2
   1 P3V3_STBY      A @BASEBOARD_FAB2_LIB.BASEBOARD_FAB2(SCH_1):P3V3_STBY
   2 PU_TPM_SPI_BMC_WP_N      B @BASEBOARD_FAB2_LIB.BASEBOARD_FAB2(SCH_1):PU_TPM_SPI_BMC_WP_N

RES_0402-4.75K,1%,1/16W,CHIP,GA  I11  RN8F3
   1 P3V3_STBY      A @BASEBOARD_FAB2_LIB.BASEBOARD_FAB2(SCH_1):P3V3_STBY
   2 PU_TPM_SPI_BMC_HOLD_N      B @BASEBOARD_FAB2_LIB.BASEBOARD_FAB2(SCH_1):PU_TPM_SPI_BMC_HOLD_N

RES_0402-4.75K,1%,1/16W,EMPTY,A  I12  RN8F4
   1 P3V3_STBY      A @BASEBOARD_FAB2_LIB.BASEBOARD_FAB2(SCH_1):P3V3_STBY
   2 PU_TPM_SPI_FLASH_RESET_2_N      B @BASEBOARD_FAB2_LIB.BASEBOARD_FAB2(SCH_1):PU_TPM_SPI_FLASH_RESET_2_N

CAP_0402-1.0UF,6.3V,10%,X6S,D9A  I15  CN8F1
   1 P3V3_STBY      A @BASEBOARD_FAB2_LIB.BASEBOARD_FAB2(SCH_1):P3V3_STBY
   2    GND      B @BASEBOARD_FAB2_LIB.BASEBOARD_FAB2(SCH_1):GND

CAP_0402LF-0.01UF,25V,10%,X7R,A  I16  CN8F2
   1 P3V3_STBY      A @BASEBOARD_FAB2_LIB.BASEBOARD_FAB2(SCH_1):P3V3_STBY
   2    GND      B @BASEBOARD_FAB2_LIB.BASEBOARD_FAB2(SCH_1):GND

W25Q256_XSOI-IC,H25002-001  I17  UN8F2
   9 PU_TPM_SPI_BMC_WP_N WP_N_IO<2> @BASEBOARD_FAB2_LIB.BASEBOARD_FAB2(SCH_1):PU_TPM_SPI_BMC_WP_N
  14 TP_TPM_SPI_0  NC<0> @BASEBOARD_FAB2_LIB.BASEBOARD_FAB2(SCH_1):TP_TPM_SPI_0
  13 TP_TPM_SPI_1  NC<1> @BASEBOARD_FAB2_LIB.BASEBOARD_FAB2(SCH_1):TP_TPM_SPI_1
  12 TP_TPM_SPI_2  NC<2> @BASEBOARD_FAB2_LIB.BASEBOARD_FAB2(SCH_1):TP_TPM_SPI_2
  11 TP_TPM_SPI_3  NC<3> @BASEBOARD_FAB2_LIB.BASEBOARD_FAB2(SCH_1):TP_TPM_SPI_3
   6 TP_TPM_SPI_4  NC<4> @BASEBOARD_FAB2_LIB.BASEBOARD_FAB2(SCH_1):TP_TPM_SPI_4
   5 TP_TPM_SPI_5  NC<5> @BASEBOARD_FAB2_LIB.BASEBOARD_FAB2(SCH_1):TP_TPM_SPI_5
   4 TP_TPM_SPI_6  NC<6> @BASEBOARD_FAB2_LIB.BASEBOARD_FAB2(SCH_1):TP_TPM_SPI_6
  10    GND    GND @BASEBOARD_FAB2_LIB.BASEBOARD_FAB2(SCH_1):GND
   8 SPI_TPM_BMC_DI_R_ DO_IO<1> @BASEBOARD_FAB2_LIB.BASEBOARD_FAB2(SCH_1):SPI_TPM_BMC_DI_R_
  16 SPI_BMC_BT_CLK    CLK @BASEBOARD_FAB2_LIB.BASEBOARD_FAB2(SCH_1):SPI_BMC_BT_CLK
   2 P3V3_STBY    VCC @BASEBOARD_FAB2_LIB.BASEBOARD_FAB2(SCH_1):P3V3_STBY
   7 SPI_BMC_BT_CS1_N   CS_N @BASEBOARD_FAB2_LIB.BASEBOARD_FAB2(SCH_1):SPI_BMC_BT_CS1_N
  15 SPI_BMC_BT_DO DI_IO<0> @BASEBOARD_FAB2_LIB.BASEBOARD_FAB2(SCH_1):SPI_BMC_BT_DO
   3 PU_TPM_SPI_FLASH_RESET_2_N RESET_N @BASEBOARD_FAB2_LIB.BASEBOARD_FAB2(SCH_1):PU_TPM_SPI_FLASH_RESET_2_N
   1 PU_TPM_SPI_BMC_HOLD_N HOLD_N_IO<3> @BASEBOARD_FAB2_LIB.BASEBOARD_FAB2(SCH_1):PU_TPM_SPI_BMC_HOLD_N


DRAWING: @BASEBOARD_FAB2_LIB.BASEBOARD_FAB2(SCH_1):PAGE247 

RES_0402-4.75K,1%,1/16W,CHIP,GA  I1  R6W10
   1 P3V3_STBY      A @BASEBOARD_FAB2_LIB.BASEBOARD_FAB2(SCH_1):P3V3_STBY
   2 PCA9555_INT_N      B @BASEBOARD_FAB2_LIB.BASEBOARD_FAB2(SCH_1):PCA9555_INT_N

RES_0402-4.75K,1%,1/16W,CHIP,GA  I3  R6W7
   1 PCA9555_A2      A @BASEBOARD_FAB2_LIB.BASEBOARD_FAB2(SCH_1):PCA9555_A2
   2    GND      B @BASEBOARD_FAB2_LIB.BASEBOARD_FAB2(SCH_1):GND

RES_0402-4.75K,1%,1/16W,EMPTY,A  I5  R6W4
   1 P3V3_STBY      A @BASEBOARD_FAB2_LIB.BASEBOARD_FAB2(SCH_1):P3V3_STBY
   2 PCA9555_A2      B @BASEBOARD_FAB2_LIB.BASEBOARD_FAB2(SCH_1):PCA9555_A2

RES_0402-4.75K,1%,1/16W,CHIP,GA  I8  R6W8
   1 PCA9555_A1      A @BASEBOARD_FAB2_LIB.BASEBOARD_FAB2(SCH_1):PCA9555_A1
   2    GND      B @BASEBOARD_FAB2_LIB.BASEBOARD_FAB2(SCH_1):GND

RES_0402-4.75K,1%,1/16W,CHIP,GA  I9  R6W9
   1 PCA9555_A0      A @BASEBOARD_FAB2_LIB.BASEBOARD_FAB2(SCH_1):PCA9555_A0
   2    GND      B @BASEBOARD_FAB2_LIB.BASEBOARD_FAB2(SCH_1):GND

RES_0402-4.75K,1%,1/16W,EMPTY,A  I10  R6W5
   1 P3V3_STBY      A @BASEBOARD_FAB2_LIB.BASEBOARD_FAB2(SCH_1):P3V3_STBY
   2 PCA9555_A1      B @BASEBOARD_FAB2_LIB.BASEBOARD_FAB2(SCH_1):PCA9555_A1

RES_0402-4.75K,1%,1/16W,EMPTY,A  I11  R6W6
   1 P3V3_STBY      A @BASEBOARD_FAB2_LIB.BASEBOARD_FAB2(SCH_1):P3V3_STBY
   2 PCA9555_A0      B @BASEBOARD_FAB2_LIB.BASEBOARD_FAB2(SCH_1):PCA9555_A0

CAP_0402LF-0.1UF,16V,10%,X7R,AA  I18  C6W1
   1 P3V3_STBY      A @BASEBOARD_FAB2_LIB.BASEBOARD_FAB2(SCH_1):P3V3_STBY
   2    GND      B @BASEBOARD_FAB2_LIB.BASEBOARD_FAB2(SCH_1):GND

RES_0402-4.75K,1%,1/16W,EMPTY,A  I67  R6W11
   1 P3V3_STBY      A @BASEBOARD_FAB2_LIB.BASEBOARD_FAB2(SCH_1):P3V3_STBY
   2 SMB_IPMB_3V3AUX_SCL      B @BASEBOARD_FAB2_LIB.BASEBOARD_FAB2(SCH_1):SMB_IPMB_3V3AUX_SCL

RES_0402-4.75K,1%,1/16W,EMPTY,A  I68  R6W12
   1 P3V3_STBY      A @BASEBOARD_FAB2_LIB.BASEBOARD_FAB2(SCH_1):P3V3_STBY
   2 SMB_IPMB_3V3AUX_SDA      B @BASEBOARD_FAB2_LIB.BASEBOARD_FAB2(SCH_1):SMB_IPMB_3V3AUX_SDA

PCA9515ADGKR-1-GP_DISCRET-G5-PA  I77  U6W2
   1     NC   NC#1     NC
   2 SMB_PMBUS_BMC_STBY_LVC3_SCL_R1   SCL0 @BASEBOARD_FAB2_LIB.BASEBOARD_FAB2(SCH_1):SMB_PMBUS_BMC_STBY_LVC3_SCL_R1
   3 SMB_PMBUS_BMC_STBY_LVC3_SDA_R1   SDA0 @BASEBOARD_FAB2_LIB.BASEBOARD_FAB2(SCH_1):SMB_PMBUS_BMC_STBY_LVC3_SDA_R1
   4    GND    GND @BASEBOARD_FAB2_LIB.BASEBOARD_FAB2(SCH_1):GND
   5 HSC_SMBUS_SWITCH_EN     EN @BASEBOARD_FAB2_LIB.BASEBOARD_FAB2(SCH_1):HSC_SMBUS_SWITCH_EN
   6 SMB_BMC_PMBUS_STBY_LVC3_SDA   SDA1 @BASEBOARD_FAB2_LIB.BASEBOARD_FAB2(SCH_1):SMB_BMC_PMBUS_STBY_LVC3_SDA
   7 SMB_BMC_PMBUS_STBY_LVC3_SCL   SCL1 @BASEBOARD_FAB2_LIB.BASEBOARD_FAB2(SCH_1):SMB_BMC_PMBUS_STBY_LVC3_SCL
   8 P3V3_STBY    VCC @BASEBOARD_FAB2_LIB.BASEBOARD_FAB2(SCH_1):P3V3_STBY

CAP_0402LF-0.1UF,16V,10%,X7R,AA  I81  C6W2
   1 P3V3_STBY      A @BASEBOARD_FAB2_LIB.BASEBOARD_FAB2(SCH_1):P3V3_STBY
   2    GND      B @BASEBOARD_FAB2_LIB.BASEBOARD_FAB2(SCH_1):GND

CAP_A_0402V-0.1UF,16V,10%,X7R,A  I85  C6W3
   1 P3V3_STBY      A @BASEBOARD_FAB2_LIB.BASEBOARD_FAB2(SCH_1):P3V3_STBY
   2    GND      B @BASEBOARD_FAB2_LIB.BASEBOARD_FAB2(SCH_1):GND

RES_0402-20.0,1%,1/16W,CHIP,G2A  I87  R6W20
   1 SMB_HOST_STBY_LVC3_SDA_R3      A @BASEBOARD_FAB2_LIB.BASEBOARD_FAB2(SCH_1):SMB_HOST_STBY_LVC3_SDA_R3
   2 SMB_HOST_STBY_LVC3_SDA      B @BASEBOARD_FAB2_LIB.BASEBOARD_FAB2(SCH_1):SMB_HOST_STBY_LVC3_SDA

AT24C64_SOICLF-IC,C47049-001-GA  I89  U6W3
   1    GND     A0 @BASEBOARD_FAB2_LIB.BASEBOARD_FAB2(SCH_1):GND
   2    GND     A1 @BASEBOARD_FAB2_LIB.BASEBOARD_FAB2(SCH_1):GND
   3 PU_ID_EEPROM_A2     A2 @BASEBOARD_FAB2_LIB.BASEBOARD_FAB2(SCH_1):PU_ID_EEPROM_A2
   6 SMB_HOST_STBY_LVC3_SCL_R3    SCL @BASEBOARD_FAB2_LIB.BASEBOARD_FAB2(SCH_1):SMB_HOST_STBY_LVC3_SCL_R3
   7 PD_ID_EEPROM_WP     WP @BASEBOARD_FAB2_LIB.BASEBOARD_FAB2(SCH_1):PD_ID_EEPROM_WP
   5 SMB_HOST_STBY_LVC3_SDA_R3    SDA @BASEBOARD_FAB2_LIB.BASEBOARD_FAB2(SCH_1):SMB_HOST_STBY_LVC3_SDA_R3

RES_0402-1.00K,1%,1/16W,CHIP,GA  I90  R6W21
   1 P3V3_STBY      A @BASEBOARD_FAB2_LIB.BASEBOARD_FAB2(SCH_1):P3V3_STBY
   2 PU_ID_EEPROM_A2      B @BASEBOARD_FAB2_LIB.BASEBOARD_FAB2(SCH_1):PU_ID_EEPROM_A2

RES_0402-1.00K,1%,1/16W,CHIP,GA  I92  R6W23
   1 PD_ID_EEPROM_WP      A @BASEBOARD_FAB2_LIB.BASEBOARD_FAB2(SCH_1):PD_ID_EEPROM_WP
   2    GND      B @BASEBOARD_FAB2_LIB.BASEBOARD_FAB2(SCH_1):GND

RES_0402-20.0,1%,1/16W,CHIP,G2A  I94  R6W22
   1 SMB_HOST_STBY_LVC3_SCL      A @BASEBOARD_FAB2_LIB.BASEBOARD_FAB2(SCH_1):SMB_HOST_STBY_LVC3_SCL
   2 SMB_HOST_STBY_LVC3_SCL_R3      B @BASEBOARD_FAB2_LIB.BASEBOARD_FAB2(SCH_1):SMB_HOST_STBY_LVC3_SCL_R3

PCA9555PWRG4-GP_DISCRET-G5-PCAA  I97  U6W1
   1 PCA9555_INT_N   INT# @BASEBOARD_FAB2_LIB.BASEBOARD_FAB2(SCH_1):PCA9555_INT_N
   2 PCA9555_A1     A1 @BASEBOARD_FAB2_LIB.BASEBOARD_FAB2(SCH_1):PCA9555_A1
   3 PCA9555_A2     A2 @BASEBOARD_FAB2_LIB.BASEBOARD_FAB2(SCH_1):PCA9555_A2
   4 LED_POSTCODE_0_R     P0 @BASEBOARD_FAB2_LIB.BASEBOARD_FAB2(SCH_1):LED_POSTCODE_0_R
   5 LED_POSTCODE_1_R     P1 @BASEBOARD_FAB2_LIB.BASEBOARD_FAB2(SCH_1):LED_POSTCODE_1_R
   6 LED_POSTCODE_2_R     P2 @BASEBOARD_FAB2_LIB.BASEBOARD_FAB2(SCH_1):LED_POSTCODE_2_R
   7 LED_POSTCODE_3_R     P3 @BASEBOARD_FAB2_LIB.BASEBOARD_FAB2(SCH_1):LED_POSTCODE_3_R
   8 LED_POSTCODE_4_R     P4 @BASEBOARD_FAB2_LIB.BASEBOARD_FAB2(SCH_1):LED_POSTCODE_4_R
   9 LED_POSTCODE_5_R     P5 @BASEBOARD_FAB2_LIB.BASEBOARD_FAB2(SCH_1):LED_POSTCODE_5_R
  10 LED_POSTCODE_6_R     P6 @BASEBOARD_FAB2_LIB.BASEBOARD_FAB2(SCH_1):LED_POSTCODE_6_R
  11 LED_POSTCODE_7_R     P7 @BASEBOARD_FAB2_LIB.BASEBOARD_FAB2(SCH_1):LED_POSTCODE_7_R
  12    GND    GND @BASEBOARD_FAB2_LIB.BASEBOARD_FAB2(SCH_1):GND
  13 FM_DEBUG_RST_BTN_N    P10 @BASEBOARD_FAB2_LIB.BASEBOARD_FAB2(SCH_1):FM_DEBUG_RST_BTN_N
  14 FP_PWR_BTN_R_N    P11 @BASEBOARD_FAB2_LIB.BASEBOARD_FAB2(SCH_1):FP_PWR_BTN_R_N
  15     NC    P12     NC
  16     NC    P13     NC
  17     NC    P14     NC
  18     NC    P15     NC
  19     NC    P16     NC
  20     NC    P17     NC
  21 PCA9555_A0     A0 @BASEBOARD_FAB2_LIB.BASEBOARD_FAB2(SCH_1):PCA9555_A0
  22 SMB_IPMB_3V3AUX_SCL    SCL @BASEBOARD_FAB2_LIB.BASEBOARD_FAB2(SCH_1):SMB_IPMB_3V3AUX_SCL
  23 SMB_IPMB_3V3AUX_SDA    SDA @BASEBOARD_FAB2_LIB.BASEBOARD_FAB2(SCH_1):SMB_IPMB_3V3AUX_SDA
  24 P3V3_STBY    VCC @BASEBOARD_FAB2_LIB.BASEBOARD_FAB2(SCH_1):P3V3_STBY


DRAWING: @BASEBOARD_FAB2_LIB.BASEBOARD_FAB2(SCH_1):PAGE249 

RES_0402-1.00K,1%,1/16W,CHIP,GA  I2  R3W1
   1 BMC_TPM_HW_RST      A @BASEBOARD_FAB2_LIB.BASEBOARD_FAB2(SCH_1):BMC_TPM_HW_RST
   2    GND      B @BASEBOARD_FAB2_LIB.BASEBOARD_FAB2(SCH_1):GND

RES_0402-10.0K,1%,1/16W,CHIP,GA  I7  R3W9
   1 VREF_2V2      A @BASEBOARD_FAB2_LIB.BASEBOARD_FAB2(SCH_1):VREF_2V2
   2    GND      B @BASEBOARD_FAB2_LIB.BASEBOARD_FAB2(SCH_1):GND

RES_0402-4.75K,1%,1/16W,CHIP,GA  I8  R3W7
   1 P3V3_STBY      A @BASEBOARD_FAB2_LIB.BASEBOARD_FAB2(SCH_1):P3V3_STBY
   2 VREF_2V2      B @BASEBOARD_FAB2_LIB.BASEBOARD_FAB2(SCH_1):VREF_2V2

RES_0402-1.00K,1%,1/16W,CHIP,GA  I12  R3W2
   1 BMC_TPM_HW_C_RST      A @BASEBOARD_FAB2_LIB.BASEBOARD_FAB2(SCH_1):BMC_TPM_HW_C_RST
   2    GND      B @BASEBOARD_FAB2_LIB.BASEBOARD_FAB2(SCH_1):GND

LMV331IDCKRG4-GP_DISCRET-G-LMVA  I15  Q9W4
   1 FM_TPM_PRES_RST_N    +IN @BASEBOARD_FAB2_LIB.BASEBOARD_FAB2(SCH_1):FM_TPM_PRES_RST_N
   3 VREF_2V2    -IN @BASEBOARD_FAB2_LIB.BASEBOARD_FAB2(SCH_1):VREF_2V2
   4 FM_TPM_PRES_N    OUT @BASEBOARD_FAB2_LIB.BASEBOARD_FAB2(SCH_1):FM_TPM_PRES_N
   5 P3V3_STBY    VCC @BASEBOARD_FAB2_LIB.BASEBOARD_FAB2(SCH_1):P3V3_STBY
   2    GND    GND @BASEBOARD_FAB2_LIB.BASEBOARD_FAB2(SCH_1):GND

RES_0402-10.0K,1%,1/16W,CHIP,GA  I17  R3W3
   1 P3V3_STBY      A @BASEBOARD_FAB2_LIB.BASEBOARD_FAB2(SCH_1):P3V3_STBY
   2 FM_TPM_PRES_RST_N      B @BASEBOARD_FAB2_LIB.BASEBOARD_FAB2(SCH_1):FM_TPM_PRES_RST_N

CAP_0402LF-0.1UF,16V,10%,X7R,AA  I21  C8W2
   1 P3V3_STBY      A @BASEBOARD_FAB2_LIB.BASEBOARD_FAB2(SCH_1):P3V3_STBY
   2    GND      B @BASEBOARD_FAB2_LIB.BASEBOARD_FAB2(SCH_1):GND

NPN_SM-MMBT3904,IC,C52245-001  I26  Q9W3
   1 FM_TPM_PRES_RST      B @BASEBOARD_FAB2_LIB.BASEBOARD_FAB2(SCH_1):FM_TPM_PRES_RST
   3 RST_BMC_SRST_N      C @BASEBOARD_FAB2_LIB.BASEBOARD_FAB2(SCH_1):RST_BMC_SRST_N
   2    GND      E @BASEBOARD_FAB2_LIB.BASEBOARD_FAB2(SCH_1):GND

RES_0402-4.75K,1%,1/16W,CHIP,GA  I27  R3W6
   1 P3V3_STBY      A @BASEBOARD_FAB2_LIB.BASEBOARD_FAB2(SCH_1):P3V3_STBY
   2 RST_BMC_SRST_N      B @BASEBOARD_FAB2_LIB.BASEBOARD_FAB2(SCH_1):RST_BMC_SRST_N

NPN_SM-MMBT3904,IC,C52245-001  I29  Q9W2
   1 FM_TPM_PRES_RST_N_R      B @BASEBOARD_FAB2_LIB.BASEBOARD_FAB2(SCH_1):FM_TPM_PRES_RST_N_R
   3 FM_TPM_PRES_RST      C @BASEBOARD_FAB2_LIB.BASEBOARD_FAB2(SCH_1):FM_TPM_PRES_RST
   2    GND      E @BASEBOARD_FAB2_LIB.BASEBOARD_FAB2(SCH_1):GND

FET_N_SOT23LF-2N7002,FET,C7925A  I30  Q9W1
   1 BMC_TPM_HW_C_RST   GATE @BASEBOARD_FAB2_LIB.BASEBOARD_FAB2(SCH_1):BMC_TPM_HW_C_RST
   2    GND    SRC @BASEBOARD_FAB2_LIB.BASEBOARD_FAB2(SCH_1):GND
   3 FM_TPM_PRES_RST_N    DRN @BASEBOARD_FAB2_LIB.BASEBOARD_FAB2(SCH_1):FM_TPM_PRES_RST_N

47KR2F-GP_RCL_GP-47KR2F-GP,64.A  I31  R3W4
   1 FM_TPM_PRES_RST_N      1 @BASEBOARD_FAB2_LIB.BASEBOARD_FAB2(SCH_1):FM_TPM_PRES_RST_N
   2 FM_TPM_PRES_RST_N_R      2 @BASEBOARD_FAB2_LIB.BASEBOARD_FAB2(SCH_1):FM_TPM_PRES_RST_N_R

CAP_0603-10UF,6.3V,20%,X6S,E15A  I32  C8W1
   1 BMC_TPM_HW_RST      A @BASEBOARD_FAB2_LIB.BASEBOARD_FAB2(SCH_1):BMC_TPM_HW_RST
   2 BMC_TPM_HW_C_RST      B @BASEBOARD_FAB2_LIB.BASEBOARD_FAB2(SCH_1):BMC_TPM_HW_C_RST

82K5R2F-GP_SMD-RG-82K5R2F-GP,6A  I33  R3W5
   1 P3V3_STBY      1 @BASEBOARD_FAB2_LIB.BASEBOARD_FAB2(SCH_1):P3V3_STBY
   2 FM_TPM_PRES_RST      2 @BASEBOARD_FAB2_LIB.BASEBOARD_FAB2(SCH_1):FM_TPM_PRES_RST


DRAWING: @BASEBOARD_FAB2_LIB.BASEBOARD_FAB2(SCH_1):PAGE143 

CAP_0402LF-0.1UF,16V,10%,X7R,AA  I55  C25W22
   1 BMC_M_VREFCA      A @BASEBOARD_FAB2_LIB.BASEBOARD_FAB2(SCH_1):BMC_M_VREFCA
   2    GND      B @BASEBOARD_FAB2_LIB.BASEBOARD_FAB2(SCH_1):GND

RES_0402-240,1.0%,1/16W,CHIP,GA  I58  R1T27
   1    GND      A @BASEBOARD_FAB2_LIB.BASEBOARD_FAB2(SCH_1):GND
   2 BMC_MIOZ      B @BASEBOARD_FAB2_LIB.BASEBOARD_FAB2(SCH_1):BMC_MIOZ

AST2520A1-GP-GP_ASIC2-GB1-AST2A  I63  U25W4
  U9 BMC_M_DQ4   MDQ4 @BASEBOARD_FAB2_LIB.BASEBOARD_FAB2(SCH_1):BMC_M_DQ4
AA10 BMC_M_DQ3   MDQ3 @BASEBOARD_FAB2_LIB.BASEBOARD_FAB2(SCH_1):BMC_M_DQ3
 Y10 BMC_M_DQ2   MDQ2 @BASEBOARD_FAB2_LIB.BASEBOARD_FAB2(SCH_1):BMC_M_DQ2
 W10 BMC_M_DQ1   MDQ1 @BASEBOARD_FAB2_LIB.BASEBOARD_FAB2(SCH_1):BMC_M_DQ1
 U10 BMC_M_DQ0   MDQ0 @BASEBOARD_FAB2_LIB.BASEBOARD_FAB2(SCH_1):BMC_M_DQ0
 U15 TP_BMC_M_A15   MA15 @BASEBOARD_FAB2_LIB.BASEBOARD_FAB2(SCH_1):TP_BMC_M_A15
  U7 BMC_M_DQ15  MDQ15 @BASEBOARD_FAB2_LIB.BASEBOARD_FAB2(SCH_1):BMC_M_DQ15
  V7 BMC_M_DQ14  MDQ14 @BASEBOARD_FAB2_LIB.BASEBOARD_FAB2(SCH_1):BMC_M_DQ14
 AB8 BMC_M_DM1   MDM1 @BASEBOARD_FAB2_LIB.BASEBOARD_FAB2(SCH_1):BMC_M_DM1
 W11 BMC_MIOZ   MIOZ @BASEBOARD_FAB2_LIB.BASEBOARD_FAB2(SCH_1):BMC_MIOZ
AB13 BMC_M_CAS_N  MCAS# @BASEBOARD_FAB2_LIB.BASEBOARD_FAB2(SCH_1):BMC_M_CAS_N
 U13 BMC_M_A10   MA10 @BASEBOARD_FAB2_LIB.BASEBOARD_FAB2(SCH_1):BMC_M_A10
AA14 BMC_M_A11   MA11 @BASEBOARD_FAB2_LIB.BASEBOARD_FAB2(SCH_1):BMC_M_A11
  T9 BMC_M_VREFCA  MVREF @BASEBOARD_FAB2_LIB.BASEBOARD_FAB2(SCH_1):BMC_M_VREFCA
  Y8 BMC_M_DQ9   MDQ9 @BASEBOARD_FAB2_LIB.BASEBOARD_FAB2(SCH_1):BMC_M_DQ9
 V11 BMC_M_ODT   MODT @BASEBOARD_FAB2_LIB.BASEBOARD_FAB2(SCH_1):BMC_M_ODT
 Y11 BMC_M_CKE   MCKE @BASEBOARD_FAB2_LIB.BASEBOARD_FAB2(SCH_1):BMC_M_CKE
AB12 BMC_M_CLK_DN   MCKN @BASEBOARD_FAB2_LIB.BASEBOARD_FAB2(SCH_1):BMC_M_CLK_DN
 W13 BMC_M_BG0 MBA2_MBG0 @BASEBOARD_FAB2_LIB.BASEBOARD_FAB2(SCH_1):BMC_M_BG0
 Y13 BMC_M_BA1   MBA1 @BASEBOARD_FAB2_LIB.BASEBOARD_FAB2(SCH_1):BMC_M_BA1
 U12 BMC_M_BA0   MBA0 @BASEBOARD_FAB2_LIB.BASEBOARD_FAB2(SCH_1):BMC_M_BA0
 Y16 BMC_M_A9    MA9 @BASEBOARD_FAB2_LIB.BASEBOARD_FAB2(SCH_1):BMC_M_A9
 W16 BMC_M_A8    MA8 @BASEBOARD_FAB2_LIB.BASEBOARD_FAB2(SCH_1):BMC_M_A8
AA16 BMC_M_A7    MA7 @BASEBOARD_FAB2_LIB.BASEBOARD_FAB2(SCH_1):BMC_M_A7
AB16 BMC_M_A6    MA6 @BASEBOARD_FAB2_LIB.BASEBOARD_FAB2(SCH_1):BMC_M_A6
 V15 BMC_M_A5    MA5 @BASEBOARD_FAB2_LIB.BASEBOARD_FAB2(SCH_1):BMC_M_A5
 W15 BMC_M_A4    MA4 @BASEBOARD_FAB2_LIB.BASEBOARD_FAB2(SCH_1):BMC_M_A4
 U14 BMC_M_A3    MA3 @BASEBOARD_FAB2_LIB.BASEBOARD_FAB2(SCH_1):BMC_M_A3
 W14 BMC_M_A2    MA2 @BASEBOARD_FAB2_LIB.BASEBOARD_FAB2(SCH_1):BMC_M_A2
 Y14 BMC_M_A12   MA12 @BASEBOARD_FAB2_LIB.BASEBOARD_FAB2(SCH_1):BMC_M_A12
AB14 BMC_M_A1    MA1 @BASEBOARD_FAB2_LIB.BASEBOARD_FAB2(SCH_1):BMC_M_A1
 V13 BMC_M_A0    MA0 @BASEBOARD_FAB2_LIB.BASEBOARD_FAB2(SCH_1):BMC_M_A0
 AB7 BMC_M_DQS1_DP MDQS1P @BASEBOARD_FAB2_LIB.BASEBOARD_FAB2(SCH_1):BMC_M_DQS1_DP
 AB6 BMC_M_DQS1_DN MDQS1N @BASEBOARD_FAB2_LIB.BASEBOARD_FAB2(SCH_1):BMC_M_DQS1_DN
 AB9 BMC_M_DQS0_DP MDQS0P @BASEBOARD_FAB2_LIB.BASEBOARD_FAB2(SCH_1):BMC_M_DQS0_DP
AB10 BMC_M_DQS0_DN MDQS0N @BASEBOARD_FAB2_LIB.BASEBOARD_FAB2(SCH_1):BMC_M_DQS0_DN
  W9 BMC_M_DQ6   MDQ6 @BASEBOARD_FAB2_LIB.BASEBOARD_FAB2(SCH_1):BMC_M_DQ6
  Y9 BMC_M_DQ5   MDQ5 @BASEBOARD_FAB2_LIB.BASEBOARD_FAB2(SCH_1):BMC_M_DQ5
  W7 BMC_M_DQ13  MDQ13 @BASEBOARD_FAB2_LIB.BASEBOARD_FAB2(SCH_1):BMC_M_DQ13
 AA6 BMC_M_DQ12  MDQ12 @BASEBOARD_FAB2_LIB.BASEBOARD_FAB2(SCH_1):BMC_M_DQ12
  U8 BMC_M_DM0   MDM0 @BASEBOARD_FAB2_LIB.BASEBOARD_FAB2(SCH_1):BMC_M_DM0
AB15 BMC_M_A13   MA13 @BASEBOARD_FAB2_LIB.BASEBOARD_FAB2(SCH_1):BMC_M_A13
 Y15 BMC_M_MACT_N MA14_MACT# @BASEBOARD_FAB2_LIB.BASEBOARD_FAB2(SCH_1):BMC_M_MACT_N
  W8 BMC_M_DQ11  MDQ11 @BASEBOARD_FAB2_LIB.BASEBOARD_FAB2(SCH_1):BMC_M_DQ11
  Y7 BMC_M_DQ10  MDQ10 @BASEBOARD_FAB2_LIB.BASEBOARD_FAB2(SCH_1):BMC_M_DQ10
 Y12 BMC_M_WE_N   MWE# @BASEBOARD_FAB2_LIB.BASEBOARD_FAB2(SCH_1):BMC_M_WE_N
 W12 BMC_M_RAS_N  MRAS# @BASEBOARD_FAB2_LIB.BASEBOARD_FAB2(SCH_1):BMC_M_RAS_N
  V9 BMC_M_DQ7   MDQ7 @BASEBOARD_FAB2_LIB.BASEBOARD_FAB2(SCH_1):BMC_M_DQ7
 AA8 BMC_M_DQ8   MDQ8 @BASEBOARD_FAB2_LIB.BASEBOARD_FAB2(SCH_1):BMC_M_DQ8
AB11 BMC_M_CLK_DP   MCKP @BASEBOARD_FAB2_LIB.BASEBOARD_FAB2(SCH_1):BMC_M_CLK_DP
AA12 BMC_M_CS_N   MCS# @BASEBOARD_FAB2_LIB.BASEBOARD_FAB2(SCH_1):BMC_M_CS_N


DRAWING: @BASEBOARD_FAB2_LIB.BASEBOARD_FAB2(SCH_1):PAGE144 

RES_0402-51,5.0%,1/16W,CHIP,G2A  I57  R1U14
   1 SGPIO_BMC_CLK_R      A @BASEBOARD_FAB2_LIB.BASEBOARD_FAB2(SCH_1):SGPIO_BMC_CLK_R
   2 SGPIO_BMC_CLK      B @BASEBOARD_FAB2_LIB.BASEBOARD_FAB2(SCH_1):SGPIO_BMC_CLK

RES_0402-51,5.0%,1/16W,CHIP,G2A  I58  R1U13
   1 SGPIO_BMC_DOUT_R      A @BASEBOARD_FAB2_LIB.BASEBOARD_FAB2(SCH_1):SGPIO_BMC_DOUT_R
   2 SGPIO_BMC_DOUT      B @BASEBOARD_FAB2_LIB.BASEBOARD_FAB2(SCH_1):SGPIO_BMC_DOUT

RES_0402-51,5.0%,1/16W,CHIP,G2A  I59  R1U12
   1 SGPIO_BMC_LD_R_N      A @BASEBOARD_FAB2_LIB.BASEBOARD_FAB2(SCH_1):SGPIO_BMC_LD_R_N
   2 SGPIO_BMC_LD_N      B @BASEBOARD_FAB2_LIB.BASEBOARD_FAB2(SCH_1):SGPIO_BMC_LD_N

RES_0402-2.7K,1%,1/16W,CHIP,G2A  I73  R25W58
   1 A_DACRSET      A @BASEBOARD_FAB2_LIB.BASEBOARD_FAB2(SCH_1):A_DACRSET
   2    GND      B @BASEBOARD_FAB2_LIB.BASEBOARD_FAB2(SCH_1):GND

RES_0402-0.0,5%,1/16W,EMPTY,G2A  I82  R1T24
   1 FM_FLASH_DESC_OVERRIDE_R      A @BASEBOARD_FAB2_LIB.BASEBOARD_FAB2(SCH_1):FM_FLASH_DESC_OVERRIDE_R
   2 FM_FLASH_DESC_OVERRIDE      B @BASEBOARD_FAB2_LIB.BASEBOARD_FAB2(SCH_1):FM_FLASH_DESC_OVERRIDE

RES_0402-0.0,5%,1/16W,CHIP,G21A  I89  R6W17
   1 SMB_IPMB_3V3AUX_SCL      A @BASEBOARD_FAB2_LIB.BASEBOARD_FAB2(SCH_1):SMB_IPMB_3V3AUX_SCL
   2 SMB_IPMB_3V3AUX_SCL_R      B @BASEBOARD_FAB2_LIB.BASEBOARD_FAB2(SCH_1):SMB_IPMB_3V3AUX_SCL_R

RES_0402-0.0,5%,1/16W,CHIP,G21A  I90  R6W18
   1 SMB_IPMB_3V3AUX_SDA      A @BASEBOARD_FAB2_LIB.BASEBOARD_FAB2(SCH_1):SMB_IPMB_3V3AUX_SDA
   2 SMB_IPMB_3V3AUX_SDA_R      B @BASEBOARD_FAB2_LIB.BASEBOARD_FAB2(SCH_1):SMB_IPMB_3V3AUX_SDA_R

AST2520A1-GP-GP_ASIC2-GB1-AST2A  I95  U25W4
 H22 PWRGD_SYS_PWROK GPIOB6_LPCPME# @BASEBOARD_FAB2_LIB.BASEBOARD_FAB2(SCH_1):PWRGD_SYS_PWROK
 J20 CLK_48M_USB_BMC GPIOB4_USBCKI @BASEBOARD_FAB2_LIB.BASEBOARD_FAB2(SCH_1):CLK_48M_USB_BMC
 M18 SMB_IPMB_3V3AUX_SCL_R GPIOY4_SCL1 @BASEBOARD_FAB2_LIB.BASEBOARD_FAB2(SCH_1):SMB_IPMB_3V3AUX_SCL_R
 A15 IRQ_PVDDQ_DEF_VRHOT_LVT3_N GPIOI7_SPI1MISO_VBMISO @BASEBOARD_FAB2_LIB.BASEBOARD_FAB2(SCH_1):IRQ_PVDDQ_DEF_VRHOT_LVT3_N
  K4 A_DACRSET DACRSET @BASEBOARD_FAB2_LIB.BASEBOARD_FAB2(SCH_1):A_DACRSET
  J4 TP_DACR   DACR @BASEBOARD_FAB2_LIB.BASEBOARD_FAB2(SCH_1):TP_DACR
  J3 TP_DACG   DACG @BASEBOARD_FAB2_LIB.BASEBOARD_FAB2(SCH_1):TP_DACG
  C8 JTAG_BMC_TMS    TMS @BASEBOARD_FAB2_LIB.BASEBOARD_FAB2(SCH_1):JTAG_BMC_TMS
 D12 JTAG_BMC_TDI    TDI @BASEBOARD_FAB2_LIB.BASEBOARD_FAB2(SCH_1):JTAG_BMC_TDI
 C10 JTAG_BMC_TCK    TCK @BASEBOARD_FAB2_LIB.BASEBOARD_FAB2(SCH_1):JTAG_BMC_TCK
  C9 TP_JTAG_BMC_RTCK   RTCK @BASEBOARD_FAB2_LIB.BASEBOARD_FAB2(SCH_1):TP_JTAG_BMC_RTCK
 E11 JTAG_BMC_TRST_N  NTRST @BASEBOARD_FAB2_LIB.BASEBOARD_FAB2(SCH_1):JTAG_BMC_TRST_N
 E15 FM_BIOS_MRC_DEBUG_MSG_DIS_N GPIOI1_SYSCK @BASEBOARD_FAB2_LIB.BASEBOARD_FAB2(SCH_1):FM_BIOS_MRC_DEBUG_MSG_DIS_N
 C18 IRQ_HSC_FAULT_N GPIOI0_SYSCS# @BASEBOARD_FAB2_LIB.BASEBOARD_FAB2(SCH_1):IRQ_HSC_FAULT_N
 C15 FM_SOL_UART_CH_SEL GPIOI5_SPI1CK_VBCK @BASEBOARD_FAB2_LIB.BASEBOARD_FAB2(SCH_1):FM_SOL_UART_CH_SEL
 B15 FM_CPU_BMC_INIT GPIOI4_SPI1CS0#_VBCS# @BASEBOARD_FAB2_LIB.BASEBOARD_FAB2(SCH_1):FM_CPU_BMC_INIT
 A14 IRQ_DIMM_SAVE_LVT3_N GPIOI6_SPI1MOSI_VBMOSI @BASEBOARD_FAB2_LIB.BASEBOARD_FAB2(SCH_1):IRQ_DIMM_SAVE_LVT3_N
  L2 SGPIO_BMC_LD_R_N GPIOJ1_SGPMLD @BASEBOARD_FAB2_LIB.BASEBOARD_FAB2(SCH_1):SGPIO_BMC_LD_R_N
  R2 SGPIO_BMC_CLK_R GPIOJ0_SGPMCK @BASEBOARD_FAB2_LIB.BASEBOARD_FAB2(SCH_1):SGPIO_BMC_CLK_R
  N3 SGPIO_BMC_DOUT_R GPIOJ2_SGPMO @BASEBOARD_FAB2_LIB.BASEBOARD_FAB2(SCH_1):SGPIO_BMC_DOUT_R
 E16 FM_FAST_PROCHOT_EN_N GPIOG3_SGPS1I1 @BASEBOARD_FAB2_LIB.BASEBOARD_FAB2(SCH_1):FM_FAST_PROCHOT_EN_N
 C19 FM_PCH_BMC_THERMTRIP_N GPIOG2_SGPS1I0 @BASEBOARD_FAB2_LIB.BASEBOARD_FAB2(SCH_1):FM_PCH_BMC_THERMTRIP_N
  J2 TP_DACB   DACB @BASEBOARD_FAB2_LIB.BASEBOARD_FAB2(SCH_1):TP_DACB
 M19 SMB_IPMB_3V3AUX_SDA_R GPIOY5_SDA1 @BASEBOARD_FAB2_LIB.BASEBOARD_FAB2(SCH_1):SMB_IPMB_3V3AUX_SDA_R
 D11 JTAG_BMC_TDO    TDO @BASEBOARD_FAB2_LIB.BASEBOARD_FAB2(SCH_1):JTAG_BMC_TDO
 K19 PWRGD_PCH_PWROK GPIOB0 @BASEBOARD_FAB2_LIB.BASEBOARD_FAB2(SCH_1):PWRGD_PCH_PWROK
 L19 FM_CPU1_SKTOCC_LVT3_N GPIOB1 @BASEBOARD_FAB2_LIB.BASEBOARD_FAB2(SCH_1):FM_CPU1_SKTOCC_LVT3_N
 L18 FM_MP_PS_FAIL_N GPIOB2 @BASEBOARD_FAB2_LIB.BASEBOARD_FAB2(SCH_1):FM_MP_PS_FAIL_N
 K18 FM_CPU0_SKTOCC_LVT3_N GPIOB3 @BASEBOARD_FAB2_LIB.BASEBOARD_FAB2(SCH_1):FM_CPU0_SKTOCC_LVT3_N
 H20 IRQ_PVDDQ_GHJ_VRHOT_LVT3_N GPIOB7 @BASEBOARD_FAB2_LIB.BASEBOARD_FAB2(SCH_1):IRQ_PVDDQ_GHJ_VRHOT_LVT3_N
 M20 TP_SMB_STORAGE_BP_3V3AUX_SCL GPIOY6_SCL2 @BASEBOARD_FAB2_LIB.BASEBOARD_FAB2(SCH_1):TP_SMB_STORAGE_BP_3V3AUX_SCL
 P20 TP_SMB_STORAGE_BP_3V3AUX_SDA GPIOY7_SDA2 @BASEBOARD_FAB2_LIB.BASEBOARD_FAB2(SCH_1):TP_SMB_STORAGE_BP_3V3AUX_SDA
 A11 SMB_VR_STBY_LVC3_SCL_R GPIOQ0_SCL3 @BASEBOARD_FAB2_LIB.BASEBOARD_FAB2(SCH_1):SMB_VR_STBY_LVC3_SCL_R
 A10 SMB_VR_STBY_LVC3_SDA_R GPIOQ1_SDA3 @BASEBOARD_FAB2_LIB.BASEBOARD_FAB2(SCH_1):SMB_VR_STBY_LVC3_SDA_R
  A9 SMB_HOST_STBY_LVC3_SCL_R GPIOQ2_SCL4 @BASEBOARD_FAB2_LIB.BASEBOARD_FAB2(SCH_1):SMB_HOST_STBY_LVC3_SCL_R
  B9 SMB_HOST_STBY_LVC3_SDA_R GPIOQ3_SDA4 @BASEBOARD_FAB2_LIB.BASEBOARD_FAB2(SCH_1):SMB_HOST_STBY_LVC3_SDA_R
  L3 SMB_SENSOR_BMC_STBY_LVC3_SCL GPIOK0_SCL5 @BASEBOARD_FAB2_LIB.BASEBOARD_FAB2(SCH_1):SMB_SENSOR_BMC_STBY_LVC3_SCL
  L4 SMB_SENSOR_BMC_STBY_LVC3_SDA GPIOK1_SDA5 @BASEBOARD_FAB2_LIB.BASEBOARD_FAB2(SCH_1):SMB_SENSOR_BMC_STBY_LVC3_SDA
  L1 SMB_SMLINK0_STBY_LVC3_SCL_R GPIOK2_SCL6 @BASEBOARD_FAB2_LIB.BASEBOARD_FAB2(SCH_1):SMB_SMLINK0_STBY_LVC3_SCL_R
  N2 SMB_SMLINK0_STBY_LVC3_SDA_R GPIOK3_SDA6 @BASEBOARD_FAB2_LIB.BASEBOARD_FAB2(SCH_1):SMB_SMLINK0_STBY_LVC3_SDA_R
 E19 FM_CPU_CATERR_LVT3_N GPIOG1_SGPS1LD @BASEBOARD_FAB2_LIB.BASEBOARD_FAB2(SCH_1):FM_CPU_CATERR_LVT3_N
 A19 FM_CPU_ERR2_LVT3_N GPIOG0_SGPS1CK @BASEBOARD_FAB2_LIB.BASEBOARD_FAB2(SCH_1):FM_CPU_ERR2_LVT3_N
  N4 SGPIO_BMC_DIN GPIOJ3_SGPMI @BASEBOARD_FAB2_LIB.BASEBOARD_FAB2(SCH_1):SGPIO_BMC_DIN
 B16 FM_BMC_CPLD_GPO GPIOI2_SYSMOSI @BASEBOARD_FAB2_LIB.BASEBOARD_FAB2(SCH_1):FM_BMC_CPLD_GPO
 C16 FM_FLASH_DESC_OVERRIDE_R GPIOI3_SYSMISO @BASEBOARD_FAB2_LIB.BASEBOARD_FAB2(SCH_1):FM_FLASH_DESC_OVERRIDE_R
 A13 SMB_SLOTX24_STBY_LVC3_SDA_R GPIOA5_TIMER6_SDA9 @BASEBOARD_FAB2_LIB.BASEBOARD_FAB2(SCH_1):SMB_SLOTX24_STBY_LVC3_SDA_R
 C14 SMB_SLOTX24_STBY_LVC3_SCL_R GPIOA4_TIMER5_SCL9 @BASEBOARD_FAB2_LIB.BASEBOARD_FAB2(SCH_1):SMB_SLOTX24_STBY_LVC3_SCL_R
  R1 SMB_BMC_PMBUS_STBY_LVC3_SDA_R GPIOK7_SDA8 @BASEBOARD_FAB2_LIB.BASEBOARD_FAB2(SCH_1):SMB_BMC_PMBUS_STBY_LVC3_SDA_R
  P2 SMB_BMC_PMBUS_STBY_LVC3_SCL_R GPIOK6_SCL8 @BASEBOARD_FAB2_LIB.BASEBOARD_FAB2(SCH_1):SMB_BMC_PMBUS_STBY_LVC3_SCL_R
  P1 SMB_OCP_FRU_STBY_LVC3_SDA_R GPIOK5_SDA7 @BASEBOARD_FAB2_LIB.BASEBOARD_FAB2(SCH_1):SMB_OCP_FRU_STBY_LVC3_SDA_R
  N1 SMB_OCP_FRU_STBY_LVC3_SCL_R GPIOK4_SCL7 @BASEBOARD_FAB2_LIB.BASEBOARD_FAB2(SCH_1):SMB_OCP_FRU_STBY_LVC3_SCL_R
 H21 IRQ_BMC_PCH_SMI_LPC_N GPIOB5_LPCPD#_LPCSMI# @BASEBOARD_FAB2_LIB.BASEBOARD_FAB2(SCH_1):IRQ_BMC_PCH_SMI_LPC_N
 N21 SMB_OCP_LAN_STBY_LVC3_SCL_R GPIOQ4_SCL14 @BASEBOARD_FAB2_LIB.BASEBOARD_FAB2(SCH_1):SMB_OCP_LAN_STBY_LVC3_SCL_R
 N22 SMB_OCP_LAN_STBY_LVC3_SDA_R GPIOQ5_SDA14 @BASEBOARD_FAB2_LIB.BASEBOARD_FAB2(SCH_1):SMB_OCP_LAN_STBY_LVC3_SDA_R


DRAWING: @BASEBOARD_FAB2_LIB.BASEBOARD_FAB2(SCH_1):PAGE145 

OSC_C_SM4-24MHZ,OSC,D34520-021  I8  Y9F2
   1 PU_24M_OSC_OE ENABLE_CONTROL @BASEBOARD_FAB2_LIB.BASEBOARD_FAB2(SCH_1):PU_24M_OSC_OE
   2    GND    GND @BASEBOARD_FAB2_LIB.BASEBOARD_FAB2(SCH_1):GND
   3 CLK_24M_BMC_CLKIN_R    OUT @BASEBOARD_FAB2_LIB.BASEBOARD_FAB2(SCH_1):CLK_24M_BMC_CLKIN_R
   4 P3V3_STBY    VDD @BASEBOARD_FAB2_LIB.BASEBOARD_FAB2(SCH_1):P3V3_STBY

RES_0402-0.0,5%,1/16W,EMPTY,G2A  I10  R9F60
   1 CLK_25M_BMC      A @BASEBOARD_FAB2_LIB.BASEBOARD_FAB2(SCH_1):CLK_25M_BMC
   2 CLK_24M_25M_BMC_CLKIN      B @BASEBOARD_FAB2_LIB.BASEBOARD_FAB2(SCH_1):CLK_24M_25M_BMC_CLKIN

RES_0402-0.0,5%,1/16W,CHIP,G21A  I11  R9F62
   1 CLK_24M_BMC_CLKIN_R      A @BASEBOARD_FAB2_LIB.BASEBOARD_FAB2(SCH_1):CLK_24M_BMC_CLKIN_R
   2 CLK_24M_25M_BMC_CLKIN      B @BASEBOARD_FAB2_LIB.BASEBOARD_FAB2(SCH_1):CLK_24M_25M_BMC_CLKIN

RES_0402-10.0K,1%,1/16W,CHIP,GA  I14  R9F61
   1 P3V3_STBY      A @BASEBOARD_FAB2_LIB.BASEBOARD_FAB2(SCH_1):P3V3_STBY
   2 PU_24M_OSC_OE      B @BASEBOARD_FAB2_LIB.BASEBOARD_FAB2(SCH_1):PU_24M_OSC_OE

CAP_A_0402V-0.1UF,16V,10%,X7R,A  I15  C9F23
   1 P3V3_STBY      A @BASEBOARD_FAB2_LIB.BASEBOARD_FAB2(SCH_1):P3V3_STBY
   2    GND      B @BASEBOARD_FAB2_LIB.BASEBOARD_FAB2(SCH_1):GND

RES_0402-0.0,5%,1/16W,CHIP,G21A  I20  R9F33
   1 PECI_BMC      A @BASEBOARD_FAB2_LIB.BASEBOARD_FAB2(SCH_1):PECI_BMC
   2 PECI_BMC_R      B @BASEBOARD_FAB2_LIB.BASEBOARD_FAB2(SCH_1):PECI_BMC_R

RES_0402-348,1%,1/16W,EMPTY,G2A  I22  R9F20
   1 PECI_BMC      A @BASEBOARD_FAB2_LIB.BASEBOARD_FAB2(SCH_1):PECI_BMC
   2    GND      B @BASEBOARD_FAB2_LIB.BASEBOARD_FAB2(SCH_1):GND

RES_0402-100.0K,1%,1/16W,CHIP,A  I30  R25W61
   1 CLK_100M_BMC_PE_R_DP      A @BASEBOARD_FAB2_LIB.BASEBOARD_FAB2(SCH_1):CLK_100M_BMC_PE_R_DP
   2    GND      B @BASEBOARD_FAB2_LIB.BASEBOARD_FAB2(SCH_1):GND

RES_0402-100.0K,1%,1/16W,CHIP,A  I31  R25W62
   1 RST_PLTRST_BUF_N      A @BASEBOARD_FAB2_LIB.BASEBOARD_FAB2(SCH_1):RST_PLTRST_BUF_N
   2    GND      B @BASEBOARD_FAB2_LIB.BASEBOARD_FAB2(SCH_1):GND

RES_0402-100.0K,1%,1/16W,CHIP,A  I34  R25W60
   1 CLK_100M_BMC_PE_R_DN      A @BASEBOARD_FAB2_LIB.BASEBOARD_FAB2(SCH_1):CLK_100M_BMC_PE_R_DN
   2    GND      B @BASEBOARD_FAB2_LIB.BASEBOARD_FAB2(SCH_1):GND

RES_0402-100.0K,1%,1/16W,CHIP,A  I36  R25W64
   1 P2E_SSB_BMC_TX_C_DP      A @BASEBOARD_FAB2_LIB.BASEBOARD_FAB2(SCH_1):P2E_SSB_BMC_TX_C_DP
   2    GND      B @BASEBOARD_FAB2_LIB.BASEBOARD_FAB2(SCH_1):GND

RES_0402-100.0K,1%,1/16W,CHIP,A  I38  R25W65
   1 P2E_SSB_BMC_TX_C_DN      A @BASEBOARD_FAB2_LIB.BASEBOARD_FAB2(SCH_1):P2E_SSB_BMC_TX_C_DN
   2    GND      B @BASEBOARD_FAB2_LIB.BASEBOARD_FAB2(SCH_1):GND

CAP_A_0402V-0.1UF,16V,10%,EMPTA  I44  C25W21
   1 P2E_SSB_BMC_RX_DN      A @BASEBOARD_FAB2_LIB.BASEBOARD_FAB2(SCH_1):P2E_SSB_BMC_RX_DN
   2 P2E_SSB_BMC_RX_C_DN      B @BASEBOARD_FAB2_LIB.BASEBOARD_FAB2(SCH_1):P2E_SSB_BMC_RX_C_DN

CAP_A_0402V-0.1UF,16V,10%,EMPTA  I45  C25W20
   1 P2E_SSB_BMC_RX_DP      A @BASEBOARD_FAB2_LIB.BASEBOARD_FAB2(SCH_1):P2E_SSB_BMC_RX_DP
   2 P2E_SSB_BMC_RX_C_DP      B @BASEBOARD_FAB2_LIB.BASEBOARD_FAB2(SCH_1):P2E_SSB_BMC_RX_C_DP

RES_0402-10.0K,1%,1/16W,EMPTY,A  I46  R25W67
   1 PD_PEREXT      A @BASEBOARD_FAB2_LIB.BASEBOARD_FAB2(SCH_1):PD_PEREXT
   2    GND      B @BASEBOARD_FAB2_LIB.BASEBOARD_FAB2(SCH_1):GND

RES_0402-0.0,5%,1/16W,EMPTY,G2A  I100  R1T15
   1 FM_BMC_ONCTL_N      A @BASEBOARD_FAB2_LIB.BASEBOARD_FAB2(SCH_1):FM_BMC_ONCTL_N
   2 FM_BMC_ONCTL_R_N      B @BASEBOARD_FAB2_LIB.BASEBOARD_FAB2(SCH_1):FM_BMC_ONCTL_R_N

RES_0402-0.0,5%,1/16W,EMPTY,G2A  I101  R1T23
   1 FM_BMC_ONCTL_R_N      A @BASEBOARD_FAB2_LIB.BASEBOARD_FAB2(SCH_1):FM_BMC_ONCTL_R_N
   2    GND      B @BASEBOARD_FAB2_LIB.BASEBOARD_FAB2(SCH_1):GND

AST2520A1-GP-GP_ASIC2-GB1-AST2A  I117  U25W4
 B12 TP_SMB_BUS11_SCL GPIOC2_SD1DAT0_SCL11 @BASEBOARD_FAB2_LIB.BASEBOARD_FAB2(SCH_1):TP_SMB_BUS11_SCL
  D9 TP_SMB_BUS11_SDA GPIOC3_SD1DAT1_SDA11 @BASEBOARD_FAB2_LIB.BASEBOARD_FAB2(SCH_1):TP_SMB_BUS11_SDA
 A12 SMB_PCIE_SSD_3V3AUX_SDA GPIOC1_SD1CMD_SDA10 @BASEBOARD_FAB2_LIB.BASEBOARD_FAB2(SCH_1):SMB_PCIE_SSD_3V3AUX_SDA
 C12 SMB_PCIE_SSD_3V3AUX_SCL GPIOC0_SD1CLK_SCL10 @BASEBOARD_FAB2_LIB.BASEBOARD_FAB2(SCH_1):SMB_PCIE_SSD_3V3AUX_SCL
 B14 FM_BMC_HEARTBEAT_N GPIOA0_MAC1LINK @BASEBOARD_FAB2_LIB.BASEBOARD_FAB2(SCH_1):FM_BMC_HEARTBEAT_N
 D14 FM_BMC_FAULT_LED_N GPIOA1_MAC2LINK @BASEBOARD_FAB2_LIB.BASEBOARD_FAB2(SCH_1):FM_BMC_FAULT_LED_N
 P21 FM_BMC_ONCTL_R_N GPIOY3_SIOONCTRL# @BASEBOARD_FAB2_LIB.BASEBOARD_FAB2(SCH_1):FM_BMC_ONCTL_R_N
 D15 H_CPU1_MEMGHJ_MEMHOT_LVT3_BMC_N GPIOG6_SGPS2I0_SALT3 @BASEBOARD_FAB2_LIB.BASEBOARD_FAB2(SCH_1):H_CPU1_MEMGHJ_MEMHOT_LVT3_BMC_N
 C11 SMB_IE_3V3AUX_SCL GPIOC6_SD1CD#_SCL13 @BASEBOARD_FAB2_LIB.BASEBOARD_FAB2(SCH_1):SMB_IE_3V3AUX_SCL
 D10 SMB_LAN_STBY_LVC3_SCL_R GPIOC4_SD1DAT2_SCL12 @BASEBOARD_FAB2_LIB.BASEBOARD_FAB2(SCH_1):SMB_LAN_STBY_LVC3_SCL_R
 E14 FM_BIOS_SMI_ACTIVE_N GPIOG7_SGPS2I1_SALT4 @BASEBOARD_FAB2_LIB.BASEBOARD_FAB2(SCH_1):FM_BIOS_SMI_ACTIVE_N
 D13 FM_OCP_MEZZA_PRES_N GPIOA2_TIMER3_SPI1CS1# @BASEBOARD_FAB2_LIB.BASEBOARD_FAB2(SCH_1):FM_OCP_MEZZA_PRES_N
 D16     NC GPIOG5_SGPS2LD_SALT2     NC
 E17     NC GPIOG4_SGPS2CK_SALT1     NC
 H19 FM_OCP_MEZZB_PRES_N GPIOF5_NRTS4_LHFRAME# @BASEBOARD_FAB2_LIB.BASEBOARD_FAB2(SCH_1):FM_OCP_MEZZB_PRES_N
 H18 FM_OCP_MEZZC_PRES_N GPIOF7_RXD4_LHRST# @BASEBOARD_FAB2_LIB.BASEBOARD_FAB2(SCH_1):FM_OCP_MEZZC_PRES_N
  U1 FM_HSC_TIMER_EXP_N GPIOL2_NDSR1 @BASEBOARD_FAB2_LIB.BASEBOARD_FAB2(SCH_1):FM_HSC_TIMER_EXP_N
  U2 FM_BIOS_TOP_SWAP GPIOL3_NRI1_VPIHS @BASEBOARD_FAB2_LIB.BASEBOARD_FAB2(SCH_1):FM_BIOS_TOP_SWAP
  P4 FM_MEM_THERM_EVENT_PCH_N GPIOL4_NDTR1_VPIVS @BASEBOARD_FAB2_LIB.BASEBOARD_FAB2(SCH_1):FM_MEM_THERM_EVENT_PCH_N
 K22 CLK_100M_BMC_PE_R_DN PEREFCLKN @BASEBOARD_FAB2_LIB.BASEBOARD_FAB2(SCH_1):CLK_100M_BMC_PE_R_DN
 K21 CLK_100M_BMC_PE_R_DP PEREFCLKP @BASEBOARD_FAB2_LIB.BASEBOARD_FAB2(SCH_1):CLK_100M_BMC_PE_R_DP
  K2 UART_BMC_RXD5   RXD5 @BASEBOARD_FAB2_LIB.BASEBOARD_FAB2(SCH_1):UART_BMC_RXD5
AB18 PECI_BMC_R   PECI @BASEBOARD_FAB2_LIB.BASEBOARD_FAB2(SCH_1):PECI_BMC_R
 D20 FM_BOARD_REV_ID0 GPIOD3_SD2DAT1 @BASEBOARD_FAB2_LIB.BASEBOARD_FAB2(SCH_1):FM_BOARD_REV_ID0
 D21 FM_BOARD_REV_ID1 GPIOD4_SD2DAT2 @BASEBOARD_FAB2_LIB.BASEBOARD_FAB2(SCH_1):FM_BOARD_REV_ID1
 E21 FM_MB_SLOT_ID1 GPIOD1_SD2CMD @BASEBOARD_FAB2_LIB.BASEBOARD_FAB2(SCH_1):FM_MB_SLOT_ID1
 W18 CLK_24M_25M_BMC_CLKIN  CLKIN @BASEBOARD_FAB2_LIB.BASEBOARD_FAB2(SCH_1):CLK_24M_25M_BMC_CLKIN
 U18 RST_BMC_SRST_N  SRST# @BASEBOARD_FAB2_LIB.BASEBOARD_FAB2(SCH_1):RST_BMC_SRST_N
 E13 FM_SSATA_PCIE_M2_SEL GPIOA3_TIMER4 @BASEBOARD_FAB2_LIB.BASEBOARD_FAB2(SCH_1):FM_SSATA_PCIE_M2_SEL
 L20 RST_PLTRST_BUF_N PERST# @BASEBOARD_FAB2_LIB.BASEBOARD_FAB2(SCH_1):RST_PLTRST_BUF_N
 M22 P2E_SSB_BMC_TX_C_DN  PERXN @BASEBOARD_FAB2_LIB.BASEBOARD_FAB2(SCH_1):P2E_SSB_BMC_TX_C_DN
 M21 P2E_SSB_BMC_TX_C_DP  PERXP @BASEBOARD_FAB2_LIB.BASEBOARD_FAB2(SCH_1):P2E_SSB_BMC_TX_C_DP
  Y1 FM_CPU0_RC_ERROR_N GPIOM0_NCTS2_VPIB2 @BASEBOARD_FAB2_LIB.BASEBOARD_FAB2(SCH_1):FM_CPU0_RC_ERROR_N
 AB2 FM_CPU1_RC_ERROR_N GPIOM1_NDCD2_VPIB3 @BASEBOARD_FAB2_LIB.BASEBOARD_FAB2(SCH_1):FM_CPU1_RC_ERROR_N
 AA1 IRQ_BOARD_BMC_ALERT_N GPIOM2_NDSR2_VPIB4 @BASEBOARD_FAB2_LIB.BASEBOARD_FAB2(SCH_1):IRQ_BOARD_BMC_ALERT_N
  Y2 FM_OC_DETECT_EN_N GPIOM3_NRI2_VPIB5 @BASEBOARD_FAB2_LIB.BASEBOARD_FAB2(SCH_1):FM_OC_DETECT_EN_N
 AA2 FM_BB_BMC_MP_GPIO GPIOM4_NDTR2_VPIB6 @BASEBOARD_FAB2_LIB.BASEBOARD_FAB2(SCH_1):FM_BB_BMC_MP_GPIO
  P5 FM_BMC_CPLD_MP_RST_N GPIOM5_NRTS2_VPIB7 @BASEBOARD_FAB2_LIB.BASEBOARD_FAB2(SCH_1):FM_BMC_CPLD_MP_RST_N
  R5 SP2_BMC_CM_UART_TX GPIOM6_TXD2_VPIB8 @BASEBOARD_FAB2_LIB.BASEBOARD_FAB2(SCH_1):SP2_BMC_CM_UART_TX
  T5 SP2_BMC_CM_UART_RX GPIOM7_RXD2_VPIB9 @BASEBOARD_FAB2_LIB.BASEBOARD_FAB2(SCH_1):SP2_BMC_CM_UART_RX
  T1 IRQ_OC_DETECT_N GPIOL1_NDCD1_VPIDE @BASEBOARD_FAB2_LIB.BASEBOARD_FAB2(SCH_1):IRQ_OC_DETECT_N
  P3 FM_PMBUS_ALERT_BUF_EN_N GPIOL5_NRTS1_VPICLK @BASEBOARD_FAB2_LIB.BASEBOARD_FAB2(SCH_1):FM_PMBUS_ALERT_BUF_EN_N
  W1 SP1_BMC_HOST_UART_RX GPIOL7_RXD1 @BASEBOARD_FAB2_LIB.BASEBOARD_FAB2(SCH_1):SP1_BMC_HOST_UART_RX
 J19 IRQ_PVDDQ_ABC_VRHOT_LVT3_N GPIOF0_NCTS4_LHAD0 @BASEBOARD_FAB2_LIB.BASEBOARD_FAB2(SCH_1):IRQ_PVDDQ_ABC_VRHOT_LVT3_N
 J18     NC GPIOF1_NDCD4_LHAD1     NC
 B22 IRQ_PVCCIN_CPU0_VRHOT_LVC3_N GPIOF2_NDSR4_LHAD2 @BASEBOARD_FAB2_LIB.BASEBOARD_FAB2(SCH_1):IRQ_PVCCIN_CPU0_VRHOT_LVC3_N
 F18 FM_PWR_BTN_N GPIOE2_NDSR3 @BASEBOARD_FAB2_LIB.BASEBOARD_FAB2(SCH_1):FM_PWR_BTN_N
 F17 FM_BMC_PWRBTN_OUT_N GPIOE3_NRI3 @BASEBOARD_FAB2_LIB.BASEBOARD_FAB2(SCH_1):FM_BMC_PWRBTN_OUT_N
 E18 FP_NMI_BTN_N GPIOE4_NDTR3 @BASEBOARD_FAB2_LIB.BASEBOARD_FAB2(SCH_1):FP_NMI_BTN_N
 A20 FM_CPU0_PROCHOT_LVT3_BMC_N GPIOE6_TXD3 @BASEBOARD_FAB2_LIB.BASEBOARD_FAB2(SCH_1):FM_CPU0_PROCHOT_LVT3_BMC_N
 B19 FM_CPU1_PROCHOT_LVT3_BMC_N GPIOE7_RXD3 @BASEBOARD_FAB2_LIB.BASEBOARD_FAB2(SCH_1):FM_CPU1_PROCHOT_LVT3_BMC_N
  K1 UART_BMC_TXD5   TXD5 @BASEBOARD_FAB2_LIB.BASEBOARD_FAB2(SCH_1):UART_BMC_TXD5
 K20 PD_PEREXT PEREXT @BASEBOARD_FAB2_LIB.BASEBOARD_FAB2(SCH_1):PD_PEREXT
 L22 P2E_SSB_BMC_RX_DN  PETXN @BASEBOARD_FAB2_LIB.BASEBOARD_FAB2(SCH_1):P2E_SSB_BMC_RX_DN
 L21 P2E_SSB_BMC_RX_DP  PETXP @BASEBOARD_FAB2_LIB.BASEBOARD_FAB2(SCH_1):P2E_SSB_BMC_RX_DP
 D19 IRQ_BMC_PCH_NMI_STBY_N GPIOE5_NRTS3 @BASEBOARD_FAB2_LIB.BASEBOARD_FAB2(SCH_1):IRQ_BMC_PCH_NMI_STBY_N
 C20 RST_BMC_SYSRST_BTN_OUT_N GPIOE1_NDCD3 @BASEBOARD_FAB2_LIB.BASEBOARD_FAB2(SCH_1):RST_BMC_SYSRST_BTN_OUT_N
 B20 RST_SYSTEM_BTN_N GPIOE0_NCTS3 @BASEBOARD_FAB2_LIB.BASEBOARD_FAB2(SCH_1):RST_SYSTEM_BTN_N
 F19 FM_MB_SLOT_ID0 GPIOD0_SD2CLK @BASEBOARD_FAB2_LIB.BASEBOARD_FAB2(SCH_1):FM_MB_SLOT_ID0
 F20 FM_MB_SLOT_ID2 GPIOD2_SD2DAT0 @BASEBOARD_FAB2_LIB.BASEBOARD_FAB2(SCH_1):FM_MB_SLOT_ID2
 C21 FM_CPU_ERR1_LVT3_BMC_N GPIOD7_SD2WP# @BASEBOARD_FAB2_LIB.BASEBOARD_FAB2(SCH_1):FM_CPU_ERR1_LVT3_BMC_N
 B11 SMB_IE_3V3AUX_SDA GPIOC7_SD1WP#_SDA13 @BASEBOARD_FAB2_LIB.BASEBOARD_FAB2(SCH_1):SMB_IE_3V3AUX_SDA
 E12 SMB_LAN_STBY_LVC3_SDA_R GPIOC5_SD1DAT3_SDA12 @BASEBOARD_FAB2_LIB.BASEBOARD_FAB2(SCH_1):SMB_LAN_STBY_LVC3_SDA_R
  T2 IRQ_UV_DETECT_N GPIOL0_NCTS1 @BASEBOARD_FAB2_LIB.BASEBOARD_FAB2(SCH_1):IRQ_UV_DETECT_N
 B21 IRQ_PVCCIN_CPU1_VRHOT_LVC3_N GPIOF3_NRI4_LHAD3 @BASEBOARD_FAB2_LIB.BASEBOARD_FAB2(SCH_1):IRQ_PVCCIN_CPU1_VRHOT_LVC3_N
 A21 IRQ_PVDDQ_KLM_VRHOT_LVT3_N GPIOF4_NDTR4_LHCLK @BASEBOARD_FAB2_LIB.BASEBOARD_FAB2(SCH_1):IRQ_PVDDQ_KLM_VRHOT_LVT3_N
 G17 FM_BATTERY_SENSE_EN_N GPIOF6_TXD4_LHSIRQ# @BASEBOARD_FAB2_LIB.BASEBOARD_FAB2(SCH_1):FM_BATTERY_SENSE_EN_N
  V1 SP1_BMC_HOST_UART_TX GPIOL6_TXD1 @BASEBOARD_FAB2_LIB.BASEBOARD_FAB2(SCH_1):SP1_BMC_HOST_UART_TX
 G18 FM_CPU_ERR0_LVT3_BMC_N GPIOD6_SD2CD# @BASEBOARD_FAB2_LIB.BASEBOARD_FAB2(SCH_1):FM_CPU_ERR0_LVT3_BMC_N
 E20 FM_BOARD_REV_ID2 GPIOD5_SD2DAT3 @BASEBOARD_FAB2_LIB.BASEBOARD_FAB2(SCH_1):FM_BOARD_REV_ID2


DRAWING: @BASEBOARD_FAB2_LIB.BASEBOARD_FAB2(SCH_1):PAGE146 

RES_0402-0.0,5%,1/16W,CHIP,G21A  I26  R25W83
   1 FM_BMC_NMI_N      A @BASEBOARD_FAB2_LIB.BASEBOARD_FAB2(SCH_1):FM_BMC_NMI_N
   2 FM_BMC_NMI_N_R      B @BASEBOARD_FAB2_LIB.BASEBOARD_FAB2(SCH_1):FM_BMC_NMI_N_R

RES_0402-0.0,5%,1/16W,CHIP,G21A  I27  R25W84
   1 IRQ_SML0_ALERT_N      A @BASEBOARD_FAB2_LIB.BASEBOARD_FAB2(SCH_1):IRQ_SML0_ALERT_N
   2 FM_BMC_NMI_N_R      B @BASEBOARD_FAB2_LIB.BASEBOARD_FAB2(SCH_1):FM_BMC_NMI_N_R

RES_0402-8.2K,1%,1/16W,CHIP,G2A  I35  R1T25
   1 A_USB2BVRES      A @BASEBOARD_FAB2_LIB.BASEBOARD_FAB2(SCH_1):A_USB2BVRES
   2    GND      B @BASEBOARD_FAB2_LIB.BASEBOARD_FAB2(SCH_1):GND

RES_0402-8.2K,1%,1/16W,CHIP,G2A  I37  R1T26
   1 A_USB2AVRES      A @BASEBOARD_FAB2_LIB.BASEBOARD_FAB2(SCH_1):A_USB2AVRES
   2    GND      B @BASEBOARD_FAB2_LIB.BASEBOARD_FAB2(SCH_1):GND

RES_0402-1.5K,1%,1/16W,CHIP,G2A  I51  R1U52
   1 P3V3_STBY      A @BASEBOARD_FAB2_LIB.BASEBOARD_FAB2(SCH_1):P3V3_STBY
   2 USB_PCH_BMC_P4_DP      B @BASEBOARD_FAB2_LIB.BASEBOARD_FAB2(SCH_1):USB_PCH_BMC_P4_DP

RES_0402-33.2,1%,1/16W,CHIP,G2A  I64  R25W70
   1 FM_CPU0_FIVR_FAULT_LVT3_R_N      A @BASEBOARD_FAB2_LIB.BASEBOARD_FAB2(SCH_1):FM_CPU0_FIVR_FAULT_LVT3_R_N
   2 FM_CPU0_FIVR_FAULT_LVT3_N      B @BASEBOARD_FAB2_LIB.BASEBOARD_FAB2(SCH_1):FM_CPU0_FIVR_FAULT_LVT3_N

RES_0402-100.0K,1%,1/16W,CHIP,A  I65  R25W63
   1 FM_PE_BMC_WAKE_N      A @BASEBOARD_FAB2_LIB.BASEBOARD_FAB2(SCH_1):FM_PE_BMC_WAKE_N
   2    GND      B @BASEBOARD_FAB2_LIB.BASEBOARD_FAB2(SCH_1):GND

RES_0402-33.2,1%,1/16W,CHIP,G2A  I67  R25W81
   1 SPI_BMC_BT_CLK      A @BASEBOARD_FAB2_LIB.BASEBOARD_FAB2(SCH_1):SPI_BMC_BT_CLK
   2 SPI_BMC_BT_CLK_R      B @BASEBOARD_FAB2_LIB.BASEBOARD_FAB2(SCH_1):SPI_BMC_BT_CLK_R

RES_0402-33.2,1%,1/16W,CHIP,G2A  I68  R25W82
   1 SPI_BMC_BT_DO      A @BASEBOARD_FAB2_LIB.BASEBOARD_FAB2(SCH_1):SPI_BMC_BT_DO
   2 SPI_BMC_BT_DO_R      B @BASEBOARD_FAB2_LIB.BASEBOARD_FAB2(SCH_1):SPI_BMC_BT_DO_R

RES_0402-22.1,1.0%,1/16W,CHIP,A  I69  R25W78
   1 SPI_BMC_BT_CS_N      A @BASEBOARD_FAB2_LIB.BASEBOARD_FAB2(SCH_1):SPI_BMC_BT_CS_N
   2 SPI_BMC_BT_CS_R_N      B @BASEBOARD_FAB2_LIB.BASEBOARD_FAB2(SCH_1):SPI_BMC_BT_CS_R_N

RES_0402-0.0,5%,1/16W,CHIP,G21A  I70  R25W74
   1 RST_PLTRST_BUF_N      A @BASEBOARD_FAB2_LIB.BASEBOARD_FAB2(SCH_1):RST_PLTRST_BUF_N
   2 RST_BMC_LVC3_N      B @BASEBOARD_FAB2_LIB.BASEBOARD_FAB2(SCH_1):RST_BMC_LVC3_N

RES_0402-33.2,1%,1/16W,CHIP,G2A  I71  R25W72
   1 LPC_LFRAME_N_CS0_N      A @BASEBOARD_FAB2_LIB.BASEBOARD_FAB2(SCH_1):LPC_LFRAME_N_CS0_N
   2 LPC_LFRAME_N_CS0_R_N      B @BASEBOARD_FAB2_LIB.BASEBOARD_FAB2(SCH_1):LPC_LFRAME_N_CS0_R_N

RES_0402-33.2,1%,1/16W,CHIP,G2A  I72  R25W71
   1 CLK_24M_BMC_LPC      A @BASEBOARD_FAB2_LIB.BASEBOARD_FAB2(SCH_1):CLK_24M_BMC_LPC
   2 CLK_24M_BMC_LPC_R1      B @BASEBOARD_FAB2_LIB.BASEBOARD_FAB2(SCH_1):CLK_24M_BMC_LPC_R1

RES_0402-33.2,1%,1/16W,CHIP,G2A  I73  R25W73
   1 IRQ_LPC_SERIRQ_N      A @BASEBOARD_FAB2_LIB.BASEBOARD_FAB2(SCH_1):IRQ_LPC_SERIRQ_N
   2 IRQ_LPC_SERIRQ_R      B @BASEBOARD_FAB2_LIB.BASEBOARD_FAB2(SCH_1):IRQ_LPC_SERIRQ_R

RES_0402-33.2,1%,1/16W,CHIP,G2A  I74  R3N24
   1 LPC_LAD2_IO2      A @BASEBOARD_FAB2_LIB.BASEBOARD_FAB2(SCH_1):LPC_LAD2_IO2
   2 LPC_LAD2_IO2_R      B @BASEBOARD_FAB2_LIB.BASEBOARD_FAB2(SCH_1):LPC_LAD2_IO2_R

RES_0402-33.2,1%,1/16W,CHIP,G2A  I75  R3N26
   1 LPC_LAD0_IO0      A @BASEBOARD_FAB2_LIB.BASEBOARD_FAB2(SCH_1):LPC_LAD0_IO0
   2 LPC_LAD0_IO0_R      B @BASEBOARD_FAB2_LIB.BASEBOARD_FAB2(SCH_1):LPC_LAD0_IO0_R

RES_0402-100.0K,1%,1/16W,CHIP,A  I76  R25W66
   1 CLK_24M_BMC_LPC_R1      A @BASEBOARD_FAB2_LIB.BASEBOARD_FAB2(SCH_1):CLK_24M_BMC_LPC_R1
   2    GND      B @BASEBOARD_FAB2_LIB.BASEBOARD_FAB2(SCH_1):GND

RES_0402-10.0K,1%,1/16W,CHIP,GA  I78  R1U7
   1    GND      A @BASEBOARD_FAB2_LIB.BASEBOARD_FAB2(SCH_1):GND
   2 PD_SP_ENTEST      B @BASEBOARD_FAB2_LIB.BASEBOARD_FAB2(SCH_1):PD_SP_ENTEST

RES_0402-33.2,1%,1/16W,CHIP,G2A  I84  R25W68
   1 LPC_LAD3_IO3      A @BASEBOARD_FAB2_LIB.BASEBOARD_FAB2(SCH_1):LPC_LAD3_IO3
   2 LPC_LAD3_IO3_R      B @BASEBOARD_FAB2_LIB.BASEBOARD_FAB2(SCH_1):LPC_LAD3_IO3_R

RES_0402-33.2,1%,1/16W,CHIP,G2A  I85  R25W69
   1 LPC_LAD1_IO1      A @BASEBOARD_FAB2_LIB.BASEBOARD_FAB2(SCH_1):LPC_LAD1_IO1
   2 LPC_LAD1_IO1_R      B @BASEBOARD_FAB2_LIB.BASEBOARD_FAB2(SCH_1):LPC_LAD1_IO1_R

RES_0402-22.1,1.0%,1/16W,CHIP,A  I96  R2T41
   1 IRQ_FORCE_NM_THROTTLE_N      A @BASEBOARD_FAB2_LIB.BASEBOARD_FAB2(SCH_1):IRQ_FORCE_NM_THROTTLE_N
   2 FM_BMC_SYS_THROTTLE_R_N      B @BASEBOARD_FAB2_LIB.BASEBOARD_FAB2(SCH_1):FM_BMC_SYS_THROTTLE_R_N

AST2520A1-GP-GP_ASIC2-GB1-AST2A  I104  U25W4
  B7 A_USB2BVRES USB2BVRES @BASEBOARD_FAB2_LIB.BASEBOARD_FAB2(SCH_1):A_USB2BVRES
  B8 A_USB2AVRES USB2AVRES @BASEBOARD_FAB2_LIB.BASEBOARD_FAB2(SCH_1):A_USB2AVRES
 A18 LED_POSTCODE_0 GPIOH0_NCTS6 @BASEBOARD_FAB2_LIB.BASEBOARD_FAB2(SCH_1):LED_POSTCODE_0
 D17 LED_POSTCODE_2 GPIOH2_NDSR6 @BASEBOARD_FAB2_LIB.BASEBOARD_FAB2(SCH_1):LED_POSTCODE_2
 B18 LED_POSTCODE_1 GPIOH1_NDCD6 @BASEBOARD_FAB2_LIB.BASEBOARD_FAB2(SCH_1):LED_POSTCODE_1
 A17 LED_POSTCODE_4 GPIOH4_NDTR6 @BASEBOARD_FAB2_LIB.BASEBOARD_FAB2(SCH_1):LED_POSTCODE_4
 C17 LED_POSTCODE_3 GPIOH3_NRI6 @BASEBOARD_FAB2_LIB.BASEBOARD_FAB2(SCH_1):LED_POSTCODE_3
 B17 LED_POSTCODE_5 GPIOH5_NRTS6 @BASEBOARD_FAB2_LIB.BASEBOARD_FAB2(SCH_1):LED_POSTCODE_5
 D18 LED_POSTCODE_7 GPIOH7_RXD6 @BASEBOARD_FAB2_LIB.BASEBOARD_FAB2(SCH_1):LED_POSTCODE_7
 A16 LED_POSTCODE_6 GPIOH6_TXD6 @BASEBOARD_FAB2_LIB.BASEBOARD_FAB2(SCH_1):LED_POSTCODE_6
 V20 FM_THROTTLE_N GPIOS0_VPOB2_SPI2CS1# @BASEBOARD_FAB2_LIB.BASEBOARD_FAB2(SCH_1):FM_THROTTLE_N
 R18 IRQ_MEZZ_LAN_ALERT_N GPIOS2_VPOB4_SALT5 @BASEBOARD_FAB2_LIB.BASEBOARD_FAB2(SCH_1):IRQ_MEZZ_LAN_ALERT_N
AB20 FM_BMC_NMI_N_R GPIOZ1_VPOG3_NORA1_SIOPWRGD @BASEBOARD_FAB2_LIB.BASEBOARD_FAB2(SCH_1):FM_BMC_NMI_N_R
AB21 FM_BMC_SYS_THROTTLE_R_N GPIOZ2_VPOG4_NORA2_SIOPBO# @BASEBOARD_FAB2_LIB.BASEBOARD_FAB2(SCH_1):FM_BMC_SYS_THROTTLE_R_N
AA21 IRQ_BMC_PCH_SCI_LPC_N GPIOZ3_VPOG5_NORA3_SIOSCI# @BASEBOARD_FAB2_LIB.BASEBOARD_FAB2(SCH_1):IRQ_BMC_PCH_SCI_LPC_N
 U21 HSC_SMBUS_SWITCH_EN GPIOZ4_VPOG6_NORA4 @BASEBOARD_FAB2_LIB.BASEBOARD_FAB2(SCH_1):HSC_SMBUS_SWITCH_EN
 W22 FM_CPU0_THERMTRIP_LATCH_LVT3_N GPIOZ5_VPOG7_NORA5 @BASEBOARD_FAB2_LIB.BASEBOARD_FAB2(SCH_1):FM_CPU0_THERMTRIP_LATCH_LVT3_N
 V22 H_CPU0_MEMABC_MEMHOT_LVT3_BMC_N GPIOZ6_VPOG8_NORA6 @BASEBOARD_FAB2_LIB.BASEBOARD_FAB2(SCH_1):H_CPU0_MEMABC_MEMHOT_LVT3_BMC_N
 W21 FM_CPU1_PROC_ID0 GPIOZ7_VPOG9_NORA7 @BASEBOARD_FAB2_LIB.BASEBOARD_FAB2(SCH_1):FM_CPU1_PROC_ID0
 Y21 FM_CPU1_PROC_ID1 GPIOAA0_VPOR2_NORD0_SALT7 @BASEBOARD_FAB2_LIB.BASEBOARD_FAB2(SCH_1):FM_CPU1_PROC_ID1
 P18 IRQ_LOM_ALERT_N GPIOS3_VPOB5_SALT6 @BASEBOARD_FAB2_LIB.BASEBOARD_FAB2(SCH_1):IRQ_LOM_ALERT_N
AA20 GPIOS7 GPIOS7_VPOB9 @BASEBOARD_FAB2_LIB.BASEBOARD_FAB2(SCH_1):GPIOS7
 Y20 FM_BIOS_SPI_BMC_CTRL GPIOZ0_VPOG2_NORA0_SIOPBI# @BASEBOARD_FAB2_LIB.BASEBOARD_FAB2(SCH_1):FM_BIOS_SPI_BMC_CTRL
 Y22 IRQ_OOB_MGMT_RISER_ALERT_N GPIOAA2_VPOR4_NORD2_SALT9 @BASEBOARD_FAB2_LIB.BASEBOARD_FAB2(SCH_1):IRQ_OOB_MGMT_RISER_ALERT_N
  A7 USB2_PCH_BMC_P5_DP USB2A_DP @BASEBOARD_FAB2_LIB.BASEBOARD_FAB2(SCH_1):USB2_PCH_BMC_P5_DP
  A8 USB2_PCH_BMC_P5_DN USB2A_DN @BASEBOARD_FAB2_LIB.BASEBOARD_FAB2(SCH_1):USB2_PCH_BMC_P5_DN
  B6 USB_PCH_BMC_P4_DP USB2B_DP @BASEBOARD_FAB2_LIB.BASEBOARD_FAB2(SCH_1):USB_PCH_BMC_P4_DP
  A6 USB_PCH_BMC_P4_DN USB2B_DN @BASEBOARD_FAB2_LIB.BASEBOARD_FAB2(SCH_1):USB_PCH_BMC_P4_DN
 U20 FP_PWR_ID_LED_N GPIOS6_VPOB8 @BASEBOARD_FAB2_LIB.BASEBOARD_FAB2(SCH_1):FP_PWR_ID_LED_N
 W20 FM_SPEAKER_PCH_N GPIOS5_VPOB7 @BASEBOARD_FAB2_LIB.BASEBOARD_FAB2(SCH_1):FM_SPEAKER_PCH_N
 R19 H_CPU0_MEMDEF_MEMHOT_LVT3_BMC_N GPIOS4_VPOB6 @BASEBOARD_FAB2_LIB.BASEBOARD_FAB2(SCH_1):H_CPU0_MEMDEF_MEMHOT_LVT3_BMC_N
 U19 FM_BMC_READY_N GPIOS1_VPOB3_BMCINT @BASEBOARD_FAB2_LIB.BASEBOARD_FAB2(SCH_1):FM_BMC_READY_N
 V21 IRQ_SML1_PMBUS_ALERT_N GPIOAA1_VPOR3_NORD1_SALT8 @BASEBOARD_FAB2_LIB.BASEBOARD_FAB2(SCH_1):IRQ_SML1_PMBUS_ALERT_N
 P19 FM_BIOS_POST_CMPLT_N GPIOAA7_VPOR9_NORD7_SALT14 @BASEBOARD_FAB2_LIB.BASEBOARD_FAB2(SCH_1):FM_BIOS_POST_CMPLT_N
 N18     NC GPIOAA6_VPOR8_NORD6_SALT13     NC
 T20     NC GPIOAA5_VPOR7_NORD5_SALT12     NC
 U22     NC GPIOAA4_VPOR6_NORD4_SALT11     NC
AA22     NC GPIOAA3_VPOR5_NORD3_SALT10     NC

AST2520A1-GP-GP_ASIC2-GB1-AST2A  I105  U25W4
 G22 RST_BMC_LVC3_N GPIOAC7_ESPIRST#_LPCRST# @BASEBOARD_FAB2_LIB.BASEBOARD_FAB2(SCH_1):RST_BMC_LVC3_N
  K3 PD_SP_ENTEST ENTEST @BASEBOARD_FAB2_LIB.BASEBOARD_FAB2(SCH_1):PD_SP_ENTEST
 V18     NC EXTRST#     NC
 B10 FM_CPU0_FIVR_FAULT_LVT3_R_N GPIOQ6_OSCCLK @BASEBOARD_FAB2_LIB.BASEBOARD_FAB2(SCH_1):FM_CPU0_FIVR_FAULT_LVT3_R_N
 N20 FM_PE_BMC_WAKE_N GPIOQ7_PEWAKE# @BASEBOARD_FAB2_LIB.BASEBOARD_FAB2(SCH_1):FM_PE_BMC_WAKE_N
 V19 SPI_BMC_DI GPIOR5_SPI2MISO @BASEBOARD_FAB2_LIB.BASEBOARD_FAB2(SCH_1):SPI_BMC_DI
 T17 SPI_BMC_CS0_N GPIOR2_SPI2CS0# @BASEBOARD_FAB2_LIB.BASEBOARD_FAB2(SCH_1):SPI_BMC_CS0_N
 T19 FM_CPU1_THERMTRIP_LATCH_LVT3_N GPIOR1_FWSPICS2# @BASEBOARD_FAB2_LIB.BASEBOARD_FAB2(SCH_1):FM_CPU1_THERMTRIP_LATCH_LVT3_N
AA19 SPI_BMC_BT_CS1_N GPIOR0_FWSPICS1# @BASEBOARD_FAB2_LIB.BASEBOARD_FAB2(SCH_1):SPI_BMC_BT_CS1_N
AB17 BMC_M_RST_N MRESET# @BASEBOARD_FAB2_LIB.BASEBOARD_FAB2(SCH_1):BMC_M_RST_N
 U16 BMC_M_MALERT_N MALERT# @BASEBOARD_FAB2_LIB.BASEBOARD_FAB2(SCH_1):BMC_M_MALERT_N
 Y18     NC HBLED#     NC
  N5 TP_VGAHS_GPIOJ4 GPIOJ4_VGAHS @BASEBOARD_FAB2_LIB.BASEBOARD_FAB2(SCH_1):TP_VGAHS_GPIOJ4
 U17 SPI_BMC_BT_DO_R FWSPIMOSI @BASEBOARD_FAB2_LIB.BASEBOARD_FAB2(SCH_1):SPI_BMC_BT_DO_R
AA18 SPI_BMC_BT_CLK_R FWSPICK @BASEBOARD_FAB2_LIB.BASEBOARD_FAB2(SCH_1):SPI_BMC_BT_CLK_R
  T3 TP_DDCDAT_GPIOJ7 GPIOJ7_DDCDAT @BASEBOARD_FAB2_LIB.BASEBOARD_FAB2(SCH_1):TP_DDCDAT_GPIOJ7
  R3 TP_DDCCLK_GPIOJ6 GPIOJ6_DDCCLK @BASEBOARD_FAB2_LIB.BASEBOARD_FAB2(SCH_1):TP_DDCCLK_GPIOJ6
  R4 TP_VGAVS_GPIOJ5 GPIOJ5_VGAVS @BASEBOARD_FAB2_LIB.BASEBOARD_FAB2(SCH_1):TP_VGAVS_GPIOJ5
 R20     NC GPIOAB3_VPOCLK_WDTRST2     NC
 T22     NC GPIOAB2_VPOVS_WDTRST1     NC
 T21     NC GPIOAB1_VPOHS_NORWE#     NC
 N19     NC GPIOAB0_VPODE_NOROE#     NC
 C22 CLK_24M_BMC_LPC_R1 GPIOAC4_ESPICK_LCLK @BASEBOARD_FAB2_LIB.BASEBOARD_FAB2(SCH_1):CLK_24M_BMC_LPC_R1
 E22 LPC_LAD3_IO3_R GPIOAC3_ESPID3_LAD3 @BASEBOARD_FAB2_LIB.BASEBOARD_FAB2(SCH_1):LPC_LAD3_IO3_R
 D22 LPC_LAD2_IO2_R GPIOAC2_ESPID2_LAD2 @BASEBOARD_FAB2_LIB.BASEBOARD_FAB2(SCH_1):LPC_LAD2_IO2_R
 G20 LPC_LAD1_IO1_R GPIOAC1_ESPID1_LAD1 @BASEBOARD_FAB2_LIB.BASEBOARD_FAB2(SCH_1):LPC_LAD1_IO1_R
 G21 LPC_LAD0_IO0_R GPIOAC0_ESPID0_LAD0 @BASEBOARD_FAB2_LIB.BASEBOARD_FAB2(SCH_1):LPC_LAD0_IO0_R
 T18 SPI_BMC_BT_DI FWSPIMISO @BASEBOARD_FAB2_LIB.BASEBOARD_FAB2(SCH_1):SPI_BMC_BT_DI
AB19 SPI_BMC_BT_CS_R_N FWSPICS0# @BASEBOARD_FAB2_LIB.BASEBOARD_FAB2(SCH_1):SPI_BMC_BT_CS_R_N
 F22 IRQ_LPC_SERIRQ_R GPIOAC6_ESPIALT#_LSIRQ# @BASEBOARD_FAB2_LIB.BASEBOARD_FAB2(SCH_1):IRQ_LPC_SERIRQ_R
 F21 LPC_LFRAME_N_CS0_R_N GPIOAC5_ESPICS#_LFRAME# @BASEBOARD_FAB2_LIB.BASEBOARD_FAB2(SCH_1):LPC_LFRAME_N_CS0_R_N
 Y19 SPI_BMC_CLK GPIOR3_SPI2CK @BASEBOARD_FAB2_LIB.BASEBOARD_FAB2(SCH_1):SPI_BMC_CLK
 W19 SPI_BMC_DO GPIOR4_SPI2MOSI @BASEBOARD_FAB2_LIB.BASEBOARD_FAB2(SCH_1):SPI_BMC_DO


DRAWING: @BASEBOARD_FAB2_LIB.BASEBOARD_FAB2(SCH_1):PAGE147 

RES_0402-22.1,1.0%,1/16W,CHIP,A  I21  R25W90
   1 RMII_BMC_PCH_SPRNGVLLE_TXD1_R      A @BASEBOARD_FAB2_LIB.BASEBOARD_FAB2(SCH_1):RMII_BMC_PCH_SPRNGVLLE_TXD1_R
   2 RMII_BMC_PCH_SPRNGVLLE_TXD1      B @BASEBOARD_FAB2_LIB.BASEBOARD_FAB2(SCH_1):RMII_BMC_PCH_SPRNGVLLE_TXD1

RES_0402-100.0K,1%,1/16W,CHIP,A  I62  R1U2
   1 FAN_TACH2      A @BASEBOARD_FAB2_LIB.BASEBOARD_FAB2(SCH_1):FAN_TACH2
   2    GND      B @BASEBOARD_FAB2_LIB.BASEBOARD_FAB2(SCH_1):GND

RES_0402-10.0K,1%,1/16W,CHIP,GA  I3  R25W92
   1 P3V3_STBY      A @BASEBOARD_FAB2_LIB.BASEBOARD_FAB2(SCH_1):P3V3_STBY
   2 RMII_BMC_PCH_SPRNGVLLE_TXD1      B @BASEBOARD_FAB2_LIB.BASEBOARD_FAB2(SCH_1):RMII_BMC_PCH_SPRNGVLLE_TXD1

RES_0402-10.0K,1%,1/16W,CHIP,GA  I4  R25W91
   1 P3V3_STBY      A @BASEBOARD_FAB2_LIB.BASEBOARD_FAB2(SCH_1):P3V3_STBY
   2 RMII_BMC_PCH_SPRNGVLLE_TXD0      B @BASEBOARD_FAB2_LIB.BASEBOARD_FAB2(SCH_1):RMII_BMC_PCH_SPRNGVLLE_TXD0

RES_0402-22.1,1.0%,1/16W,CHIP,A  I8  R25W88
   1 RMII_BMC_SPRNGVLLE_TXEN_R      A @BASEBOARD_FAB2_LIB.BASEBOARD_FAB2(SCH_1):RMII_BMC_SPRNGVLLE_TXEN_R
   2 RMII_BMC_PCH_SPRNGVLLE_TXEN      B @BASEBOARD_FAB2_LIB.BASEBOARD_FAB2(SCH_1):RMII_BMC_PCH_SPRNGVLLE_TXEN

RES_0402-22.1,1.0%,1/16W,CHIP,A  I22  R25W89
   1 RMII_BMC_PCH_SPRNGVLLE_TXD0_R      A @BASEBOARD_FAB2_LIB.BASEBOARD_FAB2(SCH_1):RMII_BMC_PCH_SPRNGVLLE_TXD0_R
   2 RMII_BMC_PCH_SPRNGVLLE_TXD0      B @BASEBOARD_FAB2_LIB.BASEBOARD_FAB2(SCH_1):RMII_BMC_PCH_SPRNGVLLE_TXD0

RES_0402-22.1,1.0%,1/16W,CHIP,A  I23  R25W85
   1 RMII_BMC_OCP_TXEN_R      A @BASEBOARD_FAB2_LIB.BASEBOARD_FAB2(SCH_1):RMII_BMC_OCP_TXEN_R
   2 RMII_BMC_OCP_TXEN      B @BASEBOARD_FAB2_LIB.BASEBOARD_FAB2(SCH_1):RMII_BMC_OCP_TXEN

RES_0402-22.1,1.0%,1/16W,CHIP,A  I24  R25W86
   1 RMII_BMC_OCP_TXD0_R      A @BASEBOARD_FAB2_LIB.BASEBOARD_FAB2(SCH_1):RMII_BMC_OCP_TXD0_R
   2 RMII_BMC_OCP_TXD0      B @BASEBOARD_FAB2_LIB.BASEBOARD_FAB2(SCH_1):RMII_BMC_OCP_TXD0

RES_0402-22.1,1.0%,1/16W,CHIP,A  I25  R25W87
   1 RMII_BMC_OCP_TXD1_R      A @BASEBOARD_FAB2_LIB.BASEBOARD_FAB2(SCH_1):RMII_BMC_OCP_TXD1_R
   2 RMII_BMC_OCP_TXD1      B @BASEBOARD_FAB2_LIB.BASEBOARD_FAB2(SCH_1):RMII_BMC_OCP_TXD1

CAP_0402-0.1UF,16V,10%,EMPTY,AA  I38  C25W8
   1 P3V3_STBY_BMC_ADCVREFN      A @BASEBOARD_FAB2_LIB.BASEBOARD_FAB2(SCH_1):P3V3_STBY_BMC_ADCVREFN
   2    GND      B @BASEBOARD_FAB2_LIB.BASEBOARD_FAB2(SCH_1):GND

CAP_0402-0.1UF,16V,10%,EMPTY,AA  I39  C25W9
   1 P3V3_STBY_BMC_ADCVREFN      A @BASEBOARD_FAB2_LIB.BASEBOARD_FAB2(SCH_1):P3V3_STBY_BMC_ADCVREFN
   2 P3V3_STBY_BMC_ADCVREFP      B @BASEBOARD_FAB2_LIB.BASEBOARD_FAB2(SCH_1):P3V3_STBY_BMC_ADCVREFP

RES_0402-2.7K,1%,1/16W,CHIP,G2A  I40  R25W57
   1    GND      A @BASEBOARD_FAB2_LIB.BASEBOARD_FAB2(SCH_1):GND
   2 PD_ADCREXT      B @BASEBOARD_FAB2_LIB.BASEBOARD_FAB2(SCH_1):PD_ADCREXT

RES_0402-10.0K,1%,1/16W,CHIP,GA  I42  R25W79
   1 P3V3_STBY      A @BASEBOARD_FAB2_LIB.BASEBOARD_FAB2(SCH_1):P3V3_STBY
   2 RMII_SPRNGVLLE_BMC_PCH_RXD0      B @BASEBOARD_FAB2_LIB.BASEBOARD_FAB2(SCH_1):RMII_SPRNGVLLE_BMC_PCH_RXD0

RES_0402-10.0K,1%,1/16W,CHIP,GA  I43  R25W80
   1 P3V3_STBY      A @BASEBOARD_FAB2_LIB.BASEBOARD_FAB2(SCH_1):P3V3_STBY
   2 RMII_SPRNGVLLE_BMC_PCH_RXD1      B @BASEBOARD_FAB2_LIB.BASEBOARD_FAB2(SCH_1):RMII_SPRNGVLLE_BMC_PCH_RXD1

RES_0402-100.0K,1%,1/16W,CHIP,A  I65  R1U4
   1 FAN_TACH1      A @BASEBOARD_FAB2_LIB.BASEBOARD_FAB2(SCH_1):FAN_TACH1
   2    GND      B @BASEBOARD_FAB2_LIB.BASEBOARD_FAB2(SCH_1):GND

RES_0402-100.0K,1%,1/16W,CHIP,A  I66  R1U5
   1 FAN_TACH0      A @BASEBOARD_FAB2_LIB.BASEBOARD_FAB2(SCH_1):FAN_TACH0
   2    GND      B @BASEBOARD_FAB2_LIB.BASEBOARD_FAB2(SCH_1):GND

CAP_0402-0.1UF,16V,10%,EMPTY,AA  I36  C25W7
   1 P3V3_STBY_BMC_ADCVREFP      A @BASEBOARD_FAB2_LIB.BASEBOARD_FAB2(SCH_1):P3V3_STBY_BMC_ADCVREFP
   2 VCC_ADCAV3V3      B @BASEBOARD_FAB2_LIB.BASEBOARD_FAB2(SCH_1):VCC_ADCAV3V3

RES_0402-100.0K,1%,1/16W,CHIP,A  I61  R1U1
   1 FAN_TACH3      A @BASEBOARD_FAB2_LIB.BASEBOARD_FAB2(SCH_1):FAN_TACH3
   2    GND      B @BASEBOARD_FAB2_LIB.BASEBOARD_FAB2(SCH_1):GND

RES_0402-10.0K,1%,1/16W,CHIP,GA  I75  R2N13
   1 FM_BIOS_PREFRB2_GOOD      A @BASEBOARD_FAB2_LIB.BASEBOARD_FAB2(SCH_1):FM_BIOS_PREFRB2_GOOD
   2    GND      B @BASEBOARD_FAB2_LIB.BASEBOARD_FAB2(SCH_1):GND

AST2520A1-GP-GP_ASIC2-GB1-AST2A  I106  U25W4
  F2     NC ADC8_GPIX0     NC
  G4 A_P3V_BAT_SCALED ADC7_GPIW7 @BASEBOARD_FAB2_LIB.BASEBOARD_FAB2(SCH_1):A_P3V_BAT_SCALED
 C13 FM_FORCE_ADR_N GPIOA6_TIMER7_MDC2 @BASEBOARD_FAB2_LIB.BASEBOARD_FAB2(SCH_1):FM_FORCE_ADR_N
 B13 FM_UV_ADR_TRIGGER_EN GPIOA7_TIMER8_MDIO2 @BASEBOARD_FAB2_LIB.BASEBOARD_FAB2(SCH_1):FM_UV_ADR_TRIGGER_EN
  D3    GND RGMIICK @BASEBOARD_FAB2_LIB.BASEBOARD_FAB2(SCH_1):GND
  Y3 FM_UARTSW_LSB_N GPION6_PWM6_VPIG6 @BASEBOARD_FAB2_LIB.BASEBOARD_FAB2(SCH_1):FM_UARTSW_LSB_N
  T4 FM_UARTSW_MSB_N GPION7_PWM7_VPIG7 @BASEBOARD_FAB2_LIB.BASEBOARD_FAB2(SCH_1):FM_UARTSW_MSB_N
  W3 FM_BACKUP_BIOS_SEL_N GPION4_PWM4_VPIG4 @BASEBOARD_FAB2_LIB.BASEBOARD_FAB2(SCH_1):FM_BACKUP_BIOS_SEL_N
 AA3 FM_CPLD_BMC_PWRDN_N GPION5_PWM5_VPIG5 @BASEBOARD_FAB2_LIB.BASEBOARD_FAB2(SCH_1):FM_CPLD_BMC_PWRDN_N
  U3 FM_CPU_MSMI_LVT3_N GPION3_PWM3_VPIG3 @BASEBOARD_FAB2_LIB.BASEBOARD_FAB2(SCH_1):FM_CPU_MSMI_LVT3_N
  W2 FAN_PWM_OUT_SYS1 GPION1_PWM1 @BASEBOARD_FAB2_LIB.BASEBOARD_FAB2(SCH_1):FAN_PWM_OUT_SYS1
  V3 FM_BIOS_PREFRB2_GOOD GPION2_PWM2_VPIG2 @BASEBOARD_FAB2_LIB.BASEBOARD_FAB2(SCH_1):FM_BIOS_PREFRB2_GOOD
  V2 FAN_PWM_OUT_SYS0 GPION0_PWM0 @BASEBOARD_FAB2_LIB.BASEBOARD_FAB2(SCH_1):FAN_PWM_OUT_SYS0
  H2 P3V3_STBY_BMC_ADCVREFP ADCVREFP @BASEBOARD_FAB2_LIB.BASEBOARD_FAB2(SCH_1):P3V3_STBY_BMC_ADCVREFP
  J1 PD_ADCREXT ADCREXT @BASEBOARD_FAB2_LIB.BASEBOARD_FAB2(SCH_1):PD_ADCREXT
  H1 P3V3_STBY_BMC_ADCVREFN ADCVREFN @BASEBOARD_FAB2_LIB.BASEBOARD_FAB2(SCH_1):P3V3_STBY_BMC_ADCVREFN
  H3     NC ADC14_GPIX6     NC
  H4     NC ADC15_GPIX7     NC
  G1     NC ADC13_GPIX5     NC
  H5     NC ADC12_GPIX4     NC
  F1     NC ADC11_GPIX3     NC
  G3     NC ADC9_GPIX1     NC
  G2     NC ADC10_GPIX2     NC
  G5 A_P3V3_STBY_SCALED ADC6_GPIW6 @BASEBOARD_FAB2_LIB.BASEBOARD_FAB2(SCH_1):A_P3V3_STBY_SCALED
  F3 A_P5V_SCALED ADC4_GPIW4 @BASEBOARD_FAB2_LIB.BASEBOARD_FAB2(SCH_1):A_P5V_SCALED
  E3 A_P12V_STBY_SCALED ADC5_GPIW5 @BASEBOARD_FAB2_LIB.BASEBOARD_FAB2(SCH_1):A_P12V_STBY_SCALED
  E1 A_P1V05_STBY_PCH_SENSOR ADC3_GPIW3 @BASEBOARD_FAB2_LIB.BASEBOARD_FAB2(SCH_1):A_P1V05_STBY_PCH_SENSOR
  E2 A_PVNN_STBY_PCH_SENSOR ADC2_GPIW2 @BASEBOARD_FAB2_LIB.BASEBOARD_FAB2(SCH_1):A_PVNN_STBY_PCH_SENSOR
  F5 A_P3V3_SCALED ADC1_GPIW1 @BASEBOARD_FAB2_LIB.BASEBOARD_FAB2(SCH_1):A_P3V3_SCALED
  F4 A_P5V_STBY_SCALED ADC0_GPIW0 @BASEBOARD_FAB2_LIB.BASEBOARD_FAB2(SCH_1):A_P5V_STBY_SCALED
  V6 FM_TPM_PRES_N GPIOP7_TACH15 @BASEBOARD_FAB2_LIB.BASEBOARD_FAB2(SCH_1):FM_TPM_PRES_N
  W6 FM_BOARD_SKU_ID4 GPIOP6_TACH14 @BASEBOARD_FAB2_LIB.BASEBOARD_FAB2(SCH_1):FM_BOARD_SKU_ID4
 AB5 FM_BOARD_SKU_ID1 GPIOP3_TACH11_VPIR9 @BASEBOARD_FAB2_LIB.BASEBOARD_FAB2(SCH_1):FM_BOARD_SKU_ID1
  Y6 FM_BOARD_SKU_ID2 GPIOP4_TACH12 @BASEBOARD_FAB2_LIB.BASEBOARD_FAB2(SCH_1):FM_BOARD_SKU_ID2
  Y5 FM_BOARD_SKU_ID3 GPIOP5_TACH13 @BASEBOARD_FAB2_LIB.BASEBOARD_FAB2(SCH_1):FM_BOARD_SKU_ID3
 AA5 FM_BOARD_SKU_ID0 GPIOP2_TACH10_VPIR8 @BASEBOARD_FAB2_LIB.BASEBOARD_FAB2(SCH_1):FM_BOARD_SKU_ID0
  W5 BMC_UV_HIGH_SET GPIOP1_TACH9_VPIR7 @BASEBOARD_FAB2_LIB.BASEBOARD_FAB2(SCH_1):BMC_UV_HIGH_SET
 AA4 FM_XRC_PRESENT_N GPIOO6_TACH6_VPIR4 @BASEBOARD_FAB2_LIB.BASEBOARD_FAB2(SCH_1):FM_XRC_PRESENT_N
  W4 FM_XRC_READY_N GPIOO7_TACH7_VPIR5 @BASEBOARD_FAB2_LIB.BASEBOARD_FAB2(SCH_1):FM_XRC_READY_N
  V4 BMC_TPM_HW_RST GPIOP0_TACH8_VPIR6 @BASEBOARD_FAB2_LIB.BASEBOARD_FAB2(SCH_1):BMC_TPM_HW_RST
 AB3 FM_POST_CARD_PRES_BMC_N GPIOO4_TACH4_VPIR2 @BASEBOARD_FAB2_LIB.BASEBOARD_FAB2(SCH_1):FM_POST_CARD_PRES_BMC_N
  Y4 FM_MP_PS_REDUNDANT_LOST_N GPIOO5_TACH5_VPIR3 @BASEBOARD_FAB2_LIB.BASEBOARD_FAB2(SCH_1):FM_MP_PS_REDUNDANT_LOST_N
 AB4 FAN_TACH3 GPIOO3_TACH3 @BASEBOARD_FAB2_LIB.BASEBOARD_FAB2(SCH_1):FAN_TACH3
  U4 FAN_TACH1 GPIOO1_TACH1_VPIG9 @BASEBOARD_FAB2_LIB.BASEBOARD_FAB2(SCH_1):FAN_TACH1
  V5 FAN_TACH2 GPIOO2_TACH2 @BASEBOARD_FAB2_LIB.BASEBOARD_FAB2(SCH_1):FAN_TACH2
  U5 FAN_TACH0 GPIOO0_TACH0_VPIG8 @BASEBOARD_FAB2_LIB.BASEBOARD_FAB2(SCH_1):FAN_TACH0
  B1 RMII_BMC_SPRNGVLLE_TXEN_R RGMII2TXCTL_RMII2TXEN_GPIOT7 @BASEBOARD_FAB2_LIB.BASEBOARD_FAB2(SCH_1):RMII_BMC_SPRNGVLLE_TXEN_R
  B2     NC RGMII2TXCK_RMII2RCLKO_GPIOT6     NC
  D5 TP_RGMII2TXD2_GPIOT4 RGMII2TXD2_GPIOU2 @BASEBOARD_FAB2_LIB.BASEBOARD_FAB2(SCH_1):TP_RGMII2TXD2_GPIOT4
  D4 TP_RGMII2TXD3_GPIOT5 RGMII2TXD3_GPIOU3 @BASEBOARD_FAB2_LIB.BASEBOARD_FAB2(SCH_1):TP_RGMII2TXD3_GPIOT5
  B3 RMII_BMC_PCH_SPRNGVLLE_TXD1_R RGMII2TXD1_RMII2TXD1_GPIOU1 @BASEBOARD_FAB2_LIB.BASEBOARD_FAB2(SCH_1):RMII_BMC_PCH_SPRNGVLLE_TXD1_R
  A2 RMII_BMC_PCH_SPRNGVLLE_TXD0_R RGMII2TXD0_RMII2TXD0_GPIOU0 @BASEBOARD_FAB2_LIB.BASEBOARD_FAB2(SCH_1):RMII_BMC_PCH_SPRNGVLLE_TXD0_R
  B5 H_CPU0_FAST_WAKE_LVT3_N RGMII1TXCK_RMII1RCLKO_GPIOT0 @BASEBOARD_FAB2_LIB.BASEBOARD_FAB2(SCH_1):H_CPU0_FAST_WAKE_LVT3_N
  E9 RMII_BMC_OCP_TXEN_R RGMII1TXCTL_RMII1TXEN_GPIOT1 @BASEBOARD_FAB2_LIB.BASEBOARD_FAB2(SCH_1):RMII_BMC_OCP_TXEN_R
  E7 TP_RGMII1TXD2_GPIOT4 RGMII1TXD2_GPIOT4 @BASEBOARD_FAB2_LIB.BASEBOARD_FAB2(SCH_1):TP_RGMII1TXD2_GPIOT4
  D7 TP_RGMII1TXD3_GPIOT5 RGMII1TXD3_GPIOT5 @BASEBOARD_FAB2_LIB.BASEBOARD_FAB2(SCH_1):TP_RGMII1TXD3_GPIOT5
  F9 RMII_BMC_OCP_TXD0_R RGMII1TXD0_RMII1TXD0_GPIOT2 @BASEBOARD_FAB2_LIB.BASEBOARD_FAB2(SCH_1):RMII_BMC_OCP_TXD0_R
  A5 RMII_BMC_OCP_TXD1_R RGMII1TXD1_RMII1TXD1_GPIOT3 @BASEBOARD_FAB2_LIB.BASEBOARD_FAB2(SCH_1):RMII_BMC_OCP_TXD1_R
  C1    GND RGMII2RXCTL_GPIOV3 @BASEBOARD_FAB2_LIB.BASEBOARD_FAB2(SCH_1):GND
  D8 FM_CPU0_PROC_ID0 GPIOR6_MDC1 @BASEBOARD_FAB2_LIB.BASEBOARD_FAB2(SCH_1):FM_CPU0_PROC_ID0
 E10 FM_CPU0_PROC_ID1 GPIOR7_MDIO1 @BASEBOARD_FAB2_LIB.BASEBOARD_FAB2(SCH_1):FM_CPU0_PROC_ID1
  A3 RMII_BMC_OCP_RXD0 RGMII1RXD0_RMII1RXD0_GPIOU6 @BASEBOARD_FAB2_LIB.BASEBOARD_FAB2(SCH_1):RMII_BMC_OCP_RXD0
  D6 RMII_BMC_OCP_RXD1 RGMII1RXD1_RMII1RXD1_GPIOU7 @BASEBOARD_FAB2_LIB.BASEBOARD_FAB2(SCH_1):RMII_BMC_OCP_RXD1
  C5 RMII_BMC_OCP_CRSDV RGMII1RXD2_RMII1CRSDV_GPIOV0 @BASEBOARD_FAB2_LIB.BASEBOARD_FAB2(SCH_1):RMII_BMC_OCP_CRSDV
  C4 RMII_BMC_OCP_RXER RGMII1RXD3_RMII1RXER_GPIOV1 @BASEBOARD_FAB2_LIB.BASEBOARD_FAB2(SCH_1):RMII_BMC_OCP_RXER
  A4 H_CPU1_MEMKLM_MEMHOT_LVT3_BMC_N RGMII1RXCTL_GPIOU5 @BASEBOARD_FAB2_LIB.BASEBOARD_FAB2(SCH_1):H_CPU1_MEMKLM_MEMHOT_LVT3_BMC_N
  B4 CLK_50M_CKMNG_BMC_1 RGMII1RXCK_RMII1RCLKI_GPIOU4 @BASEBOARD_FAB2_LIB.BASEBOARD_FAB2(SCH_1):CLK_50M_CKMNG_BMC_1
  C3 RMII_SPRNGVLLE_BMC_PCH_RXD0 RGMII2RXD0_RMII2RXD0_GPIOV4 @BASEBOARD_FAB2_LIB.BASEBOARD_FAB2(SCH_1):RMII_SPRNGVLLE_BMC_PCH_RXD0
  D1 RMII_SPRNGVLLE_BMC_PCH_RXD1 RGMII2RXD1_RMII2RXD1_GPIOV5 @BASEBOARD_FAB2_LIB.BASEBOARD_FAB2(SCH_1):RMII_SPRNGVLLE_BMC_PCH_RXD1
  D2 RMII_BMC_PCH_SPRNGVLLE_CRSDV RGMII2RXD2_RMII2CRSDV_GPIOV6 @BASEBOARD_FAB2_LIB.BASEBOARD_FAB2(SCH_1):RMII_BMC_PCH_SPRNGVLLE_CRSDV
  E6 RMII_BMC_PCH_SPRNGVLLE_RXER RGMII2RXD3_RMII2RXER_GPIOV7 @BASEBOARD_FAB2_LIB.BASEBOARD_FAB2(SCH_1):RMII_BMC_PCH_SPRNGVLLE_RXER
  C2 CLK_50M_CKMNG_BMC_2 RGMII2RXCK_RMII2RCLKI_GPIOV2 @BASEBOARD_FAB2_LIB.BASEBOARD_FAB2(SCH_1):CLK_50M_CKMNG_BMC_2


DRAWING: @BASEBOARD_FAB2_LIB.BASEBOARD_FAB2(SCH_1):PAGE151 

RES_0402-4.75K,1%,1/16W,CHIP,GA  I2  R25W95
   1 P3V3_STBY      A @BASEBOARD_FAB2_LIB.BASEBOARD_FAB2(SCH_1):P3V3_STBY
   2 SPI_BMC_BT_CLK      B @BASEBOARD_FAB2_LIB.BASEBOARD_FAB2(SCH_1):SPI_BMC_BT_CLK

RES_0402-4.75K,1%,1/16W,CHIP,GA  I9  R25W94
   1 P3V3_STBY      A @BASEBOARD_FAB2_LIB.BASEBOARD_FAB2(SCH_1):P3V3_STBY
   2 SPI_BMC_BT_CS_N      B @BASEBOARD_FAB2_LIB.BASEBOARD_FAB2(SCH_1):SPI_BMC_BT_CS_N

RES_0402-4.75K,1%,1/16W,CHIP,GA  I10  R25W96
   1 P3V3_STBY      A @BASEBOARD_FAB2_LIB.BASEBOARD_FAB2(SCH_1):P3V3_STBY
   2 SPI_BMC_BT_DO      B @BASEBOARD_FAB2_LIB.BASEBOARD_FAB2(SCH_1):SPI_BMC_BT_DO

RES_0402-4.75K,1%,1/16W,EMPTY,A  I11  R25W97
   1 P3V3_STBY      A @BASEBOARD_FAB2_LIB.BASEBOARD_FAB2(SCH_1):P3V3_STBY
   2 SPI_BMC_BT_DI      B @BASEBOARD_FAB2_LIB.BASEBOARD_FAB2(SCH_1):SPI_BMC_BT_DI

RES_0402-4.75K,1%,1/16W,CHIP,GA  I12  R25W98
   1 P3V3_STBY      A @BASEBOARD_FAB2_LIB.BASEBOARD_FAB2(SCH_1):P3V3_STBY
   2 H_CPU0_MEMDEF_MEMHOT_LVT3_BMC_N      B @BASEBOARD_FAB2_LIB.BASEBOARD_FAB2(SCH_1):H_CPU0_MEMDEF_MEMHOT_LVT3_BMC_N

RES_0402-4.75K,1%,1/16W,CHIP,GA  I13  R25W100
   1 P3V3_STBY      A @BASEBOARD_FAB2_LIB.BASEBOARD_FAB2(SCH_1):P3V3_STBY
   2 GPIOS7      B @BASEBOARD_FAB2_LIB.BASEBOARD_FAB2(SCH_1):GPIOS7

RES_0402-4.75K,1%,1/16W,EMPTY,A  I14  R25W99
   1 P3V3_STBY      A @BASEBOARD_FAB2_LIB.BASEBOARD_FAB2(SCH_1):P3V3_STBY
   2 FP_PWR_ID_LED_N      B @BASEBOARD_FAB2_LIB.BASEBOARD_FAB2(SCH_1):FP_PWR_ID_LED_N

RES_0402-4.75K,1%,1/16W,EMPTY,A  I27  R25W101
   1 P3V3_STBY      A @BASEBOARD_FAB2_LIB.BASEBOARD_FAB2(SCH_1):P3V3_STBY
   2 HSC_SMBUS_SWITCH_EN      B @BASEBOARD_FAB2_LIB.BASEBOARD_FAB2(SCH_1):HSC_SMBUS_SWITCH_EN

RES_0402-4.75K,1%,1/16W,CHIP,GA  I28  R25W102
   1 P3V3_STBY      A @BASEBOARD_FAB2_LIB.BASEBOARD_FAB2(SCH_1):P3V3_STBY
   2 FM_CPU0_THERMTRIP_LATCH_LVT3_N      B @BASEBOARD_FAB2_LIB.BASEBOARD_FAB2(SCH_1):FM_CPU0_THERMTRIP_LATCH_LVT3_N

RES_0402-4.75K,1%,1/16W,EMPTY,A  I29  R25W103
   1 P3V3_STBY      A @BASEBOARD_FAB2_LIB.BASEBOARD_FAB2(SCH_1):P3V3_STBY
   2 H_CPU0_MEMABC_MEMHOT_LVT3_BMC_N      B @BASEBOARD_FAB2_LIB.BASEBOARD_FAB2(SCH_1):H_CPU0_MEMABC_MEMHOT_LVT3_BMC_N

RES_0402-4.75K,1%,1/16W,EMPTY,A  I30  R25W104
   1 P3V3_STBY      A @BASEBOARD_FAB2_LIB.BASEBOARD_FAB2(SCH_1):P3V3_STBY
   2 FM_CPU1_PROC_ID0      B @BASEBOARD_FAB2_LIB.BASEBOARD_FAB2(SCH_1):FM_CPU1_PROC_ID0

RES_0402-4.75K,1%,1/16W,EMPTY,A  I31  R25W105
   1 P3V3_STBY      A @BASEBOARD_FAB2_LIB.BASEBOARD_FAB2(SCH_1):P3V3_STBY
   2 JTAG_BMC_TRST_N      B @BASEBOARD_FAB2_LIB.BASEBOARD_FAB2(SCH_1):JTAG_BMC_TRST_N

RES_0402-4.75K,1%,1/16W,EMPTY,A  I32  R25W106
   1 P3V3_STBY      A @BASEBOARD_FAB2_LIB.BASEBOARD_FAB2(SCH_1):P3V3_STBY
   2 RMII_BMC_OCP_TXEN      B @BASEBOARD_FAB2_LIB.BASEBOARD_FAB2(SCH_1):RMII_BMC_OCP_TXEN

RES_0402-4.75K,1%,1/16W,EMPTY,A  I33  R25W107
   1 P3V3_STBY      A @BASEBOARD_FAB2_LIB.BASEBOARD_FAB2(SCH_1):P3V3_STBY
   2 RMII_BMC_OCP_TXD0_R      B @BASEBOARD_FAB2_LIB.BASEBOARD_FAB2(SCH_1):RMII_BMC_OCP_TXD0_R

RES_0402-4.75K,1%,1/16W,CHIP,GA  I34  R25W108
   1 P3V3_STBY      A @BASEBOARD_FAB2_LIB.BASEBOARD_FAB2(SCH_1):P3V3_STBY
   2 RMII_BMC_OCP_TXD1_R      B @BASEBOARD_FAB2_LIB.BASEBOARD_FAB2(SCH_1):RMII_BMC_OCP_TXD1_R

RES_0402-4.75K,1%,1/16W,EMPTY,A  I35  R25W109
   1 P3V3_STBY      A @BASEBOARD_FAB2_LIB.BASEBOARD_FAB2(SCH_1):P3V3_STBY
   2 TP_RGMII2TXD3_GPIOT5      B @BASEBOARD_FAB2_LIB.BASEBOARD_FAB2(SCH_1):TP_RGMII2TXD3_GPIOT5

RES_0402-4.75K,1%,1/16W,CHIP,GA  I36  R25W110
   1 P3V3_STBY      A @BASEBOARD_FAB2_LIB.BASEBOARD_FAB2(SCH_1):P3V3_STBY
   2 TP_RGMII2TXD2_GPIOT4      B @BASEBOARD_FAB2_LIB.BASEBOARD_FAB2(SCH_1):TP_RGMII2TXD2_GPIOT4

RES_0402-4.75K,1%,1/16W,EMPTY,A  I43  R25W111
   1 P3V3_STBY      A @BASEBOARD_FAB2_LIB.BASEBOARD_FAB2(SCH_1):P3V3_STBY
   2 RMII_BMC_PCH_SPRNGVLLE_TXEN      B @BASEBOARD_FAB2_LIB.BASEBOARD_FAB2(SCH_1):RMII_BMC_PCH_SPRNGVLLE_TXEN

RES_0402-4.75K,1%,1/16W,EMPTY,A  I44  R25W112
   1 P3V3_STBY      A @BASEBOARD_FAB2_LIB.BASEBOARD_FAB2(SCH_1):P3V3_STBY
   2 RMII_BMC_PCH_SPRNGVLLE_TXD0_R      B @BASEBOARD_FAB2_LIB.BASEBOARD_FAB2(SCH_1):RMII_BMC_PCH_SPRNGVLLE_TXD0_R

RES_0402-4.75K,1%,1/16W,EMPTY,A  I45  R25W113
   1 P3V3_STBY      A @BASEBOARD_FAB2_LIB.BASEBOARD_FAB2(SCH_1):P3V3_STBY
   2 RMII_BMC_PCH_SPRNGVLLE_TXD1_R      B @BASEBOARD_FAB2_LIB.BASEBOARD_FAB2(SCH_1):RMII_BMC_PCH_SPRNGVLLE_TXD1_R

RES_0402-4.75K,1%,1/16W,EMPTY,A  I46  R25W114
   1 P3V3_STBY      A @BASEBOARD_FAB2_LIB.BASEBOARD_FAB2(SCH_1):P3V3_STBY
   2 TP_RGMII1TXD2_GPIOT4      B @BASEBOARD_FAB2_LIB.BASEBOARD_FAB2(SCH_1):TP_RGMII1TXD2_GPIOT4

RES_0402-4.75K,1%,1/16W,CHIP,GA  I47  R25W115
   1 P3V3_STBY      A @BASEBOARD_FAB2_LIB.BASEBOARD_FAB2(SCH_1):P3V3_STBY
   2 TP_RGMII1TXD3_GPIOT5      B @BASEBOARD_FAB2_LIB.BASEBOARD_FAB2(SCH_1):TP_RGMII1TXD3_GPIOT5

RES_0402-3.32K,1%,1/16W,CHIP,GA  I48  R25W116
   1    GND      A @BASEBOARD_FAB2_LIB.BASEBOARD_FAB2(SCH_1):GND
   2 UART_BMC_TXD5      B @BASEBOARD_FAB2_LIB.BASEBOARD_FAB2(SCH_1):UART_BMC_TXD5


DRAWING: @BASEBOARD_FAB2_LIB.BASEBOARD_FAB2(SCH_1):PAGE150 

CAP_0402-1.0UF,6.3V,10%,X6S,D9A  I1  C25W60
   1 P3V3_STBY      A @BASEBOARD_FAB2_LIB.BASEBOARD_FAB2(SCH_1):P3V3_STBY
   2    GND      B @BASEBOARD_FAB2_LIB.BASEBOARD_FAB2(SCH_1):GND

SC4D7U10V3KX-GP_SMD-BCG-SC4D7UA  I2  C25W65
   1 VCC_D_PLL_3V3      1 @BASEBOARD_FAB2_LIB.BASEBOARD_FAB2(SCH_1):VCC_D_PLL_3V3
   2    GND      2 @BASEBOARD_FAB2_LIB.BASEBOARD_FAB2(SCH_1):GND

CAP_0402-1.0UF,6.3V,10%,X6S,D9A  I4  C25W71
   1 P3V3_USB2A_ALG      A @BASEBOARD_FAB2_LIB.BASEBOARD_FAB2(SCH_1):P3V3_USB2A_ALG
   2    GND      B @BASEBOARD_FAB2_LIB.BASEBOARD_FAB2(SCH_1):GND

SC4D7U10V3KX-GP_SMD-BCG-SC4D7UA  I6  C25W70
   1 P3V3_USB2A_ALG      1 @BASEBOARD_FAB2_LIB.BASEBOARD_FAB2(SCH_1):P3V3_USB2A_ALG
   2    GND      2 @BASEBOARD_FAB2_LIB.BASEBOARD_FAB2(SCH_1):GND

0R3J-0-U-GP_RCL_GP-0R3J-0-U-GPA  I7  R25W120
   1 P3V3_STBY      1 @BASEBOARD_FAB2_LIB.BASEBOARD_FAB2(SCH_1):P3V3_STBY
   2 P3V3_USB2A_ALG      2 @BASEBOARD_FAB2_LIB.BASEBOARD_FAB2(SCH_1):P3V3_USB2A_ALG

SCD1U16V2KX-3GP_SMD-BCG-SCD1U1A  I10  C25W55
   1 P1V2_AUX_BMC      1 @BASEBOARD_FAB2_LIB.BASEBOARD_FAB2(SCH_1):P1V2_AUX_BMC
   2    GND      2 @BASEBOARD_FAB2_LIB.BASEBOARD_FAB2(SCH_1):GND

CAP_0402-1.0UF,6.3V,10%,X6S,D9A  I12  C25W54
   1 P1V2_AUX_BMC      A @BASEBOARD_FAB2_LIB.BASEBOARD_FAB2(SCH_1):P1V2_AUX_BMC
   2    GND      B @BASEBOARD_FAB2_LIB.BASEBOARD_FAB2(SCH_1):GND

CAP_0402-1.0UF,6.3V,10%,X6S,D9A  I13  C25W53
   1 P1V2_AUX_BMC      A @BASEBOARD_FAB2_LIB.BASEBOARD_FAB2(SCH_1):P1V2_AUX_BMC
   2    GND      B @BASEBOARD_FAB2_LIB.BASEBOARD_FAB2(SCH_1):GND

CAP_0402-1.0UF,6.3V,10%,X6S,D9A  I14  C25W52
   1 P1V2_AUX_BMC      A @BASEBOARD_FAB2_LIB.BASEBOARD_FAB2(SCH_1):P1V2_AUX_BMC
   2    GND      B @BASEBOARD_FAB2_LIB.BASEBOARD_FAB2(SCH_1):GND

SC4D7U10V3KX-GP_SMD-BCG-SC4D7UA  I17  C25W39
   1 VCC_A_1V1      1 @BASEBOARD_FAB2_LIB.BASEBOARD_FAB2(SCH_1):VCC_A_1V1
   2    GND      2 @BASEBOARD_FAB2_LIB.BASEBOARD_FAB2(SCH_1):GND

SCD1U16V2KX-3GP_SMD-BCG-SCD1U1A  I18  C25W38
   1 VCC_A_1V1      1 @BASEBOARD_FAB2_LIB.BASEBOARD_FAB2(SCH_1):VCC_A_1V1
   2    GND      2 @BASEBOARD_FAB2_LIB.BASEBOARD_FAB2(SCH_1):GND

CAP_0402-1.0UF,6.3V,10%,X6S,D9A  I19  C25W51
   1 P1V2_AUX_BMC      A @BASEBOARD_FAB2_LIB.BASEBOARD_FAB2(SCH_1):P1V2_AUX_BMC
   2    GND      B @BASEBOARD_FAB2_LIB.BASEBOARD_FAB2(SCH_1):GND

SC4D7U10V3KX-GP_SMD-BCG-SC4D7UA  I21  C25W50
   1 P3V3_STBY      1 @BASEBOARD_FAB2_LIB.BASEBOARD_FAB2(SCH_1):P3V3_STBY
   2    GND      2 @BASEBOARD_FAB2_LIB.BASEBOARD_FAB2(SCH_1):GND

SCD1U16V2KX-3GP_SMD-BCG-SCD1U1A  I24  C25W64
   1 VCC_D_PLL_3V3      1 @BASEBOARD_FAB2_LIB.BASEBOARD_FAB2(SCH_1):VCC_D_PLL_3V3
   2    GND      2 @BASEBOARD_FAB2_LIB.BASEBOARD_FAB2(SCH_1):GND

CAP_0402-1.0UF,6.3V,10%,X6S,D9A  I25  C25W63
   1 VCC_D_PLL_3V3      A @BASEBOARD_FAB2_LIB.BASEBOARD_FAB2(SCH_1):VCC_D_PLL_3V3
   2    GND      B @BASEBOARD_FAB2_LIB.BASEBOARD_FAB2(SCH_1):GND

HCB1608KF-800T30-GP_DISCRET-G9A  I26  FB2T6
   1 P3V3_STBY      1 @BASEBOARD_FAB2_LIB.BASEBOARD_FAB2(SCH_1):P3V3_STBY
   2 VCC_D_PLL_3V3      2 @BASEBOARD_FAB2_LIB.BASEBOARD_FAB2(SCH_1):VCC_D_PLL_3V3

SC4D7U10V3KX-GP_SMD-BCG-SC4D7UA  I28  C25W69
   1 VCC_VA_3V3      1 @BASEBOARD_FAB2_LIB.BASEBOARD_FAB2(SCH_1):VCC_VA_3V3
   2    GND      2 @BASEBOARD_FAB2_LIB.BASEBOARD_FAB2(SCH_1):GND

SCD1U16V2KX-3GP_SMD-BCG-SCD1U1A  I30  C25W68
   1 VCC_VA_3V3      1 @BASEBOARD_FAB2_LIB.BASEBOARD_FAB2(SCH_1):VCC_VA_3V3
   2    GND      2 @BASEBOARD_FAB2_LIB.BASEBOARD_FAB2(SCH_1):GND

CAP_0402-1.0UF,6.3V,10%,X6S,D9A  I31  C25W67
   1 VCC_VA_3V3      A @BASEBOARD_FAB2_LIB.BASEBOARD_FAB2(SCH_1):VCC_VA_3V3
   2    GND      B @BASEBOARD_FAB2_LIB.BASEBOARD_FAB2(SCH_1):GND

HCB1608KF-800T30-GP_DISCRET-G9A  I32  FB2T1
   1 P3V3_STBY      1 @BASEBOARD_FAB2_LIB.BASEBOARD_FAB2(SCH_1):P3V3_STBY
   2 VCC_VA_3V3      2 @BASEBOARD_FAB2_LIB.BASEBOARD_FAB2(SCH_1):VCC_VA_3V3

CAP_0402-1.0UF,6.3V,10%,X6S,D9A  I33  C25W66
   1 VCC_VA_3V3      A @BASEBOARD_FAB2_LIB.BASEBOARD_FAB2(SCH_1):VCC_VA_3V3
   2    GND      B @BASEBOARD_FAB2_LIB.BASEBOARD_FAB2(SCH_1):GND

CAP_0402-1.0UF,6.3V,10%,X6S,D9A  I35  C25W37
   1 VCC_A_1V1      A @BASEBOARD_FAB2_LIB.BASEBOARD_FAB2(SCH_1):VCC_A_1V1
   2    GND      B @BASEBOARD_FAB2_LIB.BASEBOARD_FAB2(SCH_1):GND

SCD1U16V2KX-3GP_SMD-BCG-SCD1U1A  I36  C25W49
   1 P3V3_STBY      1 @BASEBOARD_FAB2_LIB.BASEBOARD_FAB2(SCH_1):P3V3_STBY
   2    GND      2 @BASEBOARD_FAB2_LIB.BASEBOARD_FAB2(SCH_1):GND

CAP_0402-1.0UF,6.3V,10%,X6S,D9A  I38  C25W48
   1 P3V3_STBY      A @BASEBOARD_FAB2_LIB.BASEBOARD_FAB2(SCH_1):P3V3_STBY
   2    GND      B @BASEBOARD_FAB2_LIB.BASEBOARD_FAB2(SCH_1):GND

HCB1608KF-800T30-GP_DISCRET-G9A  I39  FB2T7
   1 P1V15_AUX_BMC      1 @BASEBOARD_FAB2_LIB.BASEBOARD_FAB2(SCH_1):P1V15_AUX_BMC
   2 VCC_A_1V1      2 @BASEBOARD_FAB2_LIB.BASEBOARD_FAB2(SCH_1):VCC_A_1V1

SC4D7U10V3KX-GP_SMD-BCG-SC4D7UA  I43  C25W30
   1 P1V15_AUX_BMC      1 @BASEBOARD_FAB2_LIB.BASEBOARD_FAB2(SCH_1):P1V15_AUX_BMC
   2    GND      2 @BASEBOARD_FAB2_LIB.BASEBOARD_FAB2(SCH_1):GND

CAP_0805-10UF,16V,10%,X6S,C953A  I45  C25W29
   1 P1V15_AUX_BMC      A @BASEBOARD_FAB2_LIB.BASEBOARD_FAB2(SCH_1):P1V15_AUX_BMC
   2    GND      B @BASEBOARD_FAB2_LIB.BASEBOARD_FAB2(SCH_1):GND

CAP_0402-1.0UF,6.3V,10%,X6S,D9A  I46  C25W28
   1 P1V15_AUX_BMC      A @BASEBOARD_FAB2_LIB.BASEBOARD_FAB2(SCH_1):P1V15_AUX_BMC
   2    GND      B @BASEBOARD_FAB2_LIB.BASEBOARD_FAB2(SCH_1):GND

CAP_0402-1.0UF,6.3V,10%,X6S,D9A  I48  C25W27
   1 P1V15_AUX_BMC      A @BASEBOARD_FAB2_LIB.BASEBOARD_FAB2(SCH_1):P1V15_AUX_BMC
   2    GND      B @BASEBOARD_FAB2_LIB.BASEBOARD_FAB2(SCH_1):GND

SC4D7U10V3KX-GP_SMD-BCG-SC4D7UA  I50  C25W36
   1 VCC_DACAV3V3      1 @BASEBOARD_FAB2_LIB.BASEBOARD_FAB2(SCH_1):VCC_DACAV3V3
   2    GND      2 @BASEBOARD_FAB2_LIB.BASEBOARD_FAB2(SCH_1):GND

CAP_0402-1.0UF,6.3V,10%,X6S,D9A  I51  C25W35
   1 VCC_DACAV3V3      A @BASEBOARD_FAB2_LIB.BASEBOARD_FAB2(SCH_1):VCC_DACAV3V3
   2    GND      B @BASEBOARD_FAB2_LIB.BASEBOARD_FAB2(SCH_1):GND

SCD1U16V2KX-3GP_SMD-BCG-SCD1U1A  I53  C25W34
   1 VCC_DACAV3V3      1 @BASEBOARD_FAB2_LIB.BASEBOARD_FAB2(SCH_1):VCC_DACAV3V3
   2    GND      2 @BASEBOARD_FAB2_LIB.BASEBOARD_FAB2(SCH_1):GND

SC4D7U10V3KX-GP_SMD-BCG-SC4D7UA  I54  C25W47
   1 VCC_D_3V3      1 @BASEBOARD_FAB2_LIB.BASEBOARD_FAB2(SCH_1):VCC_D_3V3
   2    GND      2 @BASEBOARD_FAB2_LIB.BASEBOARD_FAB2(SCH_1):GND

CAP_0805-10UF,16V,10%,X6S,C953A  I55  C25W46
   1 VCC_D_3V3      A @BASEBOARD_FAB2_LIB.BASEBOARD_FAB2(SCH_1):VCC_D_3V3
   2    GND      B @BASEBOARD_FAB2_LIB.BASEBOARD_FAB2(SCH_1):GND

0R3J-0-U-GP_RCL_GP-0R3J-0-U-GPA  I57  R25W93
   1 P3V3_STBY      1 @BASEBOARD_FAB2_LIB.BASEBOARD_FAB2(SCH_1):P3V3_STBY
   2 VCC_DACAV3V3      2 @BASEBOARD_FAB2_LIB.BASEBOARD_FAB2(SCH_1):VCC_DACAV3V3

CAP_0402-1.0UF,6.3V,10%,X6S,D9A  I59  C25W33
   1 VCC_ADCAV3V3      A @BASEBOARD_FAB2_LIB.BASEBOARD_FAB2(SCH_1):VCC_ADCAV3V3
   2    GND      B @BASEBOARD_FAB2_LIB.BASEBOARD_FAB2(SCH_1):GND

SCD1U16V2KX-3GP_SMD-BCG-SCD1U1A  I61  C25W45
   1 VCC_D_3V3      1 @BASEBOARD_FAB2_LIB.BASEBOARD_FAB2(SCH_1):VCC_D_3V3
   2    GND      2 @BASEBOARD_FAB2_LIB.BASEBOARD_FAB2(SCH_1):GND

CAP_0402-1.0UF,6.3V,10%,X6S,D9A  I62  C25W44
   1 VCC_D_3V3      A @BASEBOARD_FAB2_LIB.BASEBOARD_FAB2(SCH_1):VCC_D_3V3
   2    GND      B @BASEBOARD_FAB2_LIB.BASEBOARD_FAB2(SCH_1):GND

CAP_0402-1.0UF,6.3V,10%,X6S,D9A  I63  C25W43
   1 VCC_D_3V3      A @BASEBOARD_FAB2_LIB.BASEBOARD_FAB2(SCH_1):VCC_D_3V3
   2    GND      B @BASEBOARD_FAB2_LIB.BASEBOARD_FAB2(SCH_1):GND

SC4D7U10V3KX-GP_SMD-BCG-SC4D7UA  I65  C25W62
   1 P3V3_STBY      1 @BASEBOARD_FAB2_LIB.BASEBOARD_FAB2(SCH_1):P3V3_STBY
   2    GND      2 @BASEBOARD_FAB2_LIB.BASEBOARD_FAB2(SCH_1):GND

SCD1U16V2KX-3GP_SMD-BCG-SCD1U1A  I67  C25W61
   1 P3V3_STBY      1 @BASEBOARD_FAB2_LIB.BASEBOARD_FAB2(SCH_1):P3V3_STBY
   2    GND      2 @BASEBOARD_FAB2_LIB.BASEBOARD_FAB2(SCH_1):GND

SC4D7U10V3KX-GP_SMD-BCG-SC4D7UA  I69  C25W59
   1 VCC_PA_3V3      1 @BASEBOARD_FAB2_LIB.BASEBOARD_FAB2(SCH_1):VCC_PA_3V3
   2    GND      2 @BASEBOARD_FAB2_LIB.BASEBOARD_FAB2(SCH_1):GND

CAP_0402-1.0UF,6.3V,10%,X6S,D9A  I71  C25W26
   1 P1V15_AUX_BMC      A @BASEBOARD_FAB2_LIB.BASEBOARD_FAB2(SCH_1):P1V15_AUX_BMC
   2    GND      B @BASEBOARD_FAB2_LIB.BASEBOARD_FAB2(SCH_1):GND

CAP_0402-1.0UF,6.3V,10%,X6S,D9A  I72  C25W25
   1 P1V15_AUX_BMC      A @BASEBOARD_FAB2_LIB.BASEBOARD_FAB2(SCH_1):P1V15_AUX_BMC
   2    GND      B @BASEBOARD_FAB2_LIB.BASEBOARD_FAB2(SCH_1):GND

CAP_0402-1.0UF,6.3V,10%,X6S,D9A  I73  C25W24
   1 P1V15_AUX_BMC      A @BASEBOARD_FAB2_LIB.BASEBOARD_FAB2(SCH_1):P1V15_AUX_BMC
   2    GND      B @BASEBOARD_FAB2_LIB.BASEBOARD_FAB2(SCH_1):GND

CAP_0402-1.0UF,6.3V,10%,X6S,D9A  I75  C25W23
   1 P1V15_AUX_BMC      A @BASEBOARD_FAB2_LIB.BASEBOARD_FAB2(SCH_1):P1V15_AUX_BMC
   2    GND      B @BASEBOARD_FAB2_LIB.BASEBOARD_FAB2(SCH_1):GND

HCB1608KF-800T30-GP_DISCRET-G9A  I76  FB2T3
   1 P3V3_STBY      1 @BASEBOARD_FAB2_LIB.BASEBOARD_FAB2(SCH_1):P3V3_STBY
   2 VCC_ADCAV3V3      2 @BASEBOARD_FAB2_LIB.BASEBOARD_FAB2(SCH_1):VCC_ADCAV3V3

CAP_0402-1.0UF,6.3V,10%,X6S,D9A  I78  C25W32
   1 VCC_ADCAV3V3      A @BASEBOARD_FAB2_LIB.BASEBOARD_FAB2(SCH_1):VCC_ADCAV3V3
   2    GND      B @BASEBOARD_FAB2_LIB.BASEBOARD_FAB2(SCH_1):GND

SCD1U16V2KX-3GP_SMD-BCG-SCD1U1A  I79  C25W31
   1 VCC_ADCAV3V3      1 @BASEBOARD_FAB2_LIB.BASEBOARD_FAB2(SCH_1):VCC_ADCAV3V3
   2    GND      2 @BASEBOARD_FAB2_LIB.BASEBOARD_FAB2(SCH_1):GND

CAP_0402-1.0UF,6.3V,10%,X6S,D9A  I80  C25W42
   1 VCC_D_3V3      A @BASEBOARD_FAB2_LIB.BASEBOARD_FAB2(SCH_1):VCC_D_3V3
   2    GND      B @BASEBOARD_FAB2_LIB.BASEBOARD_FAB2(SCH_1):GND

CAP_0402-1.0UF,6.3V,10%,X6S,D9A  I81  C25W41
   1 VCC_D_3V3      A @BASEBOARD_FAB2_LIB.BASEBOARD_FAB2(SCH_1):VCC_D_3V3
   2    GND      B @BASEBOARD_FAB2_LIB.BASEBOARD_FAB2(SCH_1):GND

CAP_0402-1.0UF,6.3V,10%,X6S,D9A  I82  C25W40
   1 VCC_D_3V3      A @BASEBOARD_FAB2_LIB.BASEBOARD_FAB2(SCH_1):VCC_D_3V3
   2    GND      B @BASEBOARD_FAB2_LIB.BASEBOARD_FAB2(SCH_1):GND

HCB1608KF-800T30-GP_DISCRET-G9A  I84  FB2T4
   1 P3V3_STBY      1 @BASEBOARD_FAB2_LIB.BASEBOARD_FAB2(SCH_1):P3V3_STBY
   2 VCC_D_3V3      2 @BASEBOARD_FAB2_LIB.BASEBOARD_FAB2(SCH_1):VCC_D_3V3

SCD1U16V2KX-3GP_SMD-BCG-SCD1U1A  I85  C25W58
   1 VCC_PA_3V3      1 @BASEBOARD_FAB2_LIB.BASEBOARD_FAB2(SCH_1):VCC_PA_3V3
   2    GND      2 @BASEBOARD_FAB2_LIB.BASEBOARD_FAB2(SCH_1):GND

CAP_0402-1.0UF,6.3V,10%,X6S,D9A  I86  C25W57
   1 VCC_PA_3V3      A @BASEBOARD_FAB2_LIB.BASEBOARD_FAB2(SCH_1):VCC_PA_3V3
   2    GND      B @BASEBOARD_FAB2_LIB.BASEBOARD_FAB2(SCH_1):GND

CAP_0402-1.0UF,6.3V,10%,X6S,D9A  I87  C25W56
   1 VCC_PA_3V3      A @BASEBOARD_FAB2_LIB.BASEBOARD_FAB2(SCH_1):VCC_PA_3V3
   2    GND      B @BASEBOARD_FAB2_LIB.BASEBOARD_FAB2(SCH_1):GND

HCB1608KF-800T30-GP_DISCRET-G9A  I89  FB2T5
   1 P3V3_STBY      1 @BASEBOARD_FAB2_LIB.BASEBOARD_FAB2(SCH_1):P3V3_STBY
   2 VCC_PA_3V3      2 @BASEBOARD_FAB2_LIB.BASEBOARD_FAB2(SCH_1):VCC_PA_3V3


DRAWING: @BASEBOARD_FAB2_LIB.BASEBOARD_FAB2(SCH_1):PAGE148 

RES_0402-0.0,5%,1/16W,CHIP,G21A  I16  R25W59
   1 P3V3_STBY      A @BASEBOARD_FAB2_LIB.BASEBOARD_FAB2(SCH_1):P3V3_STBY
   2 VCCBAT_TW12      B @BASEBOARD_FAB2_LIB.BASEBOARD_FAB2(SCH_1):VCCBAT_TW12

CAP_A_0402V-1.0UF,6.3V,10%,X6SA  I20  C1T21
   1 PVCCIO_CPU0      A @BASEBOARD_FAB2_LIB.BASEBOARD_FAB2(SCH_1):PVCCIO_CPU0
   2    GND      B @BASEBOARD_FAB2_LIB.BASEBOARD_FAB2(SCH_1):GND

RES_0402-33.2,1%,1/16W,CHIP,G2A  I23  R25W75
   1 FM_CPU1_FIVR_FAULT_LVT3_N      A @BASEBOARD_FAB2_LIB.BASEBOARD_FAB2(SCH_1):FM_CPU1_FIVR_FAULT_LVT3_N
   2 FM_CPU1_FIVR_FAULT_LVT3_R_N      B @BASEBOARD_FAB2_LIB.BASEBOARD_FAB2(SCH_1):FM_CPU1_FIVR_FAULT_LVT3_R_N

AST2520A1-GP-GP_ASIC2-GB1-AST2A  I28  U25W4
 K17 P3V3_STBY LPVDD1 @BASEBOARD_FAB2_LIB.BASEBOARD_FAB2(SCH_1):P3V3_STBY
 J17 P3V3_STBY LPVDD0 @BASEBOARD_FAB2_LIB.BASEBOARD_FAB2(SCH_1):P3V3_STBY
  E5    GND  GND68 @BASEBOARD_FAB2_LIB.BASEBOARD_FAB2(SCH_1):GND
  K6 VCC_DACAV3V3 DACAV33 @BASEBOARD_FAB2_LIB.BASEBOARD_FAB2(SCH_1):VCC_DACAV3V3
 F12 VCC_D_3V3 PV33D0 @BASEBOARD_FAB2_LIB.BASEBOARD_FAB2(SCH_1):VCC_D_3V3
  T8 P1V2_AUX_BMC  MVDD4 @BASEBOARD_FAB2_LIB.BASEBOARD_FAB2(SCH_1):P1V2_AUX_BMC
 P22 FM_CPU1_FIVR_FAULT_LVT3_R_N GPIOY2_SIOPWREQ# @BASEBOARD_FAB2_LIB.BASEBOARD_FAB2(SCH_1):FM_CPU1_FIVR_FAULT_LVT3_R_N
 R21 FM_SLPS4_N GPIOY1_SIOS5# @BASEBOARD_FAB2_LIB.BASEBOARD_FAB2(SCH_1):FM_SLPS4_N
 R22 FM_SLPS3_N GPIOY0_SIOS3# @BASEBOARD_FAB2_LIB.BASEBOARD_FAB2(SCH_1):FM_SLPS3_N
  F6 P1V15_AUX_BMC IV11D0 @BASEBOARD_FAB2_LIB.BASEBOARD_FAB2(SCH_1):P1V15_AUX_BMC
 G10 P1V15_AUX_BMC IV11D1 @BASEBOARD_FAB2_LIB.BASEBOARD_FAB2(SCH_1):P1V15_AUX_BMC
 G11 P1V15_AUX_BMC IV11D2 @BASEBOARD_FAB2_LIB.BASEBOARD_FAB2(SCH_1):P1V15_AUX_BMC
 G12 P1V15_AUX_BMC IV11D3 @BASEBOARD_FAB2_LIB.BASEBOARD_FAB2(SCH_1):P1V15_AUX_BMC
 G13 P1V15_AUX_BMC IV11D4 @BASEBOARD_FAB2_LIB.BASEBOARD_FAB2(SCH_1):P1V15_AUX_BMC
 G14 P1V15_AUX_BMC IV11D5 @BASEBOARD_FAB2_LIB.BASEBOARD_FAB2(SCH_1):P1V15_AUX_BMC
 G15 P1V15_AUX_BMC IV11D6 @BASEBOARD_FAB2_LIB.BASEBOARD_FAB2(SCH_1):P1V15_AUX_BMC
  G7 P1V15_AUX_BMC IV11D7 @BASEBOARD_FAB2_LIB.BASEBOARD_FAB2(SCH_1):P1V15_AUX_BMC
  G8 P1V15_AUX_BMC IV11D8 @BASEBOARD_FAB2_LIB.BASEBOARD_FAB2(SCH_1):P1V15_AUX_BMC
  G9 P1V15_AUX_BMC IV11D9 @BASEBOARD_FAB2_LIB.BASEBOARD_FAB2(SCH_1):P1V15_AUX_BMC
 H16 P1V15_AUX_BMC IV11D10 @BASEBOARD_FAB2_LIB.BASEBOARD_FAB2(SCH_1):P1V15_AUX_BMC
 J16 P1V15_AUX_BMC IV11D11 @BASEBOARD_FAB2_LIB.BASEBOARD_FAB2(SCH_1):P1V15_AUX_BMC
  L7 P1V15_AUX_BMC IV11D12 @BASEBOARD_FAB2_LIB.BASEBOARD_FAB2(SCH_1):P1V15_AUX_BMC
 N16 P1V15_AUX_BMC IV11D13 @BASEBOARD_FAB2_LIB.BASEBOARD_FAB2(SCH_1):P1V15_AUX_BMC
  N7 P1V15_AUX_BMC IV11D14 @BASEBOARD_FAB2_LIB.BASEBOARD_FAB2(SCH_1):P1V15_AUX_BMC
 P10 P1V15_AUX_BMC IV11D15 @BASEBOARD_FAB2_LIB.BASEBOARD_FAB2(SCH_1):P1V15_AUX_BMC
 P11 P1V15_AUX_BMC IV11D16 @BASEBOARD_FAB2_LIB.BASEBOARD_FAB2(SCH_1):P1V15_AUX_BMC
 P12 P1V15_AUX_BMC IV11D17 @BASEBOARD_FAB2_LIB.BASEBOARD_FAB2(SCH_1):P1V15_AUX_BMC
 P13 P1V15_AUX_BMC IV11D18 @BASEBOARD_FAB2_LIB.BASEBOARD_FAB2(SCH_1):P1V15_AUX_BMC
 P14 P1V15_AUX_BMC IV11D19 @BASEBOARD_FAB2_LIB.BASEBOARD_FAB2(SCH_1):P1V15_AUX_BMC
 P16 P1V15_AUX_BMC IV11D20 @BASEBOARD_FAB2_LIB.BASEBOARD_FAB2(SCH_1):P1V15_AUX_BMC
  P7 P1V15_AUX_BMC IV11D21 @BASEBOARD_FAB2_LIB.BASEBOARD_FAB2(SCH_1):P1V15_AUX_BMC
  P9 P1V15_AUX_BMC IV11D22 @BASEBOARD_FAB2_LIB.BASEBOARD_FAB2(SCH_1):P1V15_AUX_BMC
 R16 P1V15_AUX_BMC IV11D23 @BASEBOARD_FAB2_LIB.BASEBOARD_FAB2(SCH_1):P1V15_AUX_BMC
  R7 P1V15_AUX_BMC IV11D24 @BASEBOARD_FAB2_LIB.BASEBOARD_FAB2(SCH_1):P1V15_AUX_BMC
  L5 VCC_A_1V1 VPLLAV110 @BASEBOARD_FAB2_LIB.BASEBOARD_FAB2(SCH_1):VCC_A_1V1
  L6 VCC_A_1V1 VPLLAV111 @BASEBOARD_FAB2_LIB.BASEBOARD_FAB2(SCH_1):VCC_A_1V1
 L17 P1V15_AUX_BMC PEAV11 @BASEBOARD_FAB2_LIB.BASEBOARD_FAB2(SCH_1):P1V15_AUX_BMC
 V17 P1V15_AUX_BMC PLLDV11 @BASEBOARD_FAB2_LIB.BASEBOARD_FAB2(SCH_1):P1V15_AUX_BMC
AA17 PVCCIO_CPU0 PECIVDD @BASEBOARD_FAB2_LIB.BASEBOARD_FAB2(SCH_1):PVCCIO_CPU0
 T10 P1V2_AUX_BMC  MVDD0 @BASEBOARD_FAB2_LIB.BASEBOARD_FAB2(SCH_1):P1V2_AUX_BMC
 T12 P1V2_AUX_BMC  MVDD1 @BASEBOARD_FAB2_LIB.BASEBOARD_FAB2(SCH_1):P1V2_AUX_BMC
 T13 P1V2_AUX_BMC  MVDD2 @BASEBOARD_FAB2_LIB.BASEBOARD_FAB2(SCH_1):P1V2_AUX_BMC
 T14 P1V2_AUX_BMC  MVDD3 @BASEBOARD_FAB2_LIB.BASEBOARD_FAB2(SCH_1):P1V2_AUX_BMC
 F13 VCC_D_3V3 PV33D1 @BASEBOARD_FAB2_LIB.BASEBOARD_FAB2(SCH_1):VCC_D_3V3
 F14 VCC_D_3V3 PV33D2 @BASEBOARD_FAB2_LIB.BASEBOARD_FAB2(SCH_1):VCC_D_3V3
 F15 VCC_D_3V3 PV33D3 @BASEBOARD_FAB2_LIB.BASEBOARD_FAB2(SCH_1):VCC_D_3V3
 G16 VCC_D_3V3 PV33D4 @BASEBOARD_FAB2_LIB.BASEBOARD_FAB2(SCH_1):VCC_D_3V3
 H17 VCC_D_3V3 PV33D5 @BASEBOARD_FAB2_LIB.BASEBOARD_FAB2(SCH_1):VCC_D_3V3
  K7 VCC_D_3V3 PV33D6 @BASEBOARD_FAB2_LIB.BASEBOARD_FAB2(SCH_1):VCC_D_3V3
 N17 VCC_D_3V3 PV33D7 @BASEBOARD_FAB2_LIB.BASEBOARD_FAB2(SCH_1):VCC_D_3V3
  N6 VCC_D_3V3 PV33D8 @BASEBOARD_FAB2_LIB.BASEBOARD_FAB2(SCH_1):VCC_D_3V3
 P17 VCC_D_3V3 PV33D9 @BASEBOARD_FAB2_LIB.BASEBOARD_FAB2(SCH_1):VCC_D_3V3
  P6 VCC_D_3V3 PV33D10 @BASEBOARD_FAB2_LIB.BASEBOARD_FAB2(SCH_1):VCC_D_3V3
 R17 VCC_D_3V3 PV33D11 @BASEBOARD_FAB2_LIB.BASEBOARD_FAB2(SCH_1):VCC_D_3V3
  R6 VCC_D_3V3 PV33D12 @BASEBOARD_FAB2_LIB.BASEBOARD_FAB2(SCH_1):VCC_D_3V3
 T11 VCC_D_PLL_3V3 PV33D13 @BASEBOARD_FAB2_LIB.BASEBOARD_FAB2(SCH_1):VCC_D_PLL_3V3
 T15 VCC_D_3V3 PV33D14 @BASEBOARD_FAB2_LIB.BASEBOARD_FAB2(SCH_1):VCC_D_3V3
 Y17 VCC_PA_3V3 PLLAV330 @BASEBOARD_FAB2_LIB.BASEBOARD_FAB2(SCH_1):VCC_PA_3V3
 W17 VCC_PA_3V3 PLLAV331 @BASEBOARD_FAB2_LIB.BASEBOARD_FAB2(SCH_1):VCC_PA_3V3
  J7 VCC_VA_3V3 VPLLAV330 @BASEBOARD_FAB2_LIB.BASEBOARD_FAB2(SCH_1):VCC_VA_3V3
  H7 VCC_VA_3V3 VPLLAV331 @BASEBOARD_FAB2_LIB.BASEBOARD_FAB2(SCH_1):VCC_VA_3V3
 L16 VCC_D_3V3 PEAV33 @BASEBOARD_FAB2_LIB.BASEBOARD_FAB2(SCH_1):VCC_D_3V3
  E4 VCCBAT_TW12 BATVDD @BASEBOARD_FAB2_LIB.BASEBOARD_FAB2(SCH_1):VCCBAT_TW12
  C7 P3V3_USB2A_ALG USB2AV33 @BASEBOARD_FAB2_LIB.BASEBOARD_FAB2(SCH_1):P3V3_USB2A_ALG
  K5 VCC_DACAV3V3 DACDV33 @BASEBOARD_FAB2_LIB.BASEBOARD_FAB2(SCH_1):VCC_DACAV3V3
  J6 VCC_ADCAV3V3 ADCAV33 @BASEBOARD_FAB2_LIB.BASEBOARD_FAB2(SCH_1):VCC_ADCAV3V3
  F7 P3V3_STBY R2VDD0 @BASEBOARD_FAB2_LIB.BASEBOARD_FAB2(SCH_1):P3V3_STBY
  F8 P3V3_STBY R2VDD1 @BASEBOARD_FAB2_LIB.BASEBOARD_FAB2(SCH_1):P3V3_STBY
 F10 P3V3_STBY R1VDD0 @BASEBOARD_FAB2_LIB.BASEBOARD_FAB2(SCH_1):P3V3_STBY
 F11 P3V3_STBY R1VDD1 @BASEBOARD_FAB2_LIB.BASEBOARD_FAB2(SCH_1):P3V3_STBY
  V8    GND  GND67 @BASEBOARD_FAB2_LIB.BASEBOARD_FAB2(SCH_1):GND
 V16    GND  GND66 @BASEBOARD_FAB2_LIB.BASEBOARD_FAB2(SCH_1):GND
 V14    GND  GND65 @BASEBOARD_FAB2_LIB.BASEBOARD_FAB2(SCH_1):GND
  T7    GND  GND60 @BASEBOARD_FAB2_LIB.BASEBOARD_FAB2(SCH_1):GND
 U11    GND  GND61 @BASEBOARD_FAB2_LIB.BASEBOARD_FAB2(SCH_1):GND
 V12    GND  GND64 @BASEBOARD_FAB2_LIB.BASEBOARD_FAB2(SCH_1):GND
 V10    GND  GND63 @BASEBOARD_FAB2_LIB.BASEBOARD_FAB2(SCH_1):GND
  U6    GND  GND62 @BASEBOARD_FAB2_LIB.BASEBOARD_FAB2(SCH_1):GND
 N13    GND  GND55 @BASEBOARD_FAB2_LIB.BASEBOARD_FAB2(SCH_1):GND
 N14    GND  GND56 @BASEBOARD_FAB2_LIB.BASEBOARD_FAB2(SCH_1):GND
  T6    GND  GND59 @BASEBOARD_FAB2_LIB.BASEBOARD_FAB2(SCH_1):GND
 T16    GND  GND58 @BASEBOARD_FAB2_LIB.BASEBOARD_FAB2(SCH_1):GND
  N9    GND  GND57 @BASEBOARD_FAB2_LIB.BASEBOARD_FAB2(SCH_1):GND
  M7    GND  GND50 @BASEBOARD_FAB2_LIB.BASEBOARD_FAB2(SCH_1):GND
  M9    GND  GND51 @BASEBOARD_FAB2_LIB.BASEBOARD_FAB2(SCH_1):GND
 N12    GND  GND54 @BASEBOARD_FAB2_LIB.BASEBOARD_FAB2(SCH_1):GND
 N11    GND  GND53 @BASEBOARD_FAB2_LIB.BASEBOARD_FAB2(SCH_1):GND
 N10    GND  GND52 @BASEBOARD_FAB2_LIB.BASEBOARD_FAB2(SCH_1):GND
  M2    GND  GND45 @BASEBOARD_FAB2_LIB.BASEBOARD_FAB2(SCH_1):GND
  M3    GND  GND46 @BASEBOARD_FAB2_LIB.BASEBOARD_FAB2(SCH_1):GND
  M6    GND  GND49 @BASEBOARD_FAB2_LIB.BASEBOARD_FAB2(SCH_1):GND
  M5    GND  GND48 @BASEBOARD_FAB2_LIB.BASEBOARD_FAB2(SCH_1):GND
  M4    GND  GND47 @BASEBOARD_FAB2_LIB.BASEBOARD_FAB2(SCH_1):GND
 M12    GND  GND40 @BASEBOARD_FAB2_LIB.BASEBOARD_FAB2(SCH_1):GND
 M13    GND  GND41 @BASEBOARD_FAB2_LIB.BASEBOARD_FAB2(SCH_1):GND
 M17    GND  GND44 @BASEBOARD_FAB2_LIB.BASEBOARD_FAB2(SCH_1):GND
 M16    GND  GND43 @BASEBOARD_FAB2_LIB.BASEBOARD_FAB2(SCH_1):GND
 M14    GND  GND42 @BASEBOARD_FAB2_LIB.BASEBOARD_FAB2(SCH_1):GND
 L14    GND  GND35 @BASEBOARD_FAB2_LIB.BASEBOARD_FAB2(SCH_1):GND
 M11    GND  GND39 @BASEBOARD_FAB2_LIB.BASEBOARD_FAB2(SCH_1):GND
 M10    GND  GND38 @BASEBOARD_FAB2_LIB.BASEBOARD_FAB2(SCH_1):GND
  M1    GND  GND37 @BASEBOARD_FAB2_LIB.BASEBOARD_FAB2(SCH_1):GND
  L9    GND  GND36 @BASEBOARD_FAB2_LIB.BASEBOARD_FAB2(SCH_1):GND
  K9    GND  GND30 @BASEBOARD_FAB2_LIB.BASEBOARD_FAB2(SCH_1):GND
 L13    GND  GND34 @BASEBOARD_FAB2_LIB.BASEBOARD_FAB2(SCH_1):GND
 L12    GND  GND33 @BASEBOARD_FAB2_LIB.BASEBOARD_FAB2(SCH_1):GND
 L11    GND  GND32 @BASEBOARD_FAB2_LIB.BASEBOARD_FAB2(SCH_1):GND
 L10    GND  GND31 @BASEBOARD_FAB2_LIB.BASEBOARD_FAB2(SCH_1):GND
 K16    GND  GND29 @BASEBOARD_FAB2_LIB.BASEBOARD_FAB2(SCH_1):GND
 K11    GND  GND25 @BASEBOARD_FAB2_LIB.BASEBOARD_FAB2(SCH_1):GND
 K13    GND  GND27 @BASEBOARD_FAB2_LIB.BASEBOARD_FAB2(SCH_1):GND
 K14    GND  GND28 @BASEBOARD_FAB2_LIB.BASEBOARD_FAB2(SCH_1):GND
 K12    GND  GND26 @BASEBOARD_FAB2_LIB.BASEBOARD_FAB2(SCH_1):GND
 K10    GND  GND24 @BASEBOARD_FAB2_LIB.BASEBOARD_FAB2(SCH_1):GND
 J21    GND  GND20 @BASEBOARD_FAB2_LIB.BASEBOARD_FAB2(SCH_1):GND
  J9    GND  GND23 @BASEBOARD_FAB2_LIB.BASEBOARD_FAB2(SCH_1):GND
  J5    GND  GND22 @BASEBOARD_FAB2_LIB.BASEBOARD_FAB2(SCH_1):GND
 J22    GND  GND21 @BASEBOARD_FAB2_LIB.BASEBOARD_FAB2(SCH_1):GND
 J14    GND  GND19 @BASEBOARD_FAB2_LIB.BASEBOARD_FAB2(SCH_1):GND
  H6    GND  GND14 @BASEBOARD_FAB2_LIB.BASEBOARD_FAB2(SCH_1):GND
 J10    GND  GND15 @BASEBOARD_FAB2_LIB.BASEBOARD_FAB2(SCH_1):GND
 J13    GND  GND18 @BASEBOARD_FAB2_LIB.BASEBOARD_FAB2(SCH_1):GND
 J12    GND  GND17 @BASEBOARD_FAB2_LIB.BASEBOARD_FAB2(SCH_1):GND
 J11    GND  GND16 @BASEBOARD_FAB2_LIB.BASEBOARD_FAB2(SCH_1):GND
  C6    GND   GND9 @BASEBOARD_FAB2_LIB.BASEBOARD_FAB2(SCH_1):GND
  E8    GND  GND10 @BASEBOARD_FAB2_LIB.BASEBOARD_FAB2(SCH_1):GND
  G6    GND  GND13 @BASEBOARD_FAB2_LIB.BASEBOARD_FAB2(SCH_1):GND
 G19    GND  GND12 @BASEBOARD_FAB2_LIB.BASEBOARD_FAB2(SCH_1):GND
 F16    GND  GND11 @BASEBOARD_FAB2_LIB.BASEBOARD_FAB2(SCH_1):GND
AA15    GND   GND4 @BASEBOARD_FAB2_LIB.BASEBOARD_FAB2(SCH_1):GND
 AA7    GND   GND5 @BASEBOARD_FAB2_LIB.BASEBOARD_FAB2(SCH_1):GND
 AB1    GND   GND7 @BASEBOARD_FAB2_LIB.BASEBOARD_FAB2(SCH_1):GND
AB22    GND   GND8 @BASEBOARD_FAB2_LIB.BASEBOARD_FAB2(SCH_1):GND
 AA9    GND   GND6 @BASEBOARD_FAB2_LIB.BASEBOARD_FAB2(SCH_1):GND
AA13    GND   GND3 @BASEBOARD_FAB2_LIB.BASEBOARD_FAB2(SCH_1):GND
AA11    GND   GND2 @BASEBOARD_FAB2_LIB.BASEBOARD_FAB2(SCH_1):GND
 A22    GND   GND1 @BASEBOARD_FAB2_LIB.BASEBOARD_FAB2(SCH_1):GND
  A1    GND   GND0 @BASEBOARD_FAB2_LIB.BASEBOARD_FAB2(SCH_1):GND


DRAWING: @BASEBOARD_FAB2_LIB.BASEBOARD_FAB2(SCH_1):PAGE149 

H5AN4G6NAFR-TFC-GP_MEMORY-G2-HA  I1  U25W5
  B1 P2V5_AUX_BMC VPP<0> @BASEBOARD_FAB2_LIB.BASEBOARD_FAB2(SCH_1):P2V5_AUX_BMC
  B3 P1V2_AUX_BMC VDD<0> @BASEBOARD_FAB2_LIB.BASEBOARD_FAB2(SCH_1):P1V2_AUX_BMC
  B9 P1V2_AUX_BMC VDD<1> @BASEBOARD_FAB2_LIB.BASEBOARD_FAB2(SCH_1):P1V2_AUX_BMC
  D1 P1V2_AUX_BMC VDD<2> @BASEBOARD_FAB2_LIB.BASEBOARD_FAB2(SCH_1):P1V2_AUX_BMC
  G7 P1V2_AUX_BMC VDD<3> @BASEBOARD_FAB2_LIB.BASEBOARD_FAB2(SCH_1):P1V2_AUX_BMC
  J1 P1V2_AUX_BMC VDD<4> @BASEBOARD_FAB2_LIB.BASEBOARD_FAB2(SCH_1):P1V2_AUX_BMC
  J9 P1V2_AUX_BMC VDD<5> @BASEBOARD_FAB2_LIB.BASEBOARD_FAB2(SCH_1):P1V2_AUX_BMC
  L1 P1V2_AUX_BMC VDD<6> @BASEBOARD_FAB2_LIB.BASEBOARD_FAB2(SCH_1):P1V2_AUX_BMC
  L9 P1V2_AUX_BMC VDD<7> @BASEBOARD_FAB2_LIB.BASEBOARD_FAB2(SCH_1):P1V2_AUX_BMC
  R1 P1V2_AUX_BMC VDD<8> @BASEBOARD_FAB2_LIB.BASEBOARD_FAB2(SCH_1):P1V2_AUX_BMC
  T9 P1V2_AUX_BMC VDD<9> @BASEBOARD_FAB2_LIB.BASEBOARD_FAB2(SCH_1):P1V2_AUX_BMC
  A1 P1V2_AUX_BMC VDDQ<0> @BASEBOARD_FAB2_LIB.BASEBOARD_FAB2(SCH_1):P1V2_AUX_BMC
  A9 P1V2_AUX_BMC VDDQ<1> @BASEBOARD_FAB2_LIB.BASEBOARD_FAB2(SCH_1):P1V2_AUX_BMC
  C1 P1V2_AUX_BMC VDDQ<2> @BASEBOARD_FAB2_LIB.BASEBOARD_FAB2(SCH_1):P1V2_AUX_BMC
  D9 P1V2_AUX_BMC VDDQ<3> @BASEBOARD_FAB2_LIB.BASEBOARD_FAB2(SCH_1):P1V2_AUX_BMC
  F2 P1V2_AUX_BMC VDDQ<4> @BASEBOARD_FAB2_LIB.BASEBOARD_FAB2(SCH_1):P1V2_AUX_BMC
  F8 P1V2_AUX_BMC VDDQ<5> @BASEBOARD_FAB2_LIB.BASEBOARD_FAB2(SCH_1):P1V2_AUX_BMC
  G1 P1V2_AUX_BMC VDDQ<6> @BASEBOARD_FAB2_LIB.BASEBOARD_FAB2(SCH_1):P1V2_AUX_BMC
  G9 P1V2_AUX_BMC VDDQ<7> @BASEBOARD_FAB2_LIB.BASEBOARD_FAB2(SCH_1):P1V2_AUX_BMC
  J2 P1V2_AUX_BMC VDDQ<8> @BASEBOARD_FAB2_LIB.BASEBOARD_FAB2(SCH_1):P1V2_AUX_BMC
  J8 P1V2_AUX_BMC VDDQ<9> @BASEBOARD_FAB2_LIB.BASEBOARD_FAB2(SCH_1):P1V2_AUX_BMC
  C2 BMC_M_DQ12   DQU4 @BASEBOARD_FAB2_LIB.BASEBOARD_FAB2(SCH_1):BMC_M_DQ12
  C8 BMC_M_DQ13   DQU5 @BASEBOARD_FAB2_LIB.BASEBOARD_FAB2(SCH_1):BMC_M_DQ13
  D3 BMC_M_DQ14   DQU6 @BASEBOARD_FAB2_LIB.BASEBOARD_FAB2(SCH_1):BMC_M_DQ14
  D7 BMC_M_DQ15   DQU7 @BASEBOARD_FAB2_LIB.BASEBOARD_FAB2(SCH_1):BMC_M_DQ15
  A3 BMC_M_DQ8   DQU0 @BASEBOARD_FAB2_LIB.BASEBOARD_FAB2(SCH_1):BMC_M_DQ8
  B8 BMC_M_DQ9   DQU1 @BASEBOARD_FAB2_LIB.BASEBOARD_FAB2(SCH_1):BMC_M_DQ9
  C3 BMC_M_DQ10   DQU2 @BASEBOARD_FAB2_LIB.BASEBOARD_FAB2(SCH_1):BMC_M_DQ10
  C7 BMC_M_DQ11   DQU3 @BASEBOARD_FAB2_LIB.BASEBOARD_FAB2(SCH_1):BMC_M_DQ11
  F7 BMC_M_DQ1   DQL1 @BASEBOARD_FAB2_LIB.BASEBOARD_FAB2(SCH_1):BMC_M_DQ1
  G2 BMC_M_DQ0   DQL0 @BASEBOARD_FAB2_LIB.BASEBOARD_FAB2(SCH_1):BMC_M_DQ0
  H2 BMC_M_DQ4   DQL4 @BASEBOARD_FAB2_LIB.BASEBOARD_FAB2(SCH_1):BMC_M_DQ4
  H3 BMC_M_DQ2   DQL2 @BASEBOARD_FAB2_LIB.BASEBOARD_FAB2(SCH_1):BMC_M_DQ2
  H7 BMC_M_DQ3   DQL3 @BASEBOARD_FAB2_LIB.BASEBOARD_FAB2(SCH_1):BMC_M_DQ3
  H8 BMC_M_DQ5   DQL5 @BASEBOARD_FAB2_LIB.BASEBOARD_FAB2(SCH_1):BMC_M_DQ5
  J3 BMC_M_DQ6   DQL6 @BASEBOARD_FAB2_LIB.BASEBOARD_FAB2(SCH_1):BMC_M_DQ6
  J7 BMC_M_DQ7   DQL7 @BASEBOARD_FAB2_LIB.BASEBOARD_FAB2(SCH_1):BMC_M_DQ7
  P3 BMC_M_A0     A0 @BASEBOARD_FAB2_LIB.BASEBOARD_FAB2(SCH_1):BMC_M_A0
  P7 BMC_M_A1     A1 @BASEBOARD_FAB2_LIB.BASEBOARD_FAB2(SCH_1):BMC_M_A1
  R3 BMC_M_A2     A2 @BASEBOARD_FAB2_LIB.BASEBOARD_FAB2(SCH_1):BMC_M_A2
  N7 BMC_M_A3     A3 @BASEBOARD_FAB2_LIB.BASEBOARD_FAB2(SCH_1):BMC_M_A3
  N3 BMC_M_A4     A4 @BASEBOARD_FAB2_LIB.BASEBOARD_FAB2(SCH_1):BMC_M_A4
  P8 BMC_M_A5     A5 @BASEBOARD_FAB2_LIB.BASEBOARD_FAB2(SCH_1):BMC_M_A5
  P2 BMC_M_A6     A6 @BASEBOARD_FAB2_LIB.BASEBOARD_FAB2(SCH_1):BMC_M_A6
  R8 BMC_M_A7     A7 @BASEBOARD_FAB2_LIB.BASEBOARD_FAB2(SCH_1):BMC_M_A7
  R2 BMC_M_A8     A8 @BASEBOARD_FAB2_LIB.BASEBOARD_FAB2(SCH_1):BMC_M_A8
  R7 BMC_M_A9     A9 @BASEBOARD_FAB2_LIB.BASEBOARD_FAB2(SCH_1):BMC_M_A9
  M3 BMC_M_A10 A10/AP @BASEBOARD_FAB2_LIB.BASEBOARD_FAB2(SCH_1):BMC_M_A10
  T2 BMC_M_A11    A11 @BASEBOARD_FAB2_LIB.BASEBOARD_FAB2(SCH_1):BMC_M_A11
  M7 BMC_M_A12 A12/BC# @BASEBOARD_FAB2_LIB.BASEBOARD_FAB2(SCH_1):BMC_M_A12
  T8 BMC_M_A13    A13 @BASEBOARD_FAB2_LIB.BASEBOARD_FAB2(SCH_1):BMC_M_A13
  L2 BMC_M_WE_N WE#/A14 @BASEBOARD_FAB2_LIB.BASEBOARD_FAB2(SCH_1):BMC_M_WE_N
  M8 BMC_M_CAS_N CAS#/A15 @BASEBOARD_FAB2_LIB.BASEBOARD_FAB2(SCH_1):BMC_M_CAS_N
  L8 BMC_M_RAS_N RAS#/A16 @BASEBOARD_FAB2_LIB.BASEBOARD_FAB2(SCH_1):BMC_M_RAS_N
  M1 BMC_M_VREFCA VREFCA @BASEBOARD_FAB2_LIB.BASEBOARD_FAB2(SCH_1):BMC_M_VREFCA
  F9 BMC_ZQ     ZQ @BASEBOARD_FAB2_LIB.BASEBOARD_FAB2(SCH_1):BMC_ZQ
  K2 BMC_M_CKE    CKE @BASEBOARD_FAB2_LIB.BASEBOARD_FAB2(SCH_1):BMC_M_CKE
  K3 BMC_M_ODT    ODT @BASEBOARD_FAB2_LIB.BASEBOARD_FAB2(SCH_1):BMC_M_ODT
  M2 BMC_M_BG0    BG0 @BASEBOARD_FAB2_LIB.BASEBOARD_FAB2(SCH_1):BMC_M_BG0
  N9    GND    TEN @BASEBOARD_FAB2_LIB.BASEBOARD_FAB2(SCH_1):GND
  T3 BMC_M_PAR    PAR @BASEBOARD_FAB2_LIB.BASEBOARD_FAB2(SCH_1):BMC_M_PAR
  T7     NC  NC#T7     NC
  K7 BMC_M_CLK_DP   CK_T @BASEBOARD_FAB2_LIB.BASEBOARD_FAB2(SCH_1):BMC_M_CLK_DP
  K8 BMC_M_CLK_DN   CK_C @BASEBOARD_FAB2_LIB.BASEBOARD_FAB2(SCH_1):BMC_M_CLK_DN
  R9    GND VPP<1> @BASEBOARD_FAB2_LIB.BASEBOARD_FAB2(SCH_1):GND
  L3 BMC_M_MACT_N   ACT# @BASEBOARD_FAB2_LIB.BASEBOARD_FAB2(SCH_1):BMC_M_MACT_N
  L7 BMC_M_CS_N    CS# @BASEBOARD_FAB2_LIB.BASEBOARD_FAB2(SCH_1):BMC_M_CS_N
  P1 BMC_M_RST_N RESET# @BASEBOARD_FAB2_LIB.BASEBOARD_FAB2(SCH_1):BMC_M_RST_N
  P9 BMC_M_MALERT_N ALERT# @BASEBOARD_FAB2_LIB.BASEBOARD_FAB2(SCH_1):BMC_M_MALERT_N
  B2    GND VSS<0> @BASEBOARD_FAB2_LIB.BASEBOARD_FAB2(SCH_1):GND
  E1    GND VSS<1> @BASEBOARD_FAB2_LIB.BASEBOARD_FAB2(SCH_1):GND
  E9    GND VSS<2> @BASEBOARD_FAB2_LIB.BASEBOARD_FAB2(SCH_1):GND
  G8    GND VSS<3> @BASEBOARD_FAB2_LIB.BASEBOARD_FAB2(SCH_1):GND
  K1    GND VSS<4> @BASEBOARD_FAB2_LIB.BASEBOARD_FAB2(SCH_1):GND
  K9    GND VSS<5> @BASEBOARD_FAB2_LIB.BASEBOARD_FAB2(SCH_1):GND
  M9    GND VSS<6> @BASEBOARD_FAB2_LIB.BASEBOARD_FAB2(SCH_1):GND
  N1    GND VSS<7> @BASEBOARD_FAB2_LIB.BASEBOARD_FAB2(SCH_1):GND
  T1    GND VSS<8> @BASEBOARD_FAB2_LIB.BASEBOARD_FAB2(SCH_1):GND
  A2    GND VSSQ<0> @BASEBOARD_FAB2_LIB.BASEBOARD_FAB2(SCH_1):GND
  A8    GND VSSQ<1> @BASEBOARD_FAB2_LIB.BASEBOARD_FAB2(SCH_1):GND
  C9    GND VSSQ<2> @BASEBOARD_FAB2_LIB.BASEBOARD_FAB2(SCH_1):GND
  D2    GND VSSQ<3> @BASEBOARD_FAB2_LIB.BASEBOARD_FAB2(SCH_1):GND
  D8    GND VSSQ<4> @BASEBOARD_FAB2_LIB.BASEBOARD_FAB2(SCH_1):GND
  E3    GND VSSQ<5> @BASEBOARD_FAB2_LIB.BASEBOARD_FAB2(SCH_1):GND
  E8    GND VSSQ<6> @BASEBOARD_FAB2_LIB.BASEBOARD_FAB2(SCH_1):GND
  F1    GND VSSQ<7> @BASEBOARD_FAB2_LIB.BASEBOARD_FAB2(SCH_1):GND
  H1    GND VSSQ<8> @BASEBOARD_FAB2_LIB.BASEBOARD_FAB2(SCH_1):GND
  H9    GND VSSQ<9> @BASEBOARD_FAB2_LIB.BASEBOARD_FAB2(SCH_1):GND
  A7 BMC_M_DQS1_DN DQSU_C @BASEBOARD_FAB2_LIB.BASEBOARD_FAB2(SCH_1):BMC_M_DQS1_DN
  B7 BMC_M_DQS1_DP DQSU_T @BASEBOARD_FAB2_LIB.BASEBOARD_FAB2(SCH_1):BMC_M_DQS1_DP
  F3 BMC_M_DQS0_DN DQSL_C @BASEBOARD_FAB2_LIB.BASEBOARD_FAB2(SCH_1):BMC_M_DQS0_DN
  G3 BMC_M_DQS0_DP DQSL_T @BASEBOARD_FAB2_LIB.BASEBOARD_FAB2(SCH_1):BMC_M_DQS0_DP
  E2 BMC_M_DM1 DMU#/DBIU# @BASEBOARD_FAB2_LIB.BASEBOARD_FAB2(SCH_1):BMC_M_DM1
  E7 BMC_M_DM0 DML#/DBIL# @BASEBOARD_FAB2_LIB.BASEBOARD_FAB2(SCH_1):BMC_M_DM0
  N2 BMC_M_BA0    BA0 @BASEBOARD_FAB2_LIB.BASEBOARD_FAB2(SCH_1):BMC_M_BA0
  N8 BMC_M_BA1    BA1 @BASEBOARD_FAB2_LIB.BASEBOARD_FAB2(SCH_1):BMC_M_BA1

RES_0402-33.2,1%,1/16W,CHIP,G2A  I14  R9F34
   1 RST_BMC_DDR3_R_N      A @BASEBOARD_FAB2_LIB.BASEBOARD_FAB2(SCH_1):RST_BMC_DDR3_R_N
   2 BMC_M_RST_N      B @BASEBOARD_FAB2_LIB.BASEBOARD_FAB2(SCH_1):BMC_M_RST_N

RES_0402-4.75K,1%,1/16W,CHIP,GA  I16  R9F29
   1 P1V2_AUX_BMC      A @BASEBOARD_FAB2_LIB.BASEBOARD_FAB2(SCH_1):P1V2_AUX_BMC
   2 RST_BMC_DDR3_R_N      B @BASEBOARD_FAB2_LIB.BASEBOARD_FAB2(SCH_1):RST_BMC_DDR3_R_N

TTL1G07_A_SOP-74LVC1G07,IC,C88B  I34  U9F3
   2 RST_BMC_DDR3_BUF_IN_N      A @BASEBOARD_FAB2_LIB.BASEBOARD_FAB2(SCH_1):RST_BMC_DDR3_BUF_IN_N
   4 RST_BMC_DDR3_R_N      Y @BASEBOARD_FAB2_LIB.BASEBOARD_FAB2(SCH_1):RST_BMC_DDR3_R_N

CAP_0402LF-100.0PF,50V,5%,COG,A  I37  C25W16
   1 P1V2_AUX_BMC      A @BASEBOARD_FAB2_LIB.BASEBOARD_FAB2(SCH_1):P1V2_AUX_BMC
   2    GND      B @BASEBOARD_FAB2_LIB.BASEBOARD_FAB2(SCH_1):GND

SC1U16V3KX-2GP_SMD-BCG-SC1U16VA  I38  C25W17
   1 P1V2_AUX_BMC      1 @BASEBOARD_FAB2_LIB.BASEBOARD_FAB2(SCH_1):P1V2_AUX_BMC
   2    GND      2 @BASEBOARD_FAB2_LIB.BASEBOARD_FAB2(SCH_1):GND

SCD1U16V2KX-3GP_SMD-BCG-SCD1U1A  I39  C25W15
   1 P2V5_AUX_BMC      1 @BASEBOARD_FAB2_LIB.BASEBOARD_FAB2(SCH_1):P2V5_AUX_BMC
   2    GND      2 @BASEBOARD_FAB2_LIB.BASEBOARD_FAB2(SCH_1):GND

SCD1U16V2KX-3GP_SMD-BCG-SCD1U1A  I44  C25W14
   1 P2V5_AUX_BMC      1 @BASEBOARD_FAB2_LIB.BASEBOARD_FAB2(SCH_1):P2V5_AUX_BMC
   2    GND      2 @BASEBOARD_FAB2_LIB.BASEBOARD_FAB2(SCH_1):GND

RES_0402-240,1.0%,1/16W,CHIP,GA  I55  R25W117
   1 BMC_ZQ      A @BASEBOARD_FAB2_LIB.BASEBOARD_FAB2(SCH_1):BMC_ZQ
   2    GND      B @BASEBOARD_FAB2_LIB.BASEBOARD_FAB2(SCH_1):GND

CAP_0402LF-0.1UF,16V,10%,X7R,AA  I65  C25W13
   1 BMC_M_VREFCA      A @BASEBOARD_FAB2_LIB.BASEBOARD_FAB2(SCH_1):BMC_M_VREFCA
   2    GND      B @BASEBOARD_FAB2_LIB.BASEBOARD_FAB2(SCH_1):GND

SC1U16V3KX-2GP_SMD-BCG-SC1U16VA  I68  C25W18
   1 P1V2_AUX_BMC      1 @BASEBOARD_FAB2_LIB.BASEBOARD_FAB2(SCH_1):P1V2_AUX_BMC
   2    GND      2 @BASEBOARD_FAB2_LIB.BASEBOARD_FAB2(SCH_1):GND

SC4D7U10V3KX-GP_SMD-BCG-SC4D7UA  I69  C25W19
   1 P1V2_AUX_BMC      1 @BASEBOARD_FAB2_LIB.BASEBOARD_FAB2(SCH_1):P1V2_AUX_BMC
   2    GND      2 @BASEBOARD_FAB2_LIB.BASEBOARD_FAB2(SCH_1):GND

CAP_0402-1.0UF,16V,10%,X6S,D97A  I71  C25W1
   1 P1V2_AUX_BMC      A @BASEBOARD_FAB2_LIB.BASEBOARD_FAB2(SCH_1):P1V2_AUX_BMC
   2    GND      B @BASEBOARD_FAB2_LIB.BASEBOARD_FAB2(SCH_1):GND

CAP_0402-1.0UF,16V,10%,X6S,D97A  I72  C25W2
   1 P1V2_AUX_BMC      A @BASEBOARD_FAB2_LIB.BASEBOARD_FAB2(SCH_1):P1V2_AUX_BMC
   2    GND      B @BASEBOARD_FAB2_LIB.BASEBOARD_FAB2(SCH_1):GND

CAP_0402-1.0UF,16V,10%,X6S,D97A  I73  C25W3
   1 P1V2_AUX_BMC      A @BASEBOARD_FAB2_LIB.BASEBOARD_FAB2(SCH_1):P1V2_AUX_BMC
   2    GND      B @BASEBOARD_FAB2_LIB.BASEBOARD_FAB2(SCH_1):GND

CAP_0402-1.0UF,16V,10%,X6S,D97A  I74  C25W4
   1 P1V2_AUX_BMC      A @BASEBOARD_FAB2_LIB.BASEBOARD_FAB2(SCH_1):P1V2_AUX_BMC
   2    GND      B @BASEBOARD_FAB2_LIB.BASEBOARD_FAB2(SCH_1):GND

RES_0402-221,1.0%,1/16W,CHIP,GA  I94  R9E24
   1 FM_HEARTBEAT_LED_A      A @BASEBOARD_FAB2_LIB.BASEBOARD_FAB2(SCH_1):FM_HEARTBEAT_LED_A
   2 P3V3_STBY      B @BASEBOARD_FAB2_LIB.BASEBOARD_FAB2(SCH_1):P3V3_STBY

CAP_0402-1.0UF,16V,10%,X6S,D97A  I96  C25W5
   1 P1V2_AUX_BMC      A @BASEBOARD_FAB2_LIB.BASEBOARD_FAB2(SCH_1):P1V2_AUX_BMC
   2    GND      B @BASEBOARD_FAB2_LIB.BASEBOARD_FAB2(SCH_1):GND

CAP_0402-1.0UF,16V,10%,X6S,D97A  I97  C25W6
   1 P1V2_AUX_BMC      A @BASEBOARD_FAB2_LIB.BASEBOARD_FAB2(SCH_1):P1V2_AUX_BMC
   2    GND      B @BASEBOARD_FAB2_LIB.BASEBOARD_FAB2(SCH_1):GND

LED_A1LF-GREEN,IC,C97278-010  I98  DS9E1
   2 FM_HEARTBEAT_LED_K      C @BASEBOARD_FAB2_LIB.BASEBOARD_FAB2(SCH_1):FM_HEARTBEAT_LED_K
   1 FM_HEARTBEAT_LED_A      A @BASEBOARD_FAB2_LIB.BASEBOARD_FAB2(SCH_1):FM_HEARTBEAT_LED_A

FET_N_DUAL_SMLF-NTJD4001N,FET,A  I109  Q9E1
   5 FM_HEARTBEAT_LED GATE<0> @BASEBOARD_FAB2_LIB.BASEBOARD_FAB2(SCH_1):FM_HEARTBEAT_LED
   4    GND SOURCE<0> @BASEBOARD_FAB2_LIB.BASEBOARD_FAB2(SCH_1):GND
   3 FM_HEARTBEAT_LED_K DRAIN<0> @BASEBOARD_FAB2_LIB.BASEBOARD_FAB2(SCH_1):FM_HEARTBEAT_LED_K

RES_0402-4.75K,1%,1/16W,CHIP,GA  I111  R9E21
   1 P3V3_STBY      A @BASEBOARD_FAB2_LIB.BASEBOARD_FAB2(SCH_1):P3V3_STBY
   2 FM_HEARTBEAT_LED      B @BASEBOARD_FAB2_LIB.BASEBOARD_FAB2(SCH_1):FM_HEARTBEAT_LED

FET_N_DUAL_SMLF-NTJD4001N,FET,A  I113  Q9E1
   2 FM_BMC_HEARTBEAT_N GATE<0> @BASEBOARD_FAB2_LIB.BASEBOARD_FAB2(SCH_1):FM_BMC_HEARTBEAT_N
   1    GND SOURCE<0> @BASEBOARD_FAB2_LIB.BASEBOARD_FAB2(SCH_1):GND
   6 FM_HEARTBEAT_LED DRAIN<0> @BASEBOARD_FAB2_LIB.BASEBOARD_FAB2(SCH_1):FM_HEARTBEAT_LED

RES_0402-4.75K,1%,1/16W,CHIP,GA  I120  R25W119
   1 P1V2_AUX_BMC      A @BASEBOARD_FAB2_LIB.BASEBOARD_FAB2(SCH_1):P1V2_AUX_BMC
   2 BMC_M_PAR      B @BASEBOARD_FAB2_LIB.BASEBOARD_FAB2(SCH_1):BMC_M_PAR

RES_0402-4.75K,1%,1/16W,EMPTY,A  I122  R25W118
   1 BMC_M_PAR      A @BASEBOARD_FAB2_LIB.BASEBOARD_FAB2(SCH_1):BMC_M_PAR
   2    GND      B @BASEBOARD_FAB2_LIB.BASEBOARD_FAB2(SCH_1):GND

RES_0402-1.00K,1%,1/16W,CHIP,GA  I124  R1T30
   1 P1V2_AUX_BMC      A @BASEBOARD_FAB2_LIB.BASEBOARD_FAB2(SCH_1):P1V2_AUX_BMC
   2 BMC_M_VREFCA      B @BASEBOARD_FAB2_LIB.BASEBOARD_FAB2(SCH_1):BMC_M_VREFCA

RES_0402-1.00K,1%,1/16W,CHIP,GA  I125  R1T29
   1 BMC_M_VREFCA      A @BASEBOARD_FAB2_LIB.BASEBOARD_FAB2(SCH_1):BMC_M_VREFCA
   2    GND      B @BASEBOARD_FAB2_LIB.BASEBOARD_FAB2(SCH_1):GND

CAP_0402-1.0UF,6.3V,10%,X6S,D9A  I126  C25W12
   1 BMC_M_VREFCA      A @BASEBOARD_FAB2_LIB.BASEBOARD_FAB2(SCH_1):BMC_M_VREFCA
   2    GND      B @BASEBOARD_FAB2_LIB.BASEBOARD_FAB2(SCH_1):GND

RES_0402-4.75K,1%,1/16W,CHIP,GA  I156  R8B25
   1 P3V3_STBY      A @BASEBOARD_FAB2_LIB.BASEBOARD_FAB2(SCH_1):P3V3_STBY
   2 FM_BMC_HEARTBEAT_N      B @BASEBOARD_FAB2_LIB.BASEBOARD_FAB2(SCH_1):FM_BMC_HEARTBEAT_N

CAP_0402LF-0.01UF,25V,10%,X7R,A  I158  C25W10
   1 P1V2_AUX_BMC      A @BASEBOARD_FAB2_LIB.BASEBOARD_FAB2(SCH_1):P1V2_AUX_BMC
   2 BMC_M_VREFCA      B @BASEBOARD_FAB2_LIB.BASEBOARD_FAB2(SCH_1):BMC_M_VREFCA

CAP_0402LF-0.01UF,25V,10%,X7R,A  I159  C25W11
   1 BMC_M_VREFCA      A @BASEBOARD_FAB2_LIB.BASEBOARD_FAB2(SCH_1):BMC_M_VREFCA
   2    GND      B @BASEBOARD_FAB2_LIB.BASEBOARD_FAB2(SCH_1):GND

120R2F-GP_RCL_GP-120R2F-GP,64.A  I160  R25W1
   1    GND      1 @BASEBOARD_FAB2_LIB.BASEBOARD_FAB2(SCH_1):GND
   2 BMC_M_CKE      2 @BASEBOARD_FAB2_LIB.BASEBOARD_FAB2(SCH_1):BMC_M_CKE

120R2F-GP_RCL_GP-120R2F-GP,64.A  I161  R25W2
   1    GND      1 @BASEBOARD_FAB2_LIB.BASEBOARD_FAB2(SCH_1):GND
   2 BMC_M_ODT      2 @BASEBOARD_FAB2_LIB.BASEBOARD_FAB2(SCH_1):BMC_M_ODT

120R2F-GP_RCL_GP-120R2F-GP,64.A  I162  R25W4
   1    GND      1 @BASEBOARD_FAB2_LIB.BASEBOARD_FAB2(SCH_1):GND
   2 BMC_M_MALERT_N      2 @BASEBOARD_FAB2_LIB.BASEBOARD_FAB2(SCH_1):BMC_M_MALERT_N

120R2F-GP_RCL_GP-120R2F-GP,64.A  I163  R25W3
   1    GND      1 @BASEBOARD_FAB2_LIB.BASEBOARD_FAB2(SCH_1):GND
   2 BMC_M_RST_N      2 @BASEBOARD_FAB2_LIB.BASEBOARD_FAB2(SCH_1):BMC_M_RST_N

120R2F-GP_RCL_GP-120R2F-GP,64.A  I164  R25W5
   1    GND      1 @BASEBOARD_FAB2_LIB.BASEBOARD_FAB2(SCH_1):GND
   2 BMC_M_CS_N      2 @BASEBOARD_FAB2_LIB.BASEBOARD_FAB2(SCH_1):BMC_M_CS_N

120R2F-GP_RCL_GP-120R2F-GP,64.A  I165  R25W6
   1    GND      1 @BASEBOARD_FAB2_LIB.BASEBOARD_FAB2(SCH_1):GND
   2 BMC_M_RAS_N      2 @BASEBOARD_FAB2_LIB.BASEBOARD_FAB2(SCH_1):BMC_M_RAS_N

120R2F-GP_RCL_GP-120R2F-GP,64.A  I166  R25W7
   1    GND      1 @BASEBOARD_FAB2_LIB.BASEBOARD_FAB2(SCH_1):GND
   2 BMC_M_CAS_N      2 @BASEBOARD_FAB2_LIB.BASEBOARD_FAB2(SCH_1):BMC_M_CAS_N

120R2F-GP_RCL_GP-120R2F-GP,64.A  I167  R25W8
   1    GND      1 @BASEBOARD_FAB2_LIB.BASEBOARD_FAB2(SCH_1):GND
   2 BMC_M_WE_N      2 @BASEBOARD_FAB2_LIB.BASEBOARD_FAB2(SCH_1):BMC_M_WE_N

120R2F-GP_RCL_GP-120R2F-GP,64.A  I168  R25W9
   1    GND      1 @BASEBOARD_FAB2_LIB.BASEBOARD_FAB2(SCH_1):GND
   2 BMC_M_BA0      2 @BASEBOARD_FAB2_LIB.BASEBOARD_FAB2(SCH_1):BMC_M_BA0

120R2F-GP_RCL_GP-120R2F-GP,64.A  I169  R25W10
   1    GND      1 @BASEBOARD_FAB2_LIB.BASEBOARD_FAB2(SCH_1):GND
   2 BMC_M_BA1      2 @BASEBOARD_FAB2_LIB.BASEBOARD_FAB2(SCH_1):BMC_M_BA1

120R2F-GP_RCL_GP-120R2F-GP,64.A  I170  R25W12
   1    GND      1 @BASEBOARD_FAB2_LIB.BASEBOARD_FAB2(SCH_1):GND
   2 BMC_M_A0      2 @BASEBOARD_FAB2_LIB.BASEBOARD_FAB2(SCH_1):BMC_M_A0

120R2F-GP_RCL_GP-120R2F-GP,64.A  I171  R25W11
   1    GND      1 @BASEBOARD_FAB2_LIB.BASEBOARD_FAB2(SCH_1):GND
   2 BMC_M_BG0      2 @BASEBOARD_FAB2_LIB.BASEBOARD_FAB2(SCH_1):BMC_M_BG0

120R2F-GP_RCL_GP-120R2F-GP,64.A  I172  R25W13
   1    GND      1 @BASEBOARD_FAB2_LIB.BASEBOARD_FAB2(SCH_1):GND
   2 BMC_M_A1      2 @BASEBOARD_FAB2_LIB.BASEBOARD_FAB2(SCH_1):BMC_M_A1

120R2F-GP_RCL_GP-120R2F-GP,64.A  I173  R25W16
   1    GND      1 @BASEBOARD_FAB2_LIB.BASEBOARD_FAB2(SCH_1):GND
   2 BMC_M_A4      2 @BASEBOARD_FAB2_LIB.BASEBOARD_FAB2(SCH_1):BMC_M_A4

120R2F-GP_RCL_GP-120R2F-GP,64.A  I174  R25W15
   1    GND      1 @BASEBOARD_FAB2_LIB.BASEBOARD_FAB2(SCH_1):GND
   2 BMC_M_A3      2 @BASEBOARD_FAB2_LIB.BASEBOARD_FAB2(SCH_1):BMC_M_A3

120R2F-GP_RCL_GP-120R2F-GP,64.A  I175  R25W14
   1    GND      1 @BASEBOARD_FAB2_LIB.BASEBOARD_FAB2(SCH_1):GND
   2 BMC_M_A2      2 @BASEBOARD_FAB2_LIB.BASEBOARD_FAB2(SCH_1):BMC_M_A2

120R2F-GP_RCL_GP-120R2F-GP,64.A  I176  R25W22
   1    GND      1 @BASEBOARD_FAB2_LIB.BASEBOARD_FAB2(SCH_1):GND
   2 BMC_M_A10      2 @BASEBOARD_FAB2_LIB.BASEBOARD_FAB2(SCH_1):BMC_M_A10

120R2F-GP_RCL_GP-120R2F-GP,64.A  I177  R25W23
   1    GND      1 @BASEBOARD_FAB2_LIB.BASEBOARD_FAB2(SCH_1):GND
   2 BMC_M_A11      2 @BASEBOARD_FAB2_LIB.BASEBOARD_FAB2(SCH_1):BMC_M_A11

120R2F-GP_RCL_GP-120R2F-GP,64.A  I178  R25W24
   1    GND      1 @BASEBOARD_FAB2_LIB.BASEBOARD_FAB2(SCH_1):GND
   2 BMC_M_A12      2 @BASEBOARD_FAB2_LIB.BASEBOARD_FAB2(SCH_1):BMC_M_A12

120R2F-GP_RCL_GP-120R2F-GP,64.A  I179  R25W25
   1    GND      1 @BASEBOARD_FAB2_LIB.BASEBOARD_FAB2(SCH_1):GND
   2 BMC_M_A13      2 @BASEBOARD_FAB2_LIB.BASEBOARD_FAB2(SCH_1):BMC_M_A13

120R2F-GP_RCL_GP-120R2F-GP,64.A  I180  R25W26
   1    GND      1 @BASEBOARD_FAB2_LIB.BASEBOARD_FAB2(SCH_1):GND
   2 BMC_M_MACT_N      2 @BASEBOARD_FAB2_LIB.BASEBOARD_FAB2(SCH_1):BMC_M_MACT_N

120R2F-GP_RCL_GP-120R2F-GP,64.A  I181  R25W17
   1    GND      1 @BASEBOARD_FAB2_LIB.BASEBOARD_FAB2(SCH_1):GND
   2 BMC_M_A5      2 @BASEBOARD_FAB2_LIB.BASEBOARD_FAB2(SCH_1):BMC_M_A5

120R2F-GP_RCL_GP-120R2F-GP,64.A  I182  R25W18
   1    GND      1 @BASEBOARD_FAB2_LIB.BASEBOARD_FAB2(SCH_1):GND
   2 BMC_M_A6      2 @BASEBOARD_FAB2_LIB.BASEBOARD_FAB2(SCH_1):BMC_M_A6

120R2F-GP_RCL_GP-120R2F-GP,64.A  I183  R25W19
   1    GND      1 @BASEBOARD_FAB2_LIB.BASEBOARD_FAB2(SCH_1):GND
   2 BMC_M_A7      2 @BASEBOARD_FAB2_LIB.BASEBOARD_FAB2(SCH_1):BMC_M_A7

120R2F-GP_RCL_GP-120R2F-GP,64.A  I184  R25W20
   1    GND      1 @BASEBOARD_FAB2_LIB.BASEBOARD_FAB2(SCH_1):GND
   2 BMC_M_A8      2 @BASEBOARD_FAB2_LIB.BASEBOARD_FAB2(SCH_1):BMC_M_A8

120R2F-GP_RCL_GP-120R2F-GP,64.A  I185  R25W21
   1    GND      1 @BASEBOARD_FAB2_LIB.BASEBOARD_FAB2(SCH_1):GND
   2 BMC_M_A9      2 @BASEBOARD_FAB2_LIB.BASEBOARD_FAB2(SCH_1):BMC_M_A9

120R2F-GP_RCL_GP-120R2F-GP,64.A  I186  R25W27
   1 BMC_M_CKE      1 @BASEBOARD_FAB2_LIB.BASEBOARD_FAB2(SCH_1):BMC_M_CKE
   2 P1V2_AUX_BMC      2 @BASEBOARD_FAB2_LIB.BASEBOARD_FAB2(SCH_1):P1V2_AUX_BMC

120R2F-GP_RCL_GP-120R2F-GP,64.A  I187  R25W28
   1 BMC_M_ODT      1 @BASEBOARD_FAB2_LIB.BASEBOARD_FAB2(SCH_1):BMC_M_ODT
   2 P1V2_AUX_BMC      2 @BASEBOARD_FAB2_LIB.BASEBOARD_FAB2(SCH_1):P1V2_AUX_BMC

120R2F-GP_RCL_GP-120R2F-GP,64.A  I188  R25W30
   1 BMC_M_MALERT_N      1 @BASEBOARD_FAB2_LIB.BASEBOARD_FAB2(SCH_1):BMC_M_MALERT_N
   2 P1V2_AUX_BMC      2 @BASEBOARD_FAB2_LIB.BASEBOARD_FAB2(SCH_1):P1V2_AUX_BMC

120R2F-GP_RCL_GP-120R2F-GP,64.A  I189  R25W29
   1 BMC_M_RST_N      1 @BASEBOARD_FAB2_LIB.BASEBOARD_FAB2(SCH_1):BMC_M_RST_N
   2 P1V2_AUX_BMC      2 @BASEBOARD_FAB2_LIB.BASEBOARD_FAB2(SCH_1):P1V2_AUX_BMC

120R2F-GP_RCL_GP-120R2F-GP,64.A  I190  R25W31
   1 BMC_M_CS_N      1 @BASEBOARD_FAB2_LIB.BASEBOARD_FAB2(SCH_1):BMC_M_CS_N
   2 P1V2_AUX_BMC      2 @BASEBOARD_FAB2_LIB.BASEBOARD_FAB2(SCH_1):P1V2_AUX_BMC

120R2F-GP_RCL_GP-120R2F-GP,64.A  I191  R25W32
   1 BMC_M_RAS_N      1 @BASEBOARD_FAB2_LIB.BASEBOARD_FAB2(SCH_1):BMC_M_RAS_N
   2 P1V2_AUX_BMC      2 @BASEBOARD_FAB2_LIB.BASEBOARD_FAB2(SCH_1):P1V2_AUX_BMC

120R2F-GP_RCL_GP-120R2F-GP,64.A  I192  R25W33
   1 BMC_M_CAS_N      1 @BASEBOARD_FAB2_LIB.BASEBOARD_FAB2(SCH_1):BMC_M_CAS_N
   2 P1V2_AUX_BMC      2 @BASEBOARD_FAB2_LIB.BASEBOARD_FAB2(SCH_1):P1V2_AUX_BMC

120R2F-GP_RCL_GP-120R2F-GP,64.A  I193  R25W34
   1 BMC_M_WE_N      1 @BASEBOARD_FAB2_LIB.BASEBOARD_FAB2(SCH_1):BMC_M_WE_N
   2 P1V2_AUX_BMC      2 @BASEBOARD_FAB2_LIB.BASEBOARD_FAB2(SCH_1):P1V2_AUX_BMC

120R2F-GP_RCL_GP-120R2F-GP,64.A  I194  R25W35
   1 BMC_M_BA0      1 @BASEBOARD_FAB2_LIB.BASEBOARD_FAB2(SCH_1):BMC_M_BA0
   2 P1V2_AUX_BMC      2 @BASEBOARD_FAB2_LIB.BASEBOARD_FAB2(SCH_1):P1V2_AUX_BMC

120R2F-GP_RCL_GP-120R2F-GP,64.A  I195  R25W36
   1 BMC_M_BA1      1 @BASEBOARD_FAB2_LIB.BASEBOARD_FAB2(SCH_1):BMC_M_BA1
   2 P1V2_AUX_BMC      2 @BASEBOARD_FAB2_LIB.BASEBOARD_FAB2(SCH_1):P1V2_AUX_BMC

120R2F-GP_RCL_GP-120R2F-GP,64.A  I196  R25W37
   1 BMC_M_BG0      1 @BASEBOARD_FAB2_LIB.BASEBOARD_FAB2(SCH_1):BMC_M_BG0
   2 P1V2_AUX_BMC      2 @BASEBOARD_FAB2_LIB.BASEBOARD_FAB2(SCH_1):P1V2_AUX_BMC

120R2F-GP_RCL_GP-120R2F-GP,64.A  I197  R25W38
   1 BMC_M_A0      1 @BASEBOARD_FAB2_LIB.BASEBOARD_FAB2(SCH_1):BMC_M_A0
   2 P1V2_AUX_BMC      2 @BASEBOARD_FAB2_LIB.BASEBOARD_FAB2(SCH_1):P1V2_AUX_BMC

120R2F-GP_RCL_GP-120R2F-GP,64.A  I198  R25W39
   1 BMC_M_A1      1 @BASEBOARD_FAB2_LIB.BASEBOARD_FAB2(SCH_1):BMC_M_A1
   2 P1V2_AUX_BMC      2 @BASEBOARD_FAB2_LIB.BASEBOARD_FAB2(SCH_1):P1V2_AUX_BMC

120R2F-GP_RCL_GP-120R2F-GP,64.A  I199  R25W41
   1 BMC_M_A3      1 @BASEBOARD_FAB2_LIB.BASEBOARD_FAB2(SCH_1):BMC_M_A3
   2 P1V2_AUX_BMC      2 @BASEBOARD_FAB2_LIB.BASEBOARD_FAB2(SCH_1):P1V2_AUX_BMC

120R2F-GP_RCL_GP-120R2F-GP,64.A  I200  R25W40
   1 BMC_M_A2      1 @BASEBOARD_FAB2_LIB.BASEBOARD_FAB2(SCH_1):BMC_M_A2
   2 P1V2_AUX_BMC      2 @BASEBOARD_FAB2_LIB.BASEBOARD_FAB2(SCH_1):P1V2_AUX_BMC

120R2F-GP_RCL_GP-120R2F-GP,64.A  I201  R25W42
   1 BMC_M_A4      1 @BASEBOARD_FAB2_LIB.BASEBOARD_FAB2(SCH_1):BMC_M_A4
   2 P1V2_AUX_BMC      2 @BASEBOARD_FAB2_LIB.BASEBOARD_FAB2(SCH_1):P1V2_AUX_BMC

120R2F-GP_RCL_GP-120R2F-GP,64.A  I202  R25W43
   1 BMC_M_A5      1 @BASEBOARD_FAB2_LIB.BASEBOARD_FAB2(SCH_1):BMC_M_A5
   2 P1V2_AUX_BMC      2 @BASEBOARD_FAB2_LIB.BASEBOARD_FAB2(SCH_1):P1V2_AUX_BMC

120R2F-GP_RCL_GP-120R2F-GP,64.A  I203  R25W44
   1 BMC_M_A6      1 @BASEBOARD_FAB2_LIB.BASEBOARD_FAB2(SCH_1):BMC_M_A6
   2 P1V2_AUX_BMC      2 @BASEBOARD_FAB2_LIB.BASEBOARD_FAB2(SCH_1):P1V2_AUX_BMC

120R2F-GP_RCL_GP-120R2F-GP,64.A  I204  R25W45
   1 BMC_M_A7      1 @BASEBOARD_FAB2_LIB.BASEBOARD_FAB2(SCH_1):BMC_M_A7
   2 P1V2_AUX_BMC      2 @BASEBOARD_FAB2_LIB.BASEBOARD_FAB2(SCH_1):P1V2_AUX_BMC

120R2F-GP_RCL_GP-120R2F-GP,64.A  I205  R25W46
   1 BMC_M_A8      1 @BASEBOARD_FAB2_LIB.BASEBOARD_FAB2(SCH_1):BMC_M_A8
   2 P1V2_AUX_BMC      2 @BASEBOARD_FAB2_LIB.BASEBOARD_FAB2(SCH_1):P1V2_AUX_BMC

120R2F-GP_RCL_GP-120R2F-GP,64.A  I206  R25W47
   1 BMC_M_A9      1 @BASEBOARD_FAB2_LIB.BASEBOARD_FAB2(SCH_1):BMC_M_A9
   2 P1V2_AUX_BMC      2 @BASEBOARD_FAB2_LIB.BASEBOARD_FAB2(SCH_1):P1V2_AUX_BMC

120R2F-GP_RCL_GP-120R2F-GP,64.A  I207  R25W48
   1 BMC_M_A10      1 @BASEBOARD_FAB2_LIB.BASEBOARD_FAB2(SCH_1):BMC_M_A10
   2 P1V2_AUX_BMC      2 @BASEBOARD_FAB2_LIB.BASEBOARD_FAB2(SCH_1):P1V2_AUX_BMC

120R2F-GP_RCL_GP-120R2F-GP,64.A  I208  R25W49
   1 BMC_M_A11      1 @BASEBOARD_FAB2_LIB.BASEBOARD_FAB2(SCH_1):BMC_M_A11
   2 P1V2_AUX_BMC      2 @BASEBOARD_FAB2_LIB.BASEBOARD_FAB2(SCH_1):P1V2_AUX_BMC

120R2F-GP_RCL_GP-120R2F-GP,64.A  I209  R25W50
   1 BMC_M_A12      1 @BASEBOARD_FAB2_LIB.BASEBOARD_FAB2(SCH_1):BMC_M_A12
   2 P1V2_AUX_BMC      2 @BASEBOARD_FAB2_LIB.BASEBOARD_FAB2(SCH_1):P1V2_AUX_BMC

120R2F-GP_RCL_GP-120R2F-GP,64.A  I210  R25W51
   1 BMC_M_A13      1 @BASEBOARD_FAB2_LIB.BASEBOARD_FAB2(SCH_1):BMC_M_A13
   2 P1V2_AUX_BMC      2 @BASEBOARD_FAB2_LIB.BASEBOARD_FAB2(SCH_1):P1V2_AUX_BMC

120R2F-GP_RCL_GP-120R2F-GP,64.A  I211  R25W52
   1 BMC_M_MACT_N      1 @BASEBOARD_FAB2_LIB.BASEBOARD_FAB2(SCH_1):BMC_M_MACT_N
   2 P1V2_AUX_BMC      2 @BASEBOARD_FAB2_LIB.BASEBOARD_FAB2(SCH_1):P1V2_AUX_BMC

120R2F-GP_RCL_GP-120R2F-GP,64.A  I212  R1T28
   1 BMC_M_CLK_DN      1 @BASEBOARD_FAB2_LIB.BASEBOARD_FAB2(SCH_1):BMC_M_CLK_DN
   2 BMC_M_CLK_DP      2 @BASEBOARD_FAB2_LIB.BASEBOARD_FAB2(SCH_1):BMC_M_CLK_DP

END LOGICAL PART CROSS REFERENCE
GLOBAL SIGNAL CROSS REFERENCE - 30-Nov-2015 AT 15:33:22
AGND_HSC @BASEBOARD_FAB2_LIB.BASEBOARD_FAB2(SCH_1):AGND_HSC
 C1D25    2      B CAP_0402-1.0UF,16V,10%,X6S,D97A     I3 @BASEBOARD_FAB2_LIB.BASEBOARD_FAB2(SCH_1):PAGE199
 C1D27    2      B CAP_A_0402V-0.1UF,16V,10%,X7R,A     I7 @BASEBOARD_FAB2_LIB.BASEBOARD_FAB2(SCH_1):PAGE199
 R1D43    2      B RES_0402-7.5K,1%,1/16W,CHIP,G2A     I9 @BASEBOARD_FAB2_LIB.BASEBOARD_FAB2(SCH_1):PAGE199
 EU1D2   33     EP ADM1278_SM-IC,G99251-001    I10 @BASEBOARD_FAB2_LIB.BASEBOARD_FAB2(SCH_1):PAGE199
 EU1D2   22    GND ADM1278_SM-IC,G99251-001    I10 @BASEBOARD_FAB2_LIB.BASEBOARD_FAB2(SCH_1):PAGE199
 R1D42    2      B RES_0402-11K,1%,1/16W,CHIP,G21A    I13 @BASEBOARD_FAB2_LIB.BASEBOARD_FAB2(SCH_1):PAGE199
 R1D41    2      B RES_0805-0.0,5%,1/8W,CHIP,G221A    I19 @BASEBOARD_FAB2_LIB.BASEBOARD_FAB2(SCH_1):PAGE199
 C9P14    2      B CAP_0603LF-0.033UF,50V,10%,X7RA    I24 @BASEBOARD_FAB2_LIB.BASEBOARD_FAB2(SCH_1):PAGE199
 R1D28    2      B RES_0402-100.0,1%,1/16W,EMPTY,A    I26 @BASEBOARD_FAB2_LIB.BASEBOARD_FAB2(SCH_1):PAGE199
 R9P17    2      B RES_0402-150.0K,1%,1/16W,CHIP,A    I33 @BASEBOARD_FAB2_LIB.BASEBOARD_FAB2(SCH_1):PAGE199
 R9P16    2      B RES_0402-0.0,5%,1/16W,CHIP,G21A    I36 @BASEBOARD_FAB2_LIB.BASEBOARD_FAB2(SCH_1):PAGE199
 C1D11    2      B CAP_A_0402V-0.1UF,16V,10%,X7R,A    I53 @BASEBOARD_FAB2_LIB.BASEBOARD_FAB2(SCH_1):PAGE199
 R9P24    2      B RES_0402-12.1K,1%,1/16W,CHIP,GA    I55 @BASEBOARD_FAB2_LIB.BASEBOARD_FAB2(SCH_1):PAGE199
 C9P12    2      B CAP_A_0402V-0.1UF,16V,10%,EMPTA    I67 @BASEBOARD_FAB2_LIB.BASEBOARD_FAB2(SCH_1):PAGE199
  Q1D1    4 SOURCE<0> FET_N_DUAL_SMLF-2N7002DW,FET,DA    I82 @BASEBOARD_FAB2_LIB.BASEBOARD_FAB2(SCH_1):PAGE199
  Q1D1    1 SOURCE<0> FET_N_DUAL_SMLF-2N7002DW,FET,DA    I86 @BASEBOARD_FAB2_LIB.BASEBOARD_FAB2(SCH_1):PAGE199
 R1D18    2      B RES_0402-100.0K,1%,1/16W,CHIP,A    I87 @BASEBOARD_FAB2_LIB.BASEBOARD_FAB2(SCH_1):PAGE199
 R1D11    2      B RES_0402-100.0K,1%,1/16W,CHIP,A    I88 @BASEBOARD_FAB2_LIB.BASEBOARD_FAB2(SCH_1):PAGE199
 R1D40    2      B RES_0402-40.2K,1%,1/16W,CHIP,GA   I100 @BASEBOARD_FAB2_LIB.BASEBOARD_FAB2(SCH_1):PAGE199
 R1D34    2      B RES_0402-16K,1.0%,1/16W,CHIP,GA   I102 @BASEBOARD_FAB2_LIB.BASEBOARD_FAB2(SCH_1):PAGE199
 C9P15    2      B CAP_A_0402V-0.1UF,16V,10%,X7R,A   I105 @BASEBOARD_FAB2_LIB.BASEBOARD_FAB2(SCH_1):PAGE199
 C1D26    2      B CAP_A_0402V-0.1UF,16V,10%,X7R,A   I107 @BASEBOARD_FAB2_LIB.BASEBOARD_FAB2(SCH_1):PAGE199
 C1D19    2      B CAP_0402-1.0UF,16V,10%,X6S,D97A   I119 @BASEBOARD_FAB2_LIB.BASEBOARD_FAB2(SCH_1):PAGE199
 C1D21    2      B CAP_A_0402V-0.1UF,16V,10%,X7R,A   I121 @BASEBOARD_FAB2_LIB.BASEBOARD_FAB2(SCH_1):PAGE199
 C9P17    2      B CAP_A_0402V-0.1UF,16V,10%,EMPTA    I36 @BASEBOARD_FAB2_LIB.BASEBOARD_FAB2(SCH_1):PAGE200
 C9P16    2      B CAP_A_0402V-0.1UF,16V,10%,EMPTA    I40 @BASEBOARD_FAB2_LIB.BASEBOARD_FAB2(SCH_1):PAGE200
 R9P19    2      B RES_0402-10.0K,1%,1/16W,EMPTY,A    I70 @BASEBOARD_FAB2_LIB.BASEBOARD_FAB2(SCH_1):PAGE200
 R9P11    2      B RES_0402-10.0K,1%,1/16W,CHIP,GA   I108 @BASEBOARD_FAB2_LIB.BASEBOARD_FAB2(SCH_1):PAGE200
  R9P9    2      B RES_0402-10.0K,1%,1/16W,CHIP,GA   I146 @BASEBOARD_FAB2_LIB.BASEBOARD_FAB2(SCH_1):PAGE200
 R1D12    2      B RES_0402-10.0K,1%,1/16W,CHIP,GA   I174 @BASEBOARD_FAB2_LIB.BASEBOARD_FAB2(SCH_1):PAGE200
 R1D19    2      B RES_0402-10.0K,1%,1/16W,CHIP,GA   I175 @BASEBOARD_FAB2_LIB.BASEBOARD_FAB2(SCH_1):PAGE200
  C9P6    2      B CAP_A_0402V-0.1UF,16V,10%,X7R,A   I185 @BASEBOARD_FAB2_LIB.BASEBOARD_FAB2(SCH_1):PAGE200
  C1D9    2      B CAP_A_0402V-0.1UF,16V,10%,X7R,A   I187 @BASEBOARD_FAB2_LIB.BASEBOARD_FAB2(SCH_1):PAGE200
 R9P12    2      B RES_0402-4.99K,1%,1/16W,CHIP,GA   I218 @BASEBOARD_FAB2_LIB.BASEBOARD_FAB2(SCH_1):PAGE200
  C9W1    2      2 SC22P50V2JN-4GP_SMD-BCG-SC22P5A   I235 @BASEBOARD_FAB2_LIB.BASEBOARD_FAB2(SCH_1):PAGE200
  C9W2    2      2 SC22P50V2JN-4GP_SMD-BCG-SC22P5A   I236 @BASEBOARD_FAB2_LIB.BASEBOARD_FAB2(SCH_1):PAGE200

AGND_P3V3_STBY @BASEBOARD_FAB2_LIB.BASEBOARD_FAB2(SCH_1):AGND_P3V3_STBY
  R8F9    2      B RES_0402-64.9K,1%,1/16W,CHIP,GA   I106 @BASEBOARD_FAB2_LIB.BASEBOARD_FAB2(SCH_1):PAGE240
 C2R11    2      B CAP_0603-4.7UF,6.3V,10%,X6S,E1A   I109 @BASEBOARD_FAB2_LIB.BASEBOARD_FAB2(SCH_1):PAGE240
 C8E17    2      B CAP_0402LF-1000PF,50V,10%,EMPTA   I113 @BASEBOARD_FAB2_LIB.BASEBOARD_FAB2(SCH_1):PAGE240
 EU8F1   11     G0 RT8240_QFN-IC,H66262-001   I125 @BASEBOARD_FAB2_LIB.BASEBOARD_FAB2(SCH_1):PAGE240
 EU8F1   12 GND<0> RT8240_QFN-IC,H66262-001   I125 @BASEBOARD_FAB2_LIB.BASEBOARD_FAB2(SCH_1):PAGE240
 EU8F1   13 GND<1> RT8240_QFN-IC,H66262-001   I125 @BASEBOARD_FAB2_LIB.BASEBOARD_FAB2(SCH_1):PAGE240
 R8E38    2      B RES_0402-0.0,5%,1/16W,CHIP,G21A   I140 @BASEBOARD_FAB2_LIB.BASEBOARD_FAB2(SCH_1):PAGE240
 R8E34    2      B RES_0402-10.0K,1%,1/16W,CHIP,GA   I142 @BASEBOARD_FAB2_LIB.BASEBOARD_FAB2(SCH_1):PAGE240
 R8F11    2      B RES_0402-0.0,5%,1/16W,CHIP,G21A   I146 @BASEBOARD_FAB2_LIB.BASEBOARD_FAB2(SCH_1):PAGE240

AGND_P5V_STBY @BASEBOARD_FAB2_LIB.BASEBOARD_FAB2(SCH_1):AGND_P5V_STBY
 R7E14    2      B RES_0402-75K,1%,1/16W,CHIP,G21A    I18 @BASEBOARD_FAB2_LIB.BASEBOARD_FAB2(SCH_1):PAGE241
 C8E13    2      B CAP_0402LF-1000PF,50V,10%,EMPTA    I41 @BASEBOARD_FAB2_LIB.BASEBOARD_FAB2(SCH_1):PAGE241
 R7E16    2      B RES_0402-1.37K,1%,1/16W,CHIP,GA    I51 @BASEBOARD_FAB2_LIB.BASEBOARD_FAB2(SCH_1):PAGE241
 C8E16    2      B CAP_0402LF-270PF,50V,10%,X7R,AA    I53 @BASEBOARD_FAB2_LIB.BASEBOARD_FAB2(SCH_1):PAGE241
  C8F1    2      B CAP_0402LF-2200PF,50V,10%,X7R,A    I57 @BASEBOARD_FAB2_LIB.BASEBOARD_FAB2(SCH_1):PAGE241
 R7E13    2      B RES_0402-0.0,5%,1/16W,CHIP,G21A    I58 @BASEBOARD_FAB2_LIB.BASEBOARD_FAB2(SCH_1):PAGE241
 C8E15    2      B CAP_0402LF-0.022UF,16V,10%,X7RA    I63 @BASEBOARD_FAB2_LIB.BASEBOARD_FAB2(SCH_1):PAGE241

AGND_PVPP_ABC @BASEBOARD_FAB2_LIB.BASEBOARD_FAB2(SCH_1):AGND_PVPP_ABC
 R7F15    2      B RES_0402-7.87K,1.0%,1/16W,CHIPA   I134 @BASEBOARD_FAB2_LIB.BASEBOARD_FAB2(SCH_1):PAGE231
  C7F8    2      B CAP_0402LF-1000PF,50V,10%,EMPTA   I140 @BASEBOARD_FAB2_LIB.BASEBOARD_FAB2(SCH_1):PAGE231
 R7F11    2      B RES_0402-6.34K,1%,1/16W,CHIP,GA   I166 @BASEBOARD_FAB2_LIB.BASEBOARD_FAB2(SCH_1):PAGE231
 R7F35    2      B RES_0402-0.0,5%,1/16W,CHIP,G21A   I170 @BASEBOARD_FAB2_LIB.BASEBOARD_FAB2(SCH_1):PAGE231
 EU7F1    5   AGND NCP3232L_SM-IC,H86355-001   I193 @BASEBOARD_FAB2_LIB.BASEBOARD_FAB2(SCH_1):PAGE231
 EU7F1    6    OTS NCP3232L_SM-IC,H86355-001   I193 @BASEBOARD_FAB2_LIB.BASEBOARD_FAB2(SCH_1):PAGE231
 C7F10    2      B CAP_0402-0.027UF,16V,10%,X7R,AA   I194 @BASEBOARD_FAB2_LIB.BASEBOARD_FAB2(SCH_1):PAGE231
 C3T11    2      B CAP_0603-4.7UF,6.3V,10%,X6S,E1A   I202 @BASEBOARD_FAB2_LIB.BASEBOARD_FAB2(SCH_1):PAGE231

AGND_PVPP_DEF @BASEBOARD_FAB2_LIB.BASEBOARD_FAB2(SCH_1):AGND_PVPP_DEF
 R7B20    2      B RES_0402-0.0,5%,1/16W,CHIP,G21A   I150 @BASEBOARD_FAB2_LIB.BASEBOARD_FAB2(SCH_1):PAGE232
  C7B9    2      B CAP_0402LF-1000PF,50V,10%,EMPTA   I185 @BASEBOARD_FAB2_LIB.BASEBOARD_FAB2(SCH_1):PAGE232
 R7B14    2      B RES_0402-7.87K,1.0%,1/16W,CHIPA   I193 @BASEBOARD_FAB2_LIB.BASEBOARD_FAB2(SCH_1):PAGE232
 C7B11    2      B CAP_0402-0.027UF,16V,10%,X7R,AA   I197 @BASEBOARD_FAB2_LIB.BASEBOARD_FAB2(SCH_1):PAGE232
 EU7B1    5   AGND NCP3232L_SM-IC,H86355-001   I214 @BASEBOARD_FAB2_LIB.BASEBOARD_FAB2(SCH_1):PAGE232
 EU7B1    6    OTS NCP3232L_SM-IC,H86355-001   I214 @BASEBOARD_FAB2_LIB.BASEBOARD_FAB2(SCH_1):PAGE232
 C3M10    2      B CAP_0603-4.7UF,6.3V,10%,X6S,E1A   I253 @BASEBOARD_FAB2_LIB.BASEBOARD_FAB2(SCH_1):PAGE232
 R7B13    2      B RES_0402-6.34K,1%,1/16W,CHIP,GA   I304 @BASEBOARD_FAB2_LIB.BASEBOARD_FAB2(SCH_1):PAGE232

AGND_PVPP_GHJ @BASEBOARD_FAB2_LIB.BASEBOARD_FAB2(SCH_1):AGND_PVPP_GHJ
 R4G25    2      B RES_0402-0.0,5%,1/16W,CHIP,G21A   I157 @BASEBOARD_FAB2_LIB.BASEBOARD_FAB2(SCH_1):PAGE233
  C4G7    2      B CAP_0402LF-1000PF,50V,10%,EMPTA   I183 @BASEBOARD_FAB2_LIB.BASEBOARD_FAB2(SCH_1):PAGE233
 R4G11    2      B RES_0402-7.87K,1.0%,1/16W,CHIPA   I184 @BASEBOARD_FAB2_LIB.BASEBOARD_FAB2(SCH_1):PAGE233
  C6U6    2      B CAP_0603-4.7UF,6.3V,10%,X6S,E1A   I187 @BASEBOARD_FAB2_LIB.BASEBOARD_FAB2(SCH_1):PAGE233
  C4G8    2      B CAP_0402-0.027UF,16V,10%,X7R,AA   I194 @BASEBOARD_FAB2_LIB.BASEBOARD_FAB2(SCH_1):PAGE233
 EU4G1    5   AGND NCP3232L_SM-IC,H86355-001   I225 @BASEBOARD_FAB2_LIB.BASEBOARD_FAB2(SCH_1):PAGE233
 EU4G1    6    OTS NCP3232L_SM-IC,H86355-001   I225 @BASEBOARD_FAB2_LIB.BASEBOARD_FAB2(SCH_1):PAGE233
  R4G9    2      B RES_0402-6.34K,1%,1/16W,CHIP,GA   I269 @BASEBOARD_FAB2_LIB.BASEBOARD_FAB2(SCH_1):PAGE233

AGND_PVPP_KLM @BASEBOARD_FAB2_LIB.BASEBOARD_FAB2(SCH_1):AGND_PVPP_KLM
 R4B14    2      B RES_0402-0.0,5%,1/16W,CHIP,G21A    I29 @BASEBOARD_FAB2_LIB.BASEBOARD_FAB2(SCH_1):PAGE234
  C4B5    2      B CAP_0402LF-1000PF,50V,10%,EMPTA   I129 @BASEBOARD_FAB2_LIB.BASEBOARD_FAB2(SCH_1):PAGE234
  R4B6    2      B RES_0402-7.87K,1.0%,1/16W,CHIPA   I140 @BASEBOARD_FAB2_LIB.BASEBOARD_FAB2(SCH_1):PAGE234
 C6L12    2      B CAP_0603-4.7UF,6.3V,10%,X6S,E1A   I144 @BASEBOARD_FAB2_LIB.BASEBOARD_FAB2(SCH_1):PAGE234
  C4B6    2      B CAP_0402-0.027UF,16V,10%,X7R,AA   I146 @BASEBOARD_FAB2_LIB.BASEBOARD_FAB2(SCH_1):PAGE234
 EU4A3    5   AGND NCP3232L_SM-IC,H86355-001   I184 @BASEBOARD_FAB2_LIB.BASEBOARD_FAB2(SCH_1):PAGE234
 EU4A3    6    OTS NCP3232L_SM-IC,H86355-001   I184 @BASEBOARD_FAB2_LIB.BASEBOARD_FAB2(SCH_1):PAGE234
  R4B4    2      B RES_0402-6.34K,1%,1/16W,CHIP,GA   I216 @BASEBOARD_FAB2_LIB.BASEBOARD_FAB2(SCH_1):PAGE234

A_1P8_3P3_RCOMP @BASEBOARD_FAB2_LIB.BASEBOARD_FAB2(SCH_1):A_1P8_3P3_RCOMP
  U7C1  AM4 GPIO_RCOMP_1P8_3P3 LBG_CORE_QAT_EXT_D_BGA1-IC,H91A    I34 @BASEBOARD_FAB2_LIB.BASEBOARD_FAB2(SCH_1):PAGE121
 R8C26    1      A RES_0402-100.0,1%,1/16W,CHIP,GA    I35 @BASEBOARD_FAB2_LIB.BASEBOARD_FAB2(SCH_1):PAGE121

A_ADM1085_CEXT @BASEBOARD_FAB2_LIB.BASEBOARD_FAB2(SCH_1):A_ADM1085_CEXT
 C3P45    1      A CAP_0402-0.047UF,25V,10%,X7R,AA    I60 @BASEBOARD_FAB2_LIB.BASEBOARD_FAB2(SCH_1):PAGE196
  U7D3    5   CEXT ADM1085_SMT-IC,H46130-001    I70 @BASEBOARD_FAB2_LIB.BASEBOARD_FAB2(SCH_1):PAGE196

A_CBOT @BASEBOARD_FAB2_LIB.BASEBOARD_FAB2(SCH_1):A_CBOT
 EU9E1   37   CBOT SPRINGVILLE_SM1-IC,G47144-004    I72 @BASEBOARD_FAB2_LIB.BASEBOARD_FAB2(SCH_1):PAGE139
  C9E7    2      B CAP_0402LF-0.039UF,25V,10%,X7RA    I76 @BASEBOARD_FAB2_LIB.BASEBOARD_FAB2(SCH_1):PAGE139

A_COMP_CKMNG @BASEBOARD_FAB2_LIB.BASEBOARD_FAB2(SCH_1):A_COMP_CKMNG
 R8F25    1      A RES_0402-475.0,1%,1/16W,CHIP,GA    I28 @BASEBOARD_FAB2_LIB.BASEBOARD_FAB2(SCH_1):PAGE101
 EU8F2   11   IREF ICS9FGP204_MLFP-IC,E95226-001    I34 @BASEBOARD_FAB2_LIB.BASEBOARD_FAB2(SCH_1):PAGE101

A_CPU0_ABC_RCOMP0 @BASEBOARD_FAB2_LIB.BASEBOARD_FAB2(SCH_1):A_CPU0_ABC_RCOMP0
  R4P8    1      A RES_0402-90.9,1%,1/16W,CHIP,G2A   I180 @BASEBOARD_FAB2_LIB.BASEBOARD_FAB2(SCH_1):PAGE21
  U5D1  Y43 DDR012_RCOMP<0> SKX_EXT_B_BGA1-IC,TBD   I259 @BASEBOARD_FAB2_LIB.BASEBOARD_FAB2(SCH_1):PAGE21

A_CPU0_ABC_RCOMP1 @BASEBOARD_FAB2_LIB.BASEBOARD_FAB2(SCH_1):A_CPU0_ABC_RCOMP1
 R4P10    1      A RES_0402-90.9,1%,1/16W,CHIP,G2A   I181 @BASEBOARD_FAB2_LIB.BASEBOARD_FAB2(SCH_1):PAGE21
  U5D1 AB43 DDR012_RCOMP<1> SKX_EXT_B_BGA1-IC,TBD   I259 @BASEBOARD_FAB2_LIB.BASEBOARD_FAB2(SCH_1):PAGE21

A_CPU0_ABC_RCOMP2 @BASEBOARD_FAB2_LIB.BASEBOARD_FAB2(SCH_1):A_CPU0_ABC_RCOMP2
 R4P11    1      A RES_0402-100.0,1%,1/16W,CHIP,GA   I182 @BASEBOARD_FAB2_LIB.BASEBOARD_FAB2(SCH_1):PAGE21
  U5D1 AC42 DDR012_RCOMP<2> SKX_EXT_B_BGA1-IC,TBD   I259 @BASEBOARD_FAB2_LIB.BASEBOARD_FAB2(SCH_1):PAGE21

A_CPU0_DEF_RCOMP0 @BASEBOARD_FAB2_LIB.BASEBOARD_FAB2(SCH_1):A_CPU0_DEF_RCOMP0
  R5D1    1      A RES_0402-90.9,1%,1/16W,CHIP,G2A   I177 @BASEBOARD_FAB2_LIB.BASEBOARD_FAB2(SCH_1):PAGE21
  U5D1 DC48 DDR345_RCOMP<0> SKX_EXT_B_BGA1-IC,TBD   I259 @BASEBOARD_FAB2_LIB.BASEBOARD_FAB2(SCH_1):PAGE21

A_CPU0_DEF_RCOMP1 @BASEBOARD_FAB2_LIB.BASEBOARD_FAB2(SCH_1):A_CPU0_DEF_RCOMP1
  R5D2    1      A RES_0402-90.9,1%,1/16W,CHIP,G2A   I178 @BASEBOARD_FAB2_LIB.BASEBOARD_FAB2(SCH_1):PAGE21
  U5D1 DD47 DDR345_RCOMP<1> SKX_EXT_B_BGA1-IC,TBD   I259 @BASEBOARD_FAB2_LIB.BASEBOARD_FAB2(SCH_1):PAGE21

A_CPU0_DEF_RCOMP2 @BASEBOARD_FAB2_LIB.BASEBOARD_FAB2(SCH_1):A_CPU0_DEF_RCOMP2
  R6D1    1      A RES_0402-100.0,1%,1/16W,CHIP,GA   I179 @BASEBOARD_FAB2_LIB.BASEBOARD_FAB2(SCH_1):PAGE21
  U5D1 DD49 DDR345_RCOMP<2> SKX_EXT_B_BGA1-IC,TBD   I259 @BASEBOARD_FAB2_LIB.BASEBOARD_FAB2(SCH_1):PAGE21

A_CPU0_MCP01_RBIAS @BASEBOARD_FAB2_LIB.BASEBOARD_FAB2(SCH_1):A_CPU0_MCP01_RBIAS
  R6D2    1      A RES_0402-49.9,1%,1/16W,CHIP,G2A   I204 @BASEBOARD_FAB2_LIB.BASEBOARD_FAB2(SCH_1):PAGE21
  U5D1 CU32 MCP01_RBIAS<0> SKX_EXT_B_BGA1-IC,TBD   I259 @BASEBOARD_FAB2_LIB.BASEBOARD_FAB2(SCH_1):PAGE21
  U5D1 CT31 MCP01_RBIAS<1> SKX_EXT_B_BGA1-IC,TBD   I259 @BASEBOARD_FAB2_LIB.BASEBOARD_FAB2(SCH_1):PAGE21

A_CPU0_PE012_RBIAS @BASEBOARD_FAB2_LIB.BASEBOARD_FAB2(SCH_1):A_CPU0_PE012_RBIAS
  R4P3    1      A RES_0402-49.9,1%,1/16W,CHIP,G2A   I186 @BASEBOARD_FAB2_LIB.BASEBOARD_FAB2(SCH_1):PAGE21
  U5D1 CN30 PE012_RBIAS<0> SKX_EXT_B_BGA1-IC,TBD   I259 @BASEBOARD_FAB2_LIB.BASEBOARD_FAB2(SCH_1):PAGE21
  U5D1 CL30 PE012_RBIAS<1> SKX_EXT_B_BGA1-IC,TBD   I259 @BASEBOARD_FAB2_LIB.BASEBOARD_FAB2(SCH_1):PAGE21

A_CPU0_PE3_RBIAS @BASEBOARD_FAB2_LIB.BASEBOARD_FAB2(SCH_1):A_CPU0_PE3_RBIAS
  R4P2    1      A RES_0402-49.9,1%,1/16W,CHIP,G2A   I188 @BASEBOARD_FAB2_LIB.BASEBOARD_FAB2(SCH_1):PAGE21
  U5D1 CP29 PE3_RBIAS<0> SKX_EXT_B_BGA1-IC,TBD   I259 @BASEBOARD_FAB2_LIB.BASEBOARD_FAB2(SCH_1):PAGE21
  U5D1 CR30 PE3_RBIAS<1> SKX_EXT_B_BGA1-IC,TBD   I259 @BASEBOARD_FAB2_LIB.BASEBOARD_FAB2(SCH_1):PAGE21

A_CPU0_UPI01_RBIAS @BASEBOARD_FAB2_LIB.BASEBOARD_FAB2(SCH_1):A_CPU0_UPI01_RBIAS
 R6D11    1      A RES_0402-49.9,1%,1/16W,CHIP,G2A   I184 @BASEBOARD_FAB2_LIB.BASEBOARD_FAB2(SCH_1):PAGE21
  U5D1 AT29 UPI01_RBIAS<0> SKX_EXT_B_BGA1-IC,TBD   I259 @BASEBOARD_FAB2_LIB.BASEBOARD_FAB2(SCH_1):PAGE21
  U5D1 AP29 UPI01_RBIAS<1> SKX_EXT_B_BGA1-IC,TBD   I259 @BASEBOARD_FAB2_LIB.BASEBOARD_FAB2(SCH_1):PAGE21

A_CPU0_UPI2_RBIAS @BASEBOARD_FAB2_LIB.BASEBOARD_FAB2(SCH_1):A_CPU0_UPI2_RBIAS
  R4P4    1      A RES_0402-49.9,1%,1/16W,CHIP,G2A   I189 @BASEBOARD_FAB2_LIB.BASEBOARD_FAB2(SCH_1):PAGE21
  U5D1 CL28 UPI2_RBIAS<0> SKX_EXT_B_BGA1-IC,TBD   I259 @BASEBOARD_FAB2_LIB.BASEBOARD_FAB2(SCH_1):PAGE21
  U5D1 CK29 UPI2_RBIAS<1> SKX_EXT_B_BGA1-IC,TBD   I259 @BASEBOARD_FAB2_LIB.BASEBOARD_FAB2(SCH_1):PAGE21

A_CPU1_GHJ_RCOMP0 @BASEBOARD_FAB2_LIB.BASEBOARD_FAB2(SCH_1):A_CPU1_GHJ_RCOMP0
 R7P16    1      A RES_0402-90.9,1%,1/16W,CHIP,G2A   I119 @BASEBOARD_FAB2_LIB.BASEBOARD_FAB2(SCH_1):PAGE55
  U2D1  Y43 DDR012_RCOMP<0> SKX_EXT_B_BGA1-IC,TBD   I172 @BASEBOARD_FAB2_LIB.BASEBOARD_FAB2(SCH_1):PAGE55

A_CPU1_GHJ_RCOMP1 @BASEBOARD_FAB2_LIB.BASEBOARD_FAB2(SCH_1):A_CPU1_GHJ_RCOMP1
 R7P17    1      A RES_0402-90.9,1%,1/16W,CHIP,G2A   I140 @BASEBOARD_FAB2_LIB.BASEBOARD_FAB2(SCH_1):PAGE55
  U2D1 AB43 DDR012_RCOMP<1> SKX_EXT_B_BGA1-IC,TBD   I172 @BASEBOARD_FAB2_LIB.BASEBOARD_FAB2(SCH_1):PAGE55

A_CPU1_GHJ_RCOMP2 @BASEBOARD_FAB2_LIB.BASEBOARD_FAB2(SCH_1):A_CPU1_GHJ_RCOMP2
 R7P19    1      A RES_0402-100.0,1%,1/16W,CHIP,GA   I115 @BASEBOARD_FAB2_LIB.BASEBOARD_FAB2(SCH_1):PAGE55
  U2D1 AC42 DDR012_RCOMP<2> SKX_EXT_B_BGA1-IC,TBD   I172 @BASEBOARD_FAB2_LIB.BASEBOARD_FAB2(SCH_1):PAGE55

A_CPU1_KLM_RCOMP0 @BASEBOARD_FAB2_LIB.BASEBOARD_FAB2(SCH_1):A_CPU1_KLM_RCOMP0
  R3D1    1      A RES_0402-90.9,1%,1/16W,CHIP,G2A   I116 @BASEBOARD_FAB2_LIB.BASEBOARD_FAB2(SCH_1):PAGE55
  U2D1 DC48 DDR345_RCOMP<0> SKX_EXT_B_BGA1-IC,TBD   I172 @BASEBOARD_FAB2_LIB.BASEBOARD_FAB2(SCH_1):PAGE55

A_CPU1_KLM_RCOMP1 @BASEBOARD_FAB2_LIB.BASEBOARD_FAB2(SCH_1):A_CPU1_KLM_RCOMP1
  R3D2    1      A RES_0402-90.9,1%,1/16W,CHIP,G2A   I117 @BASEBOARD_FAB2_LIB.BASEBOARD_FAB2(SCH_1):PAGE55
  U2D1 DD47 DDR345_RCOMP<1> SKX_EXT_B_BGA1-IC,TBD   I172 @BASEBOARD_FAB2_LIB.BASEBOARD_FAB2(SCH_1):PAGE55

A_CPU1_KLM_RCOMP2 @BASEBOARD_FAB2_LIB.BASEBOARD_FAB2(SCH_1):A_CPU1_KLM_RCOMP2
  R3D3    1      A RES_0402-100.0,1%,1/16W,CHIP,GA   I118 @BASEBOARD_FAB2_LIB.BASEBOARD_FAB2(SCH_1):PAGE55
  U2D1 DD49 DDR345_RCOMP<2> SKX_EXT_B_BGA1-IC,TBD   I172 @BASEBOARD_FAB2_LIB.BASEBOARD_FAB2(SCH_1):PAGE55

A_CPU1_MCP01_RBIAS @BASEBOARD_FAB2_LIB.BASEBOARD_FAB2(SCH_1):A_CPU1_MCP01_RBIAS
  R3D4    1      A RES_0402-49.9,1%,1/16W,CHIP,G2A   I155 @BASEBOARD_FAB2_LIB.BASEBOARD_FAB2(SCH_1):PAGE55
  U2D1 CU32 MCP01_RBIAS<0> SKX_EXT_B_BGA1-IC,TBD   I172 @BASEBOARD_FAB2_LIB.BASEBOARD_FAB2(SCH_1):PAGE55
  U2D1 CT31 MCP01_RBIAS<1> SKX_EXT_B_BGA1-IC,TBD   I172 @BASEBOARD_FAB2_LIB.BASEBOARD_FAB2(SCH_1):PAGE55

A_CPU1_PE012_RBIAS @BASEBOARD_FAB2_LIB.BASEBOARD_FAB2(SCH_1):A_CPU1_PE012_RBIAS
 R7P10    1      A RES_0402-49.9,1%,1/16W,CHIP,G2A   I124 @BASEBOARD_FAB2_LIB.BASEBOARD_FAB2(SCH_1):PAGE55
  U2D1 CN30 PE012_RBIAS<0> SKX_EXT_B_BGA1-IC,TBD   I172 @BASEBOARD_FAB2_LIB.BASEBOARD_FAB2(SCH_1):PAGE55
  U2D1 CL30 PE012_RBIAS<1> SKX_EXT_B_BGA1-IC,TBD   I172 @BASEBOARD_FAB2_LIB.BASEBOARD_FAB2(SCH_1):PAGE55

A_CPU1_PE3_RBIAS @BASEBOARD_FAB2_LIB.BASEBOARD_FAB2(SCH_1):A_CPU1_PE3_RBIAS
  R7P8    1      A RES_0402-49.9,1%,1/16W,CHIP,G2A   I123 @BASEBOARD_FAB2_LIB.BASEBOARD_FAB2(SCH_1):PAGE55
  U2D1 CP29 PE3_RBIAS<0> SKX_EXT_B_BGA1-IC,TBD   I172 @BASEBOARD_FAB2_LIB.BASEBOARD_FAB2(SCH_1):PAGE55
  U2D1 CR30 PE3_RBIAS<1> SKX_EXT_B_BGA1-IC,TBD   I172 @BASEBOARD_FAB2_LIB.BASEBOARD_FAB2(SCH_1):PAGE55

A_CPU1_UPI01_RBIAS @BASEBOARD_FAB2_LIB.BASEBOARD_FAB2(SCH_1):A_CPU1_UPI01_RBIAS
 R3D19    1      A RES_0402-49.9,1%,1/16W,CHIP,G2A   I125 @BASEBOARD_FAB2_LIB.BASEBOARD_FAB2(SCH_1):PAGE55
  U2D1 AT29 UPI01_RBIAS<0> SKX_EXT_B_BGA1-IC,TBD   I172 @BASEBOARD_FAB2_LIB.BASEBOARD_FAB2(SCH_1):PAGE55
  U2D1 AP29 UPI01_RBIAS<1> SKX_EXT_B_BGA1-IC,TBD   I172 @BASEBOARD_FAB2_LIB.BASEBOARD_FAB2(SCH_1):PAGE55

A_CPU1_UPI2_RBIAS @BASEBOARD_FAB2_LIB.BASEBOARD_FAB2(SCH_1):A_CPU1_UPI2_RBIAS
 R7P11    1      A RES_0402-49.9,1%,1/16W,CHIP,G2A   I126 @BASEBOARD_FAB2_LIB.BASEBOARD_FAB2(SCH_1):PAGE55
  U2D1 CL28 UPI2_RBIAS<0> SKX_EXT_B_BGA1-IC,TBD   I172 @BASEBOARD_FAB2_LIB.BASEBOARD_FAB2(SCH_1):PAGE55
  U2D1 CK29 UPI2_RBIAS<1> SKX_EXT_B_BGA1-IC,TBD   I172 @BASEBOARD_FAB2_LIB.BASEBOARD_FAB2(SCH_1):PAGE55

A_CTOP @BASEBOARD_FAB2_LIB.BASEBOARD_FAB2(SCH_1):A_CTOP
 EU9E1   40   CTOP SPRINGVILLE_SM1-IC,G47144-004    I72 @BASEBOARD_FAB2_LIB.BASEBOARD_FAB2(SCH_1):PAGE139
  C9E7    1      A CAP_0402LF-0.039UF,25V,10%,X7RA    I76 @BASEBOARD_FAB2_LIB.BASEBOARD_FAB2(SCH_1):PAGE139

A_DACRSET @BASEBOARD_FAB2_LIB.BASEBOARD_FAB2(SCH_1):A_DACRSET
R25W58    1      A RES_0402-2.7K,1%,1/16W,CHIP,G2A    I73 @BASEBOARD_FAB2_LIB.BASEBOARD_FAB2(SCH_1):PAGE144
 U25W4   K4 DACRSET AST2520A1-GP-GP_ASIC2-GB1-AST2A    I95 @BASEBOARD_FAB2_LIB.BASEBOARD_FAB2(SCH_1):PAGE144

A_EXTCLKN @BASEBOARD_FAB2_LIB.BASEBOARD_FAB2(SCH_1):A_EXTCLKN
  U7C1  D66 EXTCLKN LBG_CORE_QAT_EXT_D_BGA1-IC,H91A   I220 @BASEBOARD_FAB2_LIB.BASEBOARD_FAB2(SCH_1):PAGE116
  R7B8    1      A RES_0402-10.0K,1%,1/16W,EMPTY,A   I229 @BASEBOARD_FAB2_LIB.BASEBOARD_FAB2(SCH_1):PAGE116

A_EXTCLKP @BASEBOARD_FAB2_LIB.BASEBOARD_FAB2(SCH_1):A_EXTCLKP
  U7C1  E67 EXTCLKP LBG_CORE_QAT_EXT_D_BGA1-IC,H91A   I220 @BASEBOARD_FAB2_LIB.BASEBOARD_FAB2(SCH_1):PAGE116
  R7B7    1      A RES_0402-10.0K,1%,1/16W,EMPTY,A   I230 @BASEBOARD_FAB2_LIB.BASEBOARD_FAB2(SCH_1):PAGE116

A_HSC_C @BASEBOARD_FAB2_LIB.BASEBOARD_FAB2(SCH_1):A_HSC_C
 R1D51    1      A RES_0402-10.0,1%,1/16W,CHIP,G2A   I154 @BASEBOARD_FAB2_LIB.BASEBOARD_FAB2(SCH_1):PAGE200
  C1E2    1      A CAP_1206-0.068UF,50V,20%,X7R,1A   I155 @BASEBOARD_FAB2_LIB.BASEBOARD_FAB2(SCH_1):PAGE200

A_HSC_CSOUT @BASEBOARD_FAB2_LIB.BASEBOARD_FAB2(SCH_1):A_HSC_CSOUT
 EU1D2   19  CSOUT ADM1278_SM-IC,G99251-001    I10 @BASEBOARD_FAB2_LIB.BASEBOARD_FAB2(SCH_1):PAGE199
 R1D20    1      A RES_0402-150.0K,1%,1/16W,CHIP,A   I172 @BASEBOARD_FAB2_LIB.BASEBOARD_FAB2(SCH_1):PAGE200
 R1D14    1      A RES_0402-105.0K,1%,1/16W,CHIP,A   I173 @BASEBOARD_FAB2_LIB.BASEBOARD_FAB2(SCH_1):PAGE200

A_HSC_GATE @BASEBOARD_FAB2_LIB.BASEBOARD_FAB2(SCH_1):A_HSC_GATE
 EU1D2   24   GATE ADM1278_SM-IC,G99251-001    I10 @BASEBOARD_FAB2_LIB.BASEBOARD_FAB2(SCH_1):PAGE199
  R1E1    1      A RES_0402-10.0,1%,1/16W,CHIP,G2A    I56 @BASEBOARD_FAB2_LIB.BASEBOARD_FAB2(SCH_1):PAGE200
  R9R4    1      A RES_0402-10.0,1%,1/16W,CHIP,G2A    I58 @BASEBOARD_FAB2_LIB.BASEBOARD_FAB2(SCH_1):PAGE200
 R1D48    1      A RES_0402-10.0,1%,1/16W,CHIP,G2A    I60 @BASEBOARD_FAB2_LIB.BASEBOARD_FAB2(SCH_1):PAGE200
 R1D51    2      B RES_0402-10.0,1%,1/16W,CHIP,G2A   I154 @BASEBOARD_FAB2_LIB.BASEBOARD_FAB2(SCH_1):PAGE200

A_HSC_GATE1_R @BASEBOARD_FAB2_LIB.BASEBOARD_FAB2(SCH_1):A_HSC_GATE1_R
 EU1E3    4      G MOSFETN_1D3S_SOT5-IC,G68777-001    I54 @BASEBOARD_FAB2_LIB.BASEBOARD_FAB2(SCH_1):PAGE200
  R1E1    2      B RES_0402-10.0,1%,1/16W,CHIP,G2A    I56 @BASEBOARD_FAB2_LIB.BASEBOARD_FAB2(SCH_1):PAGE200

A_HSC_GATE2_R @BASEBOARD_FAB2_LIB.BASEBOARD_FAB2(SCH_1):A_HSC_GATE2_R
 EU9R1    4      G MOSFETN_1D3S_SOT5-IC,G68777-001    I57 @BASEBOARD_FAB2_LIB.BASEBOARD_FAB2(SCH_1):PAGE200
  R9R4    2      B RES_0402-10.0,1%,1/16W,CHIP,G2A    I58 @BASEBOARD_FAB2_LIB.BASEBOARD_FAB2(SCH_1):PAGE200

A_HSC_GATE3_R @BASEBOARD_FAB2_LIB.BASEBOARD_FAB2(SCH_1):A_HSC_GATE3_R
 EU1E1    4      G MOSFETN_1D3S_SOT5-IC,G68777-001    I59 @BASEBOARD_FAB2_LIB.BASEBOARD_FAB2(SCH_1):PAGE200
 R1D48    2      B RES_0402-10.0,1%,1/16W,CHIP,G2A    I60 @BASEBOARD_FAB2_LIB.BASEBOARD_FAB2(SCH_1):PAGE200

A_HSC_HIGH @BASEBOARD_FAB2_LIB.BASEBOARD_FAB2(SCH_1):A_HSC_HIGH
  U1D2    3   INBN TPS3700_SM-IC,H69492-001   I170 @BASEBOARD_FAB2_LIB.BASEBOARD_FAB2(SCH_1):PAGE200
 R1D20    2      B RES_0402-150.0K,1%,1/16W,CHIP,A   I172 @BASEBOARD_FAB2_LIB.BASEBOARD_FAB2(SCH_1):PAGE200
 R1D19    1      A RES_0402-10.0K,1%,1/16W,CHIP,GA   I175 @BASEBOARD_FAB2_LIB.BASEBOARD_FAB2(SCH_1):PAGE200

A_HSC_HIGH_EN @BASEBOARD_FAB2_LIB.BASEBOARD_FAB2(SCH_1):A_HSC_HIGH_EN
  Q1D1    5 GATE<0> FET_N_DUAL_SMLF-2N7002DW,FET,DA    I82 @BASEBOARD_FAB2_LIB.BASEBOARD_FAB2(SCH_1):PAGE199
 R1D18    1      A RES_0402-100.0K,1%,1/16W,CHIP,A    I87 @BASEBOARD_FAB2_LIB.BASEBOARD_FAB2(SCH_1):PAGE199
  J1B3    1    IO1 CONN3_C95678002_PIP-CONN,C9567A   I123 @BASEBOARD_FAB2_LIB.BASEBOARD_FAB2(SCH_1):PAGE199
  J1B4    1    IO1 SCONN3_D53458001_SM-EMPTY,D534A   I124 @BASEBOARD_FAB2_LIB.BASEBOARD_FAB2(SCH_1):PAGE199

A_HSC_HSN @BASEBOARD_FAB2_LIB.BASEBOARD_FAB2(SCH_1):A_HSC_HSN
 EU1D2   27    HSN ADM1278_SM-IC,G99251-001    I10 @BASEBOARD_FAB2_LIB.BASEBOARD_FAB2(SCH_1):PAGE199
 R1D45    2      B RES_0402-0.0,5%,1/16W,CHIP,G21A    I43 @BASEBOARD_FAB2_LIB.BASEBOARD_FAB2(SCH_1):PAGE200
 R9P26    2      B RES_0402-10.0,1%,1/16W,CHIP,G2A    I51 @BASEBOARD_FAB2_LIB.BASEBOARD_FAB2(SCH_1):PAGE200
 R1D47    2      B RES_0402-10.0,1%,1/16W,CHIP,G2A    I52 @BASEBOARD_FAB2_LIB.BASEBOARD_FAB2(SCH_1):PAGE200

A_HSC_HSP @BASEBOARD_FAB2_LIB.BASEBOARD_FAB2(SCH_1):A_HSC_HSP
 EU1D2   28    HSP ADM1278_SM-IC,G99251-001    I10 @BASEBOARD_FAB2_LIB.BASEBOARD_FAB2(SCH_1):PAGE199
 R1D44    2      B RES_0402-0.0,5%,1/16W,CHIP,G21A    I44 @BASEBOARD_FAB2_LIB.BASEBOARD_FAB2(SCH_1):PAGE200
 R9P27    2      B RES_0402-10.0,1%,1/16W,CHIP,G2A    I47 @BASEBOARD_FAB2_LIB.BASEBOARD_FAB2(SCH_1):PAGE200
 R1D46    2      B RES_0402-10.0,1%,1/16W,CHIP,G2A    I48 @BASEBOARD_FAB2_LIB.BASEBOARD_FAB2(SCH_1):PAGE200

A_HSC_INAP @BASEBOARD_FAB2_LIB.BASEBOARD_FAB2(SCH_1):A_HSC_INAP
  U9P2    4   INAP TPS3700_SM-IC,H69492-001   I200 @BASEBOARD_FAB2_LIB.BASEBOARD_FAB2(SCH_1):PAGE200
 R9P12    1      A RES_0402-4.99K,1%,1/16W,CHIP,GA   I218 @BASEBOARD_FAB2_LIB.BASEBOARD_FAB2(SCH_1):PAGE200
 R9P33    2      B RES_0402-100.0K,1%,1/16W,CHIP,A   I222 @BASEBOARD_FAB2_LIB.BASEBOARD_FAB2(SCH_1):PAGE200

A_HSC_ISET @BASEBOARD_FAB2_LIB.BASEBOARD_FAB2(SCH_1):A_HSC_ISET
 EU1D2    3   ISET ADM1278_SM-IC,G99251-001    I10 @BASEBOARD_FAB2_LIB.BASEBOARD_FAB2(SCH_1):PAGE199
 R1D37    2      B RES_0402-100.0K,1%,1/16W,CHIP,A    I15 @BASEBOARD_FAB2_LIB.BASEBOARD_FAB2(SCH_1):PAGE199
 R1D13    2      B RES_0402-90.9K,1%,1/16W,CHIP,GA    I84 @BASEBOARD_FAB2_LIB.BASEBOARD_FAB2(SCH_1):PAGE199
 R1D16    1      A RES_0402-69.8K,1%,1/16W,CHIP,GA    I85 @BASEBOARD_FAB2_LIB.BASEBOARD_FAB2(SCH_1):PAGE199
 C9P15    1      A CAP_A_0402V-0.1UF,16V,10%,X7R,A   I105 @BASEBOARD_FAB2_LIB.BASEBOARD_FAB2(SCH_1):PAGE199

A_HSC_ISET_S @BASEBOARD_FAB2_LIB.BASEBOARD_FAB2(SCH_1):A_HSC_ISET_S
  Q1D1    3 DRAIN<0> FET_N_DUAL_SMLF-2N7002DW,FET,DA    I82 @BASEBOARD_FAB2_LIB.BASEBOARD_FAB2(SCH_1):PAGE199
 R1D13    1      A RES_0402-90.9K,1%,1/16W,CHIP,GA    I84 @BASEBOARD_FAB2_LIB.BASEBOARD_FAB2(SCH_1):PAGE199

A_HSC_ISET_S2 @BASEBOARD_FAB2_LIB.BASEBOARD_FAB2(SCH_1):A_HSC_ISET_S2
 R1D16    2      B RES_0402-69.8K,1%,1/16W,CHIP,GA    I85 @BASEBOARD_FAB2_LIB.BASEBOARD_FAB2(SCH_1):PAGE199
  Q1D1    6 DRAIN<0> FET_N_DUAL_SMLF-2N7002DW,FET,DA    I86 @BASEBOARD_FAB2_LIB.BASEBOARD_FAB2(SCH_1):PAGE199

A_HSC_ISTART @BASEBOARD_FAB2_LIB.BASEBOARD_FAB2(SCH_1):A_HSC_ISTART
 EU1D2    4 ISTART ADM1278_SM-IC,G99251-001    I10 @BASEBOARD_FAB2_LIB.BASEBOARD_FAB2(SCH_1):PAGE199
 R1D32    2      B RES_0402-100.0K,1%,1/16W,CHIP,A    I17 @BASEBOARD_FAB2_LIB.BASEBOARD_FAB2(SCH_1):PAGE199
 R1D34    1      A RES_0402-16K,1.0%,1/16W,CHIP,GA   I102 @BASEBOARD_FAB2_LIB.BASEBOARD_FAB2(SCH_1):PAGE199

A_HSC_LOW @BASEBOARD_FAB2_LIB.BASEBOARD_FAB2(SCH_1):A_HSC_LOW
  U1D2    4   INAP TPS3700_SM-IC,H69492-001   I170 @BASEBOARD_FAB2_LIB.BASEBOARD_FAB2(SCH_1):PAGE200
 R1D14    2      B RES_0402-105.0K,1%,1/16W,CHIP,A   I173 @BASEBOARD_FAB2_LIB.BASEBOARD_FAB2(SCH_1):PAGE200
 R1D12    1      A RES_0402-10.0K,1%,1/16W,CHIP,GA   I174 @BASEBOARD_FAB2_LIB.BASEBOARD_FAB2(SCH_1):PAGE200

A_HSC_LOW_DRAIN @BASEBOARD_FAB2_LIB.BASEBOARD_FAB2(SCH_1):A_HSC_LOW_DRAIN
  Q9P1    6 DRAIN<0> FET_N_DUAL_SMLF-2N7002DW,FET,DA   I196 @BASEBOARD_FAB2_LIB.BASEBOARD_FAB2(SCH_1):PAGE200
 R9P15    1      A RES_0402-0.0,5%,1/16W,EMPTY,G2A   I198 @BASEBOARD_FAB2_LIB.BASEBOARD_FAB2(SCH_1):PAGE200

A_HSC_LOW_EN @BASEBOARD_FAB2_LIB.BASEBOARD_FAB2(SCH_1):A_HSC_LOW_EN
  Q1D1    2 GATE<0> FET_N_DUAL_SMLF-2N7002DW,FET,DA    I86 @BASEBOARD_FAB2_LIB.BASEBOARD_FAB2(SCH_1):PAGE199
 R1D11    1      A RES_0402-100.0K,1%,1/16W,CHIP,A    I88 @BASEBOARD_FAB2_LIB.BASEBOARD_FAB2(SCH_1):PAGE199
  J1B3    3    IO3 CONN3_C95678002_PIP-CONN,C9567A   I123 @BASEBOARD_FAB2_LIB.BASEBOARD_FAB2(SCH_1):PAGE199
  J1B4    3    IO3 SCONN3_D53458001_SM-EMPTY,D534A   I124 @BASEBOARD_FAB2_LIB.BASEBOARD_FAB2(SCH_1):PAGE199

A_HSC_LOW_GATE @BASEBOARD_FAB2_LIB.BASEBOARD_FAB2(SCH_1):A_HSC_LOW_GATE
  U1D2    6   OUTA TPS3700_SM-IC,H69492-001   I170 @BASEBOARD_FAB2_LIB.BASEBOARD_FAB2(SCH_1):PAGE200
 R1D10    2      B RES_0402-10.0K,1%,1/16W,CHIP,GA   I189 @BASEBOARD_FAB2_LIB.BASEBOARD_FAB2(SCH_1):PAGE200
  Q9P1    2 GATE<0> FET_N_DUAL_SMLF-2N7002DW,FET,DA   I196 @BASEBOARD_FAB2_LIB.BASEBOARD_FAB2(SCH_1):PAGE200

A_HSC_MON @BASEBOARD_FAB2_LIB.BASEBOARD_FAB2(SCH_1):A_HSC_MON
 EU1D2   26    MON ADM1278_SM-IC,G99251-001    I10 @BASEBOARD_FAB2_LIB.BASEBOARD_FAB2(SCH_1):PAGE199
 C9P17    1      A CAP_A_0402V-0.1UF,16V,10%,EMPTA    I36 @BASEBOARD_FAB2_LIB.BASEBOARD_FAB2(SCH_1):PAGE200
 C1D22    1      A CAP_A_0402V-0.1UF,16V,10%,EMPTA    I42 @BASEBOARD_FAB2_LIB.BASEBOARD_FAB2(SCH_1):PAGE200
 R1D45    1      A RES_0402-0.0,5%,1/16W,CHIP,G21A    I43 @BASEBOARD_FAB2_LIB.BASEBOARD_FAB2(SCH_1):PAGE200

A_HSC_MOP @BASEBOARD_FAB2_LIB.BASEBOARD_FAB2(SCH_1):A_HSC_MOP
 EU1D2   29    MOP ADM1278_SM-IC,G99251-001    I10 @BASEBOARD_FAB2_LIB.BASEBOARD_FAB2(SCH_1):PAGE199
 C9P16    1      A CAP_A_0402V-0.1UF,16V,10%,EMPTA    I40 @BASEBOARD_FAB2_LIB.BASEBOARD_FAB2(SCH_1):PAGE200
 C1D22    2      B CAP_A_0402V-0.1UF,16V,10%,EMPTA    I42 @BASEBOARD_FAB2_LIB.BASEBOARD_FAB2(SCH_1):PAGE200
 R1D44    1      A RES_0402-0.0,5%,1/16W,CHIP,G21A    I44 @BASEBOARD_FAB2_LIB.BASEBOARD_FAB2(SCH_1):PAGE200

A_HSC_OCP_SEL @BASEBOARD_FAB2_LIB.BASEBOARD_FAB2(SCH_1):A_HSC_OCP_SEL
 R1D15    2      B RES_0402-100.0K,1%,1/16W,CHIP,A    I92 @BASEBOARD_FAB2_LIB.BASEBOARD_FAB2(SCH_1):PAGE199
  J1B3    2    IO2 CONN3_C95678002_PIP-CONN,C9567A   I123 @BASEBOARD_FAB2_LIB.BASEBOARD_FAB2(SCH_1):PAGE199
  J1B4    2    IO2 SCONN3_D53458001_SM-EMPTY,D534A   I124 @BASEBOARD_FAB2_LIB.BASEBOARD_FAB2(SCH_1):PAGE199

A_HSC_OV @BASEBOARD_FAB2_LIB.BASEBOARD_FAB2(SCH_1):A_HSC_OV
 R9P28    2      B RES_0402-100.0K,1%,1/16W,CHIP,A     I6 @BASEBOARD_FAB2_LIB.BASEBOARD_FAB2(SCH_1):PAGE199
 C1D27    1      A CAP_A_0402V-0.1UF,16V,10%,X7R,A     I7 @BASEBOARD_FAB2_LIB.BASEBOARD_FAB2(SCH_1):PAGE199
 R1D43    1      A RES_0402-7.5K,1%,1/16W,CHIP,G2A     I9 @BASEBOARD_FAB2_LIB.BASEBOARD_FAB2(SCH_1):PAGE199
 EU1D2   32     OV ADM1278_SM-IC,G99251-001    I10 @BASEBOARD_FAB2_LIB.BASEBOARD_FAB2(SCH_1):PAGE199

A_HSC_PSET @BASEBOARD_FAB2_LIB.BASEBOARD_FAB2(SCH_1):A_HSC_PSET
 EU1D2    1   PSET ADM1278_SM-IC,G99251-001    I10 @BASEBOARD_FAB2_LIB.BASEBOARD_FAB2(SCH_1):PAGE199
 R1D39    2      B RES_0402-100.0K,1%,1/16W,CHIP,A    I16 @BASEBOARD_FAB2_LIB.BASEBOARD_FAB2(SCH_1):PAGE199
 R1D40    1      A RES_0402-40.2K,1%,1/16W,CHIP,GA   I100 @BASEBOARD_FAB2_LIB.BASEBOARD_FAB2(SCH_1):PAGE199
 C1D21    1      A CAP_A_0402V-0.1UF,16V,10%,X7R,A   I121 @BASEBOARD_FAB2_LIB.BASEBOARD_FAB2(SCH_1):PAGE199

A_HSC_PWGIN @BASEBOARD_FAB2_LIB.BASEBOARD_FAB2(SCH_1):A_HSC_PWGIN
 EU1D2   21  PWGIN ADM1278_SM-IC,G99251-001    I10 @BASEBOARD_FAB2_LIB.BASEBOARD_FAB2(SCH_1):PAGE199
 R9P23    2      B RES_0402-100.0K,1%,1/16W,CHIP,A    I54 @BASEBOARD_FAB2_LIB.BASEBOARD_FAB2(SCH_1):PAGE199
 R9P24    1      A RES_0402-12.1K,1%,1/16W,CHIP,GA    I55 @BASEBOARD_FAB2_LIB.BASEBOARD_FAB2(SCH_1):PAGE199

A_HSC_TEMP @BASEBOARD_FAB2_LIB.BASEBOARD_FAB2(SCH_1):A_HSC_TEMP
 EU1D2   25   TEMP ADM1278_SM-IC,G99251-001    I10 @BASEBOARD_FAB2_LIB.BASEBOARD_FAB2(SCH_1):PAGE199
  Q1D3    1      B NPN_SM-MMBT3904,IC,C52245-001    I58 @BASEBOARD_FAB2_LIB.BASEBOARD_FAB2(SCH_1):PAGE199
  Q1D3    3      C NPN_SM-MMBT3904,IC,C52245-001    I58 @BASEBOARD_FAB2_LIB.BASEBOARD_FAB2(SCH_1):PAGE199

A_HSC_TIMER @BASEBOARD_FAB2_LIB.BASEBOARD_FAB2(SCH_1):A_HSC_TIMER
 EU1D2    5  TIMER ADM1278_SM-IC,G99251-001    I10 @BASEBOARD_FAB2_LIB.BASEBOARD_FAB2(SCH_1):PAGE199
 C9P14    1      A CAP_0603LF-0.033UF,50V,10%,X7RA    I24 @BASEBOARD_FAB2_LIB.BASEBOARD_FAB2(SCH_1):PAGE199
 R9P21    1      A RES_0402-0.0,5%,1/16W,CHIP,G21A    I71 @BASEBOARD_FAB2_LIB.BASEBOARD_FAB2(SCH_1):PAGE200

A_HSC_TIMER_R @BASEBOARD_FAB2_LIB.BASEBOARD_FAB2(SCH_1):A_HSC_TIMER_R
 R9P19    1      A RES_0402-10.0K,1%,1/16W,EMPTY,A    I70 @BASEBOARD_FAB2_LIB.BASEBOARD_FAB2(SCH_1):PAGE200
 R9P21    2      B RES_0402-0.0,5%,1/16W,CHIP,G21A    I71 @BASEBOARD_FAB2_LIB.BASEBOARD_FAB2(SCH_1):PAGE200
  U9P2    3   INBN TPS3700_SM-IC,H69492-001   I200 @BASEBOARD_FAB2_LIB.BASEBOARD_FAB2(SCH_1):PAGE200

A_HSC_UV @BASEBOARD_FAB2_LIB.BASEBOARD_FAB2(SCH_1):A_HSC_UV
 EU1D2   31     UV ADM1278_SM-IC,G99251-001    I10 @BASEBOARD_FAB2_LIB.BASEBOARD_FAB2(SCH_1):PAGE199
 R9P29    2      B RES_0402-100.0K,1%,1/16W,CHIP,A    I12 @BASEBOARD_FAB2_LIB.BASEBOARD_FAB2(SCH_1):PAGE199
 R1D42    1      A RES_0402-11K,1%,1/16W,CHIP,G21A    I13 @BASEBOARD_FAB2_LIB.BASEBOARD_FAB2(SCH_1):PAGE199
 C1D26    1      A CAP_A_0402V-0.1UF,16V,10%,X7R,A   I107 @BASEBOARD_FAB2_LIB.BASEBOARD_FAB2(SCH_1):PAGE199

A_HSC_VCAP @BASEBOARD_FAB2_LIB.BASEBOARD_FAB2(SCH_1):A_HSC_VCAP
 EU1D2    2   VCAP ADM1278_SM-IC,G99251-001    I10 @BASEBOARD_FAB2_LIB.BASEBOARD_FAB2(SCH_1):PAGE199
 R1D37    1      A RES_0402-100.0K,1%,1/16W,CHIP,A    I15 @BASEBOARD_FAB2_LIB.BASEBOARD_FAB2(SCH_1):PAGE199
 R1D39    1      A RES_0402-100.0K,1%,1/16W,CHIP,A    I16 @BASEBOARD_FAB2_LIB.BASEBOARD_FAB2(SCH_1):PAGE199
 R1D32    1      A RES_0402-100.0K,1%,1/16W,CHIP,A    I17 @BASEBOARD_FAB2_LIB.BASEBOARD_FAB2(SCH_1):PAGE199
 R1D29    1      A RES_0402-4.75K,1%,1/16W,EMPTY,A    I37 @BASEBOARD_FAB2_LIB.BASEBOARD_FAB2(SCH_1):PAGE199
 R1D27    1      A RES_0402-4.75K,1%,1/16W,EMPTY,A    I38 @BASEBOARD_FAB2_LIB.BASEBOARD_FAB2(SCH_1):PAGE199
 C1D19    1      A CAP_0402-1.0UF,16V,10%,X6S,D97A   I119 @BASEBOARD_FAB2_LIB.BASEBOARD_FAB2(SCH_1):PAGE199

A_HSC_VOUT @BASEBOARD_FAB2_LIB.BASEBOARD_FAB2(SCH_1):A_HSC_VOUT
 EU1D2   20   VOUT ADM1278_SM-IC,G99251-001    I10 @BASEBOARD_FAB2_LIB.BASEBOARD_FAB2(SCH_1):PAGE199
 R1D36    2      B RES_0402-1.00K,1%,1/16W,CHIP,GA    I65 @BASEBOARD_FAB2_LIB.BASEBOARD_FAB2(SCH_1):PAGE199
 C9P12    1      A CAP_A_0402V-0.1UF,16V,10%,EMPTA    I67 @BASEBOARD_FAB2_LIB.BASEBOARD_FAB2(SCH_1):PAGE199

A_KR0_RBIAS @BASEBOARD_FAB2_LIB.BASEBOARD_FAB2(SCH_1):A_KR0_RBIAS
  U7C1 BB29 LAN_RBIAS_0 LBG_CORE_QAT_EXT_D_BGA1-IC,H91A    I73 @BASEBOARD_FAB2_LIB.BASEBOARD_FAB2(SCH_1):PAGE118
  R2N4    2      B RES_0402-1.0K,0.1%,1/16W,CHIP,A    I96 @BASEBOARD_FAB2_LIB.BASEBOARD_FAB2(SCH_1):PAGE118

A_KR1_RBIAS @BASEBOARD_FAB2_LIB.BASEBOARD_FAB2(SCH_1):A_KR1_RBIAS
  U7C1 BD42 LAN_RBIAS_1 LBG_CORE_QAT_EXT_D_BGA1-IC,H91A    I73 @BASEBOARD_FAB2_LIB.BASEBOARD_FAB2(SCH_1):PAGE118
  R2M6    1      A RES_0402-1.0K,0.1%,1/16W,CHIP,A    I99 @BASEBOARD_FAB2_LIB.BASEBOARD_FAB2(SCH_1):PAGE118

A_P12V_STBY_ADR_TRIGGER @BASEBOARD_FAB2_LIB.BASEBOARD_FAB2(SCH_1):A_P12V_STBY_ADR_TRIGGER
  R9P7    2      B RES_0402-249K,1.0%,1/16W,CHIP,A   I145 @BASEBOARD_FAB2_LIB.BASEBOARD_FAB2(SCH_1):PAGE200
  R9P9    1      A RES_0402-10.0K,1%,1/16W,CHIP,GA   I146 @BASEBOARD_FAB2_LIB.BASEBOARD_FAB2(SCH_1):PAGE200
  U9P1    4   INAP TPS3700_SM-IC,H69492-001   I163 @BASEBOARD_FAB2_LIB.BASEBOARD_FAB2(SCH_1):PAGE200
  C9W2    1      1 SC22P50V2JN-4GP_SMD-BCG-SC22P5A   I236 @BASEBOARD_FAB2_LIB.BASEBOARD_FAB2(SCH_1):PAGE200

A_P12V_STBY_FPH_GATE @BASEBOARD_FAB2_LIB.BASEBOARD_FAB2(SCH_1):A_P12V_STBY_FPH_GATE
  U9P1    1   OUTB TPS3700_SM-IC,H69492-001   I163 @BASEBOARD_FAB2_LIB.BASEBOARD_FAB2(SCH_1):PAGE200
 R9P10    2      B RES_0402-10.0K,1%,1/16W,CHIP,GA   I192 @BASEBOARD_FAB2_LIB.BASEBOARD_FAB2(SCH_1):PAGE200
  Q9P1    5 GATE<0> FET_N_DUAL_SMLF-2N7002DW,FET,DA   I199 @BASEBOARD_FAB2_LIB.BASEBOARD_FAB2(SCH_1):PAGE200

A_P12V_STBY_FP_TRIGGER @BASEBOARD_FAB2_LIB.BASEBOARD_FAB2(SCH_1):A_P12V_STBY_FP_TRIGGER
 R9P13    2      B RES_0402-274K,1.0%,1/16W,CHIP,A   I107 @BASEBOARD_FAB2_LIB.BASEBOARD_FAB2(SCH_1):PAGE200
 R9P11    1      A RES_0402-10.0K,1%,1/16W,CHIP,GA   I108 @BASEBOARD_FAB2_LIB.BASEBOARD_FAB2(SCH_1):PAGE200
  U9P1    3   INBN TPS3700_SM-IC,H69492-001   I163 @BASEBOARD_FAB2_LIB.BASEBOARD_FAB2(SCH_1):PAGE200
  C9W1    1      1 SC22P50V2JN-4GP_SMD-BCG-SC22P5A   I235 @BASEBOARD_FAB2_LIB.BASEBOARD_FAB2(SCH_1):PAGE200
  R6W3    2      2 232KR2F-2-GP_SMD-RG1-232KR2F-2A   I239 @BASEBOARD_FAB2_LIB.BASEBOARD_FAB2(SCH_1):PAGE200

A_P12V_STBY_SCALED @BASEBOARD_FAB2_LIB.BASEBOARD_FAB2(SCH_1):A_P12V_STBY_SCALED
 EU9G1   14    IN2 ADC128D818_SM-IC,H63642-001    I52 @BASEBOARD_FAB2_LIB.BASEBOARD_FAB2(SCH_1):PAGE165
 C9G17    1      A CAP_0402LF-47.0PF,50V,5%,COG,AA    I80 @BASEBOARD_FAB2_LIB.BASEBOARD_FAB2(SCH_1):PAGE169
 R1U32    2      B RES_0402-5.11K,1%,1/16W,CHIP,GA    I82 @BASEBOARD_FAB2_LIB.BASEBOARD_FAB2(SCH_1):PAGE169
 R1U33    1      A RES_0402-1.00K,1%,1/16W,CHIP,GA    I83 @BASEBOARD_FAB2_LIB.BASEBOARD_FAB2(SCH_1):PAGE169
 U25W4   E3 ADC5_GPIW5 AST2520A1-GP-GP_ASIC2-GB1-AST2A   I106 @BASEBOARD_FAB2_LIB.BASEBOARD_FAB2(SCH_1):PAGE147

A_P1V05_STBY_PCH_SENSOR @BASEBOARD_FAB2_LIB.BASEBOARD_FAB2(SCH_1):A_P1V05_STBY_PCH_SENSOR
 EU9G1   13    IN3 ADC128D818_SM-IC,H63642-001    I52 @BASEBOARD_FAB2_LIB.BASEBOARD_FAB2(SCH_1):PAGE165
 C1U21    1      A CAP_0402LF-47.0PF,50V,5%,COG,AA    I56 @BASEBOARD_FAB2_LIB.BASEBOARD_FAB2(SCH_1):PAGE169
 FB1U3    1      A FERRITE_SMLF-30,FB,693286-021    I57 @BASEBOARD_FAB2_LIB.BASEBOARD_FAB2(SCH_1):PAGE169
 U25W4   E1 ADC3_GPIW3 AST2520A1-GP-GP_ASIC2-GB1-AST2A   I106 @BASEBOARD_FAB2_LIB.BASEBOARD_FAB2(SCH_1):PAGE147

A_P3V3_SCALED @BASEBOARD_FAB2_LIB.BASEBOARD_FAB2(SCH_1):A_P3V3_SCALED
 EU9G1   16    IN0 ADC128D818_SM-IC,H63642-001    I52 @BASEBOARD_FAB2_LIB.BASEBOARD_FAB2(SCH_1):PAGE165
 C9G14    1      A CAP_0402LF-47.0PF,50V,5%,COG,AA   I146 @BASEBOARD_FAB2_LIB.BASEBOARD_FAB2(SCH_1):PAGE169
 R1U26    2      B RES_0402-5.11K,1%,1/16W,CHIP,GA   I148 @BASEBOARD_FAB2_LIB.BASEBOARD_FAB2(SCH_1):PAGE169
 R1U27    1      A RES_0402-8.2K,1%,1/16W,CHIP,G2A   I149 @BASEBOARD_FAB2_LIB.BASEBOARD_FAB2(SCH_1):PAGE169
 U25W4   F5 ADC1_GPIW1 AST2520A1-GP-GP_ASIC2-GB1-AST2A   I106 @BASEBOARD_FAB2_LIB.BASEBOARD_FAB2(SCH_1):PAGE147

A_P3V3_STBY_SCALED @BASEBOARD_FAB2_LIB.BASEBOARD_FAB2(SCH_1):A_P3V3_STBY_SCALED
 EU9G1   11    IN5 ADC128D818_SM-IC,H63642-001    I52 @BASEBOARD_FAB2_LIB.BASEBOARD_FAB2(SCH_1):PAGE165
 C9G20    1      A CAP_0402LF-47.0PF,50V,5%,COG,AA    I86 @BASEBOARD_FAB2_LIB.BASEBOARD_FAB2(SCH_1):PAGE169
 R1U39    2      B RES_0402-5.11K,1%,1/16W,CHIP,GA    I88 @BASEBOARD_FAB2_LIB.BASEBOARD_FAB2(SCH_1):PAGE169
 R1U38    1      A RES_0402-8.2K,1%,1/16W,CHIP,G2A   I114 @BASEBOARD_FAB2_LIB.BASEBOARD_FAB2(SCH_1):PAGE169
 U25W4   G5 ADC6_GPIW6 AST2520A1-GP-GP_ASIC2-GB1-AST2A   I106 @BASEBOARD_FAB2_LIB.BASEBOARD_FAB2(SCH_1):PAGE147

A_P3V_BAT_R @BASEBOARD_FAB2_LIB.BASEBOARD_FAB2(SCH_1):A_P3V_BAT_R
 R1U50    1      A RES_0402-200.0K,1%,1/16W,CHIP,A   I126 @BASEBOARD_FAB2_LIB.BASEBOARD_FAB2(SCH_1):PAGE169
 R2U43    2      B RES_0402-1.00K,1%,1/16W,CHIP,GA    I46 @BASEBOARD_FAB2_LIB.BASEBOARD_FAB2(SCH_1):PAGE196
 CR2U1    2     A2 DIODE2A_DUAL_SMLF-BAS70-05,DIOA    I53 @BASEBOARD_FAB2_LIB.BASEBOARD_FAB2(SCH_1):PAGE196

A_P3V_BAT_SCALED @BASEBOARD_FAB2_LIB.BASEBOARD_FAB2(SCH_1):A_P3V_BAT_SCALED
 EU9G1    9    IN7 ADC128D818_SM-IC,H63642-001    I52 @BASEBOARD_FAB2_LIB.BASEBOARD_FAB2(SCH_1):PAGE165
 R9G26    1      A RES_0402-100.0K,1%,1/16W,CHIP,A   I106 @BASEBOARD_FAB2_LIB.BASEBOARD_FAB2(SCH_1):PAGE169
 C9G22    1      A CAP_0402LF-10.0PF,50V,5%,COG,AA   I108 @BASEBOARD_FAB2_LIB.BASEBOARD_FAB2(SCH_1):PAGE169
  Q9G1    4 SOURCE<0> FET_N_DUAL_SMLF-NTJD4001N,FET,A   I157 @BASEBOARD_FAB2_LIB.BASEBOARD_FAB2(SCH_1):PAGE169
 U25W4   G4 ADC7_GPIW7 AST2520A1-GP-GP_ASIC2-GB1-AST2A   I106 @BASEBOARD_FAB2_LIB.BASEBOARD_FAB2(SCH_1):PAGE147

A_P5V_SCALED @BASEBOARD_FAB2_LIB.BASEBOARD_FAB2(SCH_1):A_P5V_SCALED
 EU9G1   15    IN1 ADC128D818_SM-IC,H63642-001    I52 @BASEBOARD_FAB2_LIB.BASEBOARD_FAB2(SCH_1):PAGE165
 C9G15    1      A CAP_0402LF-47.0PF,50V,5%,COG,AA   I139 @BASEBOARD_FAB2_LIB.BASEBOARD_FAB2(SCH_1):PAGE169
 R1U29    2      B RES_0402-5.11K,1%,1/16W,CHIP,GA   I141 @BASEBOARD_FAB2_LIB.BASEBOARD_FAB2(SCH_1):PAGE169
 R1U28    1      A RES_0402-3.48K,1.0%,1/16W,CHIPA   I142 @BASEBOARD_FAB2_LIB.BASEBOARD_FAB2(SCH_1):PAGE169
 U25W4   F3 ADC4_GPIW4 AST2520A1-GP-GP_ASIC2-GB1-AST2A   I106 @BASEBOARD_FAB2_LIB.BASEBOARD_FAB2(SCH_1):PAGE147

A_P5V_STBY_SCALED @BASEBOARD_FAB2_LIB.BASEBOARD_FAB2(SCH_1):A_P5V_STBY_SCALED
 EU9G1   10    IN6 ADC128D818_SM-IC,H63642-001    I52 @BASEBOARD_FAB2_LIB.BASEBOARD_FAB2(SCH_1):PAGE165
 C9G21    1      A CAP_0402LF-47.0PF,50V,5%,COG,AA    I68 @BASEBOARD_FAB2_LIB.BASEBOARD_FAB2(SCH_1):PAGE169
 R1U47    2      B RES_0402-5.11K,1%,1/16W,CHIP,GA   I115 @BASEBOARD_FAB2_LIB.BASEBOARD_FAB2(SCH_1):PAGE169
 R1U44    1      A RES_0402-3.48K,1.0%,1/16W,CHIPA   I116 @BASEBOARD_FAB2_LIB.BASEBOARD_FAB2(SCH_1):PAGE169
 U25W4   F4 ADC0_GPIW0 AST2520A1-GP-GP_ASIC2-GB1-AST2A   I106 @BASEBOARD_FAB2_LIB.BASEBOARD_FAB2(SCH_1):PAGE147

A_PCH_XCLK_BIASREF @BASEBOARD_FAB2_LIB.BASEBOARD_FAB2(SCH_1):A_PCH_XCLK_BIASREF
  U7C1  G44 XCLK_BIASREF LBG_CORE_QAT_EXT_D_BGA1-IC,H91A    I40 @BASEBOARD_FAB2_LIB.BASEBOARD_FAB2(SCH_1):PAGE114
  R3N1    1      A RES_0402-169,1.0%,1/16W,CHIP,GA   I149 @BASEBOARD_FAB2_LIB.BASEBOARD_FAB2(SCH_1):PAGE114

A_PCIEUP_RCOMP_N @BASEBOARD_FAB2_LIB.BASEBOARD_FAB2(SCH_1):A_PCIEUP_RCOMP_N
 R3M12    2      B RES_0402-100.0,1%,1/16W,CHIP,GA   I181 @BASEBOARD_FAB2_LIB.BASEBOARD_FAB2(SCH_1):PAGE116
  U7C1 AF58 PCIEUP_RCOMPN LBG_CORE_QAT_EXT_D_BGA1-IC,H91A   I220 @BASEBOARD_FAB2_LIB.BASEBOARD_FAB2(SCH_1):PAGE116

A_PCIEUP_RCOMP_P @BASEBOARD_FAB2_LIB.BASEBOARD_FAB2(SCH_1):A_PCIEUP_RCOMP_P
 R3M12    1      A RES_0402-100.0,1%,1/16W,CHIP,GA   I181 @BASEBOARD_FAB2_LIB.BASEBOARD_FAB2(SCH_1):PAGE116
  U7C1 AH58 PCIEUP_RCOMPP LBG_CORE_QAT_EXT_D_BGA1-IC,H91A   I220 @BASEBOARD_FAB2_LIB.BASEBOARD_FAB2(SCH_1):PAGE116

A_PCIE_RCOMP_N @BASEBOARD_FAB2_LIB.BASEBOARD_FAB2(SCH_1):A_PCIE_RCOMP_N
 R3M11    2      B RES_0402-100.0,1%,1/16W,CHIP,GA   I108 @BASEBOARD_FAB2_LIB.BASEBOARD_FAB2(SCH_1):PAGE116
  U7C1 BD58 PCIE_RCOMPN LBG_CORE_QAT_EXT_D_BGA1-IC,H91A   I220 @BASEBOARD_FAB2_LIB.BASEBOARD_FAB2(SCH_1):PAGE116

A_PCIE_RCOMP_P @BASEBOARD_FAB2_LIB.BASEBOARD_FAB2(SCH_1):A_PCIE_RCOMP_P
 R3M11    1      A RES_0402-100.0,1%,1/16W,CHIP,GA   I108 @BASEBOARD_FAB2_LIB.BASEBOARD_FAB2(SCH_1):PAGE116
  U7C1 BB56 PCIE_RCOMPP LBG_CORE_QAT_EXT_D_BGA1-IC,H91A   I220 @BASEBOARD_FAB2_LIB.BASEBOARD_FAB2(SCH_1):PAGE116

A_PG_P12V_MAIN @BASEBOARD_FAB2_LIB.BASEBOARD_FAB2(SCH_1):A_PG_P12V_MAIN
  U8D8    4   INAP TPS3700_SM-IC,H69492-001   I104 @BASEBOARD_FAB2_LIB.BASEBOARD_FAB2(SCH_1):PAGE196
 R8D38    2      B RES_0402-100.0K,1%,1/16W,CHIP,A   I112 @BASEBOARD_FAB2_LIB.BASEBOARD_FAB2(SCH_1):PAGE196
 R8D40    1      A RES_0402-3.74K,1%,1/16W,CHIP,GA   I113 @BASEBOARD_FAB2_LIB.BASEBOARD_FAB2(SCH_1):PAGE196

A_PG_P5V @BASEBOARD_FAB2_LIB.BASEBOARD_FAB2(SCH_1):A_PG_P5V
  U8D8    3   INBN TPS3700_SM-IC,H69492-001   I104 @BASEBOARD_FAB2_LIB.BASEBOARD_FAB2(SCH_1):PAGE196
 R8D39    2      B RES_0402-49.9K,1%,1/16W,CHIP,GA   I114 @BASEBOARD_FAB2_LIB.BASEBOARD_FAB2(SCH_1):PAGE196
 R8D37    1      A RES_0402-4.75K,1%,1/16W,CHIP,GA   I115 @BASEBOARD_FAB2_LIB.BASEBOARD_FAB2(SCH_1):PAGE196

A_PVCCRTC_EXT_CAP @BASEBOARD_FAB2_LIB.BASEBOARD_FAB2(SCH_1):A_PVCCRTC_EXT_CAP
  U7C1 AG22 VCCRTCEXT LBG_CORE_QAT_EXT_D_BGA1-IC,H91A    I63 @BASEBOARD_FAB2_LIB.BASEBOARD_FAB2(SCH_1):PAGE122
 C3N29    1      A CAP_A_0402V-0.1UF,16V,10%,X7R,A    I16 @BASEBOARD_FAB2_LIB.BASEBOARD_FAB2(SCH_1):PAGE130

A_PVNN_STBY_PCH_SENSOR @BASEBOARD_FAB2_LIB.BASEBOARD_FAB2(SCH_1):A_PVNN_STBY_PCH_SENSOR
 EU9G1   12    IN4 ADC128D818_SM-IC,H63642-001    I52 @BASEBOARD_FAB2_LIB.BASEBOARD_FAB2(SCH_1):PAGE165
 C9G18    1      A CAP_0402LF-47.0PF,50V,5%,COG,AA   I153 @BASEBOARD_FAB2_LIB.BASEBOARD_FAB2(SCH_1):PAGE169
 FB1U4    1      A FERRITE_SMLF-30,FB,693286-021   I155 @BASEBOARD_FAB2_LIB.BASEBOARD_FAB2(SCH_1):PAGE169
 U25W4   E2 ADC2_GPIW2 AST2520A1-GP-GP_ASIC2-GB1-AST2A   I106 @BASEBOARD_FAB2_LIB.BASEBOARD_FAB2(SCH_1):PAGE147

A_RCOMP_3P3 @BASEBOARD_FAB2_LIB.BASEBOARD_FAB2(SCH_1):A_RCOMP_3P3
  U7C1 BY25 GPIO_RCOMP_3P3 LBG_CORE_QAT_EXT_D_BGA1-IC,H91A   I147 @BASEBOARD_FAB2_LIB.BASEBOARD_FAB2(SCH_1):PAGE120
 R8C21    1      A RES_0402-100.0,1%,1/16W,CHIP,GA   I148 @BASEBOARD_FAB2_LIB.BASEBOARD_FAB2(SCH_1):PAGE120

A_TSENSE_P1V05_PCH_STBY_TMON @BASEBOARD_FAB2_LIB.BASEBOARD_FAB2(SCH_1):A_TSENSE_P1V05_PCH_STBY_TMON
 EU8A1   34  BTSEN PXE1110B_QFN-IC,H89187-001   I229 @BASEBOARD_FAB2_LIB.BASEBOARD_FAB2(SCH_1):PAGE235
 EU7A2   36 TOUT_FLT IR354XX_SM-IR35412,IC,H73684-0A   I117 @BASEBOARD_FAB2_LIB.BASEBOARD_FAB2(SCH_1):PAGE236
  CT69    1      A CAP_0402LF-1000PF,50V,10%,X7R,A   I134 @BASEBOARD_FAB2_LIB.BASEBOARD_FAB2(SCH_1):PAGE236

A_TSENSE_PVCCIN_CPU0 @BASEBOARD_FAB2_LIB.BASEBOARD_FAB2(SCH_1):A_TSENSE_PVCCIN_CPU0
 C4D17    1      A CAP_0402LF-220PF,50V,10%,X7R,AA    I66 @BASEBOARD_FAB2_LIB.BASEBOARD_FAB2(SCH_1):PAGE201
 EU4D4   43  ATSEN PXE1610B_QFN-IC,H79206-001   I155 @BASEBOARD_FAB2_LIB.BASEBOARD_FAB2(SCH_1):PAGE201
 EU4E1   36 TOUT_FLT IR354XX_SM-IR35411,IC,H73688-0A    I63 @BASEBOARD_FAB2_LIB.BASEBOARD_FAB2(SCH_1):PAGE202
 EU4D6   36 TOUT_FLT IR354XX_SM-IR35411,IC,H73688-0A    I64 @BASEBOARD_FAB2_LIB.BASEBOARD_FAB2(SCH_1):PAGE202
 EU4D3   36 TOUT_FLT IR354XX_SM-IR35411,IC,H73688-0A    I70 @BASEBOARD_FAB2_LIB.BASEBOARD_FAB2(SCH_1):PAGE203
 EU4D1   36 TOUT_FLT IR354XX_SM-IR35411,IC,H73688-0A    I71 @BASEBOARD_FAB2_LIB.BASEBOARD_FAB2(SCH_1):PAGE203
 EU4C2   36 TOUT_FLT IR354XX_SM-IR35411,IC,H73688-0A    I71 @BASEBOARD_FAB2_LIB.BASEBOARD_FAB2(SCH_1):PAGE204
   CT2    1      A CAP_0402LF-1000PF,50V,10%,X7R,A    I78 @BASEBOARD_FAB2_LIB.BASEBOARD_FAB2(SCH_1):PAGE202
  CT34    1      A CAP_0402LF-1000PF,50V,10%,X7R,A    I88 @BASEBOARD_FAB2_LIB.BASEBOARD_FAB2(SCH_1):PAGE204
  CT37    1      A CAP_0402LF-1000PF,50V,10%,X7R,A    I99 @BASEBOARD_FAB2_LIB.BASEBOARD_FAB2(SCH_1):PAGE203
  CT42    1      A CAP_0402LF-1000PF,50V,10%,X7R,A   I108 @BASEBOARD_FAB2_LIB.BASEBOARD_FAB2(SCH_1):PAGE203
   CT4    1      A CAP_0402LF-1000PF,50V,10%,X7R,A    I87 @BASEBOARD_FAB2_LIB.BASEBOARD_FAB2(SCH_1):PAGE202

A_TSENSE_PVCCIN_CPU1 @BASEBOARD_FAB2_LIB.BASEBOARD_FAB2(SCH_1):A_TSENSE_PVCCIN_CPU1
 C1C10    1      A CAP_0402LF-220PF,50V,10%,X7R,AA    I69 @BASEBOARD_FAB2_LIB.BASEBOARD_FAB2(SCH_1):PAGE206
 EU1C2   43  ATSEN PXE1610B_QFN-IC,H79206-001   I130 @BASEBOARD_FAB2_LIB.BASEBOARD_FAB2(SCH_1):PAGE206
 EU1E2   36 TOUT_FLT IR354XX_SM-IR35411,IC,H73688-0A    I20 @BASEBOARD_FAB2_LIB.BASEBOARD_FAB2(SCH_1):PAGE207
 EU1D4   36 TOUT_FLT IR354XX_SM-IR35411,IC,H73688-0A    I24 @BASEBOARD_FAB2_LIB.BASEBOARD_FAB2(SCH_1):PAGE207
 EU1D3   36 TOUT_FLT IR354XX_SM-IR35411,IC,H73688-0A    I27 @BASEBOARD_FAB2_LIB.BASEBOARD_FAB2(SCH_1):PAGE208
 EU1D1   36 TOUT_FLT IR354XX_SM-IR35411,IC,H73688-0A    I71 @BASEBOARD_FAB2_LIB.BASEBOARD_FAB2(SCH_1):PAGE208
 EU1C3   36 TOUT_FLT IR354XX_SM-IR35411,IC,H73688-0A    I56 @BASEBOARD_FAB2_LIB.BASEBOARD_FAB2(SCH_1):PAGE209
  CT15    1      A CAP_0402LF-1000PF,50V,10%,X7R,A    I67 @BASEBOARD_FAB2_LIB.BASEBOARD_FAB2(SCH_1):PAGE209
  CTI7    1      A CAP_0402LF-1000PF,50V,10%,X7R,A    I82 @BASEBOARD_FAB2_LIB.BASEBOARD_FAB2(SCH_1):PAGE208
  CT19    1      A CAP_0402LF-1000PF,50V,10%,X7R,A    I90 @BASEBOARD_FAB2_LIB.BASEBOARD_FAB2(SCH_1):PAGE208
  CT22    1      A CAP_0402LF-1000PF,50V,10%,X7R,A    I74 @BASEBOARD_FAB2_LIB.BASEBOARD_FAB2(SCH_1):PAGE207
  CT26    1      A CAP_0402LF-1000PF,50V,10%,X7R,A    I82 @BASEBOARD_FAB2_LIB.BASEBOARD_FAB2(SCH_1):PAGE207

A_TSENSE_PVCCIO_CPU0 @BASEBOARD_FAB2_LIB.BASEBOARD_FAB2(SCH_1):A_TSENSE_PVCCIO_CPU0
 EU3P1   35  ATSEN PXE1110B_QFN-IC,H89187-001    I93 @BASEBOARD_FAB2_LIB.BASEBOARD_FAB2(SCH_1):PAGE211
 EU7C1   36 TOUT_FLT IR354XX_SM-IR35412,IC,H73684-0A   I101 @BASEBOARD_FAB2_LIB.BASEBOARD_FAB2(SCH_1):PAGE212
  CT71    1      A CAP_0402LF-1000PF,50V,10%,X7R,A   I109 @BASEBOARD_FAB2_LIB.BASEBOARD_FAB2(SCH_1):PAGE212

A_TSENSE_PVCCIO_CPU1 @BASEBOARD_FAB2_LIB.BASEBOARD_FAB2(SCH_1):A_TSENSE_PVCCIO_CPU1
 EU4D5   35  ATSEN PXE1110B_QFN-IC,H89187-001    I96 @BASEBOARD_FAB2_LIB.BASEBOARD_FAB2(SCH_1):PAGE213
 EU4E2   36 TOUT_FLT IR354XX_SM-IR35412,IC,H73684-0A   I126 @BASEBOARD_FAB2_LIB.BASEBOARD_FAB2(SCH_1):PAGE214
  CT61    1      A CAP_0402LF-1000PF,50V,10%,X7R,A   I134 @BASEBOARD_FAB2_LIB.BASEBOARD_FAB2(SCH_1):PAGE214

A_TSENSE_PVDDQ_ABC @BASEBOARD_FAB2_LIB.BASEBOARD_FAB2(SCH_1):A_TSENSE_PVDDQ_ABC
  C7G3    1      A CAP_0402LF-220PF,50V,10%,X7R,AA   I320 @BASEBOARD_FAB2_LIB.BASEBOARD_FAB2(SCH_1):PAGE215
 EU7G1   35  ATSEN PXM1310B_QFN-IC,H89186-001   I358 @BASEBOARD_FAB2_LIB.BASEBOARD_FAB2(SCH_1):PAGE215
 EU7G2   36 TOUT_FLT IR354XX_SM-IR35411,IC,H73688-0A   I102 @BASEBOARD_FAB2_LIB.BASEBOARD_FAB2(SCH_1):PAGE216
 EU7G3   36 TOUT_FLT IR354XX_SM-IR35411,IC,H73688-0A   I103 @BASEBOARD_FAB2_LIB.BASEBOARD_FAB2(SCH_1):PAGE216
  CT49    1      A CAP_0402LF-1000PF,50V,10%,X7R,A   I118 @BASEBOARD_FAB2_LIB.BASEBOARD_FAB2(SCH_1):PAGE216
  CT54    1      A CAP_0402LF-1000PF,50V,10%,X7R,A   I121 @BASEBOARD_FAB2_LIB.BASEBOARD_FAB2(SCH_1):PAGE216

A_TSENSE_PVDDQ_DEF @BASEBOARD_FAB2_LIB.BASEBOARD_FAB2(SCH_1):A_TSENSE_PVDDQ_DEF
 C7A29    1      A CAP_0402LF-220PF,50V,10%,X7R,AA    I39 @BASEBOARD_FAB2_LIB.BASEBOARD_FAB2(SCH_1):PAGE218
 EU7A5   35  ATSEN PXM1310B_QFN-IC,H89186-001    I75 @BASEBOARD_FAB2_LIB.BASEBOARD_FAB2(SCH_1):PAGE218
 EU7A1   36 TOUT_FLT IR354XX_SM-IR35411,IC,H73688-0A   I106 @BASEBOARD_FAB2_LIB.BASEBOARD_FAB2(SCH_1):PAGE219
 EU7A4   36 TOUT_FLT IR354XX_SM-IR35411,IC,H73688-0A   I107 @BASEBOARD_FAB2_LIB.BASEBOARD_FAB2(SCH_1):PAGE219
  CT48    1      A CAP_0402LF-1000PF,50V,10%,X7R,A   I119 @BASEBOARD_FAB2_LIB.BASEBOARD_FAB2(SCH_1):PAGE219
  CT43    1      A CAP_0402LF-1000PF,50V,10%,X7R,A   I124 @BASEBOARD_FAB2_LIB.BASEBOARD_FAB2(SCH_1):PAGE219

A_TSENSE_PVDDQ_GHJ @BASEBOARD_FAB2_LIB.BASEBOARD_FAB2(SCH_1):A_TSENSE_PVDDQ_GHJ
 C1G24    1      A CAP_0402LF-220PF,50V,10%,X7R,AA    I36 @BASEBOARD_FAB2_LIB.BASEBOARD_FAB2(SCH_1):PAGE223
 EU1G2   35  ATSEN PXM1310B_QFN-IC,H89186-001    I90 @BASEBOARD_FAB2_LIB.BASEBOARD_FAB2(SCH_1):PAGE223
 EU1G1   36 TOUT_FLT IR354XX_SM-IR35411,IC,H73688-0A   I110 @BASEBOARD_FAB2_LIB.BASEBOARD_FAB2(SCH_1):PAGE224
 EU1F1   36 TOUT_FLT IR354XX_SM-IR35411,IC,H73688-0A   I111 @BASEBOARD_FAB2_LIB.BASEBOARD_FAB2(SCH_1):PAGE224
  CT28    1      A CAP_0402LF-1000PF,50V,10%,X7R,A   I122 @BASEBOARD_FAB2_LIB.BASEBOARD_FAB2(SCH_1):PAGE224
  CT32    1      A CAP_0402LF-1000PF,50V,10%,X7R,A   I130 @BASEBOARD_FAB2_LIB.BASEBOARD_FAB2(SCH_1):PAGE224

A_TSENSE_PVDDQ_KLM @BASEBOARD_FAB2_LIB.BASEBOARD_FAB2(SCH_1):A_TSENSE_PVDDQ_KLM
 C1B11    1      A CAP_0402LF-220PF,50V,10%,X7R,AA    I36 @BASEBOARD_FAB2_LIB.BASEBOARD_FAB2(SCH_1):PAGE226
 EU1B1   35  ATSEN PXM1310B_QFN-IC,H89186-001    I90 @BASEBOARD_FAB2_LIB.BASEBOARD_FAB2(SCH_1):PAGE226
 EU1A2   36 TOUT_FLT IR354XX_SM-IR35411,IC,H73688-0A   I101 @BASEBOARD_FAB2_LIB.BASEBOARD_FAB2(SCH_1):PAGE227
 EU1A1   36 TOUT_FLT IR354XX_SM-IR35411,IC,H73688-0A   I102 @BASEBOARD_FAB2_LIB.BASEBOARD_FAB2(SCH_1):PAGE227
   CT8    1      A CAP_0402LF-1000PF,50V,10%,X7R,A   I114 @BASEBOARD_FAB2_LIB.BASEBOARD_FAB2(SCH_1):PAGE227
  CT10    1      A CAP_0402LF-1000PF,50V,10%,X7R,A   I119 @BASEBOARD_FAB2_LIB.BASEBOARD_FAB2(SCH_1):PAGE227

A_TSENSE_PVNN_PCH_TMON @BASEBOARD_FAB2_LIB.BASEBOARD_FAB2(SCH_1):A_TSENSE_PVNN_PCH_TMON
 EU8A1   35  ATSEN PXE1110B_QFN-IC,H89187-001   I229 @BASEBOARD_FAB2_LIB.BASEBOARD_FAB2(SCH_1):PAGE235
 EU7A3   36 TOUT_FLT IR354XX_SM-IR35412,IC,H73684-0A   I116 @BASEBOARD_FAB2_LIB.BASEBOARD_FAB2(SCH_1):PAGE236
  CT64    1      A CAP_0402LF-1000PF,50V,10%,X7R,A   I136 @BASEBOARD_FAB2_LIB.BASEBOARD_FAB2(SCH_1):PAGE236

A_TSENSE_PVSA_CPU0 @BASEBOARD_FAB2_LIB.BASEBOARD_FAB2(SCH_1):A_TSENSE_PVSA_CPU0
 C4D18    1      A CAP_0402LF-220PF,50V,10%,X7R,AA    I68 @BASEBOARD_FAB2_LIB.BASEBOARD_FAB2(SCH_1):PAGE201
 EU4D4   42  BTSEN PXE1610B_QFN-IC,H79206-001   I155 @BASEBOARD_FAB2_LIB.BASEBOARD_FAB2(SCH_1):PAGE201
 EU4C1   36 TOUT_FLT IR354XX_SM-IR35412,IC,H73684-0A    I46 @BASEBOARD_FAB2_LIB.BASEBOARD_FAB2(SCH_1):PAGE205
  CT58    1      A CAP_0402LF-1000PF,50V,10%,X7R,A    I65 @BASEBOARD_FAB2_LIB.BASEBOARD_FAB2(SCH_1):PAGE205

A_TSENSE_PVSA_CPU1 @BASEBOARD_FAB2_LIB.BASEBOARD_FAB2(SCH_1):A_TSENSE_PVSA_CPU1
 C1C11    1      A CAP_0402LF-220PF,50V,10%,X7R,AA    I71 @BASEBOARD_FAB2_LIB.BASEBOARD_FAB2(SCH_1):PAGE206
 EU1C2   42  BTSEN PXE1610B_QFN-IC,H79206-001   I130 @BASEBOARD_FAB2_LIB.BASEBOARD_FAB2(SCH_1):PAGE206
 EU1C1   36 TOUT_FLT IR354XX_SM-IR35412,IC,H73684-0A    I51 @BASEBOARD_FAB2_LIB.BASEBOARD_FAB2(SCH_1):PAGE210
  CT55    1      A CAP_0402LF-1000PF,50V,10%,X7R,A    I60 @BASEBOARD_FAB2_LIB.BASEBOARD_FAB2(SCH_1):PAGE210

A_USB2AVRES @BASEBOARD_FAB2_LIB.BASEBOARD_FAB2(SCH_1):A_USB2AVRES
 R1T26    1      A RES_0402-8.2K,1%,1/16W,CHIP,G2A    I37 @BASEBOARD_FAB2_LIB.BASEBOARD_FAB2(SCH_1):PAGE146
 U25W4   B8 USB2AVRES AST2520A1-GP-GP_ASIC2-GB1-AST2A   I104 @BASEBOARD_FAB2_LIB.BASEBOARD_FAB2(SCH_1):PAGE146

A_USB2BVRES @BASEBOARD_FAB2_LIB.BASEBOARD_FAB2(SCH_1):A_USB2BVRES
 R1T25    1      A RES_0402-8.2K,1%,1/16W,CHIP,G2A    I35 @BASEBOARD_FAB2_LIB.BASEBOARD_FAB2(SCH_1):PAGE146
 U25W4   B7 USB2BVRES AST2520A1-GP-GP_ASIC2-GB1-AST2A   I104 @BASEBOARD_FAB2_LIB.BASEBOARD_FAB2(SCH_1):PAGE146

A_USB2_COMP @BASEBOARD_FAB2_LIB.BASEBOARD_FAB2(SCH_1):A_USB2_COMP
  U7C1 BN70 USB2_COMP LBG_CORE_QAT_EXT_D_BGA1-IC,H91A    I74 @BASEBOARD_FAB2_LIB.BASEBOARD_FAB2(SCH_1):PAGE115
  R8B9    1      A RES_0402-113,1%,1/16W,CHIP,G21A    I90 @BASEBOARD_FAB2_LIB.BASEBOARD_FAB2(SCH_1):PAGE115

A_USB2_VBUS @BASEBOARD_FAB2_LIB.BASEBOARD_FAB2(SCH_1):A_USB2_VBUS
  U7C1 BR67 USB2_VBUS LBG_CORE_QAT_EXT_D_BGA1-IC,H91A    I74 @BASEBOARD_FAB2_LIB.BASEBOARD_FAB2(SCH_1):PAGE115
 R8B32    1      A RES_0402-10.0K,1%,1/16W,CHIP,GA   I114 @BASEBOARD_FAB2_LIB.BASEBOARD_FAB2(SCH_1):PAGE115

BMC_MIOZ @BASEBOARD_FAB2_LIB.BASEBOARD_FAB2(SCH_1):BMC_MIOZ
 R1T27    2      B RES_0402-240,1.0%,1/16W,CHIP,GA    I58 @BASEBOARD_FAB2_LIB.BASEBOARD_FAB2(SCH_1):PAGE143
 U25W4  W11   MIOZ AST2520A1-GP-GP_ASIC2-GB1-AST2A    I63 @BASEBOARD_FAB2_LIB.BASEBOARD_FAB2(SCH_1):PAGE143

BMC_M_A0 @BASEBOARD_FAB2_LIB.BASEBOARD_FAB2(SCH_1):BMC_M_A0
 U25W5   P3     A0 H5AN4G6NAFR-TFC-GP_MEMORY-G2-HA     I1 @BASEBOARD_FAB2_LIB.BASEBOARD_FAB2(SCH_1):PAGE149
R25W12    2      2 120R2F-GP_RCL_GP-120R2F-GP,64.A   I170 @BASEBOARD_FAB2_LIB.BASEBOARD_FAB2(SCH_1):PAGE149
R25W38    1      1 120R2F-GP_RCL_GP-120R2F-GP,64.A   I197 @BASEBOARD_FAB2_LIB.BASEBOARD_FAB2(SCH_1):PAGE149
 U25W4  V13    MA0 AST2520A1-GP-GP_ASIC2-GB1-AST2A    I63 @BASEBOARD_FAB2_LIB.BASEBOARD_FAB2(SCH_1):PAGE143

BMC_M_A1 @BASEBOARD_FAB2_LIB.BASEBOARD_FAB2(SCH_1):BMC_M_A1
 U25W5   P7     A1 H5AN4G6NAFR-TFC-GP_MEMORY-G2-HA     I1 @BASEBOARD_FAB2_LIB.BASEBOARD_FAB2(SCH_1):PAGE149
R25W13    2      2 120R2F-GP_RCL_GP-120R2F-GP,64.A   I172 @BASEBOARD_FAB2_LIB.BASEBOARD_FAB2(SCH_1):PAGE149
R25W39    1      1 120R2F-GP_RCL_GP-120R2F-GP,64.A   I198 @BASEBOARD_FAB2_LIB.BASEBOARD_FAB2(SCH_1):PAGE149
 U25W4 AB14    MA1 AST2520A1-GP-GP_ASIC2-GB1-AST2A    I63 @BASEBOARD_FAB2_LIB.BASEBOARD_FAB2(SCH_1):PAGE143

BMC_M_A10 @BASEBOARD_FAB2_LIB.BASEBOARD_FAB2(SCH_1):BMC_M_A10
 U25W5   M3 A10/AP H5AN4G6NAFR-TFC-GP_MEMORY-G2-HA     I1 @BASEBOARD_FAB2_LIB.BASEBOARD_FAB2(SCH_1):PAGE149
R25W22    2      2 120R2F-GP_RCL_GP-120R2F-GP,64.A   I176 @BASEBOARD_FAB2_LIB.BASEBOARD_FAB2(SCH_1):PAGE149
R25W48    1      1 120R2F-GP_RCL_GP-120R2F-GP,64.A   I207 @BASEBOARD_FAB2_LIB.BASEBOARD_FAB2(SCH_1):PAGE149
 U25W4  U13   MA10 AST2520A1-GP-GP_ASIC2-GB1-AST2A    I63 @BASEBOARD_FAB2_LIB.BASEBOARD_FAB2(SCH_1):PAGE143

BMC_M_A11 @BASEBOARD_FAB2_LIB.BASEBOARD_FAB2(SCH_1):BMC_M_A11
 U25W5   T2    A11 H5AN4G6NAFR-TFC-GP_MEMORY-G2-HA     I1 @BASEBOARD_FAB2_LIB.BASEBOARD_FAB2(SCH_1):PAGE149
R25W23    2      2 120R2F-GP_RCL_GP-120R2F-GP,64.A   I177 @BASEBOARD_FAB2_LIB.BASEBOARD_FAB2(SCH_1):PAGE149
R25W49    1      1 120R2F-GP_RCL_GP-120R2F-GP,64.A   I208 @BASEBOARD_FAB2_LIB.BASEBOARD_FAB2(SCH_1):PAGE149
 U25W4 AA14   MA11 AST2520A1-GP-GP_ASIC2-GB1-AST2A    I63 @BASEBOARD_FAB2_LIB.BASEBOARD_FAB2(SCH_1):PAGE143

BMC_M_A12 @BASEBOARD_FAB2_LIB.BASEBOARD_FAB2(SCH_1):BMC_M_A12
 U25W5   M7 A12/BC# H5AN4G6NAFR-TFC-GP_MEMORY-G2-HA     I1 @BASEBOARD_FAB2_LIB.BASEBOARD_FAB2(SCH_1):PAGE149
R25W24    2      2 120R2F-GP_RCL_GP-120R2F-GP,64.A   I178 @BASEBOARD_FAB2_LIB.BASEBOARD_FAB2(SCH_1):PAGE149
R25W50    1      1 120R2F-GP_RCL_GP-120R2F-GP,64.A   I209 @BASEBOARD_FAB2_LIB.BASEBOARD_FAB2(SCH_1):PAGE149
 U25W4  Y14   MA12 AST2520A1-GP-GP_ASIC2-GB1-AST2A    I63 @BASEBOARD_FAB2_LIB.BASEBOARD_FAB2(SCH_1):PAGE143

BMC_M_A13 @BASEBOARD_FAB2_LIB.BASEBOARD_FAB2(SCH_1):BMC_M_A13
 U25W5   T8    A13 H5AN4G6NAFR-TFC-GP_MEMORY-G2-HA     I1 @BASEBOARD_FAB2_LIB.BASEBOARD_FAB2(SCH_1):PAGE149
R25W25    2      2 120R2F-GP_RCL_GP-120R2F-GP,64.A   I179 @BASEBOARD_FAB2_LIB.BASEBOARD_FAB2(SCH_1):PAGE149
R25W51    1      1 120R2F-GP_RCL_GP-120R2F-GP,64.A   I210 @BASEBOARD_FAB2_LIB.BASEBOARD_FAB2(SCH_1):PAGE149
 U25W4 AB15   MA13 AST2520A1-GP-GP_ASIC2-GB1-AST2A    I63 @BASEBOARD_FAB2_LIB.BASEBOARD_FAB2(SCH_1):PAGE143

BMC_M_A2 @BASEBOARD_FAB2_LIB.BASEBOARD_FAB2(SCH_1):BMC_M_A2
 U25W5   R3     A2 H5AN4G6NAFR-TFC-GP_MEMORY-G2-HA     I1 @BASEBOARD_FAB2_LIB.BASEBOARD_FAB2(SCH_1):PAGE149
R25W14    2      2 120R2F-GP_RCL_GP-120R2F-GP,64.A   I175 @BASEBOARD_FAB2_LIB.BASEBOARD_FAB2(SCH_1):PAGE149
R25W40    1      1 120R2F-GP_RCL_GP-120R2F-GP,64.A   I200 @BASEBOARD_FAB2_LIB.BASEBOARD_FAB2(SCH_1):PAGE149
 U25W4  W14    MA2 AST2520A1-GP-GP_ASIC2-GB1-AST2A    I63 @BASEBOARD_FAB2_LIB.BASEBOARD_FAB2(SCH_1):PAGE143

BMC_M_A3 @BASEBOARD_FAB2_LIB.BASEBOARD_FAB2(SCH_1):BMC_M_A3
 U25W5   N7     A3 H5AN4G6NAFR-TFC-GP_MEMORY-G2-HA     I1 @BASEBOARD_FAB2_LIB.BASEBOARD_FAB2(SCH_1):PAGE149
R25W15    2      2 120R2F-GP_RCL_GP-120R2F-GP,64.A   I174 @BASEBOARD_FAB2_LIB.BASEBOARD_FAB2(SCH_1):PAGE149
R25W41    1      1 120R2F-GP_RCL_GP-120R2F-GP,64.A   I199 @BASEBOARD_FAB2_LIB.BASEBOARD_FAB2(SCH_1):PAGE149
 U25W4  U14    MA3 AST2520A1-GP-GP_ASIC2-GB1-AST2A    I63 @BASEBOARD_FAB2_LIB.BASEBOARD_FAB2(SCH_1):PAGE143

BMC_M_A4 @BASEBOARD_FAB2_LIB.BASEBOARD_FAB2(SCH_1):BMC_M_A4
 U25W5   N3     A4 H5AN4G6NAFR-TFC-GP_MEMORY-G2-HA     I1 @BASEBOARD_FAB2_LIB.BASEBOARD_FAB2(SCH_1):PAGE149
R25W16    2      2 120R2F-GP_RCL_GP-120R2F-GP,64.A   I173 @BASEBOARD_FAB2_LIB.BASEBOARD_FAB2(SCH_1):PAGE149
R25W42    1      1 120R2F-GP_RCL_GP-120R2F-GP,64.A   I201 @BASEBOARD_FAB2_LIB.BASEBOARD_FAB2(SCH_1):PAGE149
 U25W4  W15    MA4 AST2520A1-GP-GP_ASIC2-GB1-AST2A    I63 @BASEBOARD_FAB2_LIB.BASEBOARD_FAB2(SCH_1):PAGE143

BMC_M_A5 @BASEBOARD_FAB2_LIB.BASEBOARD_FAB2(SCH_1):BMC_M_A5
 U25W5   P8     A5 H5AN4G6NAFR-TFC-GP_MEMORY-G2-HA     I1 @BASEBOARD_FAB2_LIB.BASEBOARD_FAB2(SCH_1):PAGE149
R25W17    2      2 120R2F-GP_RCL_GP-120R2F-GP,64.A   I181 @BASEBOARD_FAB2_LIB.BASEBOARD_FAB2(SCH_1):PAGE149
R25W43    1      1 120R2F-GP_RCL_GP-120R2F-GP,64.A   I202 @BASEBOARD_FAB2_LIB.BASEBOARD_FAB2(SCH_1):PAGE149
 U25W4  V15    MA5 AST2520A1-GP-GP_ASIC2-GB1-AST2A    I63 @BASEBOARD_FAB2_LIB.BASEBOARD_FAB2(SCH_1):PAGE143

BMC_M_A6 @BASEBOARD_FAB2_LIB.BASEBOARD_FAB2(SCH_1):BMC_M_A6
 U25W5   P2     A6 H5AN4G6NAFR-TFC-GP_MEMORY-G2-HA     I1 @BASEBOARD_FAB2_LIB.BASEBOARD_FAB2(SCH_1):PAGE149
R25W18    2      2 120R2F-GP_RCL_GP-120R2F-GP,64.A   I182 @BASEBOARD_FAB2_LIB.BASEBOARD_FAB2(SCH_1):PAGE149
R25W44    1      1 120R2F-GP_RCL_GP-120R2F-GP,64.A   I203 @BASEBOARD_FAB2_LIB.BASEBOARD_FAB2(SCH_1):PAGE149
 U25W4 AB16    MA6 AST2520A1-GP-GP_ASIC2-GB1-AST2A    I63 @BASEBOARD_FAB2_LIB.BASEBOARD_FAB2(SCH_1):PAGE143

BMC_M_A7 @BASEBOARD_FAB2_LIB.BASEBOARD_FAB2(SCH_1):BMC_M_A7
 U25W5   R8     A7 H5AN4G6NAFR-TFC-GP_MEMORY-G2-HA     I1 @BASEBOARD_FAB2_LIB.BASEBOARD_FAB2(SCH_1):PAGE149
R25W19    2      2 120R2F-GP_RCL_GP-120R2F-GP,64.A   I183 @BASEBOARD_FAB2_LIB.BASEBOARD_FAB2(SCH_1):PAGE149
R25W45    1      1 120R2F-GP_RCL_GP-120R2F-GP,64.A   I204 @BASEBOARD_FAB2_LIB.BASEBOARD_FAB2(SCH_1):PAGE149
 U25W4 AA16    MA7 AST2520A1-GP-GP_ASIC2-GB1-AST2A    I63 @BASEBOARD_FAB2_LIB.BASEBOARD_FAB2(SCH_1):PAGE143

BMC_M_A8 @BASEBOARD_FAB2_LIB.BASEBOARD_FAB2(SCH_1):BMC_M_A8
 U25W5   R2     A8 H5AN4G6NAFR-TFC-GP_MEMORY-G2-HA     I1 @BASEBOARD_FAB2_LIB.BASEBOARD_FAB2(SCH_1):PAGE149
R25W20    2      2 120R2F-GP_RCL_GP-120R2F-GP,64.A   I184 @BASEBOARD_FAB2_LIB.BASEBOARD_FAB2(SCH_1):PAGE149
R25W46    1      1 120R2F-GP_RCL_GP-120R2F-GP,64.A   I205 @BASEBOARD_FAB2_LIB.BASEBOARD_FAB2(SCH_1):PAGE149
 U25W4  W16    MA8 AST2520A1-GP-GP_ASIC2-GB1-AST2A    I63 @BASEBOARD_FAB2_LIB.BASEBOARD_FAB2(SCH_1):PAGE143

BMC_M_A9 @BASEBOARD_FAB2_LIB.BASEBOARD_FAB2(SCH_1):BMC_M_A9
 U25W5   R7     A9 H5AN4G6NAFR-TFC-GP_MEMORY-G2-HA     I1 @BASEBOARD_FAB2_LIB.BASEBOARD_FAB2(SCH_1):PAGE149
R25W21    2      2 120R2F-GP_RCL_GP-120R2F-GP,64.A   I185 @BASEBOARD_FAB2_LIB.BASEBOARD_FAB2(SCH_1):PAGE149
R25W47    1      1 120R2F-GP_RCL_GP-120R2F-GP,64.A   I206 @BASEBOARD_FAB2_LIB.BASEBOARD_FAB2(SCH_1):PAGE149
 U25W4  Y16    MA9 AST2520A1-GP-GP_ASIC2-GB1-AST2A    I63 @BASEBOARD_FAB2_LIB.BASEBOARD_FAB2(SCH_1):PAGE143

BMC_M_BA0 @BASEBOARD_FAB2_LIB.BASEBOARD_FAB2(SCH_1):BMC_M_BA0
 U25W5   N2    BA0 H5AN4G6NAFR-TFC-GP_MEMORY-G2-HA     I1 @BASEBOARD_FAB2_LIB.BASEBOARD_FAB2(SCH_1):PAGE149
 R25W9    2      2 120R2F-GP_RCL_GP-120R2F-GP,64.A   I168 @BASEBOARD_FAB2_LIB.BASEBOARD_FAB2(SCH_1):PAGE149
R25W35    1      1 120R2F-GP_RCL_GP-120R2F-GP,64.A   I194 @BASEBOARD_FAB2_LIB.BASEBOARD_FAB2(SCH_1):PAGE149
 U25W4  U12   MBA0 AST2520A1-GP-GP_ASIC2-GB1-AST2A    I63 @BASEBOARD_FAB2_LIB.BASEBOARD_FAB2(SCH_1):PAGE143

BMC_M_BA1 @BASEBOARD_FAB2_LIB.BASEBOARD_FAB2(SCH_1):BMC_M_BA1
 U25W5   N8    BA1 H5AN4G6NAFR-TFC-GP_MEMORY-G2-HA     I1 @BASEBOARD_FAB2_LIB.BASEBOARD_FAB2(SCH_1):PAGE149
R25W10    2      2 120R2F-GP_RCL_GP-120R2F-GP,64.A   I169 @BASEBOARD_FAB2_LIB.BASEBOARD_FAB2(SCH_1):PAGE149
R25W36    1      1 120R2F-GP_RCL_GP-120R2F-GP,64.A   I195 @BASEBOARD_FAB2_LIB.BASEBOARD_FAB2(SCH_1):PAGE149
 U25W4  Y13   MBA1 AST2520A1-GP-GP_ASIC2-GB1-AST2A    I63 @BASEBOARD_FAB2_LIB.BASEBOARD_FAB2(SCH_1):PAGE143

BMC_M_BG0 @BASEBOARD_FAB2_LIB.BASEBOARD_FAB2(SCH_1):BMC_M_BG0
 U25W5   M2    BG0 H5AN4G6NAFR-TFC-GP_MEMORY-G2-HA     I1 @BASEBOARD_FAB2_LIB.BASEBOARD_FAB2(SCH_1):PAGE149
R25W11    2      2 120R2F-GP_RCL_GP-120R2F-GP,64.A   I171 @BASEBOARD_FAB2_LIB.BASEBOARD_FAB2(SCH_1):PAGE149
R25W37    1      1 120R2F-GP_RCL_GP-120R2F-GP,64.A   I196 @BASEBOARD_FAB2_LIB.BASEBOARD_FAB2(SCH_1):PAGE149
 U25W4  W13 MBA2_MBG0 AST2520A1-GP-GP_ASIC2-GB1-AST2A    I63 @BASEBOARD_FAB2_LIB.BASEBOARD_FAB2(SCH_1):PAGE143

BMC_M_CAS_N @BASEBOARD_FAB2_LIB.BASEBOARD_FAB2(SCH_1):BMC_M_CAS_N
 U25W5   M8 CAS#/A15 H5AN4G6NAFR-TFC-GP_MEMORY-G2-HA     I1 @BASEBOARD_FAB2_LIB.BASEBOARD_FAB2(SCH_1):PAGE149
 R25W7    2      2 120R2F-GP_RCL_GP-120R2F-GP,64.A   I166 @BASEBOARD_FAB2_LIB.BASEBOARD_FAB2(SCH_1):PAGE149
R25W33    1      1 120R2F-GP_RCL_GP-120R2F-GP,64.A   I192 @BASEBOARD_FAB2_LIB.BASEBOARD_FAB2(SCH_1):PAGE149
 U25W4 AB13  MCAS# AST2520A1-GP-GP_ASIC2-GB1-AST2A    I63 @BASEBOARD_FAB2_LIB.BASEBOARD_FAB2(SCH_1):PAGE143

BMC_M_CKE @BASEBOARD_FAB2_LIB.BASEBOARD_FAB2(SCH_1):BMC_M_CKE
 U25W5   K2    CKE H5AN4G6NAFR-TFC-GP_MEMORY-G2-HA     I1 @BASEBOARD_FAB2_LIB.BASEBOARD_FAB2(SCH_1):PAGE149
 R25W1    2      2 120R2F-GP_RCL_GP-120R2F-GP,64.A   I160 @BASEBOARD_FAB2_LIB.BASEBOARD_FAB2(SCH_1):PAGE149
R25W27    1      1 120R2F-GP_RCL_GP-120R2F-GP,64.A   I186 @BASEBOARD_FAB2_LIB.BASEBOARD_FAB2(SCH_1):PAGE149
 U25W4  Y11   MCKE AST2520A1-GP-GP_ASIC2-GB1-AST2A    I63 @BASEBOARD_FAB2_LIB.BASEBOARD_FAB2(SCH_1):PAGE143

BMC_M_CLK_DN @BASEBOARD_FAB2_LIB.BASEBOARD_FAB2(SCH_1):BMC_M_CLK_DN
 U25W5   K8   CK_C H5AN4G6NAFR-TFC-GP_MEMORY-G2-HA     I1 @BASEBOARD_FAB2_LIB.BASEBOARD_FAB2(SCH_1):PAGE149
 R1T28    1      1 120R2F-GP_RCL_GP-120R2F-GP,64.A   I212 @BASEBOARD_FAB2_LIB.BASEBOARD_FAB2(SCH_1):PAGE149
 U25W4 AB12   MCKN AST2520A1-GP-GP_ASIC2-GB1-AST2A    I63 @BASEBOARD_FAB2_LIB.BASEBOARD_FAB2(SCH_1):PAGE143

BMC_M_CLK_DP @BASEBOARD_FAB2_LIB.BASEBOARD_FAB2(SCH_1):BMC_M_CLK_DP
 U25W5   K7   CK_T H5AN4G6NAFR-TFC-GP_MEMORY-G2-HA     I1 @BASEBOARD_FAB2_LIB.BASEBOARD_FAB2(SCH_1):PAGE149
 R1T28    2      2 120R2F-GP_RCL_GP-120R2F-GP,64.A   I212 @BASEBOARD_FAB2_LIB.BASEBOARD_FAB2(SCH_1):PAGE149
 U25W4 AB11   MCKP AST2520A1-GP-GP_ASIC2-GB1-AST2A    I63 @BASEBOARD_FAB2_LIB.BASEBOARD_FAB2(SCH_1):PAGE143

BMC_M_CS_N @BASEBOARD_FAB2_LIB.BASEBOARD_FAB2(SCH_1):BMC_M_CS_N
 U25W5   L7    CS# H5AN4G6NAFR-TFC-GP_MEMORY-G2-HA     I1 @BASEBOARD_FAB2_LIB.BASEBOARD_FAB2(SCH_1):PAGE149
 R25W5    2      2 120R2F-GP_RCL_GP-120R2F-GP,64.A   I164 @BASEBOARD_FAB2_LIB.BASEBOARD_FAB2(SCH_1):PAGE149
R25W31    1      1 120R2F-GP_RCL_GP-120R2F-GP,64.A   I190 @BASEBOARD_FAB2_LIB.BASEBOARD_FAB2(SCH_1):PAGE149
 U25W4 AA12   MCS# AST2520A1-GP-GP_ASIC2-GB1-AST2A    I63 @BASEBOARD_FAB2_LIB.BASEBOARD_FAB2(SCH_1):PAGE143

BMC_M_DM0 @BASEBOARD_FAB2_LIB.BASEBOARD_FAB2(SCH_1):BMC_M_DM0
 U25W5   E7 DML#/DBIL# H5AN4G6NAFR-TFC-GP_MEMORY-G2-HA     I1 @BASEBOARD_FAB2_LIB.BASEBOARD_FAB2(SCH_1):PAGE149
 U25W4   U8   MDM0 AST2520A1-GP-GP_ASIC2-GB1-AST2A    I63 @BASEBOARD_FAB2_LIB.BASEBOARD_FAB2(SCH_1):PAGE143

BMC_M_DM1 @BASEBOARD_FAB2_LIB.BASEBOARD_FAB2(SCH_1):BMC_M_DM1
 U25W5   E2 DMU#/DBIU# H5AN4G6NAFR-TFC-GP_MEMORY-G2-HA     I1 @BASEBOARD_FAB2_LIB.BASEBOARD_FAB2(SCH_1):PAGE149
 U25W4  AB8   MDM1 AST2520A1-GP-GP_ASIC2-GB1-AST2A    I63 @BASEBOARD_FAB2_LIB.BASEBOARD_FAB2(SCH_1):PAGE143

BMC_M_DQ0 @BASEBOARD_FAB2_LIB.BASEBOARD_FAB2(SCH_1):BMC_M_DQ0
 U25W5   G2   DQL0 H5AN4G6NAFR-TFC-GP_MEMORY-G2-HA     I1 @BASEBOARD_FAB2_LIB.BASEBOARD_FAB2(SCH_1):PAGE149
 U25W4  U10   MDQ0 AST2520A1-GP-GP_ASIC2-GB1-AST2A    I63 @BASEBOARD_FAB2_LIB.BASEBOARD_FAB2(SCH_1):PAGE143

BMC_M_DQ1 @BASEBOARD_FAB2_LIB.BASEBOARD_FAB2(SCH_1):BMC_M_DQ1
 U25W5   F7   DQL1 H5AN4G6NAFR-TFC-GP_MEMORY-G2-HA     I1 @BASEBOARD_FAB2_LIB.BASEBOARD_FAB2(SCH_1):PAGE149
 U25W4  W10   MDQ1 AST2520A1-GP-GP_ASIC2-GB1-AST2A    I63 @BASEBOARD_FAB2_LIB.BASEBOARD_FAB2(SCH_1):PAGE143

BMC_M_DQ10 @BASEBOARD_FAB2_LIB.BASEBOARD_FAB2(SCH_1):BMC_M_DQ10
 U25W5   C3   DQU2 H5AN4G6NAFR-TFC-GP_MEMORY-G2-HA     I1 @BASEBOARD_FAB2_LIB.BASEBOARD_FAB2(SCH_1):PAGE149
 U25W4   Y7  MDQ10 AST2520A1-GP-GP_ASIC2-GB1-AST2A    I63 @BASEBOARD_FAB2_LIB.BASEBOARD_FAB2(SCH_1):PAGE143

BMC_M_DQ11 @BASEBOARD_FAB2_LIB.BASEBOARD_FAB2(SCH_1):BMC_M_DQ11
 U25W5   C7   DQU3 H5AN4G6NAFR-TFC-GP_MEMORY-G2-HA     I1 @BASEBOARD_FAB2_LIB.BASEBOARD_FAB2(SCH_1):PAGE149
 U25W4   W8  MDQ11 AST2520A1-GP-GP_ASIC2-GB1-AST2A    I63 @BASEBOARD_FAB2_LIB.BASEBOARD_FAB2(SCH_1):PAGE143

BMC_M_DQ12 @BASEBOARD_FAB2_LIB.BASEBOARD_FAB2(SCH_1):BMC_M_DQ12
 U25W5   C2   DQU4 H5AN4G6NAFR-TFC-GP_MEMORY-G2-HA     I1 @BASEBOARD_FAB2_LIB.BASEBOARD_FAB2(SCH_1):PAGE149
 U25W4  AA6  MDQ12 AST2520A1-GP-GP_ASIC2-GB1-AST2A    I63 @BASEBOARD_FAB2_LIB.BASEBOARD_FAB2(SCH_1):PAGE143

BMC_M_DQ13 @BASEBOARD_FAB2_LIB.BASEBOARD_FAB2(SCH_1):BMC_M_DQ13
 U25W5   C8   DQU5 H5AN4G6NAFR-TFC-GP_MEMORY-G2-HA     I1 @BASEBOARD_FAB2_LIB.BASEBOARD_FAB2(SCH_1):PAGE149
 U25W4   W7  MDQ13 AST2520A1-GP-GP_ASIC2-GB1-AST2A    I63 @BASEBOARD_FAB2_LIB.BASEBOARD_FAB2(SCH_1):PAGE143

BMC_M_DQ14 @BASEBOARD_FAB2_LIB.BASEBOARD_FAB2(SCH_1):BMC_M_DQ14
 U25W5   D3   DQU6 H5AN4G6NAFR-TFC-GP_MEMORY-G2-HA     I1 @BASEBOARD_FAB2_LIB.BASEBOARD_FAB2(SCH_1):PAGE149
 U25W4   V7  MDQ14 AST2520A1-GP-GP_ASIC2-GB1-AST2A    I63 @BASEBOARD_FAB2_LIB.BASEBOARD_FAB2(SCH_1):PAGE143

BMC_M_DQ15 @BASEBOARD_FAB2_LIB.BASEBOARD_FAB2(SCH_1):BMC_M_DQ15
 U25W5   D7   DQU7 H5AN4G6NAFR-TFC-GP_MEMORY-G2-HA     I1 @BASEBOARD_FAB2_LIB.BASEBOARD_FAB2(SCH_1):PAGE149
 U25W4   U7  MDQ15 AST2520A1-GP-GP_ASIC2-GB1-AST2A    I63 @BASEBOARD_FAB2_LIB.BASEBOARD_FAB2(SCH_1):PAGE143

BMC_M_DQ2 @BASEBOARD_FAB2_LIB.BASEBOARD_FAB2(SCH_1):BMC_M_DQ2
 U25W5   H3   DQL2 H5AN4G6NAFR-TFC-GP_MEMORY-G2-HA     I1 @BASEBOARD_FAB2_LIB.BASEBOARD_FAB2(SCH_1):PAGE149
 U25W4  Y10   MDQ2 AST2520A1-GP-GP_ASIC2-GB1-AST2A    I63 @BASEBOARD_FAB2_LIB.BASEBOARD_FAB2(SCH_1):PAGE143

BMC_M_DQ3 @BASEBOARD_FAB2_LIB.BASEBOARD_FAB2(SCH_1):BMC_M_DQ3
 U25W5   H7   DQL3 H5AN4G6NAFR-TFC-GP_MEMORY-G2-HA     I1 @BASEBOARD_FAB2_LIB.BASEBOARD_FAB2(SCH_1):PAGE149
 U25W4 AA10   MDQ3 AST2520A1-GP-GP_ASIC2-GB1-AST2A    I63 @BASEBOARD_FAB2_LIB.BASEBOARD_FAB2(SCH_1):PAGE143

BMC_M_DQ4 @BASEBOARD_FAB2_LIB.BASEBOARD_FAB2(SCH_1):BMC_M_DQ4
 U25W5   H2   DQL4 H5AN4G6NAFR-TFC-GP_MEMORY-G2-HA     I1 @BASEBOARD_FAB2_LIB.BASEBOARD_FAB2(SCH_1):PAGE149
 U25W4   U9   MDQ4 AST2520A1-GP-GP_ASIC2-GB1-AST2A    I63 @BASEBOARD_FAB2_LIB.BASEBOARD_FAB2(SCH_1):PAGE143

BMC_M_DQ5 @BASEBOARD_FAB2_LIB.BASEBOARD_FAB2(SCH_1):BMC_M_DQ5
 U25W5   H8   DQL5 H5AN4G6NAFR-TFC-GP_MEMORY-G2-HA     I1 @BASEBOARD_FAB2_LIB.BASEBOARD_FAB2(SCH_1):PAGE149
 U25W4   Y9   MDQ5 AST2520A1-GP-GP_ASIC2-GB1-AST2A    I63 @BASEBOARD_FAB2_LIB.BASEBOARD_FAB2(SCH_1):PAGE143

BMC_M_DQ6 @BASEBOARD_FAB2_LIB.BASEBOARD_FAB2(SCH_1):BMC_M_DQ6
 U25W5   J3   DQL6 H5AN4G6NAFR-TFC-GP_MEMORY-G2-HA     I1 @BASEBOARD_FAB2_LIB.BASEBOARD_FAB2(SCH_1):PAGE149
 U25W4   W9   MDQ6 AST2520A1-GP-GP_ASIC2-GB1-AST2A    I63 @BASEBOARD_FAB2_LIB.BASEBOARD_FAB2(SCH_1):PAGE143

BMC_M_DQ7 @BASEBOARD_FAB2_LIB.BASEBOARD_FAB2(SCH_1):BMC_M_DQ7
 U25W5   J7   DQL7 H5AN4G6NAFR-TFC-GP_MEMORY-G2-HA     I1 @BASEBOARD_FAB2_LIB.BASEBOARD_FAB2(SCH_1):PAGE149
 U25W4   V9   MDQ7 AST2520A1-GP-GP_ASIC2-GB1-AST2A    I63 @BASEBOARD_FAB2_LIB.BASEBOARD_FAB2(SCH_1):PAGE143

BMC_M_DQ8 @BASEBOARD_FAB2_LIB.BASEBOARD_FAB2(SCH_1):BMC_M_DQ8
 U25W5   A3   DQU0 H5AN4G6NAFR-TFC-GP_MEMORY-G2-HA     I1 @BASEBOARD_FAB2_LIB.BASEBOARD_FAB2(SCH_1):PAGE149
 U25W4  AA8   MDQ8 AST2520A1-GP-GP_ASIC2-GB1-AST2A    I63 @BASEBOARD_FAB2_LIB.BASEBOARD_FAB2(SCH_1):PAGE143

BMC_M_DQ9 @BASEBOARD_FAB2_LIB.BASEBOARD_FAB2(SCH_1):BMC_M_DQ9
 U25W5   B8   DQU1 H5AN4G6NAFR-TFC-GP_MEMORY-G2-HA     I1 @BASEBOARD_FAB2_LIB.BASEBOARD_FAB2(SCH_1):PAGE149
 U25W4   Y8   MDQ9 AST2520A1-GP-GP_ASIC2-GB1-AST2A    I63 @BASEBOARD_FAB2_LIB.BASEBOARD_FAB2(SCH_1):PAGE143

BMC_M_DQS0_DN @BASEBOARD_FAB2_LIB.BASEBOARD_FAB2(SCH_1):BMC_M_DQS0_DN
 U25W5   F3 DQSL_C H5AN4G6NAFR-TFC-GP_MEMORY-G2-HA     I1 @BASEBOARD_FAB2_LIB.BASEBOARD_FAB2(SCH_1):PAGE149
 U25W4 AB10 MDQS0N AST2520A1-GP-GP_ASIC2-GB1-AST2A    I63 @BASEBOARD_FAB2_LIB.BASEBOARD_FAB2(SCH_1):PAGE143

BMC_M_DQS0_DP @BASEBOARD_FAB2_LIB.BASEBOARD_FAB2(SCH_1):BMC_M_DQS0_DP
 U25W5   G3 DQSL_T H5AN4G6NAFR-TFC-GP_MEMORY-G2-HA     I1 @BASEBOARD_FAB2_LIB.BASEBOARD_FAB2(SCH_1):PAGE149
 U25W4  AB9 MDQS0P AST2520A1-GP-GP_ASIC2-GB1-AST2A    I63 @BASEBOARD_FAB2_LIB.BASEBOARD_FAB2(SCH_1):PAGE143

BMC_M_DQS1_DN @BASEBOARD_FAB2_LIB.BASEBOARD_FAB2(SCH_1):BMC_M_DQS1_DN
 U25W5   A7 DQSU_C H5AN4G6NAFR-TFC-GP_MEMORY-G2-HA     I1 @BASEBOARD_FAB2_LIB.BASEBOARD_FAB2(SCH_1):PAGE149
 U25W4  AB6 MDQS1N AST2520A1-GP-GP_ASIC2-GB1-AST2A    I63 @BASEBOARD_FAB2_LIB.BASEBOARD_FAB2(SCH_1):PAGE143

BMC_M_DQS1_DP @BASEBOARD_FAB2_LIB.BASEBOARD_FAB2(SCH_1):BMC_M_DQS1_DP
 U25W5   B7 DQSU_T H5AN4G6NAFR-TFC-GP_MEMORY-G2-HA     I1 @BASEBOARD_FAB2_LIB.BASEBOARD_FAB2(SCH_1):PAGE149
 U25W4  AB7 MDQS1P AST2520A1-GP-GP_ASIC2-GB1-AST2A    I63 @BASEBOARD_FAB2_LIB.BASEBOARD_FAB2(SCH_1):PAGE143

BMC_M_MACT_N @BASEBOARD_FAB2_LIB.BASEBOARD_FAB2(SCH_1):BMC_M_MACT_N
 U25W5   L3   ACT# H5AN4G6NAFR-TFC-GP_MEMORY-G2-HA     I1 @BASEBOARD_FAB2_LIB.BASEBOARD_FAB2(SCH_1):PAGE149
R25W26    2      2 120R2F-GP_RCL_GP-120R2F-GP,64.A   I180 @BASEBOARD_FAB2_LIB.BASEBOARD_FAB2(SCH_1):PAGE149
R25W52    1      1 120R2F-GP_RCL_GP-120R2F-GP,64.A   I211 @BASEBOARD_FAB2_LIB.BASEBOARD_FAB2(SCH_1):PAGE149
 U25W4  Y15 MA14_MACT# AST2520A1-GP-GP_ASIC2-GB1-AST2A    I63 @BASEBOARD_FAB2_LIB.BASEBOARD_FAB2(SCH_1):PAGE143

BMC_M_MALERT_N @BASEBOARD_FAB2_LIB.BASEBOARD_FAB2(SCH_1):BMC_M_MALERT_N
 U25W5   P9 ALERT# H5AN4G6NAFR-TFC-GP_MEMORY-G2-HA     I1 @BASEBOARD_FAB2_LIB.BASEBOARD_FAB2(SCH_1):PAGE149
 R25W4    2      2 120R2F-GP_RCL_GP-120R2F-GP,64.A   I162 @BASEBOARD_FAB2_LIB.BASEBOARD_FAB2(SCH_1):PAGE149
R25W30    1      1 120R2F-GP_RCL_GP-120R2F-GP,64.A   I188 @BASEBOARD_FAB2_LIB.BASEBOARD_FAB2(SCH_1):PAGE149
 U25W4  U16 MALERT# AST2520A1-GP-GP_ASIC2-GB1-AST2A   I105 @BASEBOARD_FAB2_LIB.BASEBOARD_FAB2(SCH_1):PAGE146

BMC_M_ODT @BASEBOARD_FAB2_LIB.BASEBOARD_FAB2(SCH_1):BMC_M_ODT
 U25W5   K3    ODT H5AN4G6NAFR-TFC-GP_MEMORY-G2-HA     I1 @BASEBOARD_FAB2_LIB.BASEBOARD_FAB2(SCH_1):PAGE149
 R25W2    2      2 120R2F-GP_RCL_GP-120R2F-GP,64.A   I161 @BASEBOARD_FAB2_LIB.BASEBOARD_FAB2(SCH_1):PAGE149
R25W28    1      1 120R2F-GP_RCL_GP-120R2F-GP,64.A   I187 @BASEBOARD_FAB2_LIB.BASEBOARD_FAB2(SCH_1):PAGE149
 U25W4  V11   MODT AST2520A1-GP-GP_ASIC2-GB1-AST2A    I63 @BASEBOARD_FAB2_LIB.BASEBOARD_FAB2(SCH_1):PAGE143

BMC_M_PAR @BASEBOARD_FAB2_LIB.BASEBOARD_FAB2(SCH_1):BMC_M_PAR
 U25W5   T3    PAR H5AN4G6NAFR-TFC-GP_MEMORY-G2-HA     I1 @BASEBOARD_FAB2_LIB.BASEBOARD_FAB2(SCH_1):PAGE149
R25W119    2      B RES_0402-4.75K,1%,1/16W,CHIP,GA   I120 @BASEBOARD_FAB2_LIB.BASEBOARD_FAB2(SCH_1):PAGE149
R25W118    1      A RES_0402-4.75K,1%,1/16W,EMPTY,A   I122 @BASEBOARD_FAB2_LIB.BASEBOARD_FAB2(SCH_1):PAGE149

BMC_M_RAS_N @BASEBOARD_FAB2_LIB.BASEBOARD_FAB2(SCH_1):BMC_M_RAS_N
 U25W5   L8 RAS#/A16 H5AN4G6NAFR-TFC-GP_MEMORY-G2-HA     I1 @BASEBOARD_FAB2_LIB.BASEBOARD_FAB2(SCH_1):PAGE149
 R25W6    2      2 120R2F-GP_RCL_GP-120R2F-GP,64.A   I165 @BASEBOARD_FAB2_LIB.BASEBOARD_FAB2(SCH_1):PAGE149
R25W32    1      1 120R2F-GP_RCL_GP-120R2F-GP,64.A   I191 @BASEBOARD_FAB2_LIB.BASEBOARD_FAB2(SCH_1):PAGE149
 U25W4  W12  MRAS# AST2520A1-GP-GP_ASIC2-GB1-AST2A    I63 @BASEBOARD_FAB2_LIB.BASEBOARD_FAB2(SCH_1):PAGE143

BMC_M_RST_N @BASEBOARD_FAB2_LIB.BASEBOARD_FAB2(SCH_1):BMC_M_RST_N
 U25W5   P1 RESET# H5AN4G6NAFR-TFC-GP_MEMORY-G2-HA     I1 @BASEBOARD_FAB2_LIB.BASEBOARD_FAB2(SCH_1):PAGE149
 R9F34    2      B RES_0402-33.2,1%,1/16W,CHIP,G2A    I14 @BASEBOARD_FAB2_LIB.BASEBOARD_FAB2(SCH_1):PAGE149
 R25W3    2      2 120R2F-GP_RCL_GP-120R2F-GP,64.A   I163 @BASEBOARD_FAB2_LIB.BASEBOARD_FAB2(SCH_1):PAGE149
R25W29    1      1 120R2F-GP_RCL_GP-120R2F-GP,64.A   I189 @BASEBOARD_FAB2_LIB.BASEBOARD_FAB2(SCH_1):PAGE149
 U25W4 AB17 MRESET# AST2520A1-GP-GP_ASIC2-GB1-AST2A   I105 @BASEBOARD_FAB2_LIB.BASEBOARD_FAB2(SCH_1):PAGE146

BMC_M_VREFCA @BASEBOARD_FAB2_LIB.BASEBOARD_FAB2(SCH_1):BMC_M_VREFCA
C25W22    1      A CAP_0402LF-0.1UF,16V,10%,X7R,AA    I55 @BASEBOARD_FAB2_LIB.BASEBOARD_FAB2(SCH_1):PAGE143
 U25W5   M1 VREFCA H5AN4G6NAFR-TFC-GP_MEMORY-G2-HA     I1 @BASEBOARD_FAB2_LIB.BASEBOARD_FAB2(SCH_1):PAGE149
C25W13    1      A CAP_0402LF-0.1UF,16V,10%,X7R,AA    I65 @BASEBOARD_FAB2_LIB.BASEBOARD_FAB2(SCH_1):PAGE149
 R1T30    2      B RES_0402-1.00K,1%,1/16W,CHIP,GA   I124 @BASEBOARD_FAB2_LIB.BASEBOARD_FAB2(SCH_1):PAGE149
 R1T29    1      A RES_0402-1.00K,1%,1/16W,CHIP,GA   I125 @BASEBOARD_FAB2_LIB.BASEBOARD_FAB2(SCH_1):PAGE149
C25W12    1      A CAP_0402-1.0UF,6.3V,10%,X6S,D9A   I126 @BASEBOARD_FAB2_LIB.BASEBOARD_FAB2(SCH_1):PAGE149
C25W10    2      B CAP_0402LF-0.01UF,25V,10%,X7R,A   I158 @BASEBOARD_FAB2_LIB.BASEBOARD_FAB2(SCH_1):PAGE149
C25W11    1      A CAP_0402LF-0.01UF,25V,10%,X7R,A   I159 @BASEBOARD_FAB2_LIB.BASEBOARD_FAB2(SCH_1):PAGE149
 U25W4   T9  MVREF AST2520A1-GP-GP_ASIC2-GB1-AST2A    I63 @BASEBOARD_FAB2_LIB.BASEBOARD_FAB2(SCH_1):PAGE143

BMC_M_WE_N @BASEBOARD_FAB2_LIB.BASEBOARD_FAB2(SCH_1):BMC_M_WE_N
 U25W5   L2 WE#/A14 H5AN4G6NAFR-TFC-GP_MEMORY-G2-HA     I1 @BASEBOARD_FAB2_LIB.BASEBOARD_FAB2(SCH_1):PAGE149
 R25W8    2      2 120R2F-GP_RCL_GP-120R2F-GP,64.A   I167 @BASEBOARD_FAB2_LIB.BASEBOARD_FAB2(SCH_1):PAGE149
R25W34    1      1 120R2F-GP_RCL_GP-120R2F-GP,64.A   I193 @BASEBOARD_FAB2_LIB.BASEBOARD_FAB2(SCH_1):PAGE149
 U25W4  Y12   MWE# AST2520A1-GP-GP_ASIC2-GB1-AST2A    I63 @BASEBOARD_FAB2_LIB.BASEBOARD_FAB2(SCH_1):PAGE143

BMC_TPM_HW_C_RST @BASEBOARD_FAB2_LIB.BASEBOARD_FAB2(SCH_1):BMC_TPM_HW_C_RST
  R3W2    1      A RES_0402-1.00K,1%,1/16W,CHIP,GA    I12 @BASEBOARD_FAB2_LIB.BASEBOARD_FAB2(SCH_1):PAGE249
  Q9W1    1   GATE FET_N_SOT23LF-2N7002,FET,C7925A    I30 @BASEBOARD_FAB2_LIB.BASEBOARD_FAB2(SCH_1):PAGE249
  C8W1    2      B CAP_0603-10UF,6.3V,20%,X6S,E15A    I32 @BASEBOARD_FAB2_LIB.BASEBOARD_FAB2(SCH_1):PAGE249

BMC_TPM_HW_RST @BASEBOARD_FAB2_LIB.BASEBOARD_FAB2(SCH_1):BMC_TPM_HW_RST
  R3W1    1      A RES_0402-1.00K,1%,1/16W,CHIP,GA     I2 @BASEBOARD_FAB2_LIB.BASEBOARD_FAB2(SCH_1):PAGE249
  C8W1    1      A CAP_0603-10UF,6.3V,20%,X6S,E15A    I32 @BASEBOARD_FAB2_LIB.BASEBOARD_FAB2(SCH_1):PAGE249
 U25W4   V4 GPIOP0_TACH8_VPIR6 AST2520A1-GP-GP_ASIC2-GB1-AST2A   I106 @BASEBOARD_FAB2_LIB.BASEBOARD_FAB2(SCH_1):PAGE147

BMC_UV_HIGH_SET @BASEBOARD_FAB2_LIB.BASEBOARD_FAB2(SCH_1):BMC_UV_HIGH_SET
  Q6W1    1   GATE FET_N_SOT23LF-2N7002,FET,C7925A   I225 @BASEBOARD_FAB2_LIB.BASEBOARD_FAB2(SCH_1):PAGE200
  R6W1    2      B RES_0402-100.0K,1%,1/16W,CHIP,B   I229 @BASEBOARD_FAB2_LIB.BASEBOARD_FAB2(SCH_1):PAGE200
  R6W2    1      A RES_0402-10.0K,1%,1/16W,CHIP,GA   I230 @BASEBOARD_FAB2_LIB.BASEBOARD_FAB2(SCH_1):PAGE200
 U25W4   W5 GPIOP1_TACH9_VPIR7 AST2520A1-GP-GP_ASIC2-GB1-AST2A   I106 @BASEBOARD_FAB2_LIB.BASEBOARD_FAB2(SCH_1):PAGE147

BMC_ZQ @BASEBOARD_FAB2_LIB.BASEBOARD_FAB2(SCH_1):BMC_ZQ
 U25W5   F9     ZQ H5AN4G6NAFR-TFC-GP_MEMORY-G2-HA     I1 @BASEBOARD_FAB2_LIB.BASEBOARD_FAB2(SCH_1):PAGE149
R25W117    1      A RES_0402-240,1.0%,1/16W,CHIP,GA    I55 @BASEBOARD_FAB2_LIB.BASEBOARD_FAB2(SCH_1):PAGE149

CLK_100M_AIRMAX8_PE1_DN @BASEBOARD_FAB2_LIB.BASEBOARD_FAB2(SCH_1):CLK_100M_AIRMAX8_PE1_DN
  U7C1  K38 CLKOUT_SRCN<0> LBG_CORE_QAT_EXT_D_BGA1-IC,H91A    I40 @BASEBOARD_FAB2_LIB.BASEBOARD_FAB2(SCH_1):PAGE114
  J1F1   I4   IOI4 CONN76_H22707001_THMT1-CONN,H2A   I111 @BASEBOARD_FAB2_LIB.BASEBOARD_FAB2(SCH_1):PAGE181

CLK_100M_AIRMAX8_PE1_DP @BASEBOARD_FAB2_LIB.BASEBOARD_FAB2(SCH_1):CLK_100M_AIRMAX8_PE1_DP
  U7C1  H38 CLKOUT_SRCP<0> LBG_CORE_QAT_EXT_D_BGA1-IC,H91A    I40 @BASEBOARD_FAB2_LIB.BASEBOARD_FAB2(SCH_1):PAGE114
  J1F1   H4   IOH4 CONN76_H22707001_THMT1-CONN,H2A   I111 @BASEBOARD_FAB2_LIB.BASEBOARD_FAB2(SCH_1):PAGE181

CLK_100M_BMC_PE_DN @BASEBOARD_FAB2_LIB.BASEBOARD_FAB2(SCH_1):CLK_100M_BMC_PE_DN
  U7C1  B29 CLKOUT_PLAT0N LBG_CORE_QAT_EXT_D_BGA1-IC,H91A    I40 @BASEBOARD_FAB2_LIB.BASEBOARD_FAB2(SCH_1):PAGE114
  R7C2    2      B RES_0402-0.0,5%,1/16W,EMPTY,G2A   I141 @BASEBOARD_FAB2_LIB.BASEBOARD_FAB2(SCH_1):PAGE114

CLK_100M_BMC_PE_DP @BASEBOARD_FAB2_LIB.BASEBOARD_FAB2(SCH_1):CLK_100M_BMC_PE_DP
  U7C1  D29 CLKOUT_PLAT0P LBG_CORE_QAT_EXT_D_BGA1-IC,H91A    I40 @BASEBOARD_FAB2_LIB.BASEBOARD_FAB2(SCH_1):PAGE114
  R7C4    2      B RES_0402-0.0,5%,1/16W,EMPTY,G2A   I142 @BASEBOARD_FAB2_LIB.BASEBOARD_FAB2(SCH_1):PAGE114

CLK_100M_BMC_PE_R_DN @BASEBOARD_FAB2_LIB.BASEBOARD_FAB2(SCH_1):CLK_100M_BMC_PE_R_DN
  R7C2    1      A RES_0402-0.0,5%,1/16W,EMPTY,G2A   I141 @BASEBOARD_FAB2_LIB.BASEBOARD_FAB2(SCH_1):PAGE114
R25W60    1      A RES_0402-100.0K,1%,1/16W,CHIP,A    I34 @BASEBOARD_FAB2_LIB.BASEBOARD_FAB2(SCH_1):PAGE145
 U25W4  K22 PEREFCLKN AST2520A1-GP-GP_ASIC2-GB1-AST2A   I117 @BASEBOARD_FAB2_LIB.BASEBOARD_FAB2(SCH_1):PAGE145

CLK_100M_BMC_PE_R_DP @BASEBOARD_FAB2_LIB.BASEBOARD_FAB2(SCH_1):CLK_100M_BMC_PE_R_DP
  R7C4    1      A RES_0402-0.0,5%,1/16W,EMPTY,G2A   I142 @BASEBOARD_FAB2_LIB.BASEBOARD_FAB2(SCH_1):PAGE114
R25W61    1      A RES_0402-100.0K,1%,1/16W,CHIP,A    I30 @BASEBOARD_FAB2_LIB.BASEBOARD_FAB2(SCH_1):PAGE145
 U25W4  K21 PEREFCLKP AST2520A1-GP-GP_ASIC2-GB1-AST2A   I117 @BASEBOARD_FAB2_LIB.BASEBOARD_FAB2(SCH_1):PAGE145

CLK_100M_CPU0_BCLK0_DN @BASEBOARD_FAB2_LIB.BASEBOARD_FAB2(SCH_1):CLK_100M_CPU0_BCLK0_DN
  U5D1 AU24 BCLK0_DN SKX_EXT_B_BGA1-IC,TBD   I259 @BASEBOARD_FAB2_LIB.BASEBOARD_FAB2(SCH_1):PAGE21
 R4D25    2      B RES_0402-27.4,1%,1/16W,CHIP,G2A     I1 @BASEBOARD_FAB2_LIB.BASEBOARD_FAB2(SCH_1):PAGE103
 R6P15    1      A RES_0402-42.2,1.0%,1/16W,EMPTYA   I167 @BASEBOARD_FAB2_LIB.BASEBOARD_FAB2(SCH_1):PAGE103

CLK_100M_CPU0_BCLK0_DP @BASEBOARD_FAB2_LIB.BASEBOARD_FAB2(SCH_1):CLK_100M_CPU0_BCLK0_DP
  U5D1 AW24 BCLK0_DP SKX_EXT_B_BGA1-IC,TBD   I259 @BASEBOARD_FAB2_LIB.BASEBOARD_FAB2(SCH_1):PAGE21
 R4D29    2      B RES_0402-27.4,1%,1/16W,CHIP,G2A    I69 @BASEBOARD_FAB2_LIB.BASEBOARD_FAB2(SCH_1):PAGE103
 R6P17    1      A RES_0402-42.2,1.0%,1/16W,EMPTYA   I165 @BASEBOARD_FAB2_LIB.BASEBOARD_FAB2(SCH_1):PAGE103

CLK_100M_CPU0_BCLK0_R_DN @BASEBOARD_FAB2_LIB.BASEBOARD_FAB2(SCH_1):CLK_100M_CPU0_BCLK0_R_DN
 EU4D2   18 DIF_0N NB3W1200L_LCC-IC,H13585-001     I1 @BASEBOARD_FAB2_LIB.BASEBOARD_FAB2(SCH_1):PAGE102
 R4D25    1      A RES_0402-27.4,1%,1/16W,CHIP,G2A     I1 @BASEBOARD_FAB2_LIB.BASEBOARD_FAB2(SCH_1):PAGE103

CLK_100M_CPU0_BCLK0_R_DP @BASEBOARD_FAB2_LIB.BASEBOARD_FAB2(SCH_1):CLK_100M_CPU0_BCLK0_R_DP
 EU4D2   17 DIF_0P NB3W1200L_LCC-IC,H13585-001     I1 @BASEBOARD_FAB2_LIB.BASEBOARD_FAB2(SCH_1):PAGE102
 R4D29    1      A RES_0402-27.4,1%,1/16W,CHIP,G2A    I69 @BASEBOARD_FAB2_LIB.BASEBOARD_FAB2(SCH_1):PAGE103

CLK_100M_CPU0_BCLK1_DN @BASEBOARD_FAB2_LIB.BASEBOARD_FAB2(SCH_1):CLK_100M_CPU0_BCLK1_DN
  U5D1 CR26 BCLK1_DN SKX_EXT_B_BGA1-IC,TBD   I259 @BASEBOARD_FAB2_LIB.BASEBOARD_FAB2(SCH_1):PAGE21
 R4D20    2      B RES_0402-27.4,1%,1/16W,CHIP,G2A   I119 @BASEBOARD_FAB2_LIB.BASEBOARD_FAB2(SCH_1):PAGE103
 R4D18    1      A RES_0402-42.2,1.0%,1/16W,EMPTYA   I163 @BASEBOARD_FAB2_LIB.BASEBOARD_FAB2(SCH_1):PAGE103

CLK_100M_CPU0_BCLK1_DP @BASEBOARD_FAB2_LIB.BASEBOARD_FAB2(SCH_1):CLK_100M_CPU0_BCLK1_DP
  U5D1 CP27 BCLK1_DP SKX_EXT_B_BGA1-IC,TBD   I259 @BASEBOARD_FAB2_LIB.BASEBOARD_FAB2(SCH_1):PAGE21
 R4D22    2      B RES_0402-27.4,1%,1/16W,CHIP,G2A   I114 @BASEBOARD_FAB2_LIB.BASEBOARD_FAB2(SCH_1):PAGE103
 R4D24    1      A RES_0402-42.2,1.0%,1/16W,EMPTYA   I161 @BASEBOARD_FAB2_LIB.BASEBOARD_FAB2(SCH_1):PAGE103

CLK_100M_CPU0_BCLK1_R_DN @BASEBOARD_FAB2_LIB.BASEBOARD_FAB2(SCH_1):CLK_100M_CPU0_BCLK1_R_DN
 EU4D2   22 DIF_1N NB3W1200L_LCC-IC,H13585-001     I1 @BASEBOARD_FAB2_LIB.BASEBOARD_FAB2(SCH_1):PAGE102
 R4D20    1      A RES_0402-27.4,1%,1/16W,CHIP,G2A   I119 @BASEBOARD_FAB2_LIB.BASEBOARD_FAB2(SCH_1):PAGE103

CLK_100M_CPU0_BCLK1_R_DP @BASEBOARD_FAB2_LIB.BASEBOARD_FAB2(SCH_1):CLK_100M_CPU0_BCLK1_R_DP
 EU4D2   21 DIF_1P NB3W1200L_LCC-IC,H13585-001     I1 @BASEBOARD_FAB2_LIB.BASEBOARD_FAB2(SCH_1):PAGE102
 R4D22    1      A RES_0402-27.4,1%,1/16W,CHIP,G2A   I114 @BASEBOARD_FAB2_LIB.BASEBOARD_FAB2(SCH_1):PAGE103

CLK_100M_CPU0_BCLK2_DN @BASEBOARD_FAB2_LIB.BASEBOARD_FAB2(SCH_1):CLK_100M_CPU0_BCLK2_DN
  U5D1 CT25 BCLK2_DN SKX_EXT_B_BGA1-IC,TBD   I259 @BASEBOARD_FAB2_LIB.BASEBOARD_FAB2(SCH_1):PAGE21
 R4D14    2      B RES_0402-27.4,1%,1/16W,CHIP,G2A   I109 @BASEBOARD_FAB2_LIB.BASEBOARD_FAB2(SCH_1):PAGE103
 R6P12    1      A RES_0402-42.2,1.0%,1/16W,EMPTYA   I159 @BASEBOARD_FAB2_LIB.BASEBOARD_FAB2(SCH_1):PAGE103

CLK_100M_CPU0_BCLK2_DP @BASEBOARD_FAB2_LIB.BASEBOARD_FAB2(SCH_1):CLK_100M_CPU0_BCLK2_DP
  U5D1 CU26 BCLK2_DP SKX_EXT_B_BGA1-IC,TBD   I259 @BASEBOARD_FAB2_LIB.BASEBOARD_FAB2(SCH_1):PAGE21
 R4D17    2      B RES_0402-27.4,1%,1/16W,CHIP,G2A   I104 @BASEBOARD_FAB2_LIB.BASEBOARD_FAB2(SCH_1):PAGE103
 R6P13    1      A RES_0402-42.2,1.0%,1/16W,EMPTYA   I157 @BASEBOARD_FAB2_LIB.BASEBOARD_FAB2(SCH_1):PAGE103

CLK_100M_CPU0_BCLK2_R_DN @BASEBOARD_FAB2_LIB.BASEBOARD_FAB2(SCH_1):CLK_100M_CPU0_BCLK2_R_DN
 EU4D2   27 DIF_2N NB3W1200L_LCC-IC,H13585-001     I1 @BASEBOARD_FAB2_LIB.BASEBOARD_FAB2(SCH_1):PAGE102
 R4D14    1      A RES_0402-27.4,1%,1/16W,CHIP,G2A   I109 @BASEBOARD_FAB2_LIB.BASEBOARD_FAB2(SCH_1):PAGE103

CLK_100M_CPU0_BCLK2_R_DP @BASEBOARD_FAB2_LIB.BASEBOARD_FAB2(SCH_1):CLK_100M_CPU0_BCLK2_R_DP
 EU4D2   26 DIF_2P NB3W1200L_LCC-IC,H13585-001     I1 @BASEBOARD_FAB2_LIB.BASEBOARD_FAB2(SCH_1):PAGE102
 R4D17    1      A RES_0402-27.4,1%,1/16W,CHIP,G2A   I104 @BASEBOARD_FAB2_LIB.BASEBOARD_FAB2(SCH_1):PAGE103

CLK_100M_CPU0_PE_REFCLK_DN @BASEBOARD_FAB2_LIB.BASEBOARD_FAB2(SCH_1):CLK_100M_CPU0_PE_REFCLK_DN
  U5D1 BU24 CD_PE_REFCLK_DN SKX_EXT_B_BGA1-IC,TBD    I61 @BASEBOARD_FAB2_LIB.BASEBOARD_FAB2(SCH_1):PAGE29
 R4D10    2      B RES_0402-27.4,1%,1/16W,CHIP,G2A    I99 @BASEBOARD_FAB2_LIB.BASEBOARD_FAB2(SCH_1):PAGE103
  R6P9    1      A RES_0402-42.2,1.0%,1/16W,EMPTYA   I155 @BASEBOARD_FAB2_LIB.BASEBOARD_FAB2(SCH_1):PAGE103

CLK_100M_CPU0_PE_REFCLK_DP @BASEBOARD_FAB2_LIB.BASEBOARD_FAB2(SCH_1):CLK_100M_CPU0_PE_REFCLK_DP
  U5D1 BW24 CD_PE_REFCLK_DP SKX_EXT_B_BGA1-IC,TBD    I61 @BASEBOARD_FAB2_LIB.BASEBOARD_FAB2(SCH_1):PAGE29
 R4D12    2      B RES_0402-27.4,1%,1/16W,CHIP,G2A    I94 @BASEBOARD_FAB2_LIB.BASEBOARD_FAB2(SCH_1):PAGE103
 R6P11    1      A RES_0402-42.2,1.0%,1/16W,EMPTYA   I153 @BASEBOARD_FAB2_LIB.BASEBOARD_FAB2(SCH_1):PAGE103

CLK_100M_CPU0_PE_REFCLK_R_DN @BASEBOARD_FAB2_LIB.BASEBOARD_FAB2(SCH_1):CLK_100M_CPU0_PE_REFCLK_R_DN
 EU4D2   31 DIF_3N NB3W1200L_LCC-IC,H13585-001     I1 @BASEBOARD_FAB2_LIB.BASEBOARD_FAB2(SCH_1):PAGE102
 R4D10    1      A RES_0402-27.4,1%,1/16W,CHIP,G2A    I99 @BASEBOARD_FAB2_LIB.BASEBOARD_FAB2(SCH_1):PAGE103

CLK_100M_CPU0_PE_REFCLK_R_DP @BASEBOARD_FAB2_LIB.BASEBOARD_FAB2(SCH_1):CLK_100M_CPU0_PE_REFCLK_R_DP
 EU4D2   30 DIF_3P NB3W1200L_LCC-IC,H13585-001     I1 @BASEBOARD_FAB2_LIB.BASEBOARD_FAB2(SCH_1):PAGE102
 R4D12    1      A RES_0402-27.4,1%,1/16W,CHIP,G2A    I94 @BASEBOARD_FAB2_LIB.BASEBOARD_FAB2(SCH_1):PAGE103

CLK_100M_CPU0_RC_REFCLK0_DN @BASEBOARD_FAB2_LIB.BASEBOARD_FAB2(SCH_1):CLK_100M_CPU0_RC_REFCLK0_DN
  U5D1 AP27 RSVD<195> SKX_EXT_B_BGA1-IC,TBD   I204 @BASEBOARD_FAB2_LIB.BASEBOARD_FAB2(SCH_1):PAGE22
  R4D7    2      B RES_0402-27.4,1%,1/16W,CHIP,G2A    I89 @BASEBOARD_FAB2_LIB.BASEBOARD_FAB2(SCH_1):PAGE103
  R6P2    1      A RES_0402-42.2,1.0%,1/16W,EMPTYA   I151 @BASEBOARD_FAB2_LIB.BASEBOARD_FAB2(SCH_1):PAGE103

CLK_100M_CPU0_RC_REFCLK0_DP @BASEBOARD_FAB2_LIB.BASEBOARD_FAB2(SCH_1):CLK_100M_CPU0_RC_REFCLK0_DP
  U5D1 AM27 RSVD<206> SKX_EXT_B_BGA1-IC,TBD   I204 @BASEBOARD_FAB2_LIB.BASEBOARD_FAB2(SCH_1):PAGE22
  R4D8    2      B RES_0402-27.4,1%,1/16W,CHIP,G2A    I84 @BASEBOARD_FAB2_LIB.BASEBOARD_FAB2(SCH_1):PAGE103
  R6P1    1      A RES_0402-42.2,1.0%,1/16W,EMPTYA   I149 @BASEBOARD_FAB2_LIB.BASEBOARD_FAB2(SCH_1):PAGE103

CLK_100M_CPU0_RC_REFCLK0_R_DN @BASEBOARD_FAB2_LIB.BASEBOARD_FAB2(SCH_1):CLK_100M_CPU0_RC_REFCLK0_R_DN
 EU4D2   35 DIF_4N NB3W1200L_LCC-IC,H13585-001     I1 @BASEBOARD_FAB2_LIB.BASEBOARD_FAB2(SCH_1):PAGE102
  R4D7    1      A RES_0402-27.4,1%,1/16W,CHIP,G2A    I89 @BASEBOARD_FAB2_LIB.BASEBOARD_FAB2(SCH_1):PAGE103

CLK_100M_CPU0_RC_REFCLK0_R_DP @BASEBOARD_FAB2_LIB.BASEBOARD_FAB2(SCH_1):CLK_100M_CPU0_RC_REFCLK0_R_DP
 EU4D2   34 DIF_4P NB3W1200L_LCC-IC,H13585-001     I1 @BASEBOARD_FAB2_LIB.BASEBOARD_FAB2(SCH_1):PAGE102
  R4D8    1      A RES_0402-27.4,1%,1/16W,CHIP,G2A    I84 @BASEBOARD_FAB2_LIB.BASEBOARD_FAB2(SCH_1):PAGE103

CLK_100M_CPU0_RC_REFCLK1_DN @BASEBOARD_FAB2_LIB.BASEBOARD_FAB2(SCH_1):CLK_100M_CPU0_RC_REFCLK1_DN
  U5D1 BB25 RSVD<165> SKX_EXT_B_BGA1-IC,TBD    I15 @BASEBOARD_FAB2_LIB.BASEBOARD_FAB2(SCH_1):PAGE36
  R4D5    2      B RES_0402-27.4,1%,1/16W,CHIP,G2A    I79 @BASEBOARD_FAB2_LIB.BASEBOARD_FAB2(SCH_1):PAGE103
  R6P4    1      A RES_0402-42.2,1.0%,1/16W,EMPTYA   I147 @BASEBOARD_FAB2_LIB.BASEBOARD_FAB2(SCH_1):PAGE103

CLK_100M_CPU0_RC_REFCLK1_DP @BASEBOARD_FAB2_LIB.BASEBOARD_FAB2(SCH_1):CLK_100M_CPU0_RC_REFCLK1_DP
  U5D1 BD25 RSVD<153> SKX_EXT_B_BGA1-IC,TBD    I15 @BASEBOARD_FAB2_LIB.BASEBOARD_FAB2(SCH_1):PAGE36
  R4D6    2      B RES_0402-27.4,1%,1/16W,CHIP,G2A    I74 @BASEBOARD_FAB2_LIB.BASEBOARD_FAB2(SCH_1):PAGE103
  R6P3    1      A RES_0402-42.2,1.0%,1/16W,EMPTYA   I145 @BASEBOARD_FAB2_LIB.BASEBOARD_FAB2(SCH_1):PAGE103

CLK_100M_CPU0_RC_REFCLK1_R_DN @BASEBOARD_FAB2_LIB.BASEBOARD_FAB2(SCH_1):CLK_100M_CPU0_RC_REFCLK1_R_DN
 EU4D2   39 DIF_5N NB3W1200L_LCC-IC,H13585-001     I1 @BASEBOARD_FAB2_LIB.BASEBOARD_FAB2(SCH_1):PAGE102
  R4D5    1      A RES_0402-27.4,1%,1/16W,CHIP,G2A    I79 @BASEBOARD_FAB2_LIB.BASEBOARD_FAB2(SCH_1):PAGE103

CLK_100M_CPU0_RC_REFCLK1_R_DP @BASEBOARD_FAB2_LIB.BASEBOARD_FAB2(SCH_1):CLK_100M_CPU0_RC_REFCLK1_R_DP
 EU4D2   38 DIF_5P NB3W1200L_LCC-IC,H13585-001     I1 @BASEBOARD_FAB2_LIB.BASEBOARD_FAB2(SCH_1):PAGE102
  R4D6    1      A RES_0402-27.4,1%,1/16W,CHIP,G2A    I74 @BASEBOARD_FAB2_LIB.BASEBOARD_FAB2(SCH_1):PAGE103

CLK_100M_CPU1_BCLK0_DN @BASEBOARD_FAB2_LIB.BASEBOARD_FAB2(SCH_1):CLK_100M_CPU1_BCLK0_DN
  U2D1 AU24 BCLK0_DN SKX_EXT_B_BGA1-IC,TBD   I172 @BASEBOARD_FAB2_LIB.BASEBOARD_FAB2(SCH_1):PAGE55
  R4D3    2      B RES_0402-27.4,1%,1/16W,CHIP,G2A    I64 @BASEBOARD_FAB2_LIB.BASEBOARD_FAB2(SCH_1):PAGE103
  R6P6    1      A RES_0402-42.2,1.0%,1/16W,EMPTYA   I143 @BASEBOARD_FAB2_LIB.BASEBOARD_FAB2(SCH_1):PAGE103

CLK_100M_CPU1_BCLK0_DP @BASEBOARD_FAB2_LIB.BASEBOARD_FAB2(SCH_1):CLK_100M_CPU1_BCLK0_DP
  U2D1 AW24 BCLK0_DP SKX_EXT_B_BGA1-IC,TBD   I172 @BASEBOARD_FAB2_LIB.BASEBOARD_FAB2(SCH_1):PAGE55
  R4D4    2      B RES_0402-27.4,1%,1/16W,CHIP,G2A    I59 @BASEBOARD_FAB2_LIB.BASEBOARD_FAB2(SCH_1):PAGE103
  R6P5    1      A RES_0402-42.2,1.0%,1/16W,EMPTYA   I141 @BASEBOARD_FAB2_LIB.BASEBOARD_FAB2(SCH_1):PAGE103

CLK_100M_CPU1_BCLK0_R_DN @BASEBOARD_FAB2_LIB.BASEBOARD_FAB2(SCH_1):CLK_100M_CPU1_BCLK0_R_DN
 EU4D2   43 DIF_6N NB3W1200L_LCC-IC,H13585-001     I1 @BASEBOARD_FAB2_LIB.BASEBOARD_FAB2(SCH_1):PAGE102
  R4D3    1      A RES_0402-27.4,1%,1/16W,CHIP,G2A    I64 @BASEBOARD_FAB2_LIB.BASEBOARD_FAB2(SCH_1):PAGE103

CLK_100M_CPU1_BCLK0_R_DP @BASEBOARD_FAB2_LIB.BASEBOARD_FAB2(SCH_1):CLK_100M_CPU1_BCLK0_R_DP
 EU4D2   42 DIF_6P NB3W1200L_LCC-IC,H13585-001     I1 @BASEBOARD_FAB2_LIB.BASEBOARD_FAB2(SCH_1):PAGE102
  R4D4    1      A RES_0402-27.4,1%,1/16W,CHIP,G2A    I59 @BASEBOARD_FAB2_LIB.BASEBOARD_FAB2(SCH_1):PAGE103

CLK_100M_CPU1_BCLK1_DN @BASEBOARD_FAB2_LIB.BASEBOARD_FAB2(SCH_1):CLK_100M_CPU1_BCLK1_DN
  U2D1 CR26 BCLK1_DN SKX_EXT_B_BGA1-IC,TBD   I172 @BASEBOARD_FAB2_LIB.BASEBOARD_FAB2(SCH_1):PAGE55
  R4D1    2      B RES_0402-27.4,1%,1/16W,CHIP,G2A    I54 @BASEBOARD_FAB2_LIB.BASEBOARD_FAB2(SCH_1):PAGE103
  R6P8    1      A RES_0402-42.2,1.0%,1/16W,EMPTYA   I139 @BASEBOARD_FAB2_LIB.BASEBOARD_FAB2(SCH_1):PAGE103

CLK_100M_CPU1_BCLK1_DP @BASEBOARD_FAB2_LIB.BASEBOARD_FAB2(SCH_1):CLK_100M_CPU1_BCLK1_DP
  U2D1 CP27 BCLK1_DP SKX_EXT_B_BGA1-IC,TBD   I172 @BASEBOARD_FAB2_LIB.BASEBOARD_FAB2(SCH_1):PAGE55
  R4D2    2      B RES_0402-27.4,1%,1/16W,CHIP,G2A    I49 @BASEBOARD_FAB2_LIB.BASEBOARD_FAB2(SCH_1):PAGE103
  R6P7    1      A RES_0402-42.2,1.0%,1/16W,EMPTYA   I137 @BASEBOARD_FAB2_LIB.BASEBOARD_FAB2(SCH_1):PAGE103

CLK_100M_CPU1_BCLK1_R_DN @BASEBOARD_FAB2_LIB.BASEBOARD_FAB2(SCH_1):CLK_100M_CPU1_BCLK1_R_DN
 EU4D2   47 DIF_7N NB3W1200L_LCC-IC,H13585-001     I1 @BASEBOARD_FAB2_LIB.BASEBOARD_FAB2(SCH_1):PAGE102
  R4D1    1      A RES_0402-27.4,1%,1/16W,CHIP,G2A    I54 @BASEBOARD_FAB2_LIB.BASEBOARD_FAB2(SCH_1):PAGE103

CLK_100M_CPU1_BCLK1_R_DP @BASEBOARD_FAB2_LIB.BASEBOARD_FAB2(SCH_1):CLK_100M_CPU1_BCLK1_R_DP
 EU4D2   46 DIF_7P NB3W1200L_LCC-IC,H13585-001     I1 @BASEBOARD_FAB2_LIB.BASEBOARD_FAB2(SCH_1):PAGE102
  R4D2    1      A RES_0402-27.4,1%,1/16W,CHIP,G2A    I49 @BASEBOARD_FAB2_LIB.BASEBOARD_FAB2(SCH_1):PAGE103

CLK_100M_CPU1_BCLK2_DN @BASEBOARD_FAB2_LIB.BASEBOARD_FAB2(SCH_1):CLK_100M_CPU1_BCLK2_DN
  U2D1 CT25 BCLK2_DN SKX_EXT_B_BGA1-IC,TBD   I172 @BASEBOARD_FAB2_LIB.BASEBOARD_FAB2(SCH_1):PAGE55
 R4D11    2      B RES_0402-27.4,1%,1/16W,CHIP,G2A    I44 @BASEBOARD_FAB2_LIB.BASEBOARD_FAB2(SCH_1):PAGE103
  R7P2    1      A RES_0402-42.2,1.0%,1/16W,EMPTYA   I135 @BASEBOARD_FAB2_LIB.BASEBOARD_FAB2(SCH_1):PAGE103

CLK_100M_CPU1_BCLK2_DP @BASEBOARD_FAB2_LIB.BASEBOARD_FAB2(SCH_1):CLK_100M_CPU1_BCLK2_DP
  U2D1 CU26 BCLK2_DP SKX_EXT_B_BGA1-IC,TBD   I172 @BASEBOARD_FAB2_LIB.BASEBOARD_FAB2(SCH_1):PAGE55
  R4D9    2      B RES_0402-27.4,1%,1/16W,CHIP,G2A    I39 @BASEBOARD_FAB2_LIB.BASEBOARD_FAB2(SCH_1):PAGE103
  R7P1    1      A RES_0402-42.2,1.0%,1/16W,EMPTYA   I133 @BASEBOARD_FAB2_LIB.BASEBOARD_FAB2(SCH_1):PAGE103

CLK_100M_CPU1_BCLK2_R_DN @BASEBOARD_FAB2_LIB.BASEBOARD_FAB2(SCH_1):CLK_100M_CPU1_BCLK2_R_DN
 EU4D2   51 DIF_8N NB3W1200L_LCC-IC,H13585-001     I1 @BASEBOARD_FAB2_LIB.BASEBOARD_FAB2(SCH_1):PAGE102
 R4D11    1      A RES_0402-27.4,1%,1/16W,CHIP,G2A    I44 @BASEBOARD_FAB2_LIB.BASEBOARD_FAB2(SCH_1):PAGE103

CLK_100M_CPU1_BCLK2_R_DP @BASEBOARD_FAB2_LIB.BASEBOARD_FAB2(SCH_1):CLK_100M_CPU1_BCLK2_R_DP
 EU4D2   50 DIF_8P NB3W1200L_LCC-IC,H13585-001     I1 @BASEBOARD_FAB2_LIB.BASEBOARD_FAB2(SCH_1):PAGE102
  R4D9    1      A RES_0402-27.4,1%,1/16W,CHIP,G2A    I39 @BASEBOARD_FAB2_LIB.BASEBOARD_FAB2(SCH_1):PAGE103

CLK_100M_CPU1_PE_REFCLK_DN @BASEBOARD_FAB2_LIB.BASEBOARD_FAB2(SCH_1):CLK_100M_CPU1_PE_REFCLK_DN
  U2D1 BU24 CD_PE_REFCLK_DN SKX_EXT_B_BGA1-IC,TBD    I23 @BASEBOARD_FAB2_LIB.BASEBOARD_FAB2(SCH_1):PAGE63
 R4D16    2      B RES_0402-27.4,1%,1/16W,CHIP,G2A    I34 @BASEBOARD_FAB2_LIB.BASEBOARD_FAB2(SCH_1):PAGE103
  R7P4    1      A RES_0402-42.2,1.0%,1/16W,EMPTYA   I131 @BASEBOARD_FAB2_LIB.BASEBOARD_FAB2(SCH_1):PAGE103

CLK_100M_CPU1_PE_REFCLK_DP @BASEBOARD_FAB2_LIB.BASEBOARD_FAB2(SCH_1):CLK_100M_CPU1_PE_REFCLK_DP
  U2D1 BW24 CD_PE_REFCLK_DP SKX_EXT_B_BGA1-IC,TBD    I23 @BASEBOARD_FAB2_LIB.BASEBOARD_FAB2(SCH_1):PAGE63
 R4D13    2      B RES_0402-27.4,1%,1/16W,CHIP,G2A    I29 @BASEBOARD_FAB2_LIB.BASEBOARD_FAB2(SCH_1):PAGE103
  R7P3    1      A RES_0402-42.2,1.0%,1/16W,EMPTYA   I129 @BASEBOARD_FAB2_LIB.BASEBOARD_FAB2(SCH_1):PAGE103

CLK_100M_CPU1_PE_REFCLK_R_DN @BASEBOARD_FAB2_LIB.BASEBOARD_FAB2(SCH_1):CLK_100M_CPU1_PE_REFCLK_R_DN
 EU4D2   55 DIF_9N NB3W1200L_LCC-IC,H13585-001     I1 @BASEBOARD_FAB2_LIB.BASEBOARD_FAB2(SCH_1):PAGE102
 R4D16    1      A RES_0402-27.4,1%,1/16W,CHIP,G2A    I34 @BASEBOARD_FAB2_LIB.BASEBOARD_FAB2(SCH_1):PAGE103

CLK_100M_CPU1_PE_REFCLK_R_DP @BASEBOARD_FAB2_LIB.BASEBOARD_FAB2(SCH_1):CLK_100M_CPU1_PE_REFCLK_R_DP
 EU4D2   54 DIF_9P NB3W1200L_LCC-IC,H13585-001     I1 @BASEBOARD_FAB2_LIB.BASEBOARD_FAB2(SCH_1):PAGE102
 R4D13    1      A RES_0402-27.4,1%,1/16W,CHIP,G2A    I29 @BASEBOARD_FAB2_LIB.BASEBOARD_FAB2(SCH_1):PAGE103

CLK_100M_CPU1_RC_REFCLK0_DN @BASEBOARD_FAB2_LIB.BASEBOARD_FAB2(SCH_1):CLK_100M_CPU1_RC_REFCLK0_DN
  U2D1 AP27 RSVD<195> SKX_EXT_B_BGA1-IC,TBD   I169 @BASEBOARD_FAB2_LIB.BASEBOARD_FAB2(SCH_1):PAGE56
 R4D21    2      B RES_0402-27.4,1%,1/16W,CHIP,G2A    I24 @BASEBOARD_FAB2_LIB.BASEBOARD_FAB2(SCH_1):PAGE103
  R7P7    1      A RES_0402-42.2,1.0%,1/16W,EMPTYA   I127 @BASEBOARD_FAB2_LIB.BASEBOARD_FAB2(SCH_1):PAGE103

CLK_100M_CPU1_RC_REFCLK0_DP @BASEBOARD_FAB2_LIB.BASEBOARD_FAB2(SCH_1):CLK_100M_CPU1_RC_REFCLK0_DP
  U2D1 AM27 RSVD<206> SKX_EXT_B_BGA1-IC,TBD   I169 @BASEBOARD_FAB2_LIB.BASEBOARD_FAB2(SCH_1):PAGE56
 R4D19    2      B RES_0402-27.4,1%,1/16W,CHIP,G2A    I19 @BASEBOARD_FAB2_LIB.BASEBOARD_FAB2(SCH_1):PAGE103
  R7P6    1      A RES_0402-42.2,1.0%,1/16W,EMPTYA   I125 @BASEBOARD_FAB2_LIB.BASEBOARD_FAB2(SCH_1):PAGE103

CLK_100M_CPU1_RC_REFCLK0_R_DN @BASEBOARD_FAB2_LIB.BASEBOARD_FAB2(SCH_1):CLK_100M_CPU1_RC_REFCLK0_R_DN
 EU4D2   60 DIF_10N NB3W1200L_LCC-IC,H13585-001     I1 @BASEBOARD_FAB2_LIB.BASEBOARD_FAB2(SCH_1):PAGE102
 R4D21    1      A RES_0402-27.4,1%,1/16W,CHIP,G2A    I24 @BASEBOARD_FAB2_LIB.BASEBOARD_FAB2(SCH_1):PAGE103

CLK_100M_CPU1_RC_REFCLK0_R_DP @BASEBOARD_FAB2_LIB.BASEBOARD_FAB2(SCH_1):CLK_100M_CPU1_RC_REFCLK0_R_DP
 EU4D2   59 DIF_10P NB3W1200L_LCC-IC,H13585-001     I1 @BASEBOARD_FAB2_LIB.BASEBOARD_FAB2(SCH_1):PAGE102
 R4D19    1      A RES_0402-27.4,1%,1/16W,CHIP,G2A    I19 @BASEBOARD_FAB2_LIB.BASEBOARD_FAB2(SCH_1):PAGE103

CLK_100M_CPU1_RC_REFCLK1_DN @BASEBOARD_FAB2_LIB.BASEBOARD_FAB2(SCH_1):CLK_100M_CPU1_RC_REFCLK1_DN
  U2D1 BB25 RSVD<165> SKX_EXT_B_BGA1-IC,TBD     I9 @BASEBOARD_FAB2_LIB.BASEBOARD_FAB2(SCH_1):PAGE70
 R4D28    2      B RES_0402-27.4,1%,1/16W,CHIP,G2A    I14 @BASEBOARD_FAB2_LIB.BASEBOARD_FAB2(SCH_1):PAGE103
 R7P12    1      A RES_0402-42.2,1.0%,1/16W,EMPTYA   I123 @BASEBOARD_FAB2_LIB.BASEBOARD_FAB2(SCH_1):PAGE103

CLK_100M_CPU1_RC_REFCLK1_DP @BASEBOARD_FAB2_LIB.BASEBOARD_FAB2(SCH_1):CLK_100M_CPU1_RC_REFCLK1_DP
  U2D1 BD25 RSVD<153> SKX_EXT_B_BGA1-IC,TBD     I9 @BASEBOARD_FAB2_LIB.BASEBOARD_FAB2(SCH_1):PAGE70
 R4D23    2      B RES_0402-27.4,1%,1/16W,CHIP,G2A     I9 @BASEBOARD_FAB2_LIB.BASEBOARD_FAB2(SCH_1):PAGE103
  R7P9    1      A RES_0402-42.2,1.0%,1/16W,EMPTYA   I121 @BASEBOARD_FAB2_LIB.BASEBOARD_FAB2(SCH_1):PAGE103

CLK_100M_CPU1_RC_REFCLK1_R_DN @BASEBOARD_FAB2_LIB.BASEBOARD_FAB2(SCH_1):CLK_100M_CPU1_RC_REFCLK1_R_DN
 EU4D2   64 DIF_11N NB3W1200L_LCC-IC,H13585-001     I1 @BASEBOARD_FAB2_LIB.BASEBOARD_FAB2(SCH_1):PAGE102
 R4D28    1      A RES_0402-27.4,1%,1/16W,CHIP,G2A    I14 @BASEBOARD_FAB2_LIB.BASEBOARD_FAB2(SCH_1):PAGE103

CLK_100M_CPU1_RC_REFCLK1_R_DP @BASEBOARD_FAB2_LIB.BASEBOARD_FAB2(SCH_1):CLK_100M_CPU1_RC_REFCLK1_R_DP
 EU4D2   63 DIF_11P NB3W1200L_LCC-IC,H13585-001     I1 @BASEBOARD_FAB2_LIB.BASEBOARD_FAB2(SCH_1):PAGE102
 R4D23    1      A RES_0402-27.4,1%,1/16W,CHIP,G2A     I9 @BASEBOARD_FAB2_LIB.BASEBOARD_FAB2(SCH_1):PAGE103

CLK_100M_DB1200_DN @BASEBOARD_FAB2_LIB.BASEBOARD_FAB2(SCH_1):CLK_100M_DB1200_DN
 EU4D2   10 CLK_INN NB3W1200L_LCC-IC,H13585-001     I1 @BASEBOARD_FAB2_LIB.BASEBOARD_FAB2(SCH_1):PAGE102
  U7C1  K35 CLKOUT_SRCN<1> LBG_CORE_QAT_EXT_D_BGA1-IC,H91A    I40 @BASEBOARD_FAB2_LIB.BASEBOARD_FAB2(SCH_1):PAGE114

CLK_100M_DB1200_DP @BASEBOARD_FAB2_LIB.BASEBOARD_FAB2(SCH_1):CLK_100M_DB1200_DP
 EU4D2    9 CLK_INP NB3W1200L_LCC-IC,H13585-001     I1 @BASEBOARD_FAB2_LIB.BASEBOARD_FAB2(SCH_1):PAGE102
  U7C1  H35 CLKOUT_SRCP<1> LBG_CORE_QAT_EXT_D_BGA1-IC,H91A    I40 @BASEBOARD_FAB2_LIB.BASEBOARD_FAB2(SCH_1):PAGE114

CLK_100M_M2_DN @BASEBOARD_FAB2_LIB.BASEBOARD_FAB2(SCH_1):CLK_100M_M2_DN
  U7C1  K27 CLKOUT_SRCN<15> LBG_CORE_QAT_EXT_D_BGA1-IC,H91A    I40 @BASEBOARD_FAB2_LIB.BASEBOARD_FAB2(SCH_1):PAGE114
  J8F1   53 REFCLKN SCONN75K_H17033002_SMT1-SCONN,A    I53 @BASEBOARD_FAB2_LIB.BASEBOARD_FAB2(SCH_1):PAGE185

CLK_100M_M2_DP @BASEBOARD_FAB2_LIB.BASEBOARD_FAB2(SCH_1):CLK_100M_M2_DP
  U7C1  H27 CLKOUT_SRCP<15> LBG_CORE_QAT_EXT_D_BGA1-IC,H91A    I40 @BASEBOARD_FAB2_LIB.BASEBOARD_FAB2(SCH_1):PAGE114
  J8F1   55 REFCLKP SCONN75K_H17033002_SMT1-SCONN,A    I53 @BASEBOARD_FAB2_LIB.BASEBOARD_FAB2(SCH_1):PAGE185

CLK_100M_MEZZ1_DN @BASEBOARD_FAB2_LIB.BASEBOARD_FAB2(SCH_1):CLK_100M_MEZZ1_DN
  U7C1  D31 CLKOUT_SRCN<8> LBG_CORE_QAT_EXT_D_BGA1-IC,H91A    I40 @BASEBOARD_FAB2_LIB.BASEBOARD_FAB2(SCH_1):PAGE114
  J9B3   50   IO50 SCONN120_A28699018_SM-SCONN,A2A   I336 @BASEBOARD_FAB2_LIB.BASEBOARD_FAB2(SCH_1):PAGE186

CLK_100M_MEZZ1_DP @BASEBOARD_FAB2_LIB.BASEBOARD_FAB2(SCH_1):CLK_100M_MEZZ1_DP
  U7C1  B31 CLKOUT_SRCP<8> LBG_CORE_QAT_EXT_D_BGA1-IC,H91A    I40 @BASEBOARD_FAB2_LIB.BASEBOARD_FAB2(SCH_1):PAGE114
  J9B3   48   IO48 SCONN120_A28699018_SM-SCONN,A2A   I336 @BASEBOARD_FAB2_LIB.BASEBOARD_FAB2(SCH_1):PAGE186

CLK_100M_MEZZ2_DN @BASEBOARD_FAB2_LIB.BASEBOARD_FAB2(SCH_1):CLK_100M_MEZZ2_DN
  U7C1  J26 CLKOUT_SRCN<9> LBG_CORE_QAT_EXT_D_BGA1-IC,H91A    I40 @BASEBOARD_FAB2_LIB.BASEBOARD_FAB2(SCH_1):PAGE114
  J9B3   53   IO53 SCONN120_A28699018_SM-SCONN,A2A   I336 @BASEBOARD_FAB2_LIB.BASEBOARD_FAB2(SCH_1):PAGE186

CLK_100M_MEZZ2_DP @BASEBOARD_FAB2_LIB.BASEBOARD_FAB2(SCH_1):CLK_100M_MEZZ2_DP
  U7C1  G26 CLKOUT_SRCP<9> LBG_CORE_QAT_EXT_D_BGA1-IC,H91A    I40 @BASEBOARD_FAB2_LIB.BASEBOARD_FAB2(SCH_1):PAGE114
  J9B3   51   IO51 SCONN120_A28699018_SM-SCONN,A2A   I336 @BASEBOARD_FAB2_LIB.BASEBOARD_FAB2(SCH_1):PAGE186

CLK_100M_MEZZ3_DN @BASEBOARD_FAB2_LIB.BASEBOARD_FAB2(SCH_1):CLK_100M_MEZZ3_DN
  U7C1  B23 CLKOUT_SRCN<10> LBG_CORE_QAT_EXT_D_BGA1-IC,H91A    I40 @BASEBOARD_FAB2_LIB.BASEBOARD_FAB2(SCH_1):PAGE114
  J8E3   71   IO71 SCONN80_E67482007_SM-CONN,E674A   I119 @BASEBOARD_FAB2_LIB.BASEBOARD_FAB2(SCH_1):PAGE187

CLK_100M_MEZZ3_DP @BASEBOARD_FAB2_LIB.BASEBOARD_FAB2(SCH_1):CLK_100M_MEZZ3_DP
  U7C1  D23 CLKOUT_SRCP<10> LBG_CORE_QAT_EXT_D_BGA1-IC,H91A    I40 @BASEBOARD_FAB2_LIB.BASEBOARD_FAB2(SCH_1):PAGE114
  J8E3   69   IO69 SCONN80_E67482007_SM-CONN,E674A   I119 @BASEBOARD_FAB2_LIB.BASEBOARD_FAB2(SCH_1):PAGE187

CLK_100M_MEZZ4_DN @BASEBOARD_FAB2_LIB.BASEBOARD_FAB2(SCH_1):CLK_100M_MEZZ4_DN
  U7C1  B21 CLKOUT_SRCN<11> LBG_CORE_QAT_EXT_D_BGA1-IC,H91A    I40 @BASEBOARD_FAB2_LIB.BASEBOARD_FAB2(SCH_1):PAGE114
  J8E3   76   IO76 SCONN80_E67482007_SM-CONN,E674A   I119 @BASEBOARD_FAB2_LIB.BASEBOARD_FAB2(SCH_1):PAGE187

CLK_100M_MEZZ4_DP @BASEBOARD_FAB2_LIB.BASEBOARD_FAB2(SCH_1):CLK_100M_MEZZ4_DP
  U7C1  D21 CLKOUT_SRCP<11> LBG_CORE_QAT_EXT_D_BGA1-IC,H91A    I40 @BASEBOARD_FAB2_LIB.BASEBOARD_FAB2(SCH_1):PAGE114
  J8E3   74   IO74 SCONN80_E67482007_SM-CONN,E674A   I119 @BASEBOARD_FAB2_LIB.BASEBOARD_FAB2(SCH_1):PAGE187

CLK_100M_PCH_SLOTX24_S0_DN @BASEBOARD_FAB2_LIB.BASEBOARD_FAB2(SCH_1):CLK_100M_PCH_SLOTX24_S0_DN
  J8G1   41   IO41 SCONN200_H68296001_SM-CONN,H68A   I258 @BASEBOARD_FAB2_LIB.BASEBOARD_FAB2(SCH_1):PAGE108
  U7C1  J33 CLKOUT_SRCN<2> LBG_CORE_QAT_EXT_D_BGA1-IC,H91A    I40 @BASEBOARD_FAB2_LIB.BASEBOARD_FAB2(SCH_1):PAGE114

CLK_100M_PCH_SLOTX24_S0_DP @BASEBOARD_FAB2_LIB.BASEBOARD_FAB2(SCH_1):CLK_100M_PCH_SLOTX24_S0_DP
  J8G1   39   IO39 SCONN200_H68296001_SM-CONN,H68A   I258 @BASEBOARD_FAB2_LIB.BASEBOARD_FAB2(SCH_1):PAGE108
  U7C1  G33 CLKOUT_SRCP<2> LBG_CORE_QAT_EXT_D_BGA1-IC,H91A    I40 @BASEBOARD_FAB2_LIB.BASEBOARD_FAB2(SCH_1):PAGE114

CLK_100M_PCH_SLOTX24_S1_DN @BASEBOARD_FAB2_LIB.BASEBOARD_FAB2(SCH_1):CLK_100M_PCH_SLOTX24_S1_DN
  J8G1   44   IO44 SCONN200_H68296001_SM-CONN,H68A   I258 @BASEBOARD_FAB2_LIB.BASEBOARD_FAB2(SCH_1):PAGE108
  U7C1  K42 CLKOUT_SRCN<3> LBG_CORE_QAT_EXT_D_BGA1-IC,H91A    I40 @BASEBOARD_FAB2_LIB.BASEBOARD_FAB2(SCH_1):PAGE114

CLK_100M_PCH_SLOTX24_S1_DP @BASEBOARD_FAB2_LIB.BASEBOARD_FAB2(SCH_1):CLK_100M_PCH_SLOTX24_S1_DP
  J8G1   42   IO42 SCONN200_H68296001_SM-CONN,H68A   I258 @BASEBOARD_FAB2_LIB.BASEBOARD_FAB2(SCH_1):PAGE108
  U7C1  H42 CLKOUT_SRCP<3> LBG_CORE_QAT_EXT_D_BGA1-IC,H91A    I40 @BASEBOARD_FAB2_LIB.BASEBOARD_FAB2(SCH_1):PAGE114

CLK_100M_PCH_SLOTX24_S2_DN @BASEBOARD_FAB2_LIB.BASEBOARD_FAB2(SCH_1):CLK_100M_PCH_SLOTX24_S2_DN
  J8G1   50   IO50 SCONN200_H68296001_SM-CONN,H68A   I258 @BASEBOARD_FAB2_LIB.BASEBOARD_FAB2(SCH_1):PAGE108
  U7C1  A28 CLKOUT_SRCN<4> LBG_CORE_QAT_EXT_D_BGA1-IC,H91A    I40 @BASEBOARD_FAB2_LIB.BASEBOARD_FAB2(SCH_1):PAGE114

CLK_100M_PCH_SLOTX24_S2_DP @BASEBOARD_FAB2_LIB.BASEBOARD_FAB2(SCH_1):CLK_100M_PCH_SLOTX24_S2_DP
  J8G1   48   IO48 SCONN200_H68296001_SM-CONN,H68A   I258 @BASEBOARD_FAB2_LIB.BASEBOARD_FAB2(SCH_1):PAGE108
  U7C1  C28 CLKOUT_SRCP<4> LBG_CORE_QAT_EXT_D_BGA1-IC,H91A    I40 @BASEBOARD_FAB2_LIB.BASEBOARD_FAB2(SCH_1):PAGE114

CLK_100M_PCH_SLOTX24_S3_DN @BASEBOARD_FAB2_LIB.BASEBOARD_FAB2(SCH_1):CLK_100M_PCH_SLOTX24_S3_DN
  J8G1   47   IO47 SCONN200_H68296001_SM-CONN,H68A   I258 @BASEBOARD_FAB2_LIB.BASEBOARD_FAB2(SCH_1):PAGE108
  U7C1  J40 CLKOUT_SRCN<5> LBG_CORE_QAT_EXT_D_BGA1-IC,H91A    I40 @BASEBOARD_FAB2_LIB.BASEBOARD_FAB2(SCH_1):PAGE114

CLK_100M_PCH_SLOTX24_S3_DP @BASEBOARD_FAB2_LIB.BASEBOARD_FAB2(SCH_1):CLK_100M_PCH_SLOTX24_S3_DP
  J8G1   45   IO45 SCONN200_H68296001_SM-CONN,H68A   I258 @BASEBOARD_FAB2_LIB.BASEBOARD_FAB2(SCH_1):PAGE108
  U7C1  G40 CLKOUT_SRCP<5> LBG_CORE_QAT_EXT_D_BGA1-IC,H91A    I40 @BASEBOARD_FAB2_LIB.BASEBOARD_FAB2(SCH_1):PAGE114

CLK_100M_PCH_SLOTX24_S4_DN @BASEBOARD_FAB2_LIB.BASEBOARD_FAB2(SCH_1):CLK_100M_PCH_SLOTX24_S4_DN
  J8G1   38   IO38 SCONN200_H68296001_SM-CONN,H68A   I258 @BASEBOARD_FAB2_LIB.BASEBOARD_FAB2(SCH_1):PAGE108
  U7C1  D33 CLKOUT_SRCN<6> LBG_CORE_QAT_EXT_D_BGA1-IC,H91A    I40 @BASEBOARD_FAB2_LIB.BASEBOARD_FAB2(SCH_1):PAGE114

CLK_100M_PCH_SLOTX24_S4_DP @BASEBOARD_FAB2_LIB.BASEBOARD_FAB2(SCH_1):CLK_100M_PCH_SLOTX24_S4_DP
  J8G1   36   IO36 SCONN200_H68296001_SM-CONN,H68A   I258 @BASEBOARD_FAB2_LIB.BASEBOARD_FAB2(SCH_1):PAGE108
  U7C1  B33 CLKOUT_SRCP<6> LBG_CORE_QAT_EXT_D_BGA1-IC,H91A    I40 @BASEBOARD_FAB2_LIB.BASEBOARD_FAB2(SCH_1):PAGE114

CLK_100M_PCH_SLOTX24_S5_DN @BASEBOARD_FAB2_LIB.BASEBOARD_FAB2(SCH_1):CLK_100M_PCH_SLOTX24_S5_DN
  J8G1   35   IO35 SCONN200_H68296001_SM-CONN,H68A   I258 @BASEBOARD_FAB2_LIB.BASEBOARD_FAB2(SCH_1):PAGE108
  U7C1  H31 CLKOUT_SRCN<7> LBG_CORE_QAT_EXT_D_BGA1-IC,H91A    I40 @BASEBOARD_FAB2_LIB.BASEBOARD_FAB2(SCH_1):PAGE114

CLK_100M_PCH_SLOTX24_S5_DP @BASEBOARD_FAB2_LIB.BASEBOARD_FAB2(SCH_1):CLK_100M_PCH_SLOTX24_S5_DP
  J8G1   33   IO33 SCONN200_H68296001_SM-CONN,H68A   I258 @BASEBOARD_FAB2_LIB.BASEBOARD_FAB2(SCH_1):PAGE108
  U7C1  K31 CLKOUT_SRCP<7> LBG_CORE_QAT_EXT_D_BGA1-IC,H91A    I40 @BASEBOARD_FAB2_LIB.BASEBOARD_FAB2(SCH_1):PAGE114

CLK_100M_PCH_XDP_DN @BASEBOARD_FAB2_LIB.BASEBOARD_FAB2(SCH_1):CLK_100M_PCH_XDP_DN
  J9A3   42   IO42 SCONN60_C21100002_SMLF-CONN,C2A    I26 @BASEBOARD_FAB2_LIB.BASEBOARD_FAB2(SCH_1):PAGE111
  U7C1  A39 CLKOUT_ITPXDPN LBG_CORE_QAT_EXT_D_BGA1-IC,H91A    I40 @BASEBOARD_FAB2_LIB.BASEBOARD_FAB2(SCH_1):PAGE114

CLK_100M_PCH_XDP_DP @BASEBOARD_FAB2_LIB.BASEBOARD_FAB2(SCH_1):CLK_100M_PCH_XDP_DP
  J9A3   40   IO40 SCONN60_C21100002_SMLF-CONN,C2A    I26 @BASEBOARD_FAB2_LIB.BASEBOARD_FAB2(SCH_1):PAGE111
  U7C1  C39 CLKOUT_ITPXDPP LBG_CORE_QAT_EXT_D_BGA1-IC,H91A    I40 @BASEBOARD_FAB2_LIB.BASEBOARD_FAB2(SCH_1):PAGE114

CLK_100M_SPRV_DN @BASEBOARD_FAB2_LIB.BASEBOARD_FAB2(SCH_1):CLK_100M_SPRV_DN
  U7C1  C20 CLKOUT_SRCN<14> LBG_CORE_QAT_EXT_D_BGA1-IC,H91A    I40 @BASEBOARD_FAB2_LIB.BASEBOARD_FAB2(SCH_1):PAGE114
 EU9E1   25 PECLKN SPRINGVILLE_SM1-IC,G47144-004    I72 @BASEBOARD_FAB2_LIB.BASEBOARD_FAB2(SCH_1):PAGE139

CLK_100M_SPRV_DP @BASEBOARD_FAB2_LIB.BASEBOARD_FAB2(SCH_1):CLK_100M_SPRV_DP
  U7C1  A20 CLKOUT_SRCP<14> LBG_CORE_QAT_EXT_D_BGA1-IC,H91A    I40 @BASEBOARD_FAB2_LIB.BASEBOARD_FAB2(SCH_1):PAGE114
 EU9E1   26 PECLKP SPRINGVILLE_SM1-IC,G47144-004    I72 @BASEBOARD_FAB2_LIB.BASEBOARD_FAB2(SCH_1):PAGE139

CLK_100M_SRC12_DN @BASEBOARD_FAB2_LIB.BASEBOARD_FAB2(SCH_1):CLK_100M_SRC12_DN
  U7C1  K24 CLKOUT_SRCN<12> LBG_CORE_QAT_EXT_D_BGA1-IC,H91A    I40 @BASEBOARD_FAB2_LIB.BASEBOARD_FAB2(SCH_1):PAGE114
 CONX8   53     53 SMC-CONN60A-22-GP_CONN-G7-SMC-A    I48 @BASEBOARD_FAB2_LIB.BASEBOARD_FAB2(SCH_1):PAGE245

CLK_100M_SRC12_DP @BASEBOARD_FAB2_LIB.BASEBOARD_FAB2(SCH_1):CLK_100M_SRC12_DP
  U7C1  H24 CLKOUT_SRCP<12> LBG_CORE_QAT_EXT_D_BGA1-IC,H91A    I40 @BASEBOARD_FAB2_LIB.BASEBOARD_FAB2(SCH_1):PAGE114
 CONX8   51     51 SMC-CONN60A-22-GP_CONN-G7-SMC-A    I48 @BASEBOARD_FAB2_LIB.BASEBOARD_FAB2(SCH_1):PAGE245

CLK_100M_SRC13_DN @BASEBOARD_FAB2_LIB.BASEBOARD_FAB2(SCH_1):CLK_100M_SRC13_DN
  U7C1  C24 CLKOUT_SRCN<13> LBG_CORE_QAT_EXT_D_BGA1-IC,H91A    I40 @BASEBOARD_FAB2_LIB.BASEBOARD_FAB2(SCH_1):PAGE114
 CONX8   56     56 SMC-CONN60A-22-GP_CONN-G7-SMC-A    I48 @BASEBOARD_FAB2_LIB.BASEBOARD_FAB2(SCH_1):PAGE245

CLK_100M_SRC13_DP @BASEBOARD_FAB2_LIB.BASEBOARD_FAB2(SCH_1):CLK_100M_SRC13_DP
  U7C1  A24 CLKOUT_SRCP<13> LBG_CORE_QAT_EXT_D_BGA1-IC,H91A    I40 @BASEBOARD_FAB2_LIB.BASEBOARD_FAB2(SCH_1):PAGE114
 CONX8   54     54 SMC-CONN60A-22-GP_CONN-G7-SMC-A    I48 @BASEBOARD_FAB2_LIB.BASEBOARD_FAB2(SCH_1):PAGE245

CLK_156M_OSC_BRD_CPU0_DN @BASEBOARD_FAB2_LIB.BASEBOARD_FAB2(SCH_1):CLK_156M_OSC_BRD_CPU0_DN
  R6F7    1      A RES_0402-0.0,5%,1/16W,CHIP,G21A    I67 @BASEBOARD_FAB2_LIB.BASEBOARD_FAB2(SCH_1):PAGE104
  Y6F1    5  OUT_N OSC_C_6P10-156.25MHZ,OSC,G6383A    I71 @BASEBOARD_FAB2_LIB.BASEBOARD_FAB2(SCH_1):PAGE104

CLK_156M_OSC_BRD_CPU0_DP @BASEBOARD_FAB2_LIB.BASEBOARD_FAB2(SCH_1):CLK_156M_OSC_BRD_CPU0_DP
  R6F9    1      A RES_0402-0.0,5%,1/16W,CHIP,G21A    I68 @BASEBOARD_FAB2_LIB.BASEBOARD_FAB2(SCH_1):PAGE104
  Y6F1    4    OUT OSC_C_6P10-156.25MHZ,OSC,G6383A    I71 @BASEBOARD_FAB2_LIB.BASEBOARD_FAB2(SCH_1):PAGE104

CLK_156M_OSC_BRD_CPU1_DN @BASEBOARD_FAB2_LIB.BASEBOARD_FAB2(SCH_1):CLK_156M_OSC_BRD_CPU1_DN
  R3F2    1      A RES_0402-0.0,5%,1/16W,CHIP,G21A    I69 @BASEBOARD_FAB2_LIB.BASEBOARD_FAB2(SCH_1):PAGE104
  Y3F1    5  OUT_N OSC_C_6P10-156.25MHZ,OSC,G6383A    I72 @BASEBOARD_FAB2_LIB.BASEBOARD_FAB2(SCH_1):PAGE104

CLK_156M_OSC_BRD_CPU1_DP @BASEBOARD_FAB2_LIB.BASEBOARD_FAB2(SCH_1):CLK_156M_OSC_BRD_CPU1_DP
  R3F4    1      A RES_0402-0.0,5%,1/16W,CHIP,G21A    I70 @BASEBOARD_FAB2_LIB.BASEBOARD_FAB2(SCH_1):PAGE104
  Y3F1    4    OUT OSC_C_6P10-156.25MHZ,OSC,G6383A    I72 @BASEBOARD_FAB2_LIB.BASEBOARD_FAB2(SCH_1):PAGE104

CLK_156M_OSC_CPU0_HFI_DN @BASEBOARD_FAB2_LIB.BASEBOARD_FAB2(SCH_1):CLK_156M_OSC_CPU0_HFI_DN
  U5D1 BE16 CD_HFI_REFCLK_DN SKX_EXT_B_BGA1-IC,TBD    I61 @BASEBOARD_FAB2_LIB.BASEBOARD_FAB2(SCH_1):PAGE29
  R6F6    2      B RES_0402-0.0,5%,1/16W,EMPTY,G2A    I41 @BASEBOARD_FAB2_LIB.BASEBOARD_FAB2(SCH_1):PAGE104
  R6F7    2      B RES_0402-0.0,5%,1/16W,CHIP,G21A    I67 @BASEBOARD_FAB2_LIB.BASEBOARD_FAB2(SCH_1):PAGE104

CLK_156M_OSC_CPU0_HFI_DP @BASEBOARD_FAB2_LIB.BASEBOARD_FAB2(SCH_1):CLK_156M_OSC_CPU0_HFI_DP
  U5D1 BG16 CD_HFI_REFCLK_DP SKX_EXT_B_BGA1-IC,TBD    I61 @BASEBOARD_FAB2_LIB.BASEBOARD_FAB2(SCH_1):PAGE29
  R6F8    2      B RES_0402-0.0,5%,1/16W,EMPTY,G2A    I37 @BASEBOARD_FAB2_LIB.BASEBOARD_FAB2(SCH_1):PAGE104
  R6F9    2      B RES_0402-0.0,5%,1/16W,CHIP,G21A    I68 @BASEBOARD_FAB2_LIB.BASEBOARD_FAB2(SCH_1):PAGE104

CLK_156M_OSC_CPU1_HFI_DN @BASEBOARD_FAB2_LIB.BASEBOARD_FAB2(SCH_1):CLK_156M_OSC_CPU1_HFI_DN
  U2D1 BE16 CD_HFI_REFCLK_DN SKX_EXT_B_BGA1-IC,TBD    I23 @BASEBOARD_FAB2_LIB.BASEBOARD_FAB2(SCH_1):PAGE63
  R3F1    2      B RES_0402-0.0,5%,1/16W,EMPTY,G2A    I51 @BASEBOARD_FAB2_LIB.BASEBOARD_FAB2(SCH_1):PAGE104
  R3F2    2      B RES_0402-0.0,5%,1/16W,CHIP,G21A    I69 @BASEBOARD_FAB2_LIB.BASEBOARD_FAB2(SCH_1):PAGE104

CLK_156M_OSC_CPU1_HFI_DP @BASEBOARD_FAB2_LIB.BASEBOARD_FAB2(SCH_1):CLK_156M_OSC_CPU1_HFI_DP
  U2D1 BG16 CD_HFI_REFCLK_DP SKX_EXT_B_BGA1-IC,TBD    I23 @BASEBOARD_FAB2_LIB.BASEBOARD_FAB2(SCH_1):PAGE63
  R3F3    2      B RES_0402-0.0,5%,1/16W,EMPTY,G2A    I53 @BASEBOARD_FAB2_LIB.BASEBOARD_FAB2(SCH_1):PAGE104
  R3F4    2      B RES_0402-0.0,5%,1/16W,CHIP,G21A    I70 @BASEBOARD_FAB2_LIB.BASEBOARD_FAB2(SCH_1):PAGE104

CLK_24M_25M_BMC_CLKIN @BASEBOARD_FAB2_LIB.BASEBOARD_FAB2(SCH_1):CLK_24M_25M_BMC_CLKIN
 R9F60    2      B RES_0402-0.0,5%,1/16W,EMPTY,G2A    I10 @BASEBOARD_FAB2_LIB.BASEBOARD_FAB2(SCH_1):PAGE145
 R9F62    2      B RES_0402-0.0,5%,1/16W,CHIP,G21A    I11 @BASEBOARD_FAB2_LIB.BASEBOARD_FAB2(SCH_1):PAGE145
 U25W4  W18  CLKIN AST2520A1-GP-GP_ASIC2-GB1-AST2A   I117 @BASEBOARD_FAB2_LIB.BASEBOARD_FAB2(SCH_1):PAGE145

CLK_24M_BMC_CLKIN_R @BASEBOARD_FAB2_LIB.BASEBOARD_FAB2(SCH_1):CLK_24M_BMC_CLKIN_R
  Y9F2    3    OUT OSC_C_SM4-24MHZ,OSC,D34520-021     I8 @BASEBOARD_FAB2_LIB.BASEBOARD_FAB2(SCH_1):PAGE145
 R9F62    1      A RES_0402-0.0,5%,1/16W,CHIP,G21A    I11 @BASEBOARD_FAB2_LIB.BASEBOARD_FAB2(SCH_1):PAGE145

CLK_24M_BMC_LPC @BASEBOARD_FAB2_LIB.BASEBOARD_FAB2(SCH_1):CLK_24M_BMC_LPC
 R7C26    1      A RES_0402-33.2,1%,1/16W,CHIP,G2A   I189 @BASEBOARD_FAB2_LIB.BASEBOARD_FAB2(SCH_1):PAGE119
R25W71    1      A RES_0402-33.2,1%,1/16W,CHIP,G2A    I72 @BASEBOARD_FAB2_LIB.BASEBOARD_FAB2(SCH_1):PAGE146

CLK_24M_BMC_LPC_R @BASEBOARD_FAB2_LIB.BASEBOARD_FAB2(SCH_1):CLK_24M_BMC_LPC_R
  U7C1   R3 GPP_A9_CLKOUT_LPC0_ESPI_CLK LBG_CORE_QAT_EXT_D_BGA1-IC,H91A   I115 @BASEBOARD_FAB2_LIB.BASEBOARD_FAB2(SCH_1):PAGE119
 R7C26    2      B RES_0402-33.2,1%,1/16W,CHIP,G2A   I189 @BASEBOARD_FAB2_LIB.BASEBOARD_FAB2(SCH_1):PAGE119

CLK_24M_BMC_LPC_R1 @BASEBOARD_FAB2_LIB.BASEBOARD_FAB2(SCH_1):CLK_24M_BMC_LPC_R1
R25W71    2      B RES_0402-33.2,1%,1/16W,CHIP,G2A    I72 @BASEBOARD_FAB2_LIB.BASEBOARD_FAB2(SCH_1):PAGE146
R25W66    1      A RES_0402-100.0K,1%,1/16W,CHIP,A    I76 @BASEBOARD_FAB2_LIB.BASEBOARD_FAB2(SCH_1):PAGE146
 U25W4  C22 GPIOAC4_ESPICK_LCLK AST2520A1-GP-GP_ASIC2-GB1-AST2A   I105 @BASEBOARD_FAB2_LIB.BASEBOARD_FAB2(SCH_1):PAGE146

CLK_25M_BMC @BASEBOARD_FAB2_LIB.BASEBOARD_FAB2(SCH_1):CLK_25M_BMC
 R8F29    2      B RES_0402-33.2,1%,1/16W,CHIP,G2A    I20 @BASEBOARD_FAB2_LIB.BASEBOARD_FAB2(SCH_1):PAGE101
 R9F60    1      A RES_0402-0.0,5%,1/16W,EMPTY,G2A    I10 @BASEBOARD_FAB2_LIB.BASEBOARD_FAB2(SCH_1):PAGE145

CLK_25M_BMC_R @BASEBOARD_FAB2_LIB.BASEBOARD_FAB2(SCH_1):CLK_25M_BMC_R
 R8F29    1      A RES_0402-33.2,1%,1/16W,CHIP,G2A    I20 @BASEBOARD_FAB2_LIB.BASEBOARD_FAB2(SCH_1):PAGE101
 EU8F2   16 25MHZ_0 ICS9FGP204_MLFP-IC,E95226-001    I34 @BASEBOARD_FAB2_LIB.BASEBOARD_FAB2(SCH_1):PAGE101

CLK_25M_CPLD @BASEBOARD_FAB2_LIB.BASEBOARD_FAB2(SCH_1):CLK_25M_CPLD
 R2T47    2      B RES_0402-33.2,1%,1/16W,CHIP,G2A   I130 @BASEBOARD_FAB2_LIB.BASEBOARD_FAB2(SCH_1):PAGE101
  U8D7   L2 PL12A_PCLKT3_0 LCMXO2_A_256BGA-IC,H63395-001   I179 @BASEBOARD_FAB2_LIB.BASEBOARD_FAB2(SCH_1):PAGE190

CLK_25M_CPLD_R @BASEBOARD_FAB2_LIB.BASEBOARD_FAB2(SCH_1):CLK_25M_CPLD_R
 EU8F2   17 25MHZ_1 ICS9FGP204_MLFP-IC,E95226-001    I34 @BASEBOARD_FAB2_LIB.BASEBOARD_FAB2(SCH_1):PAGE101
 R2T47    1      A RES_0402-33.2,1%,1/16W,CHIP,G2A   I130 @BASEBOARD_FAB2_LIB.BASEBOARD_FAB2(SCH_1):PAGE101

CLK_322M_156M_CPU0_OSC_VRM_DN @BASEBOARD_FAB2_LIB.BASEBOARD_FAB2(SCH_1):CLK_322M_156M_CPU0_OSC_VRM_DN
  R6F6    1      A RES_0402-0.0,5%,1/16W,EMPTY,G2A    I41 @BASEBOARD_FAB2_LIB.BASEBOARD_FAB2(SCH_1):PAGE104
 R6F10    1      A RES_0402-0.0,5%,1/16W,EMPTY,G2A    I78 @BASEBOARD_FAB2_LIB.BASEBOARD_FAB2(SCH_1):PAGE104
  J6E1   F5   IOF5 SCONN120_H61426002_SM-CONN,H61A    I55 @BASEBOARD_FAB2_LIB.BASEBOARD_FAB2(SCH_1):PAGE194

CLK_322M_156M_CPU0_OSC_VRM_DP @BASEBOARD_FAB2_LIB.BASEBOARD_FAB2(SCH_1):CLK_322M_156M_CPU0_OSC_VRM_DP
  R6F8    1      A RES_0402-0.0,5%,1/16W,EMPTY,G2A    I37 @BASEBOARD_FAB2_LIB.BASEBOARD_FAB2(SCH_1):PAGE104
 R6F11    1      A RES_0402-0.0,5%,1/16W,EMPTY,G2A    I79 @BASEBOARD_FAB2_LIB.BASEBOARD_FAB2(SCH_1):PAGE104
  J6E1   E5   IOE5 SCONN120_H61426002_SM-CONN,H61A    I55 @BASEBOARD_FAB2_LIB.BASEBOARD_FAB2(SCH_1):PAGE194

CLK_322M_156M_CPU1_OSC_VRM_DN @BASEBOARD_FAB2_LIB.BASEBOARD_FAB2(SCH_1):CLK_322M_156M_CPU1_OSC_VRM_DN
  R3F1    1      A RES_0402-0.0,5%,1/16W,EMPTY,G2A    I51 @BASEBOARD_FAB2_LIB.BASEBOARD_FAB2(SCH_1):PAGE104
  R3F5    1      A RES_0402-0.0,5%,1/16W,EMPTY,G2A    I84 @BASEBOARD_FAB2_LIB.BASEBOARD_FAB2(SCH_1):PAGE104
  J4E1   F5   IOF5 SCONN120_H61426002_SM-CONN,H61A    I45 @BASEBOARD_FAB2_LIB.BASEBOARD_FAB2(SCH_1):PAGE193

CLK_322M_156M_CPU1_OSC_VRM_DP @BASEBOARD_FAB2_LIB.BASEBOARD_FAB2(SCH_1):CLK_322M_156M_CPU1_OSC_VRM_DP
  R3F3    1      A RES_0402-0.0,5%,1/16W,EMPTY,G2A    I53 @BASEBOARD_FAB2_LIB.BASEBOARD_FAB2(SCH_1):PAGE104
  R3F6    1      A RES_0402-0.0,5%,1/16W,EMPTY,G2A    I88 @BASEBOARD_FAB2_LIB.BASEBOARD_FAB2(SCH_1):PAGE104
  J4E1   E5   IOE5 SCONN120_H61426002_SM-CONN,H61A    I45 @BASEBOARD_FAB2_LIB.BASEBOARD_FAB2(SCH_1):PAGE193

CLK_322M_OSC_CPU0_RC_DN @BASEBOARD_FAB2_LIB.BASEBOARD_FAB2(SCH_1):CLK_322M_OSC_CPU0_RC_DN
  U5D1 AL26 RSVD<213> SKX_EXT_B_BGA1-IC,TBD   I204 @BASEBOARD_FAB2_LIB.BASEBOARD_FAB2(SCH_1):PAGE22
 R6F10    2      B RES_0402-0.0,5%,1/16W,EMPTY,G2A    I78 @BASEBOARD_FAB2_LIB.BASEBOARD_FAB2(SCH_1):PAGE104

CLK_322M_OSC_CPU0_RC_DP @BASEBOARD_FAB2_LIB.BASEBOARD_FAB2(SCH_1):CLK_322M_OSC_CPU0_RC_DP
  U5D1 AK27 RSVD<220> SKX_EXT_B_BGA1-IC,TBD   I204 @BASEBOARD_FAB2_LIB.BASEBOARD_FAB2(SCH_1):PAGE22
 R6F11    2      B RES_0402-0.0,5%,1/16W,EMPTY,G2A    I79 @BASEBOARD_FAB2_LIB.BASEBOARD_FAB2(SCH_1):PAGE104

CLK_322M_OSC_CPU1_RC_DN @BASEBOARD_FAB2_LIB.BASEBOARD_FAB2(SCH_1):CLK_322M_OSC_CPU1_RC_DN
  U2D1 AL26 RSVD<213> SKX_EXT_B_BGA1-IC,TBD   I169 @BASEBOARD_FAB2_LIB.BASEBOARD_FAB2(SCH_1):PAGE56
  R3F5    2      B RES_0402-0.0,5%,1/16W,EMPTY,G2A    I84 @BASEBOARD_FAB2_LIB.BASEBOARD_FAB2(SCH_1):PAGE104

CLK_322M_OSC_CPU1_RC_DP @BASEBOARD_FAB2_LIB.BASEBOARD_FAB2(SCH_1):CLK_322M_OSC_CPU1_RC_DP
  U2D1 AK27 RSVD<220> SKX_EXT_B_BGA1-IC,TBD   I169 @BASEBOARD_FAB2_LIB.BASEBOARD_FAB2(SCH_1):PAGE56
  R3F6    2      B RES_0402-0.0,5%,1/16W,EMPTY,G2A    I88 @BASEBOARD_FAB2_LIB.BASEBOARD_FAB2(SCH_1):PAGE104

CLK_32K_SUSCLK_PLD @BASEBOARD_FAB2_LIB.BASEBOARD_FAB2(SCH_1):CLK_32K_SUSCLK_PLD
 R8F27    2      B RES_0402-22.1,1.0%,1/16W,CHIP,A   I129 @BASEBOARD_FAB2_LIB.BASEBOARD_FAB2(SCH_1):PAGE101
  U8D7   E1 PL3A_PCLKT5_0 LCMXO2_A_256BGA-IC,H63395-001   I179 @BASEBOARD_FAB2_LIB.BASEBOARD_FAB2(SCH_1):PAGE190

CLK_32K_SUSCLK_PLD_R @BASEBOARD_FAB2_LIB.BASEBOARD_FAB2(SCH_1):CLK_32K_SUSCLK_PLD_R
 EU8F2   13  32KHZ ICS9FGP204_MLFP-IC,E95226-001    I34 @BASEBOARD_FAB2_LIB.BASEBOARD_FAB2(SCH_1):PAGE101
 R8F27    1      A RES_0402-22.1,1.0%,1/16W,CHIP,A   I129 @BASEBOARD_FAB2_LIB.BASEBOARD_FAB2(SCH_1):PAGE101

CLK_48M_USB_BMC @BASEBOARD_FAB2_LIB.BASEBOARD_FAB2(SCH_1):CLK_48M_USB_BMC
  U7C1 BW50 CLOCKSE_BMCCLK LBG_CORE_QAT_EXT_D_BGA1-IC,H91A    I40 @BASEBOARD_FAB2_LIB.BASEBOARD_FAB2(SCH_1):PAGE114
 U25W4  J20 GPIOB4_USBCKI AST2520A1-GP-GP_ASIC2-GB1-AST2A    I95 @BASEBOARD_FAB2_LIB.BASEBOARD_FAB2(SCH_1):PAGE144

CLK_50M_CKMNG_BMC_1 @BASEBOARD_FAB2_LIB.BASEBOARD_FAB2(SCH_1):CLK_50M_CKMNG_BMC_1
 R2T46    2      B RES_0402-22.1,1.0%,1/16W,CHIP,A   I125 @BASEBOARD_FAB2_LIB.BASEBOARD_FAB2(SCH_1):PAGE101
 U25W4   B4 RGMII1RXCK_RMII1RCLKI_GPIOU4 AST2520A1-GP-GP_ASIC2-GB1-AST2A   I106 @BASEBOARD_FAB2_LIB.BASEBOARD_FAB2(SCH_1):PAGE147

CLK_50M_CKMNG_BMC_1_R @BASEBOARD_FAB2_LIB.BASEBOARD_FAB2(SCH_1):CLK_50M_CKMNG_BMC_1_R
 EU8F2   32 RMII<1> ICS9FGP204_MLFP-IC,E95226-001    I34 @BASEBOARD_FAB2_LIB.BASEBOARD_FAB2(SCH_1):PAGE101
 R2T46    1      A RES_0402-22.1,1.0%,1/16W,CHIP,A   I125 @BASEBOARD_FAB2_LIB.BASEBOARD_FAB2(SCH_1):PAGE101

CLK_50M_CKMNG_BMC_2 @BASEBOARD_FAB2_LIB.BASEBOARD_FAB2(SCH_1):CLK_50M_CKMNG_BMC_2
  R8G1    2      B RES_0402-33.2,1%,1/16W,CHIP,G2A   I133 @BASEBOARD_FAB2_LIB.BASEBOARD_FAB2(SCH_1):PAGE101
 U25W4   C2 RGMII2RXCK_RMII2RCLKI_GPIOV2 AST2520A1-GP-GP_ASIC2-GB1-AST2A   I106 @BASEBOARD_FAB2_LIB.BASEBOARD_FAB2(SCH_1):PAGE147

CLK_50M_CKMNG_BMC_2_R @BASEBOARD_FAB2_LIB.BASEBOARD_FAB2(SCH_1):CLK_50M_CKMNG_BMC_2_R
 EU8F2   29 RMII<2> ICS9FGP204_MLFP-IC,E95226-001    I34 @BASEBOARD_FAB2_LIB.BASEBOARD_FAB2(SCH_1):PAGE101
  R8G1    1      A RES_0402-33.2,1%,1/16W,CHIP,G2A   I133 @BASEBOARD_FAB2_LIB.BASEBOARD_FAB2(SCH_1):PAGE101

CLK_50M_CKMNG_OCP @BASEBOARD_FAB2_LIB.BASEBOARD_FAB2(SCH_1):CLK_50M_CKMNG_OCP
 R2T42    2      B RES_0402-22.1,1.0%,1/16W,CHIP,A   I124 @BASEBOARD_FAB2_LIB.BASEBOARD_FAB2(SCH_1):PAGE101
  J9B3   29   IO29 SCONN120_A28699018_SM-SCONN,A2A   I336 @BASEBOARD_FAB2_LIB.BASEBOARD_FAB2(SCH_1):PAGE186

CLK_50M_CKMNG_OCP_R @BASEBOARD_FAB2_LIB.BASEBOARD_FAB2(SCH_1):CLK_50M_CKMNG_OCP_R
 EU8F2   33 RMII<0> ICS9FGP204_MLFP-IC,E95226-001    I34 @BASEBOARD_FAB2_LIB.BASEBOARD_FAB2(SCH_1):PAGE101
 R2T42    1      A RES_0402-22.1,1.0%,1/16W,CHIP,A   I124 @BASEBOARD_FAB2_LIB.BASEBOARD_FAB2(SCH_1):PAGE101

CLK_50M_CKMNG_PCH_10GBE @BASEBOARD_FAB2_LIB.BASEBOARD_FAB2(SCH_1):CLK_50M_CKMNG_PCH_10GBE
 R8G24    2      B RES_0402-33.2,1%,1/16W,CHIP,G2A   I132 @BASEBOARD_FAB2_LIB.BASEBOARD_FAB2(SCH_1):PAGE101
  U7C1  AJ1 GPP_K0_LAN_NCSI_CLK_IN LBG_CORE_QAT_EXT_D_BGA1-IC,H91A    I34 @BASEBOARD_FAB2_LIB.BASEBOARD_FAB2(SCH_1):PAGE121
 R7C20    1      A RES_0402-10.0K,1%,1/16W,CHIP,GA    I73 @BASEBOARD_FAB2_LIB.BASEBOARD_FAB2(SCH_1):PAGE121

CLK_50M_CKMNG_PCH_10GBE_R @BASEBOARD_FAB2_LIB.BASEBOARD_FAB2(SCH_1):CLK_50M_CKMNG_PCH_10GBE_R
 EU8F2   25 RMII<4> ICS9FGP204_MLFP-IC,E95226-001    I34 @BASEBOARD_FAB2_LIB.BASEBOARD_FAB2(SCH_1):PAGE101
 R8G24    1      A RES_0402-33.2,1%,1/16W,CHIP,G2A   I132 @BASEBOARD_FAB2_LIB.BASEBOARD_FAB2(SCH_1):PAGE101

CLK_50M_CKMNG_SPRVLLE @BASEBOARD_FAB2_LIB.BASEBOARD_FAB2(SCH_1):CLK_50M_CKMNG_SPRVLLE
 R8G25    2      B RES_0402-33.2,1%,1/16W,CHIP,G2A   I131 @BASEBOARD_FAB2_LIB.BASEBOARD_FAB2(SCH_1):PAGE101
 EU9E1    2 NC_SI_CLK_IN SPRINGVILLE_SM1-IC,G47144-004    I72 @BASEBOARD_FAB2_LIB.BASEBOARD_FAB2(SCH_1):PAGE139
 R1R12    1      A RES_0402-10.0K,1%,1/16W,CHIP,GA   I213 @BASEBOARD_FAB2_LIB.BASEBOARD_FAB2(SCH_1):PAGE139

CLK_50M_CKMNG_SPRVLLE_R @BASEBOARD_FAB2_LIB.BASEBOARD_FAB2(SCH_1):CLK_50M_CKMNG_SPRVLLE_R
 EU8F2   28 RMII<3> ICS9FGP204_MLFP-IC,E95226-001    I34 @BASEBOARD_FAB2_LIB.BASEBOARD_FAB2(SCH_1):PAGE101
 R8G25    1      A RES_0402-33.2,1%,1/16W,CHIP,G2A   I131 @BASEBOARD_FAB2_LIB.BASEBOARD_FAB2(SCH_1):PAGE101

DMI_CPU0_PCH_RX_C_DN<0> @BASEBOARD_FAB2_LIB.BASEBOARD_FAB2(SCH_1):DMI_CPU0_PCH_RX_C_DN(0)
  U5D1  CK9 DMI_RX_DN<0> SKX_EXT_B_BGA1-IC,TBD    I61 @BASEBOARD_FAB2_LIB.BASEBOARD_FAB2(SCH_1):PAGE29
 C3M44    2      B CAP_0402-0.22UF,16V,10%,X7R,A3A    I80 @BASEBOARD_FAB2_LIB.BASEBOARD_FAB2(SCH_1):PAGE129

DMI_CPU0_PCH_RX_C_DN<1> @BASEBOARD_FAB2_LIB.BASEBOARD_FAB2(SCH_1):DMI_CPU0_PCH_RX_C_DN(1)
  U5D1 CM11 DMI_RX_DN<1> SKX_EXT_B_BGA1-IC,TBD    I61 @BASEBOARD_FAB2_LIB.BASEBOARD_FAB2(SCH_1):PAGE29
 C3M41    2      B CAP_0402-0.22UF,16V,10%,X7R,A3A    I81 @BASEBOARD_FAB2_LIB.BASEBOARD_FAB2(SCH_1):PAGE129

DMI_CPU0_PCH_RX_C_DN<2> @BASEBOARD_FAB2_LIB.BASEBOARD_FAB2(SCH_1):DMI_CPU0_PCH_RX_C_DN(2)
  U5D1 CR12 DMI_RX_DN<2> SKX_EXT_B_BGA1-IC,TBD    I61 @BASEBOARD_FAB2_LIB.BASEBOARD_FAB2(SCH_1):PAGE29
 C3M45    2      B CAP_0402-0.22UF,16V,10%,X7R,A3A    I82 @BASEBOARD_FAB2_LIB.BASEBOARD_FAB2(SCH_1):PAGE129

DMI_CPU0_PCH_RX_C_DN<3> @BASEBOARD_FAB2_LIB.BASEBOARD_FAB2(SCH_1):DMI_CPU0_PCH_RX_C_DN(3)
  U5D1 CT11 DMI_RX_DN<3> SKX_EXT_B_BGA1-IC,TBD    I61 @BASEBOARD_FAB2_LIB.BASEBOARD_FAB2(SCH_1):PAGE29
 C3N13    2      B CAP_0402-0.22UF,16V,10%,X7R,A3A    I83 @BASEBOARD_FAB2_LIB.BASEBOARD_FAB2(SCH_1):PAGE129

DMI_CPU0_PCH_RX_C_DP<0> @BASEBOARD_FAB2_LIB.BASEBOARD_FAB2(SCH_1):DMI_CPU0_PCH_RX_C_DP(0)
  U5D1 CL10 DMI_RX_DP<0> SKX_EXT_B_BGA1-IC,TBD    I61 @BASEBOARD_FAB2_LIB.BASEBOARD_FAB2(SCH_1):PAGE29
 C3M40    2      B CAP_0402-0.22UF,16V,10%,X7R,A3A    I72 @BASEBOARD_FAB2_LIB.BASEBOARD_FAB2(SCH_1):PAGE129

DMI_CPU0_PCH_RX_C_DP<1> @BASEBOARD_FAB2_LIB.BASEBOARD_FAB2(SCH_1):DMI_CPU0_PCH_RX_C_DP(1)
  U5D1 CN10 DMI_RX_DP<1> SKX_EXT_B_BGA1-IC,TBD    I61 @BASEBOARD_FAB2_LIB.BASEBOARD_FAB2(SCH_1):PAGE29
 C3M37    2      B CAP_0402-0.22UF,16V,10%,X7R,A3A    I73 @BASEBOARD_FAB2_LIB.BASEBOARD_FAB2(SCH_1):PAGE129

DMI_CPU0_PCH_RX_C_DP<2> @BASEBOARD_FAB2_LIB.BASEBOARD_FAB2(SCH_1):DMI_CPU0_PCH_RX_C_DP(2)
  U5D1 CP11 DMI_RX_DP<2> SKX_EXT_B_BGA1-IC,TBD    I61 @BASEBOARD_FAB2_LIB.BASEBOARD_FAB2(SCH_1):PAGE29
  C3N9    2      B CAP_0402-0.22UF,16V,10%,X7R,A3A    I74 @BASEBOARD_FAB2_LIB.BASEBOARD_FAB2(SCH_1):PAGE129

DMI_CPU0_PCH_RX_C_DP<3> @BASEBOARD_FAB2_LIB.BASEBOARD_FAB2(SCH_1):DMI_CPU0_PCH_RX_C_DP(3)
  U5D1 CV11 DMI_RX_DP<3> SKX_EXT_B_BGA1-IC,TBD    I61 @BASEBOARD_FAB2_LIB.BASEBOARD_FAB2(SCH_1):PAGE29
  C3N8    2      B CAP_0402-0.22UF,16V,10%,X7R,A3A    I75 @BASEBOARD_FAB2_LIB.BASEBOARD_FAB2(SCH_1):PAGE129

DMI_CPU0_PCH_RX_DN<0> @BASEBOARD_FAB2_LIB.BASEBOARD_FAB2(SCH_1):DMI_CPU0_PCH_RX_DN(0)
  U7C1  H46 DMI_TXN<0> LBG_CORE_QAT_EXT_D_BGA1-IC,H91A     I9 @BASEBOARD_FAB2_LIB.BASEBOARD_FAB2(SCH_1):PAGE117
 C3M44    1      A CAP_0402-0.22UF,16V,10%,X7R,A3A    I80 @BASEBOARD_FAB2_LIB.BASEBOARD_FAB2(SCH_1):PAGE129

DMI_CPU0_PCH_RX_DN<1> @BASEBOARD_FAB2_LIB.BASEBOARD_FAB2(SCH_1):DMI_CPU0_PCH_RX_DN(1)
  U7C1  J48 DMI_TXN<1> LBG_CORE_QAT_EXT_D_BGA1-IC,H91A     I9 @BASEBOARD_FAB2_LIB.BASEBOARD_FAB2(SCH_1):PAGE117
 C3M41    1      A CAP_0402-0.22UF,16V,10%,X7R,A3A    I81 @BASEBOARD_FAB2_LIB.BASEBOARD_FAB2(SCH_1):PAGE129

DMI_CPU0_PCH_RX_DN<2> @BASEBOARD_FAB2_LIB.BASEBOARD_FAB2(SCH_1):DMI_CPU0_PCH_RX_DN(2)
  U7C1  K50 DMI_TXN<2> LBG_CORE_QAT_EXT_D_BGA1-IC,H91A     I9 @BASEBOARD_FAB2_LIB.BASEBOARD_FAB2(SCH_1):PAGE117
 C3M45    1      A CAP_0402-0.22UF,16V,10%,X7R,A3A    I82 @BASEBOARD_FAB2_LIB.BASEBOARD_FAB2(SCH_1):PAGE129

DMI_CPU0_PCH_RX_DN<3> @BASEBOARD_FAB2_LIB.BASEBOARD_FAB2(SCH_1):DMI_CPU0_PCH_RX_DN(3)
  U7C1  P52 DMI_TXN<3> LBG_CORE_QAT_EXT_D_BGA1-IC,H91A     I9 @BASEBOARD_FAB2_LIB.BASEBOARD_FAB2(SCH_1):PAGE117
 C3N13    1      A CAP_0402-0.22UF,16V,10%,X7R,A3A    I83 @BASEBOARD_FAB2_LIB.BASEBOARD_FAB2(SCH_1):PAGE129

DMI_CPU0_PCH_RX_DP<0> @BASEBOARD_FAB2_LIB.BASEBOARD_FAB2(SCH_1):DMI_CPU0_PCH_RX_DP(0)
  U7C1  K46 DMI_TXP<0> LBG_CORE_QAT_EXT_D_BGA1-IC,H91A     I9 @BASEBOARD_FAB2_LIB.BASEBOARD_FAB2(SCH_1):PAGE117
 C3M40    1      A CAP_0402-0.22UF,16V,10%,X7R,A3A    I72 @BASEBOARD_FAB2_LIB.BASEBOARD_FAB2(SCH_1):PAGE129

DMI_CPU0_PCH_RX_DP<1> @BASEBOARD_FAB2_LIB.BASEBOARD_FAB2(SCH_1):DMI_CPU0_PCH_RX_DP(1)
  U7C1  H50 DMI_TXP<1> LBG_CORE_QAT_EXT_D_BGA1-IC,H91A     I9 @BASEBOARD_FAB2_LIB.BASEBOARD_FAB2(SCH_1):PAGE117
 C3M37    1      A CAP_0402-0.22UF,16V,10%,X7R,A3A    I73 @BASEBOARD_FAB2_LIB.BASEBOARD_FAB2(SCH_1):PAGE129

DMI_CPU0_PCH_RX_DP<2> @BASEBOARD_FAB2_LIB.BASEBOARD_FAB2(SCH_1):DMI_CPU0_PCH_RX_DP(2)
  U7C1  M52 DMI_TXP<2> LBG_CORE_QAT_EXT_D_BGA1-IC,H91A     I9 @BASEBOARD_FAB2_LIB.BASEBOARD_FAB2(SCH_1):PAGE117
  C3N9    1      A CAP_0402-0.22UF,16V,10%,X7R,A3A    I74 @BASEBOARD_FAB2_LIB.BASEBOARD_FAB2(SCH_1):PAGE129

DMI_CPU0_PCH_RX_DP<3> @BASEBOARD_FAB2_LIB.BASEBOARD_FAB2(SCH_1):DMI_CPU0_PCH_RX_DP(3)
  U7C1  N54 DMI_TXP<3> LBG_CORE_QAT_EXT_D_BGA1-IC,H91A     I9 @BASEBOARD_FAB2_LIB.BASEBOARD_FAB2(SCH_1):PAGE117
  C3N8    1      A CAP_0402-0.22UF,16V,10%,X7R,A3A    I75 @BASEBOARD_FAB2_LIB.BASEBOARD_FAB2(SCH_1):PAGE129

DMI_CPU0_PCH_TX_C_DN<0> @BASEBOARD_FAB2_LIB.BASEBOARD_FAB2(SCH_1):DMI_CPU0_PCH_TX_C_DN(0)
  U7C1  D42 DMI_RXN<0> LBG_CORE_QAT_EXT_D_BGA1-IC,H91A     I9 @BASEBOARD_FAB2_LIB.BASEBOARD_FAB2(SCH_1):PAGE117
  C7C3    2      B CAP_0402-0.22UF,16V,10%,X7R,A3A    I76 @BASEBOARD_FAB2_LIB.BASEBOARD_FAB2(SCH_1):PAGE129

DMI_CPU0_PCH_TX_C_DN<1> @BASEBOARD_FAB2_LIB.BASEBOARD_FAB2(SCH_1):DMI_CPU0_PCH_TX_C_DN(1)
  U7C1  C43 DMI_RXN<1> LBG_CORE_QAT_EXT_D_BGA1-IC,H91A     I9 @BASEBOARD_FAB2_LIB.BASEBOARD_FAB2(SCH_1):PAGE117
  C7C1    2      B CAP_0402-0.22UF,16V,10%,X7R,A3A    I77 @BASEBOARD_FAB2_LIB.BASEBOARD_FAB2(SCH_1):PAGE129

DMI_CPU0_PCH_TX_C_DN<2> @BASEBOARD_FAB2_LIB.BASEBOARD_FAB2(SCH_1):DMI_CPU0_PCH_TX_C_DN(2)
  U7C1  D44 DMI_RXN<2> LBG_CORE_QAT_EXT_D_BGA1-IC,H91A     I9 @BASEBOARD_FAB2_LIB.BASEBOARD_FAB2(SCH_1):PAGE117
 C7B29    2      B CAP_0402-0.22UF,16V,10%,X7R,A3A    I78 @BASEBOARD_FAB2_LIB.BASEBOARD_FAB2(SCH_1):PAGE129

DMI_CPU0_PCH_TX_C_DN<3> @BASEBOARD_FAB2_LIB.BASEBOARD_FAB2(SCH_1):DMI_CPU0_PCH_TX_C_DN(3)
  U7C1  C45 DMI_RXN<3> LBG_CORE_QAT_EXT_D_BGA1-IC,H91A     I9 @BASEBOARD_FAB2_LIB.BASEBOARD_FAB2(SCH_1):PAGE117
 C7B26    2      B CAP_0402-0.22UF,16V,10%,X7R,A3A    I79 @BASEBOARD_FAB2_LIB.BASEBOARD_FAB2(SCH_1):PAGE129

DMI_CPU0_PCH_TX_C_DP<0> @BASEBOARD_FAB2_LIB.BASEBOARD_FAB2(SCH_1):DMI_CPU0_PCH_TX_C_DP(0)
  U7C1  B42 DMI_RXP<0> LBG_CORE_QAT_EXT_D_BGA1-IC,H91A     I9 @BASEBOARD_FAB2_LIB.BASEBOARD_FAB2(SCH_1):PAGE117
  C7C2    2      B CAP_0402-0.22UF,16V,10%,X7R,A3A    I71 @BASEBOARD_FAB2_LIB.BASEBOARD_FAB2(SCH_1):PAGE129

DMI_CPU0_PCH_TX_C_DP<1> @BASEBOARD_FAB2_LIB.BASEBOARD_FAB2(SCH_1):DMI_CPU0_PCH_TX_C_DP(1)
  U7C1  A43 DMI_RXP<1> LBG_CORE_QAT_EXT_D_BGA1-IC,H91A     I9 @BASEBOARD_FAB2_LIB.BASEBOARD_FAB2(SCH_1):PAGE117
 C7B28    2      B CAP_0402-0.22UF,16V,10%,X7R,A3A    I70 @BASEBOARD_FAB2_LIB.BASEBOARD_FAB2(SCH_1):PAGE129

DMI_CPU0_PCH_TX_C_DP<2> @BASEBOARD_FAB2_LIB.BASEBOARD_FAB2(SCH_1):DMI_CPU0_PCH_TX_C_DP(2)
  U7C1  B44 DMI_RXP<2> LBG_CORE_QAT_EXT_D_BGA1-IC,H91A     I9 @BASEBOARD_FAB2_LIB.BASEBOARD_FAB2(SCH_1):PAGE117
 C7B27    2      B CAP_0402-0.22UF,16V,10%,X7R,A3A    I69 @BASEBOARD_FAB2_LIB.BASEBOARD_FAB2(SCH_1):PAGE129

DMI_CPU0_PCH_TX_C_DP<3> @BASEBOARD_FAB2_LIB.BASEBOARD_FAB2(SCH_1):DMI_CPU0_PCH_TX_C_DP(3)
  U7C1  A45 DMI_RXP<3> LBG_CORE_QAT_EXT_D_BGA1-IC,H91A     I9 @BASEBOARD_FAB2_LIB.BASEBOARD_FAB2(SCH_1):PAGE117
 C7B25    2      B CAP_0402-0.22UF,16V,10%,X7R,A3A    I35 @BASEBOARD_FAB2_LIB.BASEBOARD_FAB2(SCH_1):PAGE129

DMI_CPU0_PCH_TX_DN<0> @BASEBOARD_FAB2_LIB.BASEBOARD_FAB2(SCH_1):DMI_CPU0_PCH_TX_DN(0)
  U5D1  CG4 DMI_TX_DN<0> SKX_EXT_B_BGA1-IC,TBD    I61 @BASEBOARD_FAB2_LIB.BASEBOARD_FAB2(SCH_1):PAGE29
  C7C3    1      A CAP_0402-0.22UF,16V,10%,X7R,A3A    I76 @BASEBOARD_FAB2_LIB.BASEBOARD_FAB2(SCH_1):PAGE129

DMI_CPU0_PCH_TX_DN<1> @BASEBOARD_FAB2_LIB.BASEBOARD_FAB2(SCH_1):DMI_CPU0_PCH_TX_DN(1)
  U5D1  CJ4 DMI_TX_DN<1> SKX_EXT_B_BGA1-IC,TBD    I61 @BASEBOARD_FAB2_LIB.BASEBOARD_FAB2(SCH_1):PAGE29
  C7C1    1      A CAP_0402-0.22UF,16V,10%,X7R,A3A    I77 @BASEBOARD_FAB2_LIB.BASEBOARD_FAB2(SCH_1):PAGE129

DMI_CPU0_PCH_TX_DN<2> @BASEBOARD_FAB2_LIB.BASEBOARD_FAB2(SCH_1):DMI_CPU0_PCH_TX_DN(2)
  U5D1  CN4 DMI_TX_DN<2> SKX_EXT_B_BGA1-IC,TBD    I61 @BASEBOARD_FAB2_LIB.BASEBOARD_FAB2(SCH_1):PAGE29
 C7B29    1      A CAP_0402-0.22UF,16V,10%,X7R,A3A    I78 @BASEBOARD_FAB2_LIB.BASEBOARD_FAB2(SCH_1):PAGE129

DMI_CPU0_PCH_TX_DN<3> @BASEBOARD_FAB2_LIB.BASEBOARD_FAB2(SCH_1):DMI_CPU0_PCH_TX_DN(3)
  U5D1  CP5 DMI_TX_DN<3> SKX_EXT_B_BGA1-IC,TBD    I61 @BASEBOARD_FAB2_LIB.BASEBOARD_FAB2(SCH_1):PAGE29
 C7B26    1      A CAP_0402-0.22UF,16V,10%,X7R,A3A    I79 @BASEBOARD_FAB2_LIB.BASEBOARD_FAB2(SCH_1):PAGE129

DMI_CPU0_PCH_TX_DP<0> @BASEBOARD_FAB2_LIB.BASEBOARD_FAB2(SCH_1):DMI_CPU0_PCH_TX_DP(0)
  U5D1  CH5 DMI_TX_DP<0> SKX_EXT_B_BGA1-IC,TBD    I61 @BASEBOARD_FAB2_LIB.BASEBOARD_FAB2(SCH_1):PAGE29
  C7C2    1      A CAP_0402-0.22UF,16V,10%,X7R,A3A    I71 @BASEBOARD_FAB2_LIB.BASEBOARD_FAB2(SCH_1):PAGE129

DMI_CPU0_PCH_TX_DP<1> @BASEBOARD_FAB2_LIB.BASEBOARD_FAB2(SCH_1):DMI_CPU0_PCH_TX_DP(1)
  U5D1  CL4 DMI_TX_DP<1> SKX_EXT_B_BGA1-IC,TBD    I61 @BASEBOARD_FAB2_LIB.BASEBOARD_FAB2(SCH_1):PAGE29
 C7B28    1      A CAP_0402-0.22UF,16V,10%,X7R,A3A    I70 @BASEBOARD_FAB2_LIB.BASEBOARD_FAB2(SCH_1):PAGE129

DMI_CPU0_PCH_TX_DP<2> @BASEBOARD_FAB2_LIB.BASEBOARD_FAB2(SCH_1):DMI_CPU0_PCH_TX_DP(2)
  U5D1  CM3 DMI_TX_DP<2> SKX_EXT_B_BGA1-IC,TBD    I61 @BASEBOARD_FAB2_LIB.BASEBOARD_FAB2(SCH_1):PAGE29
 C7B27    1      A CAP_0402-0.22UF,16V,10%,X7R,A3A    I69 @BASEBOARD_FAB2_LIB.BASEBOARD_FAB2(SCH_1):PAGE129

DMI_CPU0_PCH_TX_DP<3> @BASEBOARD_FAB2_LIB.BASEBOARD_FAB2(SCH_1):DMI_CPU0_PCH_TX_DP(3)
  U5D1  CR4 DMI_TX_DP<3> SKX_EXT_B_BGA1-IC,TBD    I61 @BASEBOARD_FAB2_LIB.BASEBOARD_FAB2(SCH_1):PAGE29
 C7B25    1      A CAP_0402-0.22UF,16V,10%,X7R,A3A    I35 @BASEBOARD_FAB2_LIB.BASEBOARD_FAB2(SCH_1):PAGE129

FAN_PWM_OUT_SYS0 @BASEBOARD_FAB2_LIB.BASEBOARD_FAB2(SCH_1):FAN_PWM_OUT_SYS0
  U7C1 BG11 GPP_G8_FANPWM0_FANPWM0IE LBG_CORE_QAT_EXT_D_BGA1-IC,H91A   I147 @BASEBOARD_FAB2_LIB.BASEBOARD_FAB2(SCH_1):PAGE120
  U8G2    2      A TTL1G07_A_SOP-74LVC1G07,IC,C88B    I88 @BASEBOARD_FAB2_LIB.BASEBOARD_FAB2(SCH_1):PAGE161
 U25W4   V2 GPION0_PWM0 AST2520A1-GP-GP_ASIC2-GB1-AST2A   I106 @BASEBOARD_FAB2_LIB.BASEBOARD_FAB2(SCH_1):PAGE147

FAN_PWM_OUT_SYS0_BUF @BASEBOARD_FAB2_LIB.BASEBOARD_FAB2(SCH_1):FAN_PWM_OUT_SYS0_BUF
  U8G2    4      Y TTL1G07_A_SOP-74LVC1G07,IC,C88B    I88 @BASEBOARD_FAB2_LIB.BASEBOARD_FAB2(SCH_1):PAGE161
 R2U42    1      A RES_0402-221,1.0%,1/16W,CHIP,GA    I99 @BASEBOARD_FAB2_LIB.BASEBOARD_FAB2(SCH_1):PAGE161

FAN_PWM_OUT_SYS0_R @BASEBOARD_FAB2_LIB.BASEBOARD_FAB2(SCH_1):FAN_PWM_OUT_SYS0_R
  J1F2    4    IO4 CONN6_C74770005_PIP-HDR,C74770A     I1 @BASEBOARD_FAB2_LIB.BASEBOARD_FAB2(SCH_1):PAGE161
 CR1E1    2      A DIODE_SM-SDMK0340L,EMPTY,H7179A    I50 @BASEBOARD_FAB2_LIB.BASEBOARD_FAB2(SCH_1):PAGE161
 R1E12    2      B RES_0402-4.75K,1%,1/16W,CHIP,GA    I51 @BASEBOARD_FAB2_LIB.BASEBOARD_FAB2(SCH_1):PAGE161
 R2U42    2      B RES_0402-221,1.0%,1/16W,CHIP,GA    I99 @BASEBOARD_FAB2_LIB.BASEBOARD_FAB2(SCH_1):PAGE161
  R9T1    1      A RES_0402-0.0,5%,1/16W,CHIP,G21A   I261 @BASEBOARD_FAB2_LIB.BASEBOARD_FAB2(SCH_1):PAGE181

FAN_PWM_OUT_SYS0_R1 @BASEBOARD_FAB2_LIB.BASEBOARD_FAB2(SCH_1):FAN_PWM_OUT_SYS0_R1
  J1F1   F4   IOF4 CONN76_H22707001_THMT1-CONN,H2A   I111 @BASEBOARD_FAB2_LIB.BASEBOARD_FAB2(SCH_1):PAGE181
  R9T1    2      B RES_0402-0.0,5%,1/16W,CHIP,G21A   I261 @BASEBOARD_FAB2_LIB.BASEBOARD_FAB2(SCH_1):PAGE181
  R1F9    2      B RES_0402-0.0,5%,1/16W,EMPTY,G2A   I107 @BASEBOARD_FAB2_LIB.BASEBOARD_FAB2(SCH_1):PAGE182

FAN_PWM_OUT_SYS1 @BASEBOARD_FAB2_LIB.BASEBOARD_FAB2(SCH_1):FAN_PWM_OUT_SYS1
  U7C1 AV11 GPP_G9_FANPWM1_FAMPWM1IE LBG_CORE_QAT_EXT_D_BGA1-IC,H91A   I147 @BASEBOARD_FAB2_LIB.BASEBOARD_FAB2(SCH_1):PAGE120
  U8G3    2      A TTL1G07_A_SOP-74LVC1G07,IC,C88B    I92 @BASEBOARD_FAB2_LIB.BASEBOARD_FAB2(SCH_1):PAGE161
 U25W4   W2 GPION1_PWM1 AST2520A1-GP-GP_ASIC2-GB1-AST2A   I106 @BASEBOARD_FAB2_LIB.BASEBOARD_FAB2(SCH_1):PAGE147

FAN_PWM_OUT_SYS1_BUF @BASEBOARD_FAB2_LIB.BASEBOARD_FAB2(SCH_1):FAN_PWM_OUT_SYS1_BUF
  U8G3    4      Y TTL1G07_A_SOP-74LVC1G07,IC,C88B    I92 @BASEBOARD_FAB2_LIB.BASEBOARD_FAB2(SCH_1):PAGE161
 R2U44    1      A RES_0402-221,1.0%,1/16W,CHIP,GA   I102 @BASEBOARD_FAB2_LIB.BASEBOARD_FAB2(SCH_1):PAGE161

FAN_PWM_OUT_SYS1_R @BASEBOARD_FAB2_LIB.BASEBOARD_FAB2(SCH_1):FAN_PWM_OUT_SYS1_R
  J1B2    4    IO4 CONN6_C74770005_PIP-HDR,C74770A    I32 @BASEBOARD_FAB2_LIB.BASEBOARD_FAB2(SCH_1):PAGE161
 CR1B1    2      A DIODE_SM-SDMK0340L,EMPTY,H7179A    I64 @BASEBOARD_FAB2_LIB.BASEBOARD_FAB2(SCH_1):PAGE161
 R7F33    2      B RES_0402-4.75K,1%,1/16W,CHIP,GA    I65 @BASEBOARD_FAB2_LIB.BASEBOARD_FAB2(SCH_1):PAGE161
 R2U44    2      B RES_0402-221,1.0%,1/16W,CHIP,GA   I102 @BASEBOARD_FAB2_LIB.BASEBOARD_FAB2(SCH_1):PAGE161

FAN_TACH0 @BASEBOARD_FAB2_LIB.BASEBOARD_FAB2(SCH_1):FAN_TACH0
  U7C1 AY11 GPP_G0_FANTACH0_FANTACH0IE LBG_CORE_QAT_EXT_D_BGA1-IC,H91A   I147 @BASEBOARD_FAB2_LIB.BASEBOARD_FAB2(SCH_1):PAGE120
  R1F2    1      A RES_0402-100.0,1%,1/16W,CHIP,GA    I43 @BASEBOARD_FAB2_LIB.BASEBOARD_FAB2(SCH_1):PAGE161
  R1F1    2      B RES_0402-4.75K,1%,1/16W,CHIP,GA    I45 @BASEBOARD_FAB2_LIB.BASEBOARD_FAB2(SCH_1):PAGE161
  C1F9    1      A CAP_A_0402V-0.01UF,25V,10%,X7RA    I46 @BASEBOARD_FAB2_LIB.BASEBOARD_FAB2(SCH_1):PAGE161
  R1F8    1      A RES_0402-0.0,5%,1/16W,CHIP,G21A   I268 @BASEBOARD_FAB2_LIB.BASEBOARD_FAB2(SCH_1):PAGE181
  R1U5    1      A RES_0402-100.0K,1%,1/16W,CHIP,A    I66 @BASEBOARD_FAB2_LIB.BASEBOARD_FAB2(SCH_1):PAGE147
 U25W4   U5 GPIOO0_TACH0_VPIG8 AST2520A1-GP-GP_ASIC2-GB1-AST2A   I106 @BASEBOARD_FAB2_LIB.BASEBOARD_FAB2(SCH_1):PAGE147

FAN_TACH0_CPU0_D1 @BASEBOARD_FAB2_LIB.BASEBOARD_FAB2(SCH_1):FAN_TACH0_CPU0_D1
  J1F2    3    IO3 CONN6_C74770005_PIP-HDR,C74770A     I1 @BASEBOARD_FAB2_LIB.BASEBOARD_FAB2(SCH_1):PAGE161
 CR1F1    1      C DIODE_SM-SDMK0340L,IC,H71799-0A    I42 @BASEBOARD_FAB2_LIB.BASEBOARD_FAB2(SCH_1):PAGE161

FAN_TACH0_CPU0_D2 @BASEBOARD_FAB2_LIB.BASEBOARD_FAB2(SCH_1):FAN_TACH0_CPU0_D2
 CR1F1    2      A DIODE_SM-SDMK0340L,IC,H71799-0A    I42 @BASEBOARD_FAB2_LIB.BASEBOARD_FAB2(SCH_1):PAGE161
  R1F2    2      B RES_0402-100.0,1%,1/16W,CHIP,GA    I43 @BASEBOARD_FAB2_LIB.BASEBOARD_FAB2(SCH_1):PAGE161

FAN_TACH0_R @BASEBOARD_FAB2_LIB.BASEBOARD_FAB2(SCH_1):FAN_TACH0_R
  J1F1   D4  GNDD4 CONN76_H22707001_THMT1-CONN,H2A   I111 @BASEBOARD_FAB2_LIB.BASEBOARD_FAB2(SCH_1):PAGE181
  R1F8    2      B RES_0402-0.0,5%,1/16W,CHIP,G21A   I268 @BASEBOARD_FAB2_LIB.BASEBOARD_FAB2(SCH_1):PAGE181
 R1C31    2      B RES_0402-0.0,5%,1/16W,EMPTY,G2A   I110 @BASEBOARD_FAB2_LIB.BASEBOARD_FAB2(SCH_1):PAGE182

FAN_TACH1 @BASEBOARD_FAB2_LIB.BASEBOARD_FAB2(SCH_1):FAN_TACH1
  U7C1 AV15 GPP_G1_FANTACH1_FANTACH1IE LBG_CORE_QAT_EXT_D_BGA1-IC,H91A   I147 @BASEBOARD_FAB2_LIB.BASEBOARD_FAB2(SCH_1):PAGE120
  R9T7    1      A RES_0402-100.0,1%,1/16W,CHIP,GA   I134 @BASEBOARD_FAB2_LIB.BASEBOARD_FAB2(SCH_1):PAGE161
  R9T5    2      B RES_0402-4.75K,1%,1/16W,CHIP,GA   I135 @BASEBOARD_FAB2_LIB.BASEBOARD_FAB2(SCH_1):PAGE161
  C9T1    1      A CAP_A_0402V-0.01UF,25V,10%,X7RA   I137 @BASEBOARD_FAB2_LIB.BASEBOARD_FAB2(SCH_1):PAGE161
 R9R10    1      A RES_0402-0.0,5%,1/16W,CHIP,G21A   I256 @BASEBOARD_FAB2_LIB.BASEBOARD_FAB2(SCH_1):PAGE181
  R1U4    1      A RES_0402-100.0K,1%,1/16W,CHIP,A    I65 @BASEBOARD_FAB2_LIB.BASEBOARD_FAB2(SCH_1):PAGE147
 U25W4   U4 GPIOO1_TACH1_VPIG9 AST2520A1-GP-GP_ASIC2-GB1-AST2A   I106 @BASEBOARD_FAB2_LIB.BASEBOARD_FAB2(SCH_1):PAGE147

FAN_TACH1_CPU1_D1 @BASEBOARD_FAB2_LIB.BASEBOARD_FAB2(SCH_1):FAN_TACH1_CPU1_D1
  J1F2    5    IO5 CONN6_C74770005_PIP-HDR,C74770A     I1 @BASEBOARD_FAB2_LIB.BASEBOARD_FAB2(SCH_1):PAGE161
 CR1F2    1      C DIODE_SM-SDMK0340L,IC,H71799-0A   I133 @BASEBOARD_FAB2_LIB.BASEBOARD_FAB2(SCH_1):PAGE161

FAN_TACH1_CPU1_D2 @BASEBOARD_FAB2_LIB.BASEBOARD_FAB2(SCH_1):FAN_TACH1_CPU1_D2
 CR1F2    2      A DIODE_SM-SDMK0340L,IC,H71799-0A   I133 @BASEBOARD_FAB2_LIB.BASEBOARD_FAB2(SCH_1):PAGE161
  R9T7    2      B RES_0402-100.0,1%,1/16W,CHIP,GA   I134 @BASEBOARD_FAB2_LIB.BASEBOARD_FAB2(SCH_1):PAGE161

FAN_TACH1_R @BASEBOARD_FAB2_LIB.BASEBOARD_FAB2(SCH_1):FAN_TACH1_R
  J1F1   C4   IOC4 CONN76_H22707001_THMT1-CONN,H2A   I111 @BASEBOARD_FAB2_LIB.BASEBOARD_FAB2(SCH_1):PAGE181
 R9R10    2      B RES_0402-0.0,5%,1/16W,CHIP,G21A   I256 @BASEBOARD_FAB2_LIB.BASEBOARD_FAB2(SCH_1):PAGE181
 R1C11    2      B RES_0402-0.0,5%,1/16W,EMPTY,G2A    I97 @BASEBOARD_FAB2_LIB.BASEBOARD_FAB2(SCH_1):PAGE182

FAN_TACH2 @BASEBOARD_FAB2_LIB.BASEBOARD_FAB2(SCH_1):FAN_TACH2
  U7C1 BE22 GPP_G2_FANTACH2_FANTACH2IE LBG_CORE_QAT_EXT_D_BGA1-IC,H91A   I147 @BASEBOARD_FAB2_LIB.BASEBOARD_FAB2(SCH_1):PAGE120
 R1B22    1      A RES_0402-100.0,1%,1/16W,CHIP,GA    I67 @BASEBOARD_FAB2_LIB.BASEBOARD_FAB2(SCH_1):PAGE161
 C1B15    1      A CAP_A_0402V-0.01UF,25V,10%,X7RA    I68 @BASEBOARD_FAB2_LIB.BASEBOARD_FAB2(SCH_1):PAGE161
 R1B21    2      B RES_0402-4.75K,1%,1/16W,CHIP,GA    I70 @BASEBOARD_FAB2_LIB.BASEBOARD_FAB2(SCH_1):PAGE161
 R9R12    1      A RES_0402-0.0,5%,1/16W,CHIP,G21A   I255 @BASEBOARD_FAB2_LIB.BASEBOARD_FAB2(SCH_1):PAGE181
  R1U2    1      A RES_0402-100.0K,1%,1/16W,CHIP,A    I62 @BASEBOARD_FAB2_LIB.BASEBOARD_FAB2(SCH_1):PAGE147
 U25W4   V5 GPIOO2_TACH2 AST2520A1-GP-GP_ASIC2-GB1-AST2A   I106 @BASEBOARD_FAB2_LIB.BASEBOARD_FAB2(SCH_1):PAGE147

FAN_TACH2_CPU1_D1 @BASEBOARD_FAB2_LIB.BASEBOARD_FAB2(SCH_1):FAN_TACH2_CPU1_D1
  J1B2    3    IO3 CONN6_C74770005_PIP-HDR,C74770A    I32 @BASEBOARD_FAB2_LIB.BASEBOARD_FAB2(SCH_1):PAGE161
 CR1B2    1      C DIODE_SM-SDMK0340L,IC,H71799-0A    I62 @BASEBOARD_FAB2_LIB.BASEBOARD_FAB2(SCH_1):PAGE161

FAN_TACH2_CPU1_D2 @BASEBOARD_FAB2_LIB.BASEBOARD_FAB2(SCH_1):FAN_TACH2_CPU1_D2
 CR1B2    2      A DIODE_SM-SDMK0340L,IC,H71799-0A    I62 @BASEBOARD_FAB2_LIB.BASEBOARD_FAB2(SCH_1):PAGE161
 R1B22    2      B RES_0402-100.0,1%,1/16W,CHIP,GA    I67 @BASEBOARD_FAB2_LIB.BASEBOARD_FAB2(SCH_1):PAGE161

FAN_TACH2_R @BASEBOARD_FAB2_LIB.BASEBOARD_FAB2(SCH_1):FAN_TACH2_R
  J1F1   B4   IOB4 CONN76_H22707001_THMT1-CONN,H2A   I111 @BASEBOARD_FAB2_LIB.BASEBOARD_FAB2(SCH_1):PAGE181
 R9R12    2      B RES_0402-0.0,5%,1/16W,CHIP,G21A   I255 @BASEBOARD_FAB2_LIB.BASEBOARD_FAB2(SCH_1):PAGE181
  R1C9    2      B RES_0402-0.0,5%,1/16W,EMPTY,G2A   I104 @BASEBOARD_FAB2_LIB.BASEBOARD_FAB2(SCH_1):PAGE182

FAN_TACH3 @BASEBOARD_FAB2_LIB.BASEBOARD_FAB2(SCH_1):FAN_TACH3
  U7C1  AY7 GPP_G3_FANTACH3_FANTACH3IE LBG_CORE_QAT_EXT_D_BGA1-IC,H91A   I147 @BASEBOARD_FAB2_LIB.BASEBOARD_FAB2(SCH_1):PAGE120
 R1B23    1      A RES_0402-100.0,1%,1/16W,CHIP,GA   I124 @BASEBOARD_FAB2_LIB.BASEBOARD_FAB2(SCH_1):PAGE161
 R1B24    2      B RES_0402-4.75K,1%,1/16W,CHIP,GA   I126 @BASEBOARD_FAB2_LIB.BASEBOARD_FAB2(SCH_1):PAGE161
 C1B17    1      A CAP_A_0402V-0.01UF,25V,10%,X7RA   I128 @BASEBOARD_FAB2_LIB.BASEBOARD_FAB2(SCH_1):PAGE161
  R9R9    1      A RES_0402-0.0,5%,1/16W,CHIP,G21A   I254 @BASEBOARD_FAB2_LIB.BASEBOARD_FAB2(SCH_1):PAGE181
  R1U1    1      A RES_0402-100.0K,1%,1/16W,CHIP,A    I61 @BASEBOARD_FAB2_LIB.BASEBOARD_FAB2(SCH_1):PAGE147
 U25W4  AB4 GPIOO3_TACH3 AST2520A1-GP-GP_ASIC2-GB1-AST2A   I106 @BASEBOARD_FAB2_LIB.BASEBOARD_FAB2(SCH_1):PAGE147

FAN_TACH3_CPU1_D1 @BASEBOARD_FAB2_LIB.BASEBOARD_FAB2(SCH_1):FAN_TACH3_CPU1_D1
  J1B2    5    IO5 CONN6_C74770005_PIP-HDR,C74770A    I32 @BASEBOARD_FAB2_LIB.BASEBOARD_FAB2(SCH_1):PAGE161
 CR1B3    1      C DIODE_SM-SDMK0340L,IC,H71799-0A   I123 @BASEBOARD_FAB2_LIB.BASEBOARD_FAB2(SCH_1):PAGE161

FAN_TACH3_CPU1_D2 @BASEBOARD_FAB2_LIB.BASEBOARD_FAB2(SCH_1):FAN_TACH3_CPU1_D2
 CR1B3    2      A DIODE_SM-SDMK0340L,IC,H71799-0A   I123 @BASEBOARD_FAB2_LIB.BASEBOARD_FAB2(SCH_1):PAGE161
 R1B23    2      B RES_0402-100.0,1%,1/16W,CHIP,GA   I124 @BASEBOARD_FAB2_LIB.BASEBOARD_FAB2(SCH_1):PAGE161

FAN_TACH3_R @BASEBOARD_FAB2_LIB.BASEBOARD_FAB2(SCH_1):FAN_TACH3_R
  J1F1   A4  GNDA4 CONN76_H22707001_THMT1-CONN,H2A   I111 @BASEBOARD_FAB2_LIB.BASEBOARD_FAB2(SCH_1):PAGE181
  R9R9    2      B RES_0402-0.0,5%,1/16W,CHIP,G21A   I254 @BASEBOARD_FAB2_LIB.BASEBOARD_FAB2(SCH_1):PAGE181
 R1C10    2      B RES_0402-0.0,5%,1/16W,EMPTY,G2A   I101 @BASEBOARD_FAB2_LIB.BASEBOARD_FAB2(SCH_1):PAGE182

FM_100M_N @BASEBOARD_FAB2_LIB.BASEBOARD_FAB2(SCH_1):FM_100M_N
 EU4D2    4 100M_133M_N NB3W1200L_LCC-IC,H13585-001     I1 @BASEBOARD_FAB2_LIB.BASEBOARD_FAB2(SCH_1):PAGE102
 R4D40    2      B RES_0402-4.75K,1%,1/16W,CHIP,GA    I45 @BASEBOARD_FAB2_LIB.BASEBOARD_FAB2(SCH_1):PAGE102
 R6P23    1      A RES_0402-4.75K,1%,1/16W,EMPTY,A    I46 @BASEBOARD_FAB2_LIB.BASEBOARD_FAB2(SCH_1):PAGE102

FM_10GBE_LOM_DISABLE_N @BASEBOARD_FAB2_LIB.BASEBOARD_FAB2(SCH_1):FM_10GBE_LOM_DISABLE_N
 R8C23    2      B RES_0402-0.0,5%,1/16W,EMPTY,G2A   I125 @BASEBOARD_FAB2_LIB.BASEBOARD_FAB2(SCH_1):PAGE118
  U7C1 BY21 GPP_I9_LAN_DIS_N LBG_CORE_QAT_EXT_D_BGA1-IC,H91A   I147 @BASEBOARD_FAB2_LIB.BASEBOARD_FAB2(SCH_1):PAGE120

FM_156M_CPU0_BRD_OSC_EN @BASEBOARD_FAB2_LIB.BASEBOARD_FAB2(SCH_1):FM_156M_CPU0_BRD_OSC_EN
 R8D43    1      A RES_0402-0.0,5%,1/16W,CHIP,G21A    I93 @BASEBOARD_FAB2_LIB.BASEBOARD_FAB2(SCH_1):PAGE104
  U8D7  T10  PB18B LCMXO2_A_256BGA-IC,H63395-001   I179 @BASEBOARD_FAB2_LIB.BASEBOARD_FAB2(SCH_1):PAGE190

FM_156M_CPU1_BRD_OSC_EN @BASEBOARD_FAB2_LIB.BASEBOARD_FAB2(SCH_1):FM_156M_CPU1_BRD_OSC_EN
 R7D36    1      A RES_0402-0.0,5%,1/16W,CHIP,G21A    I96 @BASEBOARD_FAB2_LIB.BASEBOARD_FAB2(SCH_1):PAGE104
  U8D7   N8  PB12C LCMXO2_A_256BGA-IC,H63395-001   I179 @BASEBOARD_FAB2_LIB.BASEBOARD_FAB2(SCH_1):PAGE190

FM_1GB_LOM_DISABLE_N @BASEBOARD_FAB2_LIB.BASEBOARD_FAB2(SCH_1):FM_1GB_LOM_DISABLE_N
 R8C24    2      B RES_0402-0.0,5%,1/16W,CHIP,G21A   I120 @BASEBOARD_FAB2_LIB.BASEBOARD_FAB2(SCH_1):PAGE118
 EU9E1   28 DEV_OFF_N SPRINGVILLE_SM1-IC,G47144-004    I72 @BASEBOARD_FAB2_LIB.BASEBOARD_FAB2(SCH_1):PAGE139

FM_ADC128_A0 @BASEBOARD_FAB2_LIB.BASEBOARD_FAB2(SCH_1):FM_ADC128_A0
 EU9G1    7     A0 ADC128D818_SM-IC,H63642-001    I52 @BASEBOARD_FAB2_LIB.BASEBOARD_FAB2(SCH_1):PAGE165
 R1U45    1      A RES_0402-4.75K,1%,1/16W,CHIP,GA    I55 @BASEBOARD_FAB2_LIB.BASEBOARD_FAB2(SCH_1):PAGE165
 R9G23    2      B RES_0402-4.75K,1%,1/16W,EMPTY,A    I57 @BASEBOARD_FAB2_LIB.BASEBOARD_FAB2(SCH_1):PAGE165

FM_ADC128_A1 @BASEBOARD_FAB2_LIB.BASEBOARD_FAB2(SCH_1):FM_ADC128_A1
 EU9G1    8     A1 ADC128D818_SM-IC,H63642-001    I52 @BASEBOARD_FAB2_LIB.BASEBOARD_FAB2(SCH_1):PAGE165
 R1U48    1      A RES_0402-4.75K,1%,1/16W,CHIP,GA    I56 @BASEBOARD_FAB2_LIB.BASEBOARD_FAB2(SCH_1):PAGE165
 R9G25    2      B RES_0402-4.75K,1%,1/16W,EMPTY,A    I58 @BASEBOARD_FAB2_LIB.BASEBOARD_FAB2(SCH_1):PAGE165

FM_ADR_COMPLETE @BASEBOARD_FAB2_LIB.BASEBOARD_FAB2(SCH_1):FM_ADR_COMPLETE
  R4T2    1      A RES_0402-0.0,5%,1/16W,EMPTY,G2A     I1 @BASEBOARD_FAB2_LIB.BASEBOARD_FAB2(SCH_1):PAGE89
 R2N26    1      A RES_0402-33.2,1%,1/16W,CHIP,G2A   I219 @BASEBOARD_FAB2_LIB.BASEBOARD_FAB2(SCH_1):PAGE120
  U8D7   C8 PT17A_PCLKT0_1 LCMXO2_A_256BGA-IC,H63395-001    I59 @BASEBOARD_FAB2_LIB.BASEBOARD_FAB2(SCH_1):PAGE191

FM_ADR_COMPLETE_ABC_N @BASEBOARD_FAB2_LIB.BASEBOARD_FAB2(SCH_1):FM_ADR_COMPLETE_ABC_N
  J4G1  230 SAVE_N_NC SCONN288_H44441004_PIP-SCONN,HA     I1 @BASEBOARD_FAB2_LIB.BASEBOARD_FAB2(SCH_1):PAGE43
  J6T1  230 SAVE_N_NC SCONN288_H44441003_PIP-SCONN,HA    I13 @BASEBOARD_FAB2_LIB.BASEBOARD_FAB2(SCH_1):PAGE44
  J4G2  230 SAVE_N_NC SCONN288_H44441004_PIP-SCONN,HA   I111 @BASEBOARD_FAB2_LIB.BASEBOARD_FAB2(SCH_1):PAGE45
  J6U1  230 SAVE_N_NC SCONN288_H44441003_PIP-SCONN,HA    I14 @BASEBOARD_FAB2_LIB.BASEBOARD_FAB2(SCH_1):PAGE46
  J4G3  230 SAVE_N_NC SCONN288_H44441004_PIP-SCONN,HA   I111 @BASEBOARD_FAB2_LIB.BASEBOARD_FAB2(SCH_1):PAGE47
  J6U2  230 SAVE_N_NC SCONN288_H44441003_PIP-SCONN,HA   I111 @BASEBOARD_FAB2_LIB.BASEBOARD_FAB2(SCH_1):PAGE48
  R6F4    2      B RES_0402-49.9,1%,1/16W,CHIP,G2A     I3 @BASEBOARD_FAB2_LIB.BASEBOARD_FAB2(SCH_1):PAGE89

FM_ADR_COMPLETE_DEF_N @BASEBOARD_FAB2_LIB.BASEBOARD_FAB2(SCH_1):FM_ADR_COMPLETE_DEF_N
  J4B1  230 SAVE_N_NC SCONN288_H44441004_PIP-SCONN,HA   I111 @BASEBOARD_FAB2_LIB.BASEBOARD_FAB2(SCH_1):PAGE49
  J6M1  230 SAVE_N_NC SCONN288_H44441003_PIP-SCONN,HA   I158 @BASEBOARD_FAB2_LIB.BASEBOARD_FAB2(SCH_1):PAGE50
  J4A2  230 SAVE_N_NC SCONN288_H44441004_PIP-SCONN,HA   I111 @BASEBOARD_FAB2_LIB.BASEBOARD_FAB2(SCH_1):PAGE51
  J6L2  230 SAVE_N_NC SCONN288_H44441003_PIP-SCONN,HA    I12 @BASEBOARD_FAB2_LIB.BASEBOARD_FAB2(SCH_1):PAGE52
  J4A1  230 SAVE_N_NC SCONN288_H44441004_PIP-SCONN,HA   I111 @BASEBOARD_FAB2_LIB.BASEBOARD_FAB2(SCH_1):PAGE53
  J6L1  230 SAVE_N_NC SCONN288_H44441003_PIP-SCONN,HA   I111 @BASEBOARD_FAB2_LIB.BASEBOARD_FAB2(SCH_1):PAGE54
  R6F1    2      B RES_0402-49.9,1%,1/16W,CHIP,G2A     I4 @BASEBOARD_FAB2_LIB.BASEBOARD_FAB2(SCH_1):PAGE89

FM_ADR_COMPLETE_DLY @BASEBOARD_FAB2_LIB.BASEBOARD_FAB2(SCH_1):FM_ADR_COMPLETE_DLY
  R4T1    1      A RES_0402-0.0,5%,1/16W,CHIP,G21A     I2 @BASEBOARD_FAB2_LIB.BASEBOARD_FAB2(SCH_1):PAGE89
  U8D7  B16   PR1D LCMXO2_A_256BGA-IC,H63395-001    I59 @BASEBOARD_FAB2_LIB.BASEBOARD_FAB2(SCH_1):PAGE191

FM_ADR_COMPLETE_GHJ_N @BASEBOARD_FAB2_LIB.BASEBOARD_FAB2(SCH_1):FM_ADR_COMPLETE_GHJ_N
  J1G1  230 SAVE_N_NC SCONN288_H44441004_PIP-SCONN,HA   I111 @BASEBOARD_FAB2_LIB.BASEBOARD_FAB2(SCH_1):PAGE77
  J9T1  230 SAVE_N_NC SCONN288_H44441003_PIP-SCONN,HA    I13 @BASEBOARD_FAB2_LIB.BASEBOARD_FAB2(SCH_1):PAGE78
  J1G2  230 SAVE_N_NC SCONN288_H44441004_PIP-SCONN,HA   I111 @BASEBOARD_FAB2_LIB.BASEBOARD_FAB2(SCH_1):PAGE79
  J9U1  230 SAVE_N_NC SCONN288_H44441003_PIP-SCONN,HA    I24 @BASEBOARD_FAB2_LIB.BASEBOARD_FAB2(SCH_1):PAGE80
  J1G3  230 SAVE_N_NC SCONN288_H44441004_PIP-SCONN,HA   I186 @BASEBOARD_FAB2_LIB.BASEBOARD_FAB2(SCH_1):PAGE81
  J9U2  230 SAVE_N_NC SCONN288_H44441003_PIP-SCONN,HA   I187 @BASEBOARD_FAB2_LIB.BASEBOARD_FAB2(SCH_1):PAGE82
  R6F5    2      B RES_0402-49.9,1%,1/16W,CHIP,G2A     I5 @BASEBOARD_FAB2_LIB.BASEBOARD_FAB2(SCH_1):PAGE89

FM_ADR_COMPLETE_KLM_N @BASEBOARD_FAB2_LIB.BASEBOARD_FAB2(SCH_1):FM_ADR_COMPLETE_KLM_N
  J1B1  230 SAVE_N_NC SCONN288_H44441004_PIP-SCONN,HA   I111 @BASEBOARD_FAB2_LIB.BASEBOARD_FAB2(SCH_1):PAGE83
  J9M1  230 SAVE_N_NC SCONN288_H44441003_PIP-SCONN,HA    I14 @BASEBOARD_FAB2_LIB.BASEBOARD_FAB2(SCH_1):PAGE84
  J1A2  230 SAVE_N_NC SCONN288_H44441004_PIP-SCONN,HA   I111 @BASEBOARD_FAB2_LIB.BASEBOARD_FAB2(SCH_1):PAGE85
  J9L2  230 SAVE_N_NC SCONN288_H44441003_PIP-SCONN,HA    I12 @BASEBOARD_FAB2_LIB.BASEBOARD_FAB2(SCH_1):PAGE86
  J1A1  230 SAVE_N_NC SCONN288_H44441004_PIP-SCONN,HA   I186 @BASEBOARD_FAB2_LIB.BASEBOARD_FAB2(SCH_1):PAGE87
  J9L1  230 SAVE_N_NC SCONN288_H44441003_PIP-SCONN,HA   I111 @BASEBOARD_FAB2_LIB.BASEBOARD_FAB2(SCH_1):PAGE88
  R6F2    2      B RES_0402-49.9,1%,1/16W,CHIP,G2A     I6 @BASEBOARD_FAB2_LIB.BASEBOARD_FAB2(SCH_1):PAGE89

FM_ADR_COMPLETE_R @BASEBOARD_FAB2_LIB.BASEBOARD_FAB2(SCH_1):FM_ADR_COMPLETE_R
  R4T2    2      B RES_0402-0.0,5%,1/16W,EMPTY,G2A     I1 @BASEBOARD_FAB2_LIB.BASEBOARD_FAB2(SCH_1):PAGE89
  R4T1    2      B RES_0402-0.0,5%,1/16W,CHIP,G21A     I2 @BASEBOARD_FAB2_LIB.BASEBOARD_FAB2(SCH_1):PAGE89
  Q6F1    1   GATE FET_N_SOT23-2N7002,FET,C79254-A    I18 @BASEBOARD_FAB2_LIB.BASEBOARD_FAB2(SCH_1):PAGE89

FM_ADR_COMPLETE_R1 @BASEBOARD_FAB2_LIB.BASEBOARD_FAB2(SCH_1):FM_ADR_COMPLETE_R1
  U7C1  BD9 GPP_G17_ADR_COMPLETE LBG_CORE_QAT_EXT_D_BGA1-IC,H91A   I147 @BASEBOARD_FAB2_LIB.BASEBOARD_FAB2(SCH_1):PAGE120
 R2N26    2      B RES_0402-33.2,1%,1/16W,CHIP,G2A   I219 @BASEBOARD_FAB2_LIB.BASEBOARD_FAB2(SCH_1):PAGE120

FM_ADR_MODE_SEL @BASEBOARD_FAB2_LIB.BASEBOARD_FAB2(SCH_1):FM_ADR_MODE_SEL
  R2M7    2      B RES_0402-33.2,1%,1/16W,CHIP,G2A   I174 @BASEBOARD_FAB2_LIB.BASEBOARD_FAB2(SCH_1):PAGE119
  U8D7   T2   PB3C LCMXO2_A_256BGA-IC,H63395-001   I179 @BASEBOARD_FAB2_LIB.BASEBOARD_FAB2(SCH_1):PAGE190

FM_ADR_MODE_SEL_R @BASEBOARD_FAB2_LIB.BASEBOARD_FAB2(SCH_1):FM_ADR_MODE_SEL_R
  U7C1 CA43 GPP_D19 LBG_CORE_QAT_EXT_D_BGA1-IC,H91A   I115 @BASEBOARD_FAB2_LIB.BASEBOARD_FAB2(SCH_1):PAGE119
  R2M7    1      A RES_0402-33.2,1%,1/16W,CHIP,G2A   I174 @BASEBOARD_FAB2_LIB.BASEBOARD_FAB2(SCH_1):PAGE119

FM_ADR_SMI_GPIO_N @BASEBOARD_FAB2_LIB.BASEBOARD_FAB2(SCH_1):FM_ADR_SMI_GPIO_N
 R2P12    2      B RES_0402-0.0,5%,1/16W,EMPTY,G2A    I23 @BASEBOARD_FAB2_LIB.BASEBOARD_FAB2(SCH_1):PAGE89
  U7C1 BJ48 GPP_E7_CPU_GP1 LBG_CORE_QAT_EXT_D_BGA1-IC,H91A   I147 @BASEBOARD_FAB2_LIB.BASEBOARD_FAB2(SCH_1):PAGE120
 R8E11    2      B RES_0402-0.0,5%,1/16W,EMPTY,G2A   I279 @BASEBOARD_FAB2_LIB.BASEBOARD_FAB2(SCH_1):PAGE156
  R2M2    2      B RES_0402-4.75K,1%,1/16W,CHIP,GA   I346 @BASEBOARD_FAB2_LIB.BASEBOARD_FAB2(SCH_1):PAGE157
  R2R4    2      B RES_0402-0.0,5%,1/16W,CHIP,G21A   I184 @BASEBOARD_FAB2_LIB.BASEBOARD_FAB2(SCH_1):PAGE191

FM_ADR_SMI_GPIO_R_N @BASEBOARD_FAB2_LIB.BASEBOARD_FAB2(SCH_1):FM_ADR_SMI_GPIO_R_N
  U8D7   C4   PT9A LCMXO2_A_256BGA-IC,H63395-001    I59 @BASEBOARD_FAB2_LIB.BASEBOARD_FAB2(SCH_1):PAGE191
  R2R4    1      A RES_0402-0.0,5%,1/16W,CHIP,G21A   I184 @BASEBOARD_FAB2_LIB.BASEBOARD_FAB2(SCH_1):PAGE191

FM_ALL_WAKE_N @BASEBOARD_FAB2_LIB.BASEBOARD_FAB2(SCH_1):FM_ALL_WAKE_N
  U8E4    2      A TTL1G126_A_SOT-74HC1G126,IC,A7B     I1 @BASEBOARD_FAB2_LIB.BASEBOARD_FAB2(SCH_1):PAGE142
 R8E29    2      B RES_0402-0.0,5%,1/16W,EMPTY,G2A    I18 @BASEBOARD_FAB2_LIB.BASEBOARD_FAB2(SCH_1):PAGE142
 R8E30    2      B RES_0402-10.0K,1%,1/16W,CHIP,GA    I23 @BASEBOARD_FAB2_LIB.BASEBOARD_FAB2(SCH_1):PAGE142
 R8E26    2      B RES_0402-0.0,5%,1/16W,CHIP,G21A    I30 @BASEBOARD_FAB2_LIB.BASEBOARD_FAB2(SCH_1):PAGE142
 R8E28    2      B RES_0402-0.0,5%,1/16W,CHIP,G21A    I31 @BASEBOARD_FAB2_LIB.BASEBOARD_FAB2(SCH_1):PAGE142
 R8E27    2      B RES_0402-0.0,5%,1/16W,CHIP,G21A    I32 @BASEBOARD_FAB2_LIB.BASEBOARD_FAB2(SCH_1):PAGE142
 R8E21    2      B RES_0402-0.0,5%,1/16W,CHIP,G21A    I33 @BASEBOARD_FAB2_LIB.BASEBOARD_FAB2(SCH_1):PAGE142

FM_BACKUP_BIOS_SEL_N @BASEBOARD_FAB2_LIB.BASEBOARD_FAB2(SCH_1):FM_BACKUP_BIOS_SEL_N
  U7C1  AW4 GPP_H1_SRCCLKREQ7_N LBG_CORE_QAT_EXT_D_BGA1-IC,H91A   I147 @BASEBOARD_FAB2_LIB.BASEBOARD_FAB2(SCH_1):PAGE120
  U2T2    1      A TTL1G32_A_SOT-74LVC1G32,IC,E60B   I100 @BASEBOARD_FAB2_LIB.BASEBOARD_FAB2(SCH_1):PAGE154
  Q8F1    1   GATE FET_N_SOT23LF-2N7002,FET,C7925A   I126 @BASEBOARD_FAB2_LIB.BASEBOARD_FAB2(SCH_1):PAGE154
  R2T6    2      B RES_0402-4.75K,1%,1/16W,CHIP,GA   I127 @BASEBOARD_FAB2_LIB.BASEBOARD_FAB2(SCH_1):PAGE154
 U25W4   W3 GPION4_PWM4_VPIG4 AST2520A1-GP-GP_ASIC2-GB1-AST2A   I106 @BASEBOARD_FAB2_LIB.BASEBOARD_FAB2(SCH_1):PAGE147

FM_BATTERY_SENSE_EN @BASEBOARD_FAB2_LIB.BASEBOARD_FAB2(SCH_1):FM_BATTERY_SENSE_EN
  Q9G1    5 GATE<0> FET_N_DUAL_SMLF-NTJD4001N,FET,A   I157 @BASEBOARD_FAB2_LIB.BASEBOARD_FAB2(SCH_1):PAGE169
  Q9G1    6 DRAIN<0> FET_N_DUAL_SMLF-NTJD4001N,FET,A   I162 @BASEBOARD_FAB2_LIB.BASEBOARD_FAB2(SCH_1):PAGE169
 R1U49    2      B RES_0402-2.7K,1%,1/16W,CHIP,G2A   I163 @BASEBOARD_FAB2_LIB.BASEBOARD_FAB2(SCH_1):PAGE169

FM_BATTERY_SENSE_EN_N @BASEBOARD_FAB2_LIB.BASEBOARD_FAB2(SCH_1):FM_BATTERY_SENSE_EN_N
  U7C1   H9   GPD7 LBG_CORE_QAT_EXT_D_BGA1-IC,H91A    I73 @BASEBOARD_FAB2_LIB.BASEBOARD_FAB2(SCH_1):PAGE118
  Q9G1    2 GATE<0> FET_N_DUAL_SMLF-NTJD4001N,FET,A   I162 @BASEBOARD_FAB2_LIB.BASEBOARD_FAB2(SCH_1):PAGE169
 R9G35    2      B RES_0402-2.7K,1%,1/16W,CHIP,G2A   I164 @BASEBOARD_FAB2_LIB.BASEBOARD_FAB2(SCH_1):PAGE169
 U25W4  G17 GPIOF6_TXD4_LHSIRQ# AST2520A1-GP-GP_ASIC2-GB1-AST2A   I117 @BASEBOARD_FAB2_LIB.BASEBOARD_FAB2(SCH_1):PAGE145

FM_BB_BMC_MP_GPIO @BASEBOARD_FAB2_LIB.BASEBOARD_FAB2(SCH_1):FM_BB_BMC_MP_GPIO
  U7C1 BW39 GPP_C19 LBG_CORE_QAT_EXT_D_BGA1-IC,H91A   I115 @BASEBOARD_FAB2_LIB.BASEBOARD_FAB2(SCH_1):PAGE119
  J1C1   C4   IOC4 CONN76_H22707001_THMT1-CONN,H2A    I18 @BASEBOARD_FAB2_LIB.BASEBOARD_FAB2(SCH_1):PAGE182
 U25W4  AA2 GPIOM4_NDTR2_VPIB6 AST2520A1-GP-GP_ASIC2-GB1-AST2A   I117 @BASEBOARD_FAB2_LIB.BASEBOARD_FAB2(SCH_1):PAGE145

FM_BEEP_LED_P @BASEBOARD_FAB2_LIB.BASEBOARD_FAB2(SCH_1):FM_BEEP_LED_P
 R1L33    1      A RES_0402-221,1.0%,1/16W,CHIP,GA    I45 @BASEBOARD_FAB2_LIB.BASEBOARD_FAB2(SCH_1):PAGE175
 DS9A3    2      A LED_1NCLF-YELLOW,IC,C96565-003    I67 @BASEBOARD_FAB2_LIB.BASEBOARD_FAB2(SCH_1):PAGE175

FM_BIOS_MRC_DEBUG_MSG_DIS_N @BASEBOARD_FAB2_LIB.BASEBOARD_FAB2(SCH_1):FM_BIOS_MRC_DEBUG_MSG_DIS_N
  U7C1 BV25 GPP_I10 LBG_CORE_QAT_EXT_D_BGA1-IC,H91A   I147 @BASEBOARD_FAB2_LIB.BASEBOARD_FAB2(SCH_1):PAGE120
 U25W4  E15 GPIOI1_SYSCK AST2520A1-GP-GP_ASIC2-GB1-AST2A    I95 @BASEBOARD_FAB2_LIB.BASEBOARD_FAB2(SCH_1):PAGE144

FM_BIOS_POST_CMPLT_N @BASEBOARD_FAB2_LIB.BASEBOARD_FAB2(SCH_1):FM_BIOS_POST_CMPLT_N
  U7C1 BJ22 GPP_B20 LBG_CORE_QAT_EXT_D_BGA1-IC,H91A   I115 @BASEBOARD_FAB2_LIB.BASEBOARD_FAB2(SCH_1):PAGE119
  U7C1 BY33 GPP_C21 LBG_CORE_QAT_EXT_D_BGA1-IC,H91A   I115 @BASEBOARD_FAB2_LIB.BASEBOARD_FAB2(SCH_1):PAGE119
  R8C6    2      B RES_0402-4.75K,1%,1/16W,CHIP,GA   I303 @BASEBOARD_FAB2_LIB.BASEBOARD_FAB2(SCH_1):PAGE133
 U25W4  P19 GPIOAA7_VPOR9_NORD7_SALT14 AST2520A1-GP-GP_ASIC2-GB1-AST2A   I104 @BASEBOARD_FAB2_LIB.BASEBOARD_FAB2(SCH_1):PAGE146

FM_BIOS_PREFRB2_GOOD @BASEBOARD_FAB2_LIB.BASEBOARD_FAB2(SCH_1):FM_BIOS_PREFRB2_GOOD
  U7C1 BK20 GPP_B19 LBG_CORE_QAT_EXT_D_BGA1-IC,H91A   I115 @BASEBOARD_FAB2_LIB.BASEBOARD_FAB2(SCH_1):PAGE119
 R2N13    1      A RES_0402-10.0K,1%,1/16W,CHIP,GA    I75 @BASEBOARD_FAB2_LIB.BASEBOARD_FAB2(SCH_1):PAGE147
 U25W4   V3 GPION2_PWM2_VPIG2 AST2520A1-GP-GP_ASIC2-GB1-AST2A   I106 @BASEBOARD_FAB2_LIB.BASEBOARD_FAB2(SCH_1):PAGE147

FM_BIOS_SMI_ACTIVE_N @BASEBOARD_FAB2_LIB.BASEBOARD_FAB2(SCH_1):FM_BIOS_SMI_ACTIVE_N
  U7C1 BE15 GPP_G19_SMI_N LBG_CORE_QAT_EXT_D_BGA1-IC,H91A   I147 @BASEBOARD_FAB2_LIB.BASEBOARD_FAB2(SCH_1):PAGE120
  U7C1  BA2 GPP_H21_SSATAXPCIE3_SSATAGP3 LBG_CORE_QAT_EXT_D_BGA1-IC,H91A   I147 @BASEBOARD_FAB2_LIB.BASEBOARD_FAB2(SCH_1):PAGE120
 R2N32    2      B RES_0402-4.75K,1%,1/16W,CHIP,GA   I341 @BASEBOARD_FAB2_LIB.BASEBOARD_FAB2(SCH_1):PAGE133
 U25W4  E14 GPIOG7_SGPS2I1_SALT4 AST2520A1-GP-GP_ASIC2-GB1-AST2A   I117 @BASEBOARD_FAB2_LIB.BASEBOARD_FAB2(SCH_1):PAGE145

FM_BIOS_SPI_BMC_CTRL @BASEBOARD_FAB2_LIB.BASEBOARD_FAB2(SCH_1):FM_BIOS_SPI_BMC_CTRL
  U8F1    1      S PI3B3257A_TSSOPLF-IC,E16801-001    I74 @BASEBOARD_FAB2_LIB.BASEBOARD_FAB2(SCH_1):PAGE154
  U2T1    1      S PI3B3257A_TSSOPLF-IC,E16801-001    I75 @BASEBOARD_FAB2_LIB.BASEBOARD_FAB2(SCH_1):PAGE154
  R1U6    1      A RES_0402-10.0K,1%,1/16W,CHIP,GA   I128 @BASEBOARD_FAB2_LIB.BASEBOARD_FAB2(SCH_1):PAGE154
 U25W4  Y20 GPIOZ0_VPOG2_NORA0_SIOPBI# AST2520A1-GP-GP_ASIC2-GB1-AST2A   I104 @BASEBOARD_FAB2_LIB.BASEBOARD_FAB2(SCH_1):PAGE146

FM_BIOS_TOP_SWAP @BASEBOARD_FAB2_LIB.BASEBOARD_FAB2(SCH_1):FM_BIOS_TOP_SWAP
  U7C1 AP15 GPP_F17_USB2_OC6_N LBG_CORE_QAT_EXT_D_BGA1-IC,H91A   I147 @BASEBOARD_FAB2_LIB.BASEBOARD_FAB2(SCH_1):PAGE120
  U8E3    2      A TTL1G126_A_SOT-74HC1G126,IC,A7B   I130 @BASEBOARD_FAB2_LIB.BASEBOARD_FAB2(SCH_1):PAGE136
 R8E16    1      A RES_0402-20.0K,1%,1/16W,CHIP,GA   I140 @BASEBOARD_FAB2_LIB.BASEBOARD_FAB2(SCH_1):PAGE136
  J7G3   10   IO10 CONN12_C73564003_PIP-CONN,C735A   I174 @BASEBOARD_FAB2_LIB.BASEBOARD_FAB2(SCH_1):PAGE136
 R8E19    2      B RES_0402-4.75K,1%,1/16W,EMPTY,A   I361 @BASEBOARD_FAB2_LIB.BASEBOARD_FAB2(SCH_1):PAGE157
 U25W4   U2 GPIOL3_NRI1_VPIHS AST2520A1-GP-GP_ASIC2-GB1-AST2A   I117 @BASEBOARD_FAB2_LIB.BASEBOARD_FAB2(SCH_1):PAGE145

FM_BIOS_TOP_SWAP_SPKR @BASEBOARD_FAB2_LIB.BASEBOARD_FAB2(SCH_1):FM_BIOS_TOP_SWAP_SPKR
  U7C1 BH13 GPP_B14_SPKR LBG_CORE_QAT_EXT_D_BGA1-IC,H91A   I115 @BASEBOARD_FAB2_LIB.BASEBOARD_FAB2(SCH_1):PAGE119
 R8E20    2      B RES_0402-33.2,1%,1/16W,CHIP,G2A   I126 @BASEBOARD_FAB2_LIB.BASEBOARD_FAB2(SCH_1):PAGE136
  Q9A3    1   GATE FET_N_SOT23LF-2N7002,FET,C7925A    I49 @BASEBOARD_FAB2_LIB.BASEBOARD_FAB2(SCH_1):PAGE175

FM_BIOS_TOP_SWAP_SPKR_R @BASEBOARD_FAB2_LIB.BASEBOARD_FAB2(SCH_1):FM_BIOS_TOP_SWAP_SPKR_R
 R8E20    1      A RES_0402-33.2,1%,1/16W,CHIP,G2A   I126 @BASEBOARD_FAB2_LIB.BASEBOARD_FAB2(SCH_1):PAGE136
  U8E3    4      Y TTL1G126_A_SOT-74HC1G126,IC,A7B   I130 @BASEBOARD_FAB2_LIB.BASEBOARD_FAB2(SCH_1):PAGE136

FM_BIOS_USB_RECOVERY @BASEBOARD_FAB2_LIB.BASEBOARD_FAB2(SCH_1):FM_BIOS_USB_RECOVERY
  U7C1 AH17 GPP_F5_SATA_DEVSLP3 LBG_CORE_QAT_EXT_D_BGA1-IC,H91A   I147 @BASEBOARD_FAB2_LIB.BASEBOARD_FAB2(SCH_1):PAGE120
 R3T14    1      A RES_0402-10.0K,1%,1/16W,CHIP,GA   I156 @BASEBOARD_FAB2_LIB.BASEBOARD_FAB2(SCH_1):PAGE136
  J7G3    4    IO4 CONN12_C73564003_PIP-CONN,C735A   I174 @BASEBOARD_FAB2_LIB.BASEBOARD_FAB2(SCH_1):PAGE136

FM_BMC_CPLD_GPO @BASEBOARD_FAB2_LIB.BASEBOARD_FAB2(SCH_1):FM_BMC_CPLD_GPO
  U7C1 CA45 GPP_D7 LBG_CORE_QAT_EXT_D_BGA1-IC,H91A   I115 @BASEBOARD_FAB2_LIB.BASEBOARD_FAB2(SCH_1):PAGE119
  R2M5    2      B RES_0402-4.75K,1%,1/16W,CHIP,GA   I348 @BASEBOARD_FAB2_LIB.BASEBOARD_FAB2(SCH_1):PAGE157
  U8D7   R1  PL14C LCMXO2_A_256BGA-IC,H63395-001   I179 @BASEBOARD_FAB2_LIB.BASEBOARD_FAB2(SCH_1):PAGE190
 U25W4  B16 GPIOI2_SYSMOSI AST2520A1-GP-GP_ASIC2-GB1-AST2A    I95 @BASEBOARD_FAB2_LIB.BASEBOARD_FAB2(SCH_1):PAGE144

FM_BMC_CPLD_MP_RST_N @BASEBOARD_FAB2_LIB.BASEBOARD_FAB2(SCH_1):FM_BMC_CPLD_MP_RST_N
  U7C1  A15   GPD9 LBG_CORE_QAT_EXT_D_BGA1-IC,H91A    I73 @BASEBOARD_FAB2_LIB.BASEBOARD_FAB2(SCH_1):PAGE118
  R1L7    2      B RES_0402-4.75K,1%,1/16W,CHIP,GA   I382 @BASEBOARD_FAB2_LIB.BASEBOARD_FAB2(SCH_1):PAGE157
  U8D7   R4   PB6D LCMXO2_A_256BGA-IC,H63395-001   I179 @BASEBOARD_FAB2_LIB.BASEBOARD_FAB2(SCH_1):PAGE190
 U25W4   P5 GPIOM5_NRTS2_VPIB7 AST2520A1-GP-GP_ASIC2-GB1-AST2A   I117 @BASEBOARD_FAB2_LIB.BASEBOARD_FAB2(SCH_1):PAGE145

FM_BMC_DISABLE @BASEBOARD_FAB2_LIB.BASEBOARD_FAB2(SCH_1):FM_BMC_DISABLE
  J9G1    5    IO5 CONN12_C73564003_PIP-CONN,C735A   I128 @BASEBOARD_FAB2_LIB.BASEBOARD_FAB2(SCH_1):PAGE137

FM_BMC_ENABLE_N @BASEBOARD_FAB2_LIB.BASEBOARD_FAB2(SCH_1):FM_BMC_ENABLE_N
  U7C1 BM38 GPP_D5 LBG_CORE_QAT_EXT_D_BGA1-IC,H91A   I115 @BASEBOARD_FAB2_LIB.BASEBOARD_FAB2(SCH_1):PAGE119
 R9E14    2      B RES_0402-0.0,5%,1/16W,CHIP,G21A   I379 @BASEBOARD_FAB2_LIB.BASEBOARD_FAB2(SCH_1):PAGE157

FM_BMC_FAULT_LED @BASEBOARD_FAB2_LIB.BASEBOARD_FAB2(SCH_1):FM_BMC_FAULT_LED
  Q9F1    5 GATE<0> FET_N_DUAL_SMLF-NTJD4001N,FET,A    I79 @BASEBOARD_FAB2_LIB.BASEBOARD_FAB2(SCH_1):PAGE177
  Q9F1    6 DRAIN<0> FET_N_DUAL_SMLF-NTJD4001N,FET,A    I80 @BASEBOARD_FAB2_LIB.BASEBOARD_FAB2(SCH_1):PAGE177
 R9F52    2      B RES_0402-4.75K,1%,1/16W,CHIP,GA    I82 @BASEBOARD_FAB2_LIB.BASEBOARD_FAB2(SCH_1):PAGE177

FM_BMC_FAULT_LED_N @BASEBOARD_FAB2_LIB.BASEBOARD_FAB2(SCH_1):FM_BMC_FAULT_LED_N
  U7C1 BR38 GPP_D8 LBG_CORE_QAT_EXT_D_BGA1-IC,H91A   I115 @BASEBOARD_FAB2_LIB.BASEBOARD_FAB2(SCH_1):PAGE119
 R9F30    2      B RES_0402-4.75K,1%,1/16W,CHIP,GA    I76 @BASEBOARD_FAB2_LIB.BASEBOARD_FAB2(SCH_1):PAGE177
  Q9F1    2 GATE<0> FET_N_DUAL_SMLF-NTJD4001N,FET,A    I80 @BASEBOARD_FAB2_LIB.BASEBOARD_FAB2(SCH_1):PAGE177
 U25W4  D14 GPIOA1_MAC2LINK AST2520A1-GP-GP_ASIC2-GB1-AST2A   I117 @BASEBOARD_FAB2_LIB.BASEBOARD_FAB2(SCH_1):PAGE145

FM_BMC_HEARTBEAT_N @BASEBOARD_FAB2_LIB.BASEBOARD_FAB2(SCH_1):FM_BMC_HEARTBEAT_N
  U7C1 CA48 GPP_D20 LBG_CORE_QAT_EXT_D_BGA1-IC,H91A   I115 @BASEBOARD_FAB2_LIB.BASEBOARD_FAB2(SCH_1):PAGE119
  Q9E1    2 GATE<0> FET_N_DUAL_SMLF-NTJD4001N,FET,A   I113 @BASEBOARD_FAB2_LIB.BASEBOARD_FAB2(SCH_1):PAGE149
 R8B25    2      B RES_0402-4.75K,1%,1/16W,CHIP,GA   I156 @BASEBOARD_FAB2_LIB.BASEBOARD_FAB2(SCH_1):PAGE149
 U25W4  B14 GPIOA0_MAC1LINK AST2520A1-GP-GP_ASIC2-GB1-AST2A   I117 @BASEBOARD_FAB2_LIB.BASEBOARD_FAB2(SCH_1):PAGE145

FM_BMC_NMI_N @BASEBOARD_FAB2_LIB.BASEBOARD_FAB2(SCH_1):FM_BMC_NMI_N
  U7C1  BF3 GPP_H20_SSATAXPCIE2_SSATAGP2 LBG_CORE_QAT_EXT_D_BGA1-IC,H91A   I147 @BASEBOARD_FAB2_LIB.BASEBOARD_FAB2(SCH_1):PAGE120
 R2N27    2      B RES_0402-4.75K,1%,1/16W,CHIP,GA    I97 @BASEBOARD_FAB2_LIB.BASEBOARD_FAB2(SCH_1):PAGE157
 R2N25    2      B RES_0402-51.1,1.0%,1/16W,CHIP,A   I302 @BASEBOARD_FAB2_LIB.BASEBOARD_FAB2(SCH_1):PAGE157
R25W83    1      A RES_0402-0.0,5%,1/16W,CHIP,G21A    I26 @BASEBOARD_FAB2_LIB.BASEBOARD_FAB2(SCH_1):PAGE146

FM_BMC_NMI_N_R @BASEBOARD_FAB2_LIB.BASEBOARD_FAB2(SCH_1):FM_BMC_NMI_N_R
R25W83    2      B RES_0402-0.0,5%,1/16W,CHIP,G21A    I26 @BASEBOARD_FAB2_LIB.BASEBOARD_FAB2(SCH_1):PAGE146
R25W84    2      B RES_0402-0.0,5%,1/16W,CHIP,G21A    I27 @BASEBOARD_FAB2_LIB.BASEBOARD_FAB2(SCH_1):PAGE146
 U25W4 AB20 GPIOZ1_VPOG3_NORA1_SIOPWRGD AST2520A1-GP-GP_ASIC2-GB1-AST2A   I104 @BASEBOARD_FAB2_LIB.BASEBOARD_FAB2(SCH_1):PAGE146

FM_BMC_ONCTL_N @BASEBOARD_FAB2_LIB.BASEBOARD_FAB2(SCH_1):FM_BMC_ONCTL_N
  U8D7   C7  PT13B LCMXO2_A_256BGA-IC,H63395-001    I59 @BASEBOARD_FAB2_LIB.BASEBOARD_FAB2(SCH_1):PAGE191
 R1T15    1      A RES_0402-0.0,5%,1/16W,EMPTY,G2A   I100 @BASEBOARD_FAB2_LIB.BASEBOARD_FAB2(SCH_1):PAGE145

FM_BMC_ONCTL_R_N @BASEBOARD_FAB2_LIB.BASEBOARD_FAB2(SCH_1):FM_BMC_ONCTL_R_N
 R1T15    2      B RES_0402-0.0,5%,1/16W,EMPTY,G2A   I100 @BASEBOARD_FAB2_LIB.BASEBOARD_FAB2(SCH_1):PAGE145
 R1T23    1      A RES_0402-0.0,5%,1/16W,EMPTY,G2A   I101 @BASEBOARD_FAB2_LIB.BASEBOARD_FAB2(SCH_1):PAGE145
 U25W4  P21 GPIOY3_SIOONCTRL# AST2520A1-GP-GP_ASIC2-GB1-AST2A   I117 @BASEBOARD_FAB2_LIB.BASEBOARD_FAB2(SCH_1):PAGE145

FM_BMC_PWRBTN_OUT_N @BASEBOARD_FAB2_LIB.BASEBOARD_FAB2(SCH_1):FM_BMC_PWRBTN_OUT_N
  U8F3    3     2A TTL2G07_SOT23LF-74LVC2G07,IC,DB   I201 @BASEBOARD_FAB2_LIB.BASEBOARD_FAB2(SCH_1):PAGE156
 R2T34    2      B RES_0402-4.75K,1%,1/16W,CHIP,GA   I206 @BASEBOARD_FAB2_LIB.BASEBOARD_FAB2(SCH_1):PAGE156
 U25W4  F17 GPIOE3_NRI3 AST2520A1-GP-GP_ASIC2-GB1-AST2A   I117 @BASEBOARD_FAB2_LIB.BASEBOARD_FAB2(SCH_1):PAGE145

FM_BMC_READY_N @BASEBOARD_FAB2_LIB.BASEBOARD_FAB2(SCH_1):FM_BMC_READY_N
  U7C1   V1 GPP_A23 LBG_CORE_QAT_EXT_D_BGA1-IC,H91A   I115 @BASEBOARD_FAB2_LIB.BASEBOARD_FAB2(SCH_1):PAGE119
  U7C1 AH13 GPP_F4_SATAXPCIE7_SATAGP7 LBG_CORE_QAT_EXT_D_BGA1-IC,H91A   I147 @BASEBOARD_FAB2_LIB.BASEBOARD_FAB2(SCH_1):PAGE120
  R7D6    2      B RES_0402-4.75K,1%,1/16W,CHIP,GA   I306 @BASEBOARD_FAB2_LIB.BASEBOARD_FAB2(SCH_1):PAGE133
  R1F9    1      A RES_0402-0.0,5%,1/16W,EMPTY,G2A   I107 @BASEBOARD_FAB2_LIB.BASEBOARD_FAB2(SCH_1):PAGE182
 U25W4  U19 GPIOS1_VPOB3_BMCINT AST2520A1-GP-GP_ASIC2-GB1-AST2A   I104 @BASEBOARD_FAB2_LIB.BASEBOARD_FAB2(SCH_1):PAGE146

FM_BMC_SYS_THROTTLE_R_N @BASEBOARD_FAB2_LIB.BASEBOARD_FAB2(SCH_1):FM_BMC_SYS_THROTTLE_R_N
 R2T41    2      B RES_0402-22.1,1.0%,1/16W,CHIP,A    I96 @BASEBOARD_FAB2_LIB.BASEBOARD_FAB2(SCH_1):PAGE146
 U25W4 AB21 GPIOZ2_VPOG4_NORA2_SIOPBO# AST2520A1-GP-GP_ASIC2-GB1-AST2A   I104 @BASEBOARD_FAB2_LIB.BASEBOARD_FAB2(SCH_1):PAGE146

FM_BOARD_REV_ID0 @BASEBOARD_FAB2_LIB.BASEBOARD_FAB2(SCH_1):FM_BOARD_REV_ID0
  U7C1 CA30 GPP_C12 LBG_CORE_QAT_EXT_D_BGA1-IC,H91A   I115 @BASEBOARD_FAB2_LIB.BASEBOARD_FAB2(SCH_1):PAGE119
 R1T10    1      A RES_0402-1.00K,1%,1/16W,EMPTY,A     I5 @BASEBOARD_FAB2_LIB.BASEBOARD_FAB2(SCH_1):PAGE164
  R1T4    2      B RES_0402-2.7K,1%,1/16W,CHIP,G2A    I14 @BASEBOARD_FAB2_LIB.BASEBOARD_FAB2(SCH_1):PAGE164
 U25W4  D20 GPIOD3_SD2DAT1 AST2520A1-GP-GP_ASIC2-GB1-AST2A   I117 @BASEBOARD_FAB2_LIB.BASEBOARD_FAB2(SCH_1):PAGE145

FM_BOARD_REV_ID1 @BASEBOARD_FAB2_LIB.BASEBOARD_FAB2(SCH_1):FM_BOARD_REV_ID1
  U7C1 BV38 GPP_C13 LBG_CORE_QAT_EXT_D_BGA1-IC,H91A   I115 @BASEBOARD_FAB2_LIB.BASEBOARD_FAB2(SCH_1):PAGE119
 R1T12    1      A RES_0402-1.00K,1%,1/16W,CHIP,GA     I6 @BASEBOARD_FAB2_LIB.BASEBOARD_FAB2(SCH_1):PAGE164
  R1T6    2      B RES_0402-2.7K,1%,1/16W,EMPTY,GA    I13 @BASEBOARD_FAB2_LIB.BASEBOARD_FAB2(SCH_1):PAGE164
 U25W4  D21 GPIOD4_SD2DAT2 AST2520A1-GP-GP_ASIC2-GB1-AST2A   I117 @BASEBOARD_FAB2_LIB.BASEBOARD_FAB2(SCH_1):PAGE145

FM_BOARD_REV_ID2 @BASEBOARD_FAB2_LIB.BASEBOARD_FAB2(SCH_1):FM_BOARD_REV_ID2
  U7C1 BV33 GPP_C11 LBG_CORE_QAT_EXT_D_BGA1-IC,H91A   I115 @BASEBOARD_FAB2_LIB.BASEBOARD_FAB2(SCH_1):PAGE119
 R1T11    1      A RES_0402-1.00K,1%,1/16W,CHIP,GA     I7 @BASEBOARD_FAB2_LIB.BASEBOARD_FAB2(SCH_1):PAGE164
  R1T5    2      B RES_0402-2.7K,1%,1/16W,EMPTY,GA    I11 @BASEBOARD_FAB2_LIB.BASEBOARD_FAB2(SCH_1):PAGE164
 U25W4  E20 GPIOD5_SD2DAT3 AST2520A1-GP-GP_ASIC2-GB1-AST2A   I117 @BASEBOARD_FAB2_LIB.BASEBOARD_FAB2(SCH_1):PAGE145

FM_BOARD_SKU_ID0 @BASEBOARD_FAB2_LIB.BASEBOARD_FAB2(SCH_1):FM_BOARD_SKU_ID0
  U7C1 BD13 GPP_G12 LBG_CORE_QAT_EXT_D_BGA1-IC,H91A   I147 @BASEBOARD_FAB2_LIB.BASEBOARD_FAB2(SCH_1):PAGE120
 R1U18    1      A RES_0402-1.00K,1%,1/16W,CHIP,GA    I19 @BASEBOARD_FAB2_LIB.BASEBOARD_FAB2(SCH_1):PAGE164
 R1U23    2      B RES_0402-2.7K,1%,1/16W,EMPTY,GA    I28 @BASEBOARD_FAB2_LIB.BASEBOARD_FAB2(SCH_1):PAGE164
 U25W4  AA5 GPIOP2_TACH10_VPIR8 AST2520A1-GP-GP_ASIC2-GB1-AST2A   I106 @BASEBOARD_FAB2_LIB.BASEBOARD_FAB2(SCH_1):PAGE147

FM_BOARD_SKU_ID1 @BASEBOARD_FAB2_LIB.BASEBOARD_FAB2(SCH_1):FM_BOARD_SKU_ID1
  U7C1 AY18 GPP_G13 LBG_CORE_QAT_EXT_D_BGA1-IC,H91A   I147 @BASEBOARD_FAB2_LIB.BASEBOARD_FAB2(SCH_1):PAGE120
 R1U16    1      A RES_0402-1.00K,1%,1/16W,EMPTY,A    I20 @BASEBOARD_FAB2_LIB.BASEBOARD_FAB2(SCH_1):PAGE164
 R1U22    2      B RES_0402-2.7K,1%,1/16W,CHIP,G2A    I27 @BASEBOARD_FAB2_LIB.BASEBOARD_FAB2(SCH_1):PAGE164
 U25W4  AB5 GPIOP3_TACH11_VPIR9 AST2520A1-GP-GP_ASIC2-GB1-AST2A   I106 @BASEBOARD_FAB2_LIB.BASEBOARD_FAB2(SCH_1):PAGE147

FM_BOARD_SKU_ID2 @BASEBOARD_FAB2_LIB.BASEBOARD_FAB2(SCH_1):FM_BOARD_SKU_ID2
  U7C1  AV7 GPP_G14 LBG_CORE_QAT_EXT_D_BGA1-IC,H91A   I147 @BASEBOARD_FAB2_LIB.BASEBOARD_FAB2(SCH_1):PAGE120
 R1U17    1      A RES_0402-1.00K,1%,1/16W,CHIP,GA    I21 @BASEBOARD_FAB2_LIB.BASEBOARD_FAB2(SCH_1):PAGE164
 R1U24    2      B RES_0402-2.7K,1%,1/16W,EMPTY,GA    I25 @BASEBOARD_FAB2_LIB.BASEBOARD_FAB2(SCH_1):PAGE164
 U25W4   Y6 GPIOP4_TACH12 AST2520A1-GP-GP_ASIC2-GB1-AST2A   I106 @BASEBOARD_FAB2_LIB.BASEBOARD_FAB2(SCH_1):PAGE147

FM_BOARD_SKU_ID3 @BASEBOARD_FAB2_LIB.BASEBOARD_FAB2(SCH_1):FM_BOARD_SKU_ID3
  U7C1 BE18 GPP_G15 LBG_CORE_QAT_EXT_D_BGA1-IC,H91A   I147 @BASEBOARD_FAB2_LIB.BASEBOARD_FAB2(SCH_1):PAGE120
 R1U15    1      A RES_0402-1.00K,1%,1/16W,EMPTY,A    I22 @BASEBOARD_FAB2_LIB.BASEBOARD_FAB2(SCH_1):PAGE164
 R1U21    2      B RES_0402-2.7K,1%,1/16W,CHIP,G2A    I24 @BASEBOARD_FAB2_LIB.BASEBOARD_FAB2(SCH_1):PAGE164
 U25W4   Y5 GPIOP5_TACH13 AST2520A1-GP-GP_ASIC2-GB1-AST2A   I106 @BASEBOARD_FAB2_LIB.BASEBOARD_FAB2(SCH_1):PAGE147

FM_BOARD_SKU_ID4 @BASEBOARD_FAB2_LIB.BASEBOARD_FAB2(SCH_1):FM_BOARD_SKU_ID4
  U7C1 BD17 GPP_G16 LBG_CORE_QAT_EXT_D_BGA1-IC,H91A   I147 @BASEBOARD_FAB2_LIB.BASEBOARD_FAB2(SCH_1):PAGE120
 R2N17    2      B RES_0402-2.7K,1%,1/16W,EMPTY,GA    I29 @BASEBOARD_FAB2_LIB.BASEBOARD_FAB2(SCH_1):PAGE164
 R2N18    1      A RES_0402-1.00K,1%,1/16W,CHIP,GA    I32 @BASEBOARD_FAB2_LIB.BASEBOARD_FAB2(SCH_1):PAGE164
 U25W4   W6 GPIOP6_TACH14 AST2520A1-GP-GP_ASIC2-GB1-AST2A   I106 @BASEBOARD_FAB2_LIB.BASEBOARD_FAB2(SCH_1):PAGE147

FM_CPLD_ADR_TRIGGER_N @BASEBOARD_FAB2_LIB.BASEBOARD_FAB2(SCH_1):FM_CPLD_ADR_TRIGGER_N
  R2M1    1      A RES_0402-33.2,1%,1/16W,CHIP,G2A   I218 @BASEBOARD_FAB2_LIB.BASEBOARD_FAB2(SCH_1):PAGE120
  U8D7  E14   PR2B LCMXO2_A_256BGA-IC,H63395-001    I59 @BASEBOARD_FAB2_LIB.BASEBOARD_FAB2(SCH_1):PAGE191

FM_CPLD_ADR_TRIGGER_R_N @BASEBOARD_FAB2_LIB.BASEBOARD_FAB2(SCH_1):FM_CPLD_ADR_TRIGGER_R_N
  U7C1 BE52 GPP_E3_CPU_GP0 LBG_CORE_QAT_EXT_D_BGA1-IC,H91A   I147 @BASEBOARD_FAB2_LIB.BASEBOARD_FAB2(SCH_1):PAGE120
  R2M1    2      B RES_0402-33.2,1%,1/16W,CHIP,G2A   I218 @BASEBOARD_FAB2_LIB.BASEBOARD_FAB2(SCH_1):PAGE120

FM_CPLD_BMC_PWRDN_N @BASEBOARD_FAB2_LIB.BASEBOARD_FAB2(SCH_1):FM_CPLD_BMC_PWRDN_N
  U7C1 BW41 GPP_D6 LBG_CORE_QAT_EXT_D_BGA1-IC,H91A   I115 @BASEBOARD_FAB2_LIB.BASEBOARD_FAB2(SCH_1):PAGE119
  R2U4    2      B RES_0402-4.75K,1%,1/16W,CHIP,GA   I367 @BASEBOARD_FAB2_LIB.BASEBOARD_FAB2(SCH_1):PAGE157
  U8D7   N9  PB16D LCMXO2_A_256BGA-IC,H63395-001   I179 @BASEBOARD_FAB2_LIB.BASEBOARD_FAB2(SCH_1):PAGE190
 U25W4  AA3 GPION5_PWM5_VPIG5 AST2520A1-GP-GP_ASIC2-GB1-AST2A   I106 @BASEBOARD_FAB2_LIB.BASEBOARD_FAB2(SCH_1):PAGE147

FM_CPLD_DBG_PWR_EN @BASEBOARD_FAB2_LIB.BASEBOARD_FAB2(SCH_1):FM_CPLD_DBG_PWR_EN
  R1L9    2      B RES_0402-100.0K,1%,1/16W,CHIP,A   I130 @BASEBOARD_FAB2_LIB.BASEBOARD_FAB2(SCH_1):PAGE155
  Q1L2    3 DRAIN<0> FET_N_DUAL_SMLF-NTJD4001N,FET,A   I187 @BASEBOARD_FAB2_LIB.BASEBOARD_FAB2(SCH_1):PAGE155
  Q1L2    2 GATE<0> FET_N_DUAL_SMLF-NTJD4001N,FET,A   I188 @BASEBOARD_FAB2_LIB.BASEBOARD_FAB2(SCH_1):PAGE155

FM_CPLD_DBG_PWR_EN_N @BASEBOARD_FAB2_LIB.BASEBOARD_FAB2(SCH_1):FM_CPLD_DBG_PWR_EN_N
  R1L2    1      A RES_0402-10.0,1%,1/16W,CHIP,G2A   I186 @BASEBOARD_FAB2_LIB.BASEBOARD_FAB2(SCH_1):PAGE155
  U8D7   T8  PB12B LCMXO2_A_256BGA-IC,H63395-001   I179 @BASEBOARD_FAB2_LIB.BASEBOARD_FAB2(SCH_1):PAGE190

FM_CPLD_DBG_PWR_EN_R_N @BASEBOARD_FAB2_LIB.BASEBOARD_FAB2(SCH_1):FM_CPLD_DBG_PWR_EN_R_N
  R1L2    2      B RES_0402-10.0,1%,1/16W,CHIP,G2A   I186 @BASEBOARD_FAB2_LIB.BASEBOARD_FAB2(SCH_1):PAGE155
  Q1L2    5 GATE<0> FET_N_DUAL_SMLF-NTJD4001N,FET,A   I187 @BASEBOARD_FAB2_LIB.BASEBOARD_FAB2(SCH_1):PAGE155

FM_CPLD_UART_CH_LOCK_N @BASEBOARD_FAB2_LIB.BASEBOARD_FAB2(SCH_1):FM_CPLD_UART_CH_LOCK_N
 R7D30    2      B RES_0402-4.75K,1%,1/16W,CHIP,GA   I121 @BASEBOARD_FAB2_LIB.BASEBOARD_FAB2(SCH_1):PAGE135
  J8G2    9    IO9 CONN12_C73564003_PIP-CONN,C735A   I124 @BASEBOARD_FAB2_LIB.BASEBOARD_FAB2(SCH_1):PAGE135
  U8D7   M9  PB18C LCMXO2_A_256BGA-IC,H63395-001   I179 @BASEBOARD_FAB2_LIB.BASEBOARD_FAB2(SCH_1):PAGE190

FM_CPU0_AND_CPU1_MCP_PRES @BASEBOARD_FAB2_LIB.BASEBOARD_FAB2(SCH_1):FM_CPU0_AND_CPU1_MCP_PRES
  U1M6    1   OE_N 74CBTLV1G125_SMLF-IC,C88177-00A   I127 @BASEBOARD_FAB2_LIB.BASEBOARD_FAB2(SCH_1):PAGE113
  U8D7  D11  PT21D LCMXO2_A_256BGA-IC,H63395-001    I59 @BASEBOARD_FAB2_LIB.BASEBOARD_FAB2(SCH_1):PAGE191

FM_CPU0_CD_PRES @BASEBOARD_FAB2_LIB.BASEBOARD_FAB2(SCH_1):FM_CPU0_CD_PRES
  U2M1    6      S NC7SB3157_SMLF-IC,C99406-001   I255 @BASEBOARD_FAB2_LIB.BASEBOARD_FAB2(SCH_1):PAGE113
  U8D7  C11  PT21B LCMXO2_A_256BGA-IC,H63395-001    I59 @BASEBOARD_FAB2_LIB.BASEBOARD_FAB2(SCH_1):PAGE191

FM_CPU0_FIVR_FAULT_LVT3 @BASEBOARD_FAB2_LIB.BASEBOARD_FAB2(SCH_1):FM_CPU0_FIVR_FAULT_LVT3
 R7D29    2      B RES_0402-33.2,1%,1/16W,CHIP,G2A    I30 @BASEBOARD_FAB2_LIB.BASEBOARD_FAB2(SCH_1):PAGE92
  U8D7  M16  PR12B LCMXO2_A_256BGA-IC,H63395-001    I59 @BASEBOARD_FAB2_LIB.BASEBOARD_FAB2(SCH_1):PAGE191

FM_CPU0_FIVR_FAULT_LVT3_N @BASEBOARD_FAB2_LIB.BASEBOARD_FAB2(SCH_1):FM_CPU0_FIVR_FAULT_LVT3_N
  U7C1 BE11 GPP_G10_FANPWM2_FANPWM2IE LBG_CORE_QAT_EXT_D_BGA1-IC,H91A   I147 @BASEBOARD_FAB2_LIB.BASEBOARD_FAB2(SCH_1):PAGE120
  U8D7   F5   PL5C LCMXO2_A_256BGA-IC,H63395-001   I179 @BASEBOARD_FAB2_LIB.BASEBOARD_FAB2(SCH_1):PAGE190
R25W70    2      B RES_0402-33.2,1%,1/16W,CHIP,G2A    I64 @BASEBOARD_FAB2_LIB.BASEBOARD_FAB2(SCH_1):PAGE146

FM_CPU0_FIVR_FAULT_LVT3_R_N @BASEBOARD_FAB2_LIB.BASEBOARD_FAB2(SCH_1):FM_CPU0_FIVR_FAULT_LVT3_R_N
R25W70    1      A RES_0402-33.2,1%,1/16W,CHIP,G2A    I64 @BASEBOARD_FAB2_LIB.BASEBOARD_FAB2(SCH_1):PAGE146
 U25W4  B10 GPIOQ6_OSCCLK AST2520A1-GP-GP_ASIC2-GB1-AST2A   I105 @BASEBOARD_FAB2_LIB.BASEBOARD_FAB2(SCH_1):PAGE146

FM_CPU0_FIVR_FAULT_R_LVT3 @BASEBOARD_FAB2_LIB.BASEBOARD_FAB2(SCH_1):FM_CPU0_FIVR_FAULT_R_LVT3
 R7D29    1      A RES_0402-33.2,1%,1/16W,CHIP,G2A    I30 @BASEBOARD_FAB2_LIB.BASEBOARD_FAB2(SCH_1):PAGE92
  U7D2   12     A1 GTL2014_SM-IC,D66151-001    I32 @BASEBOARD_FAB2_LIB.BASEBOARD_FAB2(SCH_1):PAGE92

FM_CPU0_MCP_CLK_EN_N @BASEBOARD_FAB2_LIB.BASEBOARD_FAB2(SCH_1):FM_CPU0_MCP_CLK_EN_N
 EU4D2   29 OE_3_N NB3W1200L_LCC-IC,H13585-001     I1 @BASEBOARD_FAB2_LIB.BASEBOARD_FAB2(SCH_1):PAGE102
 EU4D2   36 OE_4_N NB3W1200L_LCC-IC,H13585-001     I1 @BASEBOARD_FAB2_LIB.BASEBOARD_FAB2(SCH_1):PAGE102
 EU4D2   37 OE_5_N NB3W1200L_LCC-IC,H13585-001     I1 @BASEBOARD_FAB2_LIB.BASEBOARD_FAB2(SCH_1):PAGE102
 R4D70    2      B RES_0402-4.75K,1%,1/16W,CHIP,GA    I94 @BASEBOARD_FAB2_LIB.BASEBOARD_FAB2(SCH_1):PAGE102
  U8D7  F15   PR3B LCMXO2_A_256BGA-IC,H63395-001    I59 @BASEBOARD_FAB2_LIB.BASEBOARD_FAB2(SCH_1):PAGE191

FM_CPU0_OR_CPU1_MCP_PRES @BASEBOARD_FAB2_LIB.BASEBOARD_FAB2(SCH_1):FM_CPU0_OR_CPU1_MCP_PRES
  U9A5    1   OE_N 74CBTLV1G125_SMLF-IC,C88177-00A   I185 @BASEBOARD_FAB2_LIB.BASEBOARD_FAB2(SCH_1):PAGE113
  U1M5    1   OE_N 74CBTLV1G125_SMLF-IC,C88177-00A   I196 @BASEBOARD_FAB2_LIB.BASEBOARD_FAB2(SCH_1):PAGE113
  U8D7  A11  PT21A LCMXO2_A_256BGA-IC,H63395-001    I59 @BASEBOARD_FAB2_LIB.BASEBOARD_FAB2(SCH_1):PAGE191

FM_CPU0_PKGID0 @BASEBOARD_FAB2_LIB.BASEBOARD_FAB2(SCH_1):FM_CPU0_PKGID0
  R5N1    2      B RES_0402-10.0K,1%,1/16W,CHIP,GA   I238 @BASEBOARD_FAB2_LIB.BASEBOARD_FAB2(SCH_1):PAGE21
  U5D1 DC72 PKGID<0> SKX_EXT_B_BGA1-IC,TBD   I259 @BASEBOARD_FAB2_LIB.BASEBOARD_FAB2(SCH_1):PAGE21
  U8D7   F2 PL3B_PCLKC5_0 LCMXO2_A_256BGA-IC,H63395-001   I179 @BASEBOARD_FAB2_LIB.BASEBOARD_FAB2(SCH_1):PAGE190

FM_CPU0_PKGID1 @BASEBOARD_FAB2_LIB.BASEBOARD_FAB2(SCH_1):FM_CPU0_PKGID1
  R5N5    2      B RES_0402-10.0K,1%,1/16W,CHIP,GA   I239 @BASEBOARD_FAB2_LIB.BASEBOARD_FAB2(SCH_1):PAGE21
  U5D1 CW72 PKGID<1> SKX_EXT_B_BGA1-IC,TBD   I259 @BASEBOARD_FAB2_LIB.BASEBOARD_FAB2(SCH_1):PAGE21
  U4R1    1   OE_N 74CBTLV1G125_SMLF-IC,C88177-00A   I206 @BASEBOARD_FAB2_LIB.BASEBOARD_FAB2(SCH_1):PAGE113
  U8D7   G3   PL5B LCMXO2_A_256BGA-IC,H63395-001   I179 @BASEBOARD_FAB2_LIB.BASEBOARD_FAB2(SCH_1):PAGE190

FM_CPU0_PKGID2 @BASEBOARD_FAB2_LIB.BASEBOARD_FAB2(SCH_1):FM_CPU0_PKGID2
  R5N3    2      B RES_0402-10.0K,1%,1/16W,CHIP,GA   I240 @BASEBOARD_FAB2_LIB.BASEBOARD_FAB2(SCH_1):PAGE21
  U5D1 DA72 PKGID<2> SKX_EXT_B_BGA1-IC,TBD   I259 @BASEBOARD_FAB2_LIB.BASEBOARD_FAB2(SCH_1):PAGE21
  U8D7   G2   PL5A LCMXO2_A_256BGA-IC,H63395-001   I179 @BASEBOARD_FAB2_LIB.BASEBOARD_FAB2(SCH_1):PAGE190

FM_CPU0_PROCHOT_LVT3_BMC_N @BASEBOARD_FAB2_LIB.BASEBOARD_FAB2(SCH_1):FM_CPU0_PROCHOT_LVT3_BMC_N
 R1T36    2      B RES_0402-0.0,5%,1/16W,CHIP,G21A   I122 @BASEBOARD_FAB2_LIB.BASEBOARD_FAB2(SCH_1):PAGE93
 U25W4  A20 GPIOE6_TXD3 AST2520A1-GP-GP_ASIC2-GB1-AST2A   I117 @BASEBOARD_FAB2_LIB.BASEBOARD_FAB2(SCH_1):PAGE145

FM_CPU0_PROCHOT_LVT3_K_N @BASEBOARD_FAB2_LIB.BASEBOARD_FAB2(SCH_1):FM_CPU0_PROCHOT_LVT3_K_N
 R2T38    1      A RES_0402-33.2,1%,1/16W,CHIP,G2A    I39 @BASEBOARD_FAB2_LIB.BASEBOARD_FAB2(SCH_1):PAGE93
 R2T71    1      A RES_0402-0.0,5%,1/16W,EMPTY,G2A   I109 @BASEBOARD_FAB2_LIB.BASEBOARD_FAB2(SCH_1):PAGE93
 R2T67    2      B RES_0402-0.0,5%,1/16W,CHIP,G21A   I113 @BASEBOARD_FAB2_LIB.BASEBOARD_FAB2(SCH_1):PAGE93

FM_CPU0_PROCHOT_LVT3_N @BASEBOARD_FAB2_LIB.BASEBOARD_FAB2(SCH_1):FM_CPU0_PROCHOT_LVT3_N
 R2T38    2      B RES_0402-33.2,1%,1/16W,CHIP,G2A    I39 @BASEBOARD_FAB2_LIB.BASEBOARD_FAB2(SCH_1):PAGE93
 R1T36    1      A RES_0402-0.0,5%,1/16W,CHIP,G21A   I122 @BASEBOARD_FAB2_LIB.BASEBOARD_FAB2(SCH_1):PAGE93
 R1T35    1      A RES_0402-0.0,5%,1/16W,EMPTY,G2A   I135 @BASEBOARD_FAB2_LIB.BASEBOARD_FAB2(SCH_1):PAGE93

FM_CPU0_PROCHOT_LVT3_R_N @BASEBOARD_FAB2_LIB.BASEBOARD_FAB2(SCH_1):FM_CPU0_PROCHOT_LVT3_R_N
  U2T4   12     A1 GTL2014_SM-IC,D66151-001    I30 @BASEBOARD_FAB2_LIB.BASEBOARD_FAB2(SCH_1):PAGE93
 R2T67    1      A RES_0402-0.0,5%,1/16W,CHIP,G21A   I113 @BASEBOARD_FAB2_LIB.BASEBOARD_FAB2(SCH_1):PAGE93

FM_CPU0_PROCHOT_PCH_N @BASEBOARD_FAB2_LIB.BASEBOARD_FAB2(SCH_1):FM_CPU0_PROCHOT_PCH_N
 R1T35    2      B RES_0402-0.0,5%,1/16W,EMPTY,G2A   I135 @BASEBOARD_FAB2_LIB.BASEBOARD_FAB2(SCH_1):PAGE93
  U7C1   Y7 GPP_L16_TESTCH1_D5 LBG_CORE_QAT_EXT_D_BGA1-IC,H91A    I34 @BASEBOARD_FAB2_LIB.BASEBOARD_FAB2(SCH_1):PAGE121

FM_CPU0_PROC_ID0 @BASEBOARD_FAB2_LIB.BASEBOARD_FAB2(SCH_1):FM_CPU0_PROC_ID0
  R5N4    2      B RES_0402-1.8K,1%,1/16W,CHIP,G2A   I241 @BASEBOARD_FAB2_LIB.BASEBOARD_FAB2(SCH_1):PAGE21
  U5D1 CY71 PROC_ID<0> SKX_EXT_B_BGA1-IC,TBD   I259 @BASEBOARD_FAB2_LIB.BASEBOARD_FAB2(SCH_1):PAGE21
  U8D7   F1   PL4B LCMXO2_A_256BGA-IC,H63395-001   I179 @BASEBOARD_FAB2_LIB.BASEBOARD_FAB2(SCH_1):PAGE190
 U25W4   D8 GPIOR6_MDC1 AST2520A1-GP-GP_ASIC2-GB1-AST2A   I106 @BASEBOARD_FAB2_LIB.BASEBOARD_FAB2(SCH_1):PAGE147

FM_CPU0_PROC_ID1 @BASEBOARD_FAB2_LIB.BASEBOARD_FAB2(SCH_1):FM_CPU0_PROC_ID1
  R5N2    2      B RES_0402-1.8K,1%,1/16W,CHIP,G2A   I227 @BASEBOARD_FAB2_LIB.BASEBOARD_FAB2(SCH_1):PAGE21
  U5D1 DB71 PROC_ID<1> SKX_EXT_B_BGA1-IC,TBD   I259 @BASEBOARD_FAB2_LIB.BASEBOARD_FAB2(SCH_1):PAGE21
  U8D7   F3   PL4A LCMXO2_A_256BGA-IC,H63395-001   I179 @BASEBOARD_FAB2_LIB.BASEBOARD_FAB2(SCH_1):PAGE190
 U25W4  E10 GPIOR7_MDIO1 AST2520A1-GP-GP_ASIC2-GB1-AST2A   I106 @BASEBOARD_FAB2_LIB.BASEBOARD_FAB2(SCH_1):PAGE147

FM_CPU0_RC_EN @BASEBOARD_FAB2_LIB.BASEBOARD_FAB2(SCH_1):FM_CPU0_RC_EN
  U7C1 BD20 GPP_G22_SSATA_DEVSLP2 LBG_CORE_QAT_EXT_D_BGA1-IC,H91A   I147 @BASEBOARD_FAB2_LIB.BASEBOARD_FAB2(SCH_1):PAGE120
 R8D44    2      B RES_0402-10.0K,1%,1/16W,CHIP,GA   I362 @BASEBOARD_FAB2_LIB.BASEBOARD_FAB2(SCH_1):PAGE133
  U8D7   R3   PB3D LCMXO2_A_256BGA-IC,H63395-001   I179 @BASEBOARD_FAB2_LIB.BASEBOARD_FAB2(SCH_1):PAGE190

FM_CPU0_RC_ERROR_N @BASEBOARD_FAB2_LIB.BASEBOARD_FAB2(SCH_1):FM_CPU0_RC_ERROR_N
  U5D1  Y23 RSVD<257> SKX_EXT_B_BGA1-IC,TBD   I204 @BASEBOARD_FAB2_LIB.BASEBOARD_FAB2(SCH_1):PAGE22
  U7C1  B14 GPD10_SLP_S5_N LBG_CORE_QAT_EXT_D_BGA1-IC,H91A    I73 @BASEBOARD_FAB2_LIB.BASEBOARD_FAB2(SCH_1):PAGE118
  U7C1 BH50 GPP_E0_SATAXPCIE0_SATAGP0 LBG_CORE_QAT_EXT_D_BGA1-IC,H91A   I147 @BASEBOARD_FAB2_LIB.BASEBOARD_FAB2(SCH_1):PAGE120
  R2M8    2      B RES_0402-1.5K,1%,1/16W,CHIP,G2A   I349 @BASEBOARD_FAB2_LIB.BASEBOARD_FAB2(SCH_1):PAGE133
 U25W4   Y1 GPIOM0_NCTS2_VPIB2 AST2520A1-GP-GP_ASIC2-GB1-AST2A   I117 @BASEBOARD_FAB2_LIB.BASEBOARD_FAB2(SCH_1):PAGE145

FM_CPU0_SKTOCC_LVT3_N @BASEBOARD_FAB2_LIB.BASEBOARD_FAB2(SCH_1):FM_CPU0_SKTOCC_LVT3_N
  R4R5    2      B RES_0402-4.75K,1%,1/16W,CHIP,GA   I258 @BASEBOARD_FAB2_LIB.BASEBOARD_FAB2(SCH_1):PAGE21
  U5D1 AB13 SKTOCC_N SKX_EXT_B_BGA1-IC,TBD   I259 @BASEBOARD_FAB2_LIB.BASEBOARD_FAB2(SCH_1):PAGE21
  U7C1  G11 GPD6_SLP_A_N LBG_CORE_QAT_EXT_D_BGA1-IC,H91A    I73 @BASEBOARD_FAB2_LIB.BASEBOARD_FAB2(SCH_1):PAGE118
  U8D7  T14  PB22D LCMXO2_A_256BGA-IC,H63395-001   I179 @BASEBOARD_FAB2_LIB.BASEBOARD_FAB2(SCH_1):PAGE190
 U25W4  K18 GPIOB3 AST2520A1-GP-GP_ASIC2-GB1-AST2A    I95 @BASEBOARD_FAB2_LIB.BASEBOARD_FAB2(SCH_1):PAGE144

FM_CPU0_SM_WP @BASEBOARD_FAB2_LIB.BASEBOARD_FAB2(SCH_1):FM_CPU0_SM_WP
  U5D1 CV59  SM_WP SKX_EXT_B_BGA1-IC,TBD   I259 @BASEBOARD_FAB2_LIB.BASEBOARD_FAB2(SCH_1):PAGE21
 R3P54    2      B RES_0402-3.32K,1%,1/16W,EMPTY,A   I331 @BASEBOARD_FAB2_LIB.BASEBOARD_FAB2(SCH_1):PAGE156
 R3P56    1      A RES_0402-1.00K,1%,1/16W,CHIP,GA   I333 @BASEBOARD_FAB2_LIB.BASEBOARD_FAB2(SCH_1):PAGE156

FM_CPU0_STL_BRD_OSC_EN @BASEBOARD_FAB2_LIB.BASEBOARD_FAB2(SCH_1):FM_CPU0_STL_BRD_OSC_EN
  Y6F1    1 ENABLE_DISABLE OSC_C_6P10-156.25MHZ,OSC,G6383A    I71 @BASEBOARD_FAB2_LIB.BASEBOARD_FAB2(SCH_1):PAGE104
 R8D43    2      B RES_0402-0.0,5%,1/16W,CHIP,G21A    I93 @BASEBOARD_FAB2_LIB.BASEBOARD_FAB2(SCH_1):PAGE104
 R7D40    2      B RES_0402-0.0,5%,1/16W,EMPTY,G2A    I94 @BASEBOARD_FAB2_LIB.BASEBOARD_FAB2(SCH_1):PAGE104

FM_CPU0_THERMTRIP_LATCH_LVT3_N @BASEBOARD_FAB2_LIB.BASEBOARD_FAB2(SCH_1):FM_CPU0_THERMTRIP_LATCH_LVT3_N
  U7C1 BN44 GPP_D23 LBG_CORE_QAT_EXT_D_BGA1-IC,H91A   I115 @BASEBOARD_FAB2_LIB.BASEBOARD_FAB2(SCH_1):PAGE119
  U8D7  G12   PR3D LCMXO2_A_256BGA-IC,H63395-001    I59 @BASEBOARD_FAB2_LIB.BASEBOARD_FAB2(SCH_1):PAGE191
R25W102    2      B RES_0402-4.75K,1%,1/16W,CHIP,GA    I28 @BASEBOARD_FAB2_LIB.BASEBOARD_FAB2(SCH_1):PAGE151
 U25W4  W22 GPIOZ5_VPOG7_NORA5 AST2520A1-GP-GP_ASIC2-GB1-AST2A   I104 @BASEBOARD_FAB2_LIB.BASEBOARD_FAB2(SCH_1):PAGE146

FM_CPU0_THERMTRIP_LVT3_N @BASEBOARD_FAB2_LIB.BASEBOARD_FAB2(SCH_1):FM_CPU0_THERMTRIP_LVT3_N
 R7D34    2      B RES_0402-33.2,1%,1/16W,CHIP,G2A    I24 @BASEBOARD_FAB2_LIB.BASEBOARD_FAB2(SCH_1):PAGE92
  U8D7  N15  PR13C LCMXO2_A_256BGA-IC,H63395-001    I59 @BASEBOARD_FAB2_LIB.BASEBOARD_FAB2(SCH_1):PAGE191

FM_CPU0_THERMTRIP_LVT3_R_N @BASEBOARD_FAB2_LIB.BASEBOARD_FAB2(SCH_1):FM_CPU0_THERMTRIP_LVT3_R_N
 R7D34    1      A RES_0402-33.2,1%,1/16W,CHIP,G2A    I24 @BASEBOARD_FAB2_LIB.BASEBOARD_FAB2(SCH_1):PAGE92
  U7D2    9     A3 GTL2014_SM-IC,D66151-001    I32 @BASEBOARD_FAB2_LIB.BASEBOARD_FAB2(SCH_1):PAGE92

FM_CPU0_VRM_322M_156M_OSC_EN @BASEBOARD_FAB2_LIB.BASEBOARD_FAB2(SCH_1):FM_CPU0_VRM_322M_156M_OSC_EN
 R7D39    2      B RES_0402-0.0,5%,1/16W,EMPTY,G2A    I95 @BASEBOARD_FAB2_LIB.BASEBOARD_FAB2(SCH_1):PAGE104
  J6B1   E1   IOE1 SCONN120_H61426002_SM-CONN,H61A    I56 @BASEBOARD_FAB2_LIB.BASEBOARD_FAB2(SCH_1):PAGE194

FM_CPU0_VRM_OSC_EN @BASEBOARD_FAB2_LIB.BASEBOARD_FAB2(SCH_1):FM_CPU0_VRM_OSC_EN
 R7D40    1      A RES_0402-0.0,5%,1/16W,EMPTY,G2A    I94 @BASEBOARD_FAB2_LIB.BASEBOARD_FAB2(SCH_1):PAGE104
 R7D39    1      A RES_0402-0.0,5%,1/16W,EMPTY,G2A    I95 @BASEBOARD_FAB2_LIB.BASEBOARD_FAB2(SCH_1):PAGE104
  U8D7  R13  PB22C LCMXO2_A_256BGA-IC,H63395-001   I179 @BASEBOARD_FAB2_LIB.BASEBOARD_FAB2(SCH_1):PAGE190

FM_CPU1_CD_PRES @BASEBOARD_FAB2_LIB.BASEBOARD_FAB2(SCH_1):FM_CPU1_CD_PRES
  U1M2    6      S NC7SB3157_SMLF-IC,C99406-001   I107 @BASEBOARD_FAB2_LIB.BASEBOARD_FAB2(SCH_1):PAGE113
  U8D7  F10  PT21C LCMXO2_A_256BGA-IC,H63395-001    I59 @BASEBOARD_FAB2_LIB.BASEBOARD_FAB2(SCH_1):PAGE191

FM_CPU1_FIVR_FAULT_LVT3 @BASEBOARD_FAB2_LIB.BASEBOARD_FAB2(SCH_1):FM_CPU1_FIVR_FAULT_LVT3
 R3P46    2      B RES_0402-33.2,1%,1/16W,CHIP,G2A    I12 @BASEBOARD_FAB2_LIB.BASEBOARD_FAB2(SCH_1):PAGE92
  U8D7  G13   PR4D LCMXO2_A_256BGA-IC,H63395-001    I59 @BASEBOARD_FAB2_LIB.BASEBOARD_FAB2(SCH_1):PAGE191

FM_CPU1_FIVR_FAULT_LVT3_N @BASEBOARD_FAB2_LIB.BASEBOARD_FAB2(SCH_1):FM_CPU1_FIVR_FAULT_LVT3_N
  U7C1 BA20 GPP_G11_FANPWM3_FANPMW3IE LBG_CORE_QAT_EXT_D_BGA1-IC,H91A   I147 @BASEBOARD_FAB2_LIB.BASEBOARD_FAB2(SCH_1):PAGE120
  U8D7   E6  PT13C LCMXO2_A_256BGA-IC,H63395-001    I59 @BASEBOARD_FAB2_LIB.BASEBOARD_FAB2(SCH_1):PAGE191
R25W75    1      A RES_0402-33.2,1%,1/16W,CHIP,G2A    I23 @BASEBOARD_FAB2_LIB.BASEBOARD_FAB2(SCH_1):PAGE148

FM_CPU1_FIVR_FAULT_LVT3_R_N @BASEBOARD_FAB2_LIB.BASEBOARD_FAB2(SCH_1):FM_CPU1_FIVR_FAULT_LVT3_R_N
R25W75    2      B RES_0402-33.2,1%,1/16W,CHIP,G2A    I23 @BASEBOARD_FAB2_LIB.BASEBOARD_FAB2(SCH_1):PAGE148
 U25W4  P22 GPIOY2_SIOPWREQ# AST2520A1-GP-GP_ASIC2-GB1-AST2A    I28 @BASEBOARD_FAB2_LIB.BASEBOARD_FAB2(SCH_1):PAGE148

FM_CPU1_FIVR_FAULT_R_LVT3 @BASEBOARD_FAB2_LIB.BASEBOARD_FAB2(SCH_1):FM_CPU1_FIVR_FAULT_R_LVT3
  U3P2   12     A1 GTL2014_SM-IC,D66151-001     I1 @BASEBOARD_FAB2_LIB.BASEBOARD_FAB2(SCH_1):PAGE92
 R3P46    1      A RES_0402-33.2,1%,1/16W,CHIP,G2A    I12 @BASEBOARD_FAB2_LIB.BASEBOARD_FAB2(SCH_1):PAGE92

FM_CPU1_MCP_CLK_EN_N @BASEBOARD_FAB2_LIB.BASEBOARD_FAB2(SCH_1):FM_CPU1_MCP_CLK_EN_N
 EU4D2   53 OE_9_N NB3W1200L_LCC-IC,H13585-001     I1 @BASEBOARD_FAB2_LIB.BASEBOARD_FAB2(SCH_1):PAGE102
 EU4D2   61 OE_10_N NB3W1200L_LCC-IC,H13585-001     I1 @BASEBOARD_FAB2_LIB.BASEBOARD_FAB2(SCH_1):PAGE102
 EU4D2   62 OE_11_N NB3W1200L_LCC-IC,H13585-001     I1 @BASEBOARD_FAB2_LIB.BASEBOARD_FAB2(SCH_1):PAGE102
 R4D69    2      B RES_0402-4.75K,1%,1/16W,CHIP,GA    I93 @BASEBOARD_FAB2_LIB.BASEBOARD_FAB2(SCH_1):PAGE102
  U8D7  F16   PR4B LCMXO2_A_256BGA-IC,H63395-001    I59 @BASEBOARD_FAB2_LIB.BASEBOARD_FAB2(SCH_1):PAGE191

FM_CPU1_PKGID0 @BASEBOARD_FAB2_LIB.BASEBOARD_FAB2(SCH_1):FM_CPU1_PKGID0
  R8N2    2      B RES_0402-10.0K,1%,1/16W,CHIP,GA   I161 @BASEBOARD_FAB2_LIB.BASEBOARD_FAB2(SCH_1):PAGE55
  U2D1 DC72 PKGID<0> SKX_EXT_B_BGA1-IC,TBD   I172 @BASEBOARD_FAB2_LIB.BASEBOARD_FAB2(SCH_1):PAGE55
  U8D7  R12 PB25A_SN LCMXO2_A_256BGA-IC,H63395-001   I179 @BASEBOARD_FAB2_LIB.BASEBOARD_FAB2(SCH_1):PAGE190

FM_CPU1_PKGID1 @BASEBOARD_FAB2_LIB.BASEBOARD_FAB2(SCH_1):FM_CPU1_PKGID1
  R8N5    2      B RES_0402-10.0K,1%,1/16W,CHIP,GA   I160 @BASEBOARD_FAB2_LIB.BASEBOARD_FAB2(SCH_1):PAGE55
  U2D1 CW72 PKGID<1> SKX_EXT_B_BGA1-IC,TBD   I172 @BASEBOARD_FAB2_LIB.BASEBOARD_FAB2(SCH_1):PAGE55
  U6M1    1   OE_N 74CBTLV1G125_SMLF-IC,C88177-00A   I190 @BASEBOARD_FAB2_LIB.BASEBOARD_FAB2(SCH_1):PAGE113
  U8D7  P12  PB24A LCMXO2_A_256BGA-IC,H63395-001   I179 @BASEBOARD_FAB2_LIB.BASEBOARD_FAB2(SCH_1):PAGE190

FM_CPU1_PKGID2 @BASEBOARD_FAB2_LIB.BASEBOARD_FAB2(SCH_1):FM_CPU1_PKGID2
  R8N3    2      B RES_0402-10.0K,1%,1/16W,CHIP,GA   I159 @BASEBOARD_FAB2_LIB.BASEBOARD_FAB2(SCH_1):PAGE55
  U2D1 DA72 PKGID<2> SKX_EXT_B_BGA1-IC,TBD   I172 @BASEBOARD_FAB2_LIB.BASEBOARD_FAB2(SCH_1):PAGE55
  U8D7  T11  PB21A LCMXO2_A_256BGA-IC,H63395-001   I179 @BASEBOARD_FAB2_LIB.BASEBOARD_FAB2(SCH_1):PAGE190

FM_CPU1_PROCHOT_LVT3_BMC_N @BASEBOARD_FAB2_LIB.BASEBOARD_FAB2(SCH_1):FM_CPU1_PROCHOT_LVT3_BMC_N
 R1T37    2      B RES_0402-0.0,5%,1/16W,CHIP,G21A   I123 @BASEBOARD_FAB2_LIB.BASEBOARD_FAB2(SCH_1):PAGE93
 U25W4  B19 GPIOE7_RXD3 AST2520A1-GP-GP_ASIC2-GB1-AST2A   I117 @BASEBOARD_FAB2_LIB.BASEBOARD_FAB2(SCH_1):PAGE145

FM_CPU1_PROCHOT_LVT3_K_N @BASEBOARD_FAB2_LIB.BASEBOARD_FAB2(SCH_1):FM_CPU1_PROCHOT_LVT3_K_N
 R7D24    1      A RES_0402-33.2,1%,1/16W,CHIP,G2A    I62 @BASEBOARD_FAB2_LIB.BASEBOARD_FAB2(SCH_1):PAGE93
 R7D43    1      A RES_0402-0.0,5%,1/16W,EMPTY,G2A   I110 @BASEBOARD_FAB2_LIB.BASEBOARD_FAB2(SCH_1):PAGE93
 R7D41    2      B RES_0402-0.0,5%,1/16W,CHIP,G21A   I114 @BASEBOARD_FAB2_LIB.BASEBOARD_FAB2(SCH_1):PAGE93

FM_CPU1_PROCHOT_LVT3_N @BASEBOARD_FAB2_LIB.BASEBOARD_FAB2(SCH_1):FM_CPU1_PROCHOT_LVT3_N
 R7D24    2      B RES_0402-33.2,1%,1/16W,CHIP,G2A    I62 @BASEBOARD_FAB2_LIB.BASEBOARD_FAB2(SCH_1):PAGE93
 R1T37    1      A RES_0402-0.0,5%,1/16W,CHIP,G21A   I123 @BASEBOARD_FAB2_LIB.BASEBOARD_FAB2(SCH_1):PAGE93
 R1T38    1      A RES_0402-0.0,5%,1/16W,EMPTY,G2A   I137 @BASEBOARD_FAB2_LIB.BASEBOARD_FAB2(SCH_1):PAGE93

FM_CPU1_PROCHOT_LVT3_R_N @BASEBOARD_FAB2_LIB.BASEBOARD_FAB2(SCH_1):FM_CPU1_PROCHOT_LVT3_R_N
  U2T4   13     A0 GTL2014_SM-IC,D66151-001    I30 @BASEBOARD_FAB2_LIB.BASEBOARD_FAB2(SCH_1):PAGE93
 R7D41    1      A RES_0402-0.0,5%,1/16W,CHIP,G21A   I114 @BASEBOARD_FAB2_LIB.BASEBOARD_FAB2(SCH_1):PAGE93

FM_CPU1_PROCHOT_PCH_N @BASEBOARD_FAB2_LIB.BASEBOARD_FAB2(SCH_1):FM_CPU1_PROCHOT_PCH_N
 R1T38    2      B RES_0402-0.0,5%,1/16W,EMPTY,G2A   I137 @BASEBOARD_FAB2_LIB.BASEBOARD_FAB2(SCH_1):PAGE93
  U7C1  AA9 GPP_L17_TESTCH1_D6 LBG_CORE_QAT_EXT_D_BGA1-IC,H91A    I34 @BASEBOARD_FAB2_LIB.BASEBOARD_FAB2(SCH_1):PAGE121

FM_CPU1_PROC_ID0 @BASEBOARD_FAB2_LIB.BASEBOARD_FAB2(SCH_1):FM_CPU1_PROC_ID0
  R8N4    2      B RES_0402-1.8K,1%,1/16W,CHIP,G2A   I158 @BASEBOARD_FAB2_LIB.BASEBOARD_FAB2(SCH_1):PAGE55
  U2D1 CY71 PROC_ID<0> SKX_EXT_B_BGA1-IC,TBD   I172 @BASEBOARD_FAB2_LIB.BASEBOARD_FAB2(SCH_1):PAGE55
  U8D7  M15  PR13B LCMXO2_A_256BGA-IC,H63395-001    I59 @BASEBOARD_FAB2_LIB.BASEBOARD_FAB2(SCH_1):PAGE191
R25W104    2      B RES_0402-4.75K,1%,1/16W,EMPTY,A    I30 @BASEBOARD_FAB2_LIB.BASEBOARD_FAB2(SCH_1):PAGE151
 U25W4  W21 GPIOZ7_VPOG9_NORA7 AST2520A1-GP-GP_ASIC2-GB1-AST2A   I104 @BASEBOARD_FAB2_LIB.BASEBOARD_FAB2(SCH_1):PAGE146

FM_CPU1_PROC_ID1 @BASEBOARD_FAB2_LIB.BASEBOARD_FAB2(SCH_1):FM_CPU1_PROC_ID1
  R8N1    2      B RES_0402-1.8K,1%,1/16W,CHIP,G2A   I157 @BASEBOARD_FAB2_LIB.BASEBOARD_FAB2(SCH_1):PAGE55
  U2D1 DB71 PROC_ID<1> SKX_EXT_B_BGA1-IC,TBD   I172 @BASEBOARD_FAB2_LIB.BASEBOARD_FAB2(SCH_1):PAGE55
  U8D7  M14  PR13A LCMXO2_A_256BGA-IC,H63395-001    I59 @BASEBOARD_FAB2_LIB.BASEBOARD_FAB2(SCH_1):PAGE191
 U25W4  Y21 GPIOAA0_VPOR2_NORD0_SALT7 AST2520A1-GP-GP_ASIC2-GB1-AST2A   I104 @BASEBOARD_FAB2_LIB.BASEBOARD_FAB2(SCH_1):PAGE146

FM_CPU1_RC_EN @BASEBOARD_FAB2_LIB.BASEBOARD_FAB2(SCH_1):FM_CPU1_RC_EN
  U7C1 BY29 GPP_C9 LBG_CORE_QAT_EXT_D_BGA1-IC,H91A   I115 @BASEBOARD_FAB2_LIB.BASEBOARD_FAB2(SCH_1):PAGE119
 R2P22    2      B RES_0402-10.0K,1%,1/16W,CHIP,GA   I360 @BASEBOARD_FAB2_LIB.BASEBOARD_FAB2(SCH_1):PAGE133
  U8D7   P4   PB3A LCMXO2_A_256BGA-IC,H63395-001   I179 @BASEBOARD_FAB2_LIB.BASEBOARD_FAB2(SCH_1):PAGE190

FM_CPU1_RC_ERROR_N @BASEBOARD_FAB2_LIB.BASEBOARD_FAB2(SCH_1):FM_CPU1_RC_ERROR_N
  U2D1  Y23 RSVD<257> SKX_EXT_B_BGA1-IC,TBD   I169 @BASEBOARD_FAB2_LIB.BASEBOARD_FAB2(SCH_1):PAGE56
  U7C1 AY52 GPP_E1_SATAXPCIE1_SATAGP1 LBG_CORE_QAT_EXT_D_BGA1-IC,H91A   I147 @BASEBOARD_FAB2_LIB.BASEBOARD_FAB2(SCH_1):PAGE120
  U7C1 BV23 GPP_I6_RESET_DONE LBG_CORE_QAT_EXT_D_BGA1-IC,H91A   I147 @BASEBOARD_FAB2_LIB.BASEBOARD_FAB2(SCH_1):PAGE120
 R2N29    2      B RES_0402-1.5K,1%,1/16W,CHIP,G2A   I352 @BASEBOARD_FAB2_LIB.BASEBOARD_FAB2(SCH_1):PAGE133
 U25W4  AB2 GPIOM1_NDCD2_VPIB3 AST2520A1-GP-GP_ASIC2-GB1-AST2A   I117 @BASEBOARD_FAB2_LIB.BASEBOARD_FAB2(SCH_1):PAGE145

FM_CPU1_SKTOCC_LVT3_N @BASEBOARD_FAB2_LIB.BASEBOARD_FAB2(SCH_1):FM_CPU1_SKTOCC_LVT3_N
  U2D1 AB13 SKTOCC_N SKX_EXT_B_BGA1-IC,TBD   I172 @BASEBOARD_FAB2_LIB.BASEBOARD_FAB2(SCH_1):PAGE55
 R6P39    2      B RES_0402-4.75K,1%,1/16W,CHIP,GA   I181 @BASEBOARD_FAB2_LIB.BASEBOARD_FAB2(SCH_1):PAGE55
  U1M7    6      S NC7SB3157_SMLF-IC,C99406-001    I40 @BASEBOARD_FAB2_LIB.BASEBOARD_FAB2(SCH_1):PAGE112
  U1M4    1   OE_N 74CBTLV1G125_SMLF-IC,C88177-00A   I127 @BASEBOARD_FAB2_LIB.BASEBOARD_FAB2(SCH_1):PAGE112
  U7C1  H13 GPD1_ACPRESENT LBG_CORE_QAT_EXT_D_BGA1-IC,H91A    I73 @BASEBOARD_FAB2_LIB.BASEBOARD_FAB2(SCH_1):PAGE118
  U8D7  T12  PB22B LCMXO2_A_256BGA-IC,H63395-001   I179 @BASEBOARD_FAB2_LIB.BASEBOARD_FAB2(SCH_1):PAGE190
 U25W4  L19 GPIOB1 AST2520A1-GP-GP_ASIC2-GB1-AST2A    I95 @BASEBOARD_FAB2_LIB.BASEBOARD_FAB2(SCH_1):PAGE144

FM_CPU1_SM_WP @BASEBOARD_FAB2_LIB.BASEBOARD_FAB2(SCH_1):FM_CPU1_SM_WP
  U2D1 CV59  SM_WP SKX_EXT_B_BGA1-IC,TBD   I172 @BASEBOARD_FAB2_LIB.BASEBOARD_FAB2(SCH_1):PAGE55
 R1C35    2      B RES_0402-3.32K,1%,1/16W,EMPTY,A   I336 @BASEBOARD_FAB2_LIB.BASEBOARD_FAB2(SCH_1):PAGE156
 R1C36    1      A RES_0402-1.00K,1%,1/16W,CHIP,GA   I337 @BASEBOARD_FAB2_LIB.BASEBOARD_FAB2(SCH_1):PAGE156

FM_CPU1_STL_BRD_OSC_EN @BASEBOARD_FAB2_LIB.BASEBOARD_FAB2(SCH_1):FM_CPU1_STL_BRD_OSC_EN
  Y3F1    1 ENABLE_DISABLE OSC_C_6P10-156.25MHZ,OSC,G6383A    I72 @BASEBOARD_FAB2_LIB.BASEBOARD_FAB2(SCH_1):PAGE104
 R7D36    2      B RES_0402-0.0,5%,1/16W,CHIP,G21A    I96 @BASEBOARD_FAB2_LIB.BASEBOARD_FAB2(SCH_1):PAGE104
 R7D38    2      B RES_0402-0.0,5%,1/16W,EMPTY,G2A    I97 @BASEBOARD_FAB2_LIB.BASEBOARD_FAB2(SCH_1):PAGE104

FM_CPU1_THERMTRIP_LATCH_LVT3_N @BASEBOARD_FAB2_LIB.BASEBOARD_FAB2(SCH_1):FM_CPU1_THERMTRIP_LATCH_LVT3_N
  U7C1 AV18 GPP_G6_FANTACH6_FANTACH6IE LBG_CORE_QAT_EXT_D_BGA1-IC,H91A   I147 @BASEBOARD_FAB2_LIB.BASEBOARD_FAB2(SCH_1):PAGE120
  U8D7   C5  PT10B LCMXO2_A_256BGA-IC,H63395-001    I59 @BASEBOARD_FAB2_LIB.BASEBOARD_FAB2(SCH_1):PAGE191
 U25W4  T19 GPIOR1_FWSPICS2# AST2520A1-GP-GP_ASIC2-GB1-AST2A   I105 @BASEBOARD_FAB2_LIB.BASEBOARD_FAB2(SCH_1):PAGE146

FM_CPU1_THERMTRIP_LVT3_N @BASEBOARD_FAB2_LIB.BASEBOARD_FAB2(SCH_1):FM_CPU1_THERMTRIP_LVT3_N
 R3P42    2      B RES_0402-33.2,1%,1/16W,CHIP,G2A    I14 @BASEBOARD_FAB2_LIB.BASEBOARD_FAB2(SCH_1):PAGE92
  U8D7  G14   PR5B LCMXO2_A_256BGA-IC,H63395-001    I59 @BASEBOARD_FAB2_LIB.BASEBOARD_FAB2(SCH_1):PAGE191

FM_CPU1_THERMTRIP_LVT3_R_N @BASEBOARD_FAB2_LIB.BASEBOARD_FAB2(SCH_1):FM_CPU1_THERMTRIP_LVT3_R_N
  U3P2    9     A3 GTL2014_SM-IC,D66151-001     I1 @BASEBOARD_FAB2_LIB.BASEBOARD_FAB2(SCH_1):PAGE92
 R3P42    1      A RES_0402-33.2,1%,1/16W,CHIP,G2A    I14 @BASEBOARD_FAB2_LIB.BASEBOARD_FAB2(SCH_1):PAGE92

FM_CPU1_VRM_322M_156M_OSC_EN @BASEBOARD_FAB2_LIB.BASEBOARD_FAB2(SCH_1):FM_CPU1_VRM_322M_156M_OSC_EN
 R7D37    2      B RES_0402-0.0,5%,1/16W,EMPTY,G2A    I98 @BASEBOARD_FAB2_LIB.BASEBOARD_FAB2(SCH_1):PAGE104
  J4B2   E1   IOE1 SCONN120_H61426002_SM-CONN,H61A    I46 @BASEBOARD_FAB2_LIB.BASEBOARD_FAB2(SCH_1):PAGE193

FM_CPU1_VRM_OSC_EN @BASEBOARD_FAB2_LIB.BASEBOARD_FAB2(SCH_1):FM_CPU1_VRM_OSC_EN
 R7D38    1      A RES_0402-0.0,5%,1/16W,EMPTY,G2A    I97 @BASEBOARD_FAB2_LIB.BASEBOARD_FAB2(SCH_1):PAGE104
 R7D37    1      A RES_0402-0.0,5%,1/16W,EMPTY,G2A    I98 @BASEBOARD_FAB2_LIB.BASEBOARD_FAB2(SCH_1):PAGE104
  U8D7  N14  PR14B LCMXO2_A_256BGA-IC,H63395-001    I59 @BASEBOARD_FAB2_LIB.BASEBOARD_FAB2(SCH_1):PAGE191

FM_CPU_BMC_INIT @BASEBOARD_FAB2_LIB.BASEBOARD_FAB2(SCH_1):FM_CPU_BMC_INIT
  U7C1  AD1 GPP_A17 LBG_CORE_QAT_EXT_D_BGA1-IC,H91A   I115 @BASEBOARD_FAB2_LIB.BASEBOARD_FAB2(SCH_1):PAGE119
 R6D16    1      A RES_0402-0.0,5%,1/16W,EMPTY,G2A   I299 @BASEBOARD_FAB2_LIB.BASEBOARD_FAB2(SCH_1):PAGE156
 R3D31    1      A RES_0402-0.0,5%,1/16W,EMPTY,G2A   I300 @BASEBOARD_FAB2_LIB.BASEBOARD_FAB2(SCH_1):PAGE156
 U25W4  B15 GPIOI4_SPI1CS0#_VBCS# AST2520A1-GP-GP_ASIC2-GB1-AST2A    I95 @BASEBOARD_FAB2_LIB.BASEBOARD_FAB2(SCH_1):PAGE144

FM_CPU_CATERR_DLY_LVT3_N @BASEBOARD_FAB2_LIB.BASEBOARD_FAB2(SCH_1):FM_CPU_CATERR_DLY_LVT3_N
  R2N1    2      B RES_0402-33.2,1%,1/16W,CHIP,G2A   I173 @BASEBOARD_FAB2_LIB.BASEBOARD_FAB2(SCH_1):PAGE119
  U8D7   E2 PL2A_L_GPLLT_IN LCMXO2_A_256BGA-IC,H63395-001   I179 @BASEBOARD_FAB2_LIB.BASEBOARD_FAB2(SCH_1):PAGE190

FM_CPU_CATERR_DLY_LVT3_R_N @BASEBOARD_FAB2_LIB.BASEBOARD_FAB2(SCH_1):FM_CPU_CATERR_DLY_LVT3_R_N
  U7C1 CA37 GPP_C23 LBG_CORE_QAT_EXT_D_BGA1-IC,H91A   I115 @BASEBOARD_FAB2_LIB.BASEBOARD_FAB2(SCH_1):PAGE119
  R2N1    1      A RES_0402-33.2,1%,1/16W,CHIP,G2A   I173 @BASEBOARD_FAB2_LIB.BASEBOARD_FAB2(SCH_1):PAGE119

FM_CPU_CATERR_LVT3_N @BASEBOARD_FAB2_LIB.BASEBOARD_FAB2(SCH_1):FM_CPU_CATERR_LVT3_N
 R3P43    2      B RES_0402-33.2,1%,1/16W,CHIP,G2A    I13 @BASEBOARD_FAB2_LIB.BASEBOARD_FAB2(SCH_1):PAGE92
  U8D7  R14  PB25D LCMXO2_A_256BGA-IC,H63395-001   I179 @BASEBOARD_FAB2_LIB.BASEBOARD_FAB2(SCH_1):PAGE190
 U25W4  E19 GPIOG1_SGPS1LD AST2520A1-GP-GP_ASIC2-GB1-AST2A    I95 @BASEBOARD_FAB2_LIB.BASEBOARD_FAB2(SCH_1):PAGE144

FM_CPU_CATERR_LVT3_R2_N @BASEBOARD_FAB2_LIB.BASEBOARD_FAB2(SCH_1):FM_CPU_CATERR_LVT3_R2_N
  U3P2   10     A2 GTL2014_SM-IC,D66151-001     I1 @BASEBOARD_FAB2_LIB.BASEBOARD_FAB2(SCH_1):PAGE92
 R3P43    1      A RES_0402-33.2,1%,1/16W,CHIP,G2A    I13 @BASEBOARD_FAB2_LIB.BASEBOARD_FAB2(SCH_1):PAGE92

FM_CPU_ERR0_LVT3_BMC_N @BASEBOARD_FAB2_LIB.BASEBOARD_FAB2(SCH_1):FM_CPU_ERR0_LVT3_BMC_N
 R8F38    2      B RES_0402-0.0,5%,1/16W,CHIP,G21A   I119 @BASEBOARD_FAB2_LIB.BASEBOARD_FAB2(SCH_1):PAGE93
 U25W4  G18 GPIOD6_SD2CD# AST2520A1-GP-GP_ASIC2-GB1-AST2A   I117 @BASEBOARD_FAB2_LIB.BASEBOARD_FAB2(SCH_1):PAGE145

FM_CPU_ERR0_LVT3_K_N @BASEBOARD_FAB2_LIB.BASEBOARD_FAB2(SCH_1):FM_CPU_ERR0_LVT3_K_N
 R2T30    1      A RES_0402-33.2,1%,1/16W,CHIP,G2A    I42 @BASEBOARD_FAB2_LIB.BASEBOARD_FAB2(SCH_1):PAGE93
 R2T58    2      B RES_0402-0.0,5%,1/16W,EMPTY,G2A    I94 @BASEBOARD_FAB2_LIB.BASEBOARD_FAB2(SCH_1):PAGE93
 R2T65    2      B RES_0402-0.0,5%,1/16W,CHIP,G21A   I111 @BASEBOARD_FAB2_LIB.BASEBOARD_FAB2(SCH_1):PAGE93

FM_CPU_ERR0_LVT3_N @BASEBOARD_FAB2_LIB.BASEBOARD_FAB2(SCH_1):FM_CPU_ERR0_LVT3_N
 R2T30    2      B RES_0402-33.2,1%,1/16W,CHIP,G2A    I42 @BASEBOARD_FAB2_LIB.BASEBOARD_FAB2(SCH_1):PAGE93
 R8F38    1      A RES_0402-0.0,5%,1/16W,CHIP,G21A   I119 @BASEBOARD_FAB2_LIB.BASEBOARD_FAB2(SCH_1):PAGE93
 R8F37    1      A RES_0402-0.0,5%,1/16W,EMPTY,G2A   I131 @BASEBOARD_FAB2_LIB.BASEBOARD_FAB2(SCH_1):PAGE93

FM_CPU_ERR0_LVT3_R_N @BASEBOARD_FAB2_LIB.BASEBOARD_FAB2(SCH_1):FM_CPU_ERR0_LVT3_R_N
  U2T4    9     A3 GTL2014_SM-IC,D66151-001    I30 @BASEBOARD_FAB2_LIB.BASEBOARD_FAB2(SCH_1):PAGE93
 R2T65    1      A RES_0402-0.0,5%,1/16W,CHIP,G21A   I111 @BASEBOARD_FAB2_LIB.BASEBOARD_FAB2(SCH_1):PAGE93

FM_CPU_ERR0_PCH_N @BASEBOARD_FAB2_LIB.BASEBOARD_FAB2(SCH_1):FM_CPU_ERR0_PCH_N
 R8F37    2      B RES_0402-0.0,5%,1/16W,EMPTY,G2A   I131 @BASEBOARD_FAB2_LIB.BASEBOARD_FAB2(SCH_1):PAGE93
  U7C1  AE7 GPP_L18_TESTCH1_D7 LBG_CORE_QAT_EXT_D_BGA1-IC,H91A    I34 @BASEBOARD_FAB2_LIB.BASEBOARD_FAB2(SCH_1):PAGE121

FM_CPU_ERR1_LVT3_BMC_N @BASEBOARD_FAB2_LIB.BASEBOARD_FAB2(SCH_1):FM_CPU_ERR1_LVT3_BMC_N
 R2T64    2      B RES_0402-0.0,5%,1/16W,CHIP,G21A   I121 @BASEBOARD_FAB2_LIB.BASEBOARD_FAB2(SCH_1):PAGE93
 U25W4  C21 GPIOD7_SD2WP# AST2520A1-GP-GP_ASIC2-GB1-AST2A   I117 @BASEBOARD_FAB2_LIB.BASEBOARD_FAB2(SCH_1):PAGE145

FM_CPU_ERR1_LVT3_K_N @BASEBOARD_FAB2_LIB.BASEBOARD_FAB2(SCH_1):FM_CPU_ERR1_LVT3_K_N
 R2T33    1      A RES_0402-33.2,1%,1/16W,CHIP,G2A    I40 @BASEBOARD_FAB2_LIB.BASEBOARD_FAB2(SCH_1):PAGE93
 R2T62    2      B RES_0402-0.0,5%,1/16W,EMPTY,G2A    I93 @BASEBOARD_FAB2_LIB.BASEBOARD_FAB2(SCH_1):PAGE93
 R2T66    2      B RES_0402-0.0,5%,1/16W,CHIP,G21A   I112 @BASEBOARD_FAB2_LIB.BASEBOARD_FAB2(SCH_1):PAGE93

FM_CPU_ERR1_LVT3_N @BASEBOARD_FAB2_LIB.BASEBOARD_FAB2(SCH_1):FM_CPU_ERR1_LVT3_N
 R2T33    2      B RES_0402-33.2,1%,1/16W,CHIP,G2A    I40 @BASEBOARD_FAB2_LIB.BASEBOARD_FAB2(SCH_1):PAGE93
 R2T64    1      A RES_0402-0.0,5%,1/16W,CHIP,G21A   I121 @BASEBOARD_FAB2_LIB.BASEBOARD_FAB2(SCH_1):PAGE93
 R2T63    1      A RES_0402-0.0,5%,1/16W,EMPTY,G2A   I133 @BASEBOARD_FAB2_LIB.BASEBOARD_FAB2(SCH_1):PAGE93

FM_CPU_ERR1_LVT3_R_N @BASEBOARD_FAB2_LIB.BASEBOARD_FAB2(SCH_1):FM_CPU_ERR1_LVT3_R_N
  U2T4   10     A2 GTL2014_SM-IC,D66151-001    I30 @BASEBOARD_FAB2_LIB.BASEBOARD_FAB2(SCH_1):PAGE93
 R2T66    1      A RES_0402-0.0,5%,1/16W,CHIP,G21A   I112 @BASEBOARD_FAB2_LIB.BASEBOARD_FAB2(SCH_1):PAGE93

FM_CPU_ERR1_PCH_N @BASEBOARD_FAB2_LIB.BASEBOARD_FAB2(SCH_1):FM_CPU_ERR1_PCH_N
 R2T63    2      B RES_0402-0.0,5%,1/16W,EMPTY,G2A   I133 @BASEBOARD_FAB2_LIB.BASEBOARD_FAB2(SCH_1):PAGE93
  U7C1 AG11 GPP_L19_TESTCH1_CLK LBG_CORE_QAT_EXT_D_BGA1-IC,H91A    I34 @BASEBOARD_FAB2_LIB.BASEBOARD_FAB2(SCH_1):PAGE121

FM_CPU_ERR2_LVT3_N @BASEBOARD_FAB2_LIB.BASEBOARD_FAB2(SCH_1):FM_CPU_ERR2_LVT3_N
 R7D31    2      B RES_0402-33.2,1%,1/16W,CHIP,G2A    I29 @BASEBOARD_FAB2_LIB.BASEBOARD_FAB2(SCH_1):PAGE92
  U7C1 AV52 GPP_E4_SATA_DEVSLP0 LBG_CORE_QAT_EXT_D_BGA1-IC,H91A   I147 @BASEBOARD_FAB2_LIB.BASEBOARD_FAB2(SCH_1):PAGE120
 U25W4  A19 GPIOG0_SGPS1CK AST2520A1-GP-GP_ASIC2-GB1-AST2A    I95 @BASEBOARD_FAB2_LIB.BASEBOARD_FAB2(SCH_1):PAGE144

FM_CPU_ERR2_LVT3_R_N @BASEBOARD_FAB2_LIB.BASEBOARD_FAB2(SCH_1):FM_CPU_ERR2_LVT3_R_N
 R7D31    1      A RES_0402-33.2,1%,1/16W,CHIP,G2A    I29 @BASEBOARD_FAB2_LIB.BASEBOARD_FAB2(SCH_1):PAGE92
  U7D2   10     A2 GTL2014_SM-IC,D66151-001    I32 @BASEBOARD_FAB2_LIB.BASEBOARD_FAB2(SCH_1):PAGE92

FM_CPU_MSMI_LVT3_N @BASEBOARD_FAB2_LIB.BASEBOARD_FAB2(SCH_1):FM_CPU_MSMI_LVT3_N
 R7D25    2      B RES_0402-33.2,1%,1/16W,CHIP,G2A    I70 @BASEBOARD_FAB2_LIB.BASEBOARD_FAB2(SCH_1):PAGE92
  U7C1 AT52 GPP_E5_SATA_DEVSLP1 LBG_CORE_QAT_EXT_D_BGA1-IC,H91A   I147 @BASEBOARD_FAB2_LIB.BASEBOARD_FAB2(SCH_1):PAGE120
  U8D7  T13  PB24B LCMXO2_A_256BGA-IC,H63395-001   I179 @BASEBOARD_FAB2_LIB.BASEBOARD_FAB2(SCH_1):PAGE190
 U25W4   U3 GPION3_PWM3_VPIG3 AST2520A1-GP-GP_ASIC2-GB1-AST2A   I106 @BASEBOARD_FAB2_LIB.BASEBOARD_FAB2(SCH_1):PAGE147

FM_CPU_MSMI_LVT3_R_N @BASEBOARD_FAB2_LIB.BASEBOARD_FAB2(SCH_1):FM_CPU_MSMI_LVT3_R_N
  U7D2   13     A0 GTL2014_SM-IC,D66151-001    I32 @BASEBOARD_FAB2_LIB.BASEBOARD_FAB2(SCH_1):PAGE92
 R7D25    1      A RES_0402-33.2,1%,1/16W,CHIP,G2A    I70 @BASEBOARD_FAB2_LIB.BASEBOARD_FAB2(SCH_1):PAGE92

FM_CTNR_PS_ON @BASEBOARD_FAB2_LIB.BASEBOARD_FAB2(SCH_1):FM_CTNR_PS_ON
  U1E2    1   A<0> TTL1G08_SOTLF-NC7SZ08,IC,D1032B   I121 @BASEBOARD_FAB2_LIB.BASEBOARD_FAB2(SCH_1):PAGE161
  R8E5    2      B RES_0402-33.2,1%,1/16W,CHIP,G2A   I218 @BASEBOARD_FAB2_LIB.BASEBOARD_FAB2(SCH_1):PAGE181
  U8D7   B3   PT9C LCMXO2_A_256BGA-IC,H63395-001    I59 @BASEBOARD_FAB2_LIB.BASEBOARD_FAB2(SCH_1):PAGE191
 EU8B1    2     ON SLG55021_SM-IC,G56246-001    I13 @BASEBOARD_FAB2_LIB.BASEBOARD_FAB2(SCH_1):PAGE198
 R8E12    2      B RES_0402-4.75K,1%,1/16W,EMPTY,A    I78 @BASEBOARD_FAB2_LIB.BASEBOARD_FAB2(SCH_1):PAGE198
  R8B4    1      A RES_0402-100.0K,1%,1/16W,CHIP,A    I83 @BASEBOARD_FAB2_LIB.BASEBOARD_FAB2(SCH_1):PAGE198

FM_CTNR_PS_ON_R @BASEBOARD_FAB2_LIB.BASEBOARD_FAB2(SCH_1):FM_CTNR_PS_ON_R
  R8E5    1      A RES_0402-33.2,1%,1/16W,CHIP,G2A   I218 @BASEBOARD_FAB2_LIB.BASEBOARD_FAB2(SCH_1):PAGE181
  U8E1    8   Y<0> TTL08_QFN15-74LVC08A,IC,D90404B   I243 @BASEBOARD_FAB2_LIB.BASEBOARD_FAB2(SCH_1):PAGE181

FM_DB1200ZL_BCLKS_EN_N @BASEBOARD_FAB2_LIB.BASEBOARD_FAB2(SCH_1):FM_DB1200ZL_BCLKS_EN_N
 EU4D2   19 OE_0_N NB3W1200L_LCC-IC,H13585-001     I1 @BASEBOARD_FAB2_LIB.BASEBOARD_FAB2(SCH_1):PAGE102
 EU4D2   20 OE_1_N NB3W1200L_LCC-IC,H13585-001     I1 @BASEBOARD_FAB2_LIB.BASEBOARD_FAB2(SCH_1):PAGE102
 EU4D2   28 OE_2_N NB3W1200L_LCC-IC,H13585-001     I1 @BASEBOARD_FAB2_LIB.BASEBOARD_FAB2(SCH_1):PAGE102
 EU4D2   44 OE_6_N NB3W1200L_LCC-IC,H13585-001     I1 @BASEBOARD_FAB2_LIB.BASEBOARD_FAB2(SCH_1):PAGE102
 EU4D2   45 OE_7_N NB3W1200L_LCC-IC,H13585-001     I1 @BASEBOARD_FAB2_LIB.BASEBOARD_FAB2(SCH_1):PAGE102
 EU4D2   52 OE_8_N NB3W1200L_LCC-IC,H13585-001     I1 @BASEBOARD_FAB2_LIB.BASEBOARD_FAB2(SCH_1):PAGE102
 R6P48    2      B RES_0402-4.75K,1%,1/16W,CHIP,GA    I91 @BASEBOARD_FAB2_LIB.BASEBOARD_FAB2(SCH_1):PAGE102
  U8D7  R11  PB22A LCMXO2_A_256BGA-IC,H63395-001   I179 @BASEBOARD_FAB2_LIB.BASEBOARD_FAB2(SCH_1):PAGE190

FM_DB1200_PWRGD @BASEBOARD_FAB2_LIB.BASEBOARD_FAB2(SCH_1):FM_DB1200_PWRGD
 EU4D2    6 PWRGD_PWRDN_N NB3W1200L_LCC-IC,H13585-001     I1 @BASEBOARD_FAB2_LIB.BASEBOARD_FAB2(SCH_1):PAGE102
  U8D7  C15   PR1C LCMXO2_A_256BGA-IC,H63395-001    I59 @BASEBOARD_FAB2_LIB.BASEBOARD_FAB2(SCH_1):PAGE191

FM_DB1200_SMB_SA0 @BASEBOARD_FAB2_LIB.BASEBOARD_FAB2(SCH_1):FM_DB1200_SMB_SA0
 EU4D2   11   SA_0 NB3W1200L_LCC-IC,H13585-001     I1 @BASEBOARD_FAB2_LIB.BASEBOARD_FAB2(SCH_1):PAGE102
 R4D35    2      B RES_0402-10.0K,1%,1/16W,EMPTY,A    I38 @BASEBOARD_FAB2_LIB.BASEBOARD_FAB2(SCH_1):PAGE102
 R6P21    1      A RES_0402-1.00K,1%,1/16W,CHIP,GA    I80 @BASEBOARD_FAB2_LIB.BASEBOARD_FAB2(SCH_1):PAGE102

FM_DB1200_SMB_SA1 @BASEBOARD_FAB2_LIB.BASEBOARD_FAB2(SCH_1):FM_DB1200_SMB_SA1
 EU4D2   14   SA_1 NB3W1200L_LCC-IC,H13585-001     I1 @BASEBOARD_FAB2_LIB.BASEBOARD_FAB2(SCH_1):PAGE102
 R4D38    2      B RES_0402-10.0K,1%,1/16W,EMPTY,A    I37 @BASEBOARD_FAB2_LIB.BASEBOARD_FAB2(SCH_1):PAGE102
 R6P20    1      A RES_0402-1.00K,1%,1/16W,CHIP,GA    I81 @BASEBOARD_FAB2_LIB.BASEBOARD_FAB2(SCH_1):PAGE102

FM_DB_PRESENT @BASEBOARD_FAB2_LIB.BASEBOARD_FAB2(SCH_1):FM_DB_PRESENT
  Q1L3    3      C NPN_SM-MMBT3904,IC,C52245-001     I8 @BASEBOARD_FAB2_LIB.BASEBOARD_FAB2(SCH_1):PAGE168
 R1L36    2      B RES_0402-1.00K,1%,1/16W,CHIP,GA    I11 @BASEBOARD_FAB2_LIB.BASEBOARD_FAB2(SCH_1):PAGE168
  Q1L4    2 GATE<0> FET_N_DUAL_SMLF-2N7002DW,FET,DA    I19 @BASEBOARD_FAB2_LIB.BASEBOARD_FAB2(SCH_1):PAGE168

FM_DB_UART_SEL0_N @BASEBOARD_FAB2_LIB.BASEBOARD_FAB2(SCH_1):FM_DB_UART_SEL0_N
 CR1L1    2      A DIODE_SM-1N4148W,IC,D89194-001     I2 @BASEBOARD_FAB2_LIB.BASEBOARD_FAB2(SCH_1):PAGE168
  R1L6    2      B RES_0402-0.0,5%,1/16W,CHIP,G21A     I6 @BASEBOARD_FAB2_LIB.BASEBOARD_FAB2(SCH_1):PAGE168

FM_DB_UART_SEL1_N @BASEBOARD_FAB2_LIB.BASEBOARD_FAB2(SCH_1):FM_DB_UART_SEL1_N
 CR1L1    1      C DIODE_SM-1N4148W,IC,D89194-001     I2 @BASEBOARD_FAB2_LIB.BASEBOARD_FAB2(SCH_1):PAGE168
 CR1L2    2      A DIODE_SM-1N4148W,IC,D89194-001     I3 @BASEBOARD_FAB2_LIB.BASEBOARD_FAB2(SCH_1):PAGE168

FM_DB_UART_SEL2_N @BASEBOARD_FAB2_LIB.BASEBOARD_FAB2(SCH_1):FM_DB_UART_SEL2_N
 CR1L2    1      C DIODE_SM-1N4148W,IC,D89194-001     I3 @BASEBOARD_FAB2_LIB.BASEBOARD_FAB2(SCH_1):PAGE168
 CR1L3    2      A DIODE_SM-1N4148W,IC,D89194-001     I4 @BASEBOARD_FAB2_LIB.BASEBOARD_FAB2(SCH_1):PAGE168

FM_DB_UART_SEL3_N @BASEBOARD_FAB2_LIB.BASEBOARD_FAB2(SCH_1):FM_DB_UART_SEL3_N
 CR1L3    1      C DIODE_SM-1N4148W,IC,D89194-001     I4 @BASEBOARD_FAB2_LIB.BASEBOARD_FAB2(SCH_1):PAGE168
 CR1L4    2      A DIODE_SM-1N4148W,IC,D89194-001     I5 @BASEBOARD_FAB2_LIB.BASEBOARD_FAB2(SCH_1):PAGE168

FM_DB_UART_SEL4_N @BASEBOARD_FAB2_LIB.BASEBOARD_FAB2(SCH_1):FM_DB_UART_SEL4_N
 CR1L4    1      C DIODE_SM-1N4148W,IC,D89194-001     I5 @BASEBOARD_FAB2_LIB.BASEBOARD_FAB2(SCH_1):PAGE168
  Q1L3    1      B NPN_SM-MMBT3904,IC,C52245-001     I8 @BASEBOARD_FAB2_LIB.BASEBOARD_FAB2(SCH_1):PAGE168

FM_DEBUG_RST_BTN_N @BASEBOARD_FAB2_LIB.BASEBOARD_FAB2(SCH_1):FM_DEBUG_RST_BTN_N
 R1L29    2      B RES_0402-33.2,1%,1/16W,CHIP,G2A    I68 @BASEBOARD_FAB2_LIB.BASEBOARD_FAB2(SCH_1):PAGE111
  J9A2   11   IO11 CONN14_H54902001_PIP-CONN,H549A   I171 @BASEBOARD_FAB2_LIB.BASEBOARD_FAB2(SCH_1):PAGE155
 R1L22    1      A RES_0402-200.0,1%,1/16W,CHIP,GA    I22 @BASEBOARD_FAB2_LIB.BASEBOARD_FAB2(SCH_1):PAGE175
 R1L19    2      B RES_0402-4.75K,1%,1/16W,EMPTY,A    I24 @BASEBOARD_FAB2_LIB.BASEBOARD_FAB2(SCH_1):PAGE175
  S9A1    1   PIN1 SWITCH_D37771002_SM-IC,D37771-A    I78 @BASEBOARD_FAB2_LIB.BASEBOARD_FAB2(SCH_1):PAGE175
  S9A1    2   PIN2 SWITCH_D37771002_SM-IC,D37771-A    I78 @BASEBOARD_FAB2_LIB.BASEBOARD_FAB2(SCH_1):PAGE175
  U8D7   G5   PL4C LCMXO2_A_256BGA-IC,H63395-001   I179 @BASEBOARD_FAB2_LIB.BASEBOARD_FAB2(SCH_1):PAGE190
  U6W1   13    P10 PCA9555PWRG4-GP_DISCRET-G5-PCAA    I97 @BASEBOARD_FAB2_LIB.BASEBOARD_FAB2(SCH_1):PAGE247

FM_DEBUG_RST_BTN_R1_N @BASEBOARD_FAB2_LIB.BASEBOARD_FAB2(SCH_1):FM_DEBUG_RST_BTN_R1_N
 R1L28    2      B RES_0402-4.75K,1%,1/16W,CHIP,GA    I66 @BASEBOARD_FAB2_LIB.BASEBOARD_FAB2(SCH_1):PAGE111
 R1L29    1      A RES_0402-33.2,1%,1/16W,CHIP,G2A    I68 @BASEBOARD_FAB2_LIB.BASEBOARD_FAB2(SCH_1):PAGE111
  U1L4    4      Y TTL1G07_A_SOP-74LVC1G07,IC,C88B    I85 @BASEBOARD_FAB2_LIB.BASEBOARD_FAB2(SCH_1):PAGE111

FM_DIMM_EVENT_COD_N @BASEBOARD_FAB2_LIB.BASEBOARD_FAB2(SCH_1):FM_DIMM_EVENT_COD_N
  J4G1   78 EVENT_N SCONN288_H44441004_PIP-SCONN,HA     I1 @BASEBOARD_FAB2_LIB.BASEBOARD_FAB2(SCH_1):PAGE43
  J6T1   78 EVENT_N SCONN288_H44441003_PIP-SCONN,HA    I13 @BASEBOARD_FAB2_LIB.BASEBOARD_FAB2(SCH_1):PAGE44
  J4G2   78 EVENT_N SCONN288_H44441004_PIP-SCONN,HA   I111 @BASEBOARD_FAB2_LIB.BASEBOARD_FAB2(SCH_1):PAGE45
  J6U1   78 EVENT_N SCONN288_H44441003_PIP-SCONN,HA    I14 @BASEBOARD_FAB2_LIB.BASEBOARD_FAB2(SCH_1):PAGE46
  J4G3   78 EVENT_N SCONN288_H44441004_PIP-SCONN,HA   I111 @BASEBOARD_FAB2_LIB.BASEBOARD_FAB2(SCH_1):PAGE47
  J6U2   78 EVENT_N SCONN288_H44441003_PIP-SCONN,HA   I111 @BASEBOARD_FAB2_LIB.BASEBOARD_FAB2(SCH_1):PAGE48
  J4B1   78 EVENT_N SCONN288_H44441004_PIP-SCONN,HA   I111 @BASEBOARD_FAB2_LIB.BASEBOARD_FAB2(SCH_1):PAGE49
  J6M1   78 EVENT_N SCONN288_H44441003_PIP-SCONN,HA   I158 @BASEBOARD_FAB2_LIB.BASEBOARD_FAB2(SCH_1):PAGE50
  J4A2   78 EVENT_N SCONN288_H44441004_PIP-SCONN,HA   I111 @BASEBOARD_FAB2_LIB.BASEBOARD_FAB2(SCH_1):PAGE51
  J6L2   78 EVENT_N SCONN288_H44441003_PIP-SCONN,HA    I12 @BASEBOARD_FAB2_LIB.BASEBOARD_FAB2(SCH_1):PAGE52
  J4A1   78 EVENT_N SCONN288_H44441004_PIP-SCONN,HA   I111 @BASEBOARD_FAB2_LIB.BASEBOARD_FAB2(SCH_1):PAGE53
  J6L1   78 EVENT_N SCONN288_H44441003_PIP-SCONN,HA   I111 @BASEBOARD_FAB2_LIB.BASEBOARD_FAB2(SCH_1):PAGE54
  J1G1   78 EVENT_N SCONN288_H44441004_PIP-SCONN,HA   I111 @BASEBOARD_FAB2_LIB.BASEBOARD_FAB2(SCH_1):PAGE77
  J9T1   78 EVENT_N SCONN288_H44441003_PIP-SCONN,HA    I13 @BASEBOARD_FAB2_LIB.BASEBOARD_FAB2(SCH_1):PAGE78
  J1G2   78 EVENT_N SCONN288_H44441004_PIP-SCONN,HA   I111 @BASEBOARD_FAB2_LIB.BASEBOARD_FAB2(SCH_1):PAGE79
  J9U1   78 EVENT_N SCONN288_H44441003_PIP-SCONN,HA    I24 @BASEBOARD_FAB2_LIB.BASEBOARD_FAB2(SCH_1):PAGE80
  J1G3   78 EVENT_N SCONN288_H44441004_PIP-SCONN,HA   I186 @BASEBOARD_FAB2_LIB.BASEBOARD_FAB2(SCH_1):PAGE81
  J9U2   78 EVENT_N SCONN288_H44441003_PIP-SCONN,HA   I187 @BASEBOARD_FAB2_LIB.BASEBOARD_FAB2(SCH_1):PAGE82
  J1B1   78 EVENT_N SCONN288_H44441004_PIP-SCONN,HA   I111 @BASEBOARD_FAB2_LIB.BASEBOARD_FAB2(SCH_1):PAGE83
  J9M1   78 EVENT_N SCONN288_H44441003_PIP-SCONN,HA    I14 @BASEBOARD_FAB2_LIB.BASEBOARD_FAB2(SCH_1):PAGE84
  J1A2   78 EVENT_N SCONN288_H44441004_PIP-SCONN,HA   I111 @BASEBOARD_FAB2_LIB.BASEBOARD_FAB2(SCH_1):PAGE85
  J9L2   78 EVENT_N SCONN288_H44441003_PIP-SCONN,HA    I12 @BASEBOARD_FAB2_LIB.BASEBOARD_FAB2(SCH_1):PAGE86
  J1A1   78 EVENT_N SCONN288_H44441004_PIP-SCONN,HA   I186 @BASEBOARD_FAB2_LIB.BASEBOARD_FAB2(SCH_1):PAGE87
  J9L1   78 EVENT_N SCONN288_H44441003_PIP-SCONN,HA   I111 @BASEBOARD_FAB2_LIB.BASEBOARD_FAB2(SCH_1):PAGE88
  Q4U1    2 GATE<0> FET_N_DUAL_SMLF-NTJD4001N,FET,A    I98 @BASEBOARD_FAB2_LIB.BASEBOARD_FAB2(SCH_1):PAGE94
  R4U2    2      B RES_0402-2.21K,1%,1/16W,CHIP,GA   I100 @BASEBOARD_FAB2_LIB.BASEBOARD_FAB2(SCH_1):PAGE94

FM_DIMM_EVENT_FET @BASEBOARD_FAB2_LIB.BASEBOARD_FAB2(SCH_1):FM_DIMM_EVENT_FET
  R4U3    2      B RES_0402-4.75K,1%,1/16W,CHIP,GA    I94 @BASEBOARD_FAB2_LIB.BASEBOARD_FAB2(SCH_1):PAGE94
  Q4U1    6 DRAIN<0> FET_N_DUAL_SMLF-NTJD4001N,FET,A    I98 @BASEBOARD_FAB2_LIB.BASEBOARD_FAB2(SCH_1):PAGE94
  Q4U1    5 GATE<0> FET_N_DUAL_SMLF-NTJD4001N,FET,A   I102 @BASEBOARD_FAB2_LIB.BASEBOARD_FAB2(SCH_1):PAGE94
  R4U4    1      A RES_0402-33.0K,5%,1/16W,CHIP,GA   I104 @BASEBOARD_FAB2_LIB.BASEBOARD_FAB2(SCH_1):PAGE94

FM_DISABLE_FAN_N @BASEBOARD_FAB2_LIB.BASEBOARD_FAB2(SCH_1):FM_DISABLE_FAN_N
  U1E2    2   B<0> TTL1G08_SOTLF-NC7SZ08,IC,D1032B   I121 @BASEBOARD_FAB2_LIB.BASEBOARD_FAB2(SCH_1):PAGE161
 CR9P2    2      A DIODE_SMLF-BAT54WS,IC,C73510-0A   I213 @BASEBOARD_FAB2_LIB.BASEBOARD_FAB2(SCH_1):PAGE200
 CR9P1    2      A DIODE_SMLF-BAT54WS,IC,C73510-0A   I214 @BASEBOARD_FAB2_LIB.BASEBOARD_FAB2(SCH_1):PAGE200
  R9P5    2      B RES_0402-10.0K,1%,1/16W,CHIP,GA   I215 @BASEBOARD_FAB2_LIB.BASEBOARD_FAB2(SCH_1):PAGE200

FM_DIS_ADR_DLY @BASEBOARD_FAB2_LIB.BASEBOARD_FAB2(SCH_1):FM_DIS_ADR_DLY
 R2P19    2      B RES_0402-10.0K,1%,1/16W,CHIP,GA   I107 @BASEBOARD_FAB2_LIB.BASEBOARD_FAB2(SCH_1):PAGE135
  J8G2   10   IO10 CONN12_C73564003_PIP-CONN,C735A   I124 @BASEBOARD_FAB2_LIB.BASEBOARD_FAB2(SCH_1):PAGE135
  U8D7   T3   PB6C LCMXO2_A_256BGA-IC,H63395-001   I179 @BASEBOARD_FAB2_LIB.BASEBOARD_FAB2(SCH_1):PAGE190

FM_DUAL_BIOS_SEL_N @BASEBOARD_FAB2_LIB.BASEBOARD_FAB2(SCH_1):FM_DUAL_BIOS_SEL_N
  U2T3    1      A TTL1G32_A_SOT-74LVC1G32,IC,E60B    I99 @BASEBOARD_FAB2_LIB.BASEBOARD_FAB2(SCH_1):PAGE154
 R2T11    2      B RES_0402-4.75K,1%,1/16W,CHIP,GA   I105 @BASEBOARD_FAB2_LIB.BASEBOARD_FAB2(SCH_1):PAGE154
  Q8F1    3    DRN FET_N_SOT23LF-2N7002,FET,C7925A   I126 @BASEBOARD_FAB2_LIB.BASEBOARD_FAB2(SCH_1):PAGE154

FM_ENABLE_FAN_POWER @BASEBOARD_FAB2_LIB.BASEBOARD_FAB2(SCH_1):FM_ENABLE_FAN_POWER
 R1E11    2      B RES_0402-10.0K,1%,1/16W,EMPTY,A   I120 @BASEBOARD_FAB2_LIB.BASEBOARD_FAB2(SCH_1):PAGE161
  U1E2    4   Y<0> TTL1G08_SOTLF-NC7SZ08,IC,D1032B   I121 @BASEBOARD_FAB2_LIB.BASEBOARD_FAB2(SCH_1):PAGE161
  J1F1   I3  GNDI3 CONN76_H22707001_THMT1-CONN,H2A   I111 @BASEBOARD_FAB2_LIB.BASEBOARD_FAB2(SCH_1):PAGE181
 EU9M1    2     ON SLG55021_SM-IC,G56246-001    I69 @BASEBOARD_FAB2_LIB.BASEBOARD_FAB2(SCH_1):PAGE198

FM_FAST_PROCHOT_AND_OUT_0_N @BASEBOARD_FAB2_LIB.BASEBOARD_FAB2(SCH_1):FM_FAST_PROCHOT_AND_OUT_0_N
  U8E1    3   Y<0> TTL08_QFN15-74LVC08A,IC,D90404B    I10 @BASEBOARD_FAB2_LIB.BASEBOARD_FAB2(SCH_1):PAGE170
  U8E1   12   A<0> TTL08_QFN15-74LVC08A,IC,D90404B    I12 @BASEBOARD_FAB2_LIB.BASEBOARD_FAB2(SCH_1):PAGE170

FM_FAST_PROCHOT_AND_OUT_1_N @BASEBOARD_FAB2_LIB.BASEBOARD_FAB2(SCH_1):FM_FAST_PROCHOT_AND_OUT_1_N
  U8E1    6   Y<0> TTL08_QFN15-74LVC08A,IC,D90404B    I11 @BASEBOARD_FAB2_LIB.BASEBOARD_FAB2(SCH_1):PAGE170
  U8E1   13   B<0> TTL08_QFN15-74LVC08A,IC,D90404B    I12 @BASEBOARD_FAB2_LIB.BASEBOARD_FAB2(SCH_1):PAGE170

FM_FAST_PROCHOT_EN @BASEBOARD_FAB2_LIB.BASEBOARD_FAB2(SCH_1):FM_FAST_PROCHOT_EN
  U1R2    1     OE TTL1G126_A_SOT-74HC1G126,IC,A7B    I20 @BASEBOARD_FAB2_LIB.BASEBOARD_FAB2(SCH_1):PAGE170
  R9F3    2      B RES_0402-4.75K,1%,1/16W,CHIP,GA    I65 @BASEBOARD_FAB2_LIB.BASEBOARD_FAB2(SCH_1):PAGE170
  Q8F2    3    DRN FET_N_SOT23LF-2N7002,FET,C7925A    I67 @BASEBOARD_FAB2_LIB.BASEBOARD_FAB2(SCH_1):PAGE170

FM_FAST_PROCHOT_EN_N @BASEBOARD_FAB2_LIB.BASEBOARD_FAB2(SCH_1):FM_FAST_PROCHOT_EN_N
  U7C1 BH17 GPP_B21 LBG_CORE_QAT_EXT_D_BGA1-IC,H91A   I115 @BASEBOARD_FAB2_LIB.BASEBOARD_FAB2(SCH_1):PAGE119
  R2T3    2      B RES_0402-4.75K,1%,1/16W,CHIP,GA    I54 @BASEBOARD_FAB2_LIB.BASEBOARD_FAB2(SCH_1):PAGE170
  Q8F2    1   GATE FET_N_SOT23LF-2N7002,FET,C7925A    I67 @BASEBOARD_FAB2_LIB.BASEBOARD_FAB2(SCH_1):PAGE170
 U25W4  E16 GPIOG3_SGPS1I1 AST2520A1-GP-GP_ASIC2-GB1-AST2A    I95 @BASEBOARD_FAB2_LIB.BASEBOARD_FAB2(SCH_1):PAGE144

FM_FAST_PROCHOT_THROTTLE_DLY_BU @BASEBOARD_FAB2_LIB.BASEBOARD_FAB2(SCH_1):FM_FAST_PROCHOT_THROTTLE_DLY_BUF_N
  U1R2    4      Y TTL1G126_A_SOT-74HC1G126,IC,A7B    I20 @BASEBOARD_FAB2_LIB.BASEBOARD_FAB2(SCH_1):PAGE170
  U1R1    2      A TTL1G07_A_SOP-74LVC1G07,IC,C88B    I46 @BASEBOARD_FAB2_LIB.BASEBOARD_FAB2(SCH_1):PAGE170
  R1R5    2      B RES_0402-4.75K,1%,1/16W,CHIP,GA    I73 @BASEBOARD_FAB2_LIB.BASEBOARD_FAB2(SCH_1):PAGE170

FM_FAST_PROCHOT_THROTTLE_DLY_N @BASEBOARD_FAB2_LIB.BASEBOARD_FAB2(SCH_1):FM_FAST_PROCHOT_THROTTLE_DLY_N
  U1R2    2      A TTL1G126_A_SOT-74HC1G126,IC,A7B    I20 @BASEBOARD_FAB2_LIB.BASEBOARD_FAB2(SCH_1):PAGE170
  U8D7  J12   PR6D LCMXO2_A_256BGA-IC,H63395-001    I59 @BASEBOARD_FAB2_LIB.BASEBOARD_FAB2(SCH_1):PAGE191

FM_FAST_PROCHOT_THROTTLE_IN_N @BASEBOARD_FAB2_LIB.BASEBOARD_FAB2(SCH_1):FM_FAST_PROCHOT_THROTTLE_IN_N
  U8E1   11   Y<0> TTL08_QFN15-74LVC08A,IC,D90404B    I12 @BASEBOARD_FAB2_LIB.BASEBOARD_FAB2(SCH_1):PAGE170
  U8D7  G16   PR6A LCMXO2_A_256BGA-IC,H63395-001    I59 @BASEBOARD_FAB2_LIB.BASEBOARD_FAB2(SCH_1):PAGE191

FM_FLASH_ATTACH_CFG_STRAP @BASEBOARD_FAB2_LIB.BASEBOARD_FAB2(SCH_1):FM_FLASH_ATTACH_CFG_STRAP
  U7C1  BB1 GPP_H12_SML2ALERT_N_IE_N LBG_CORE_QAT_EXT_D_BGA1-IC,H91A   I147 @BASEBOARD_FAB2_LIB.BASEBOARD_FAB2(SCH_1):PAGE120
 R3P62    2      B RES_0402-4.75K,1%,1/16W,EMPTY,A    I22 @BASEBOARD_FAB2_LIB.BASEBOARD_FAB2(SCH_1):PAGE126
 R3P64    1      A RES_0402-1.00K,1%,1/16W,EMPTY,A    I23 @BASEBOARD_FAB2_LIB.BASEBOARD_FAB2(SCH_1):PAGE126

FM_FLASH_DESC_OVERRIDE @BASEBOARD_FAB2_LIB.BASEBOARD_FAB2(SCH_1):FM_FLASH_DESC_OVERRIDE
  U7C1  U24 HDA_SDO LBG_CORE_QAT_EXT_D_BGA1-IC,H91A    I34 @BASEBOARD_FAB2_LIB.BASEBOARD_FAB2(SCH_1):PAGE121
  R3N2    2      B RES_0402-4.75K,1%,1/16W,EMPTY,A    I72 @BASEBOARD_FAB2_LIB.BASEBOARD_FAB2(SCH_1):PAGE125
 R1T24    2      B RES_0402-0.0,5%,1/16W,EMPTY,G2A    I82 @BASEBOARD_FAB2_LIB.BASEBOARD_FAB2(SCH_1):PAGE144

FM_FLASH_DESC_OVERRIDE_R @BASEBOARD_FAB2_LIB.BASEBOARD_FAB2(SCH_1):FM_FLASH_DESC_OVERRIDE_R
 R1T24    1      A RES_0402-0.0,5%,1/16W,EMPTY,G2A    I82 @BASEBOARD_FAB2_LIB.BASEBOARD_FAB2(SCH_1):PAGE144
 U25W4  C16 GPIOI3_SYSMISO AST2520A1-GP-GP_ASIC2-GB1-AST2A    I95 @BASEBOARD_FAB2_LIB.BASEBOARD_FAB2(SCH_1):PAGE144

FM_FORCE_ADR_N @BASEBOARD_FAB2_LIB.BASEBOARD_FAB2(SCH_1):FM_FORCE_ADR_N
  U7C1 AR13 GPP_F15_USB2_OC4_N LBG_CORE_QAT_EXT_D_BGA1-IC,H91A   I147 @BASEBOARD_FAB2_LIB.BASEBOARD_FAB2(SCH_1):PAGE120
  U8D7   D7  PT13D LCMXO2_A_256BGA-IC,H63395-001    I59 @BASEBOARD_FAB2_LIB.BASEBOARD_FAB2(SCH_1):PAGE191
  R2R7    2      B RES_0402-4.75K,1%,1/16W,CHIP,GA   I172 @BASEBOARD_FAB2_LIB.BASEBOARD_FAB2(SCH_1):PAGE191
 U25W4  C13 GPIOA6_TIMER7_MDC2 AST2520A1-GP-GP_ASIC2-GB1-AST2A   I106 @BASEBOARD_FAB2_LIB.BASEBOARD_FAB2(SCH_1):PAGE147

FM_GBE0_LVC3_MOD_ABS @BASEBOARD_FAB2_LIB.BASEBOARD_FAB2(SCH_1):FM_GBE0_LVC3_MOD_ABS
  U7C1 BV10 GPP_J16_LAN_SDP_P0_0 LBG_CORE_QAT_EXT_D_BGA1-IC,H91A   I147 @BASEBOARD_FAB2_LIB.BASEBOARD_FAB2(SCH_1):PAGE120
  J8E4   37   IO37 SCONN64_H87568002_A_SMT-CONN,HA    I27 @BASEBOARD_FAB2_LIB.BASEBOARD_FAB2(SCH_1):PAGE188

FM_GBE1_LVC3_MOD_ABS @BASEBOARD_FAB2_LIB.BASEBOARD_FAB2(SCH_1):FM_GBE1_LVC3_MOD_ABS
  U7C1 BY10 GPP_J18_LAN_SDP_P1_0 LBG_CORE_QAT_EXT_D_BGA1-IC,H91A   I147 @BASEBOARD_FAB2_LIB.BASEBOARD_FAB2(SCH_1):PAGE120
  J8E4   38   IO38 SCONN64_H87568002_A_SMT-CONN,HA    I27 @BASEBOARD_FAB2_LIB.BASEBOARD_FAB2(SCH_1):PAGE188

FM_GBE2_LVC3_MOD_ABS @BASEBOARD_FAB2_LIB.BASEBOARD_FAB2(SCH_1):FM_GBE2_LVC3_MOD_ABS
  U7C1 BW13 GPP_J20_LAN_SDP_P2_0 LBG_CORE_QAT_EXT_D_BGA1-IC,H91A   I147 @BASEBOARD_FAB2_LIB.BASEBOARD_FAB2(SCH_1):PAGE120
  J8E4   31   IO31 SCONN64_H87568002_A_SMT-CONN,HA    I27 @BASEBOARD_FAB2_LIB.BASEBOARD_FAB2(SCH_1):PAGE188

FM_GBE3_LVC3_MOD_ABS @BASEBOARD_FAB2_LIB.BASEBOARD_FAB2(SCH_1):FM_GBE3_LVC3_MOD_ABS
  U7C1 BY12 GPP_J22_LAN_SDP_P3_0 LBG_CORE_QAT_EXT_D_BGA1-IC,H91A   I147 @BASEBOARD_FAB2_LIB.BASEBOARD_FAB2(SCH_1):PAGE120
  J8E4   32   IO32 SCONN64_H87568002_A_SMT-CONN,HA    I27 @BASEBOARD_FAB2_LIB.BASEBOARD_FAB2(SCH_1):PAGE188

FM_GBE_LOM_DISABLE_N @BASEBOARD_FAB2_LIB.BASEBOARD_FAB2(SCH_1):FM_GBE_LOM_DISABLE_N
  U7C1  A13 GPD11_GBEPHY LBG_CORE_QAT_EXT_D_BGA1-IC,H91A    I73 @BASEBOARD_FAB2_LIB.BASEBOARD_FAB2(SCH_1):PAGE118
 R8C24    1      A RES_0402-0.0,5%,1/16W,CHIP,G21A   I120 @BASEBOARD_FAB2_LIB.BASEBOARD_FAB2(SCH_1):PAGE118
 R8C23    1      A RES_0402-0.0,5%,1/16W,EMPTY,G2A   I125 @BASEBOARD_FAB2_LIB.BASEBOARD_FAB2(SCH_1):PAGE118
  R2N6    2      B RES_0402-10.0K,1%,1/16W,CHIP,GA   I128 @BASEBOARD_FAB2_LIB.BASEBOARD_FAB2(SCH_1):PAGE118

FM_GLOBAL_RST_WARN_N @BASEBOARD_FAB2_LIB.BASEBOARD_FAB2(SCH_1):FM_GLOBAL_RST_WARN_N
  U7C1 BL18 GPP_B12_GLB_RST_WARN_N LBG_CORE_QAT_EXT_D_BGA1-IC,H91A   I115 @BASEBOARD_FAB2_LIB.BASEBOARD_FAB2(SCH_1):PAGE119
  U8D7   P1  PL13D LCMXO2_A_256BGA-IC,H63395-001   I179 @BASEBOARD_FAB2_LIB.BASEBOARD_FAB2(SCH_1):PAGE190

FM_HBW_BYPASS_LOWBW_N @BASEBOARD_FAB2_LIB.BASEBOARD_FAB2(SCH_1):FM_HBW_BYPASS_LOWBW_N
 EU4D2    5 HBW_BYPASS_LOBW_N NB3W1200L_LCC-IC,H13585-001     I1 @BASEBOARD_FAB2_LIB.BASEBOARD_FAB2(SCH_1):PAGE102
 R6P22    1      A RES_0402-4.75K,1%,1/16W,EMPTY,A    I47 @BASEBOARD_FAB2_LIB.BASEBOARD_FAB2(SCH_1):PAGE102
 R4D41    2      B RES_0402-4.75K,1%,1/16W,CHIP,GA    I53 @BASEBOARD_FAB2_LIB.BASEBOARD_FAB2(SCH_1):PAGE102

FM_HEARTBEAT_LED @BASEBOARD_FAB2_LIB.BASEBOARD_FAB2(SCH_1):FM_HEARTBEAT_LED
  Q9E1    5 GATE<0> FET_N_DUAL_SMLF-NTJD4001N,FET,A   I109 @BASEBOARD_FAB2_LIB.BASEBOARD_FAB2(SCH_1):PAGE149
 R9E21    2      B RES_0402-4.75K,1%,1/16W,CHIP,GA   I111 @BASEBOARD_FAB2_LIB.BASEBOARD_FAB2(SCH_1):PAGE149
  Q9E1    6 DRAIN<0> FET_N_DUAL_SMLF-NTJD4001N,FET,A   I113 @BASEBOARD_FAB2_LIB.BASEBOARD_FAB2(SCH_1):PAGE149

FM_HEARTBEAT_LED_A @BASEBOARD_FAB2_LIB.BASEBOARD_FAB2(SCH_1):FM_HEARTBEAT_LED_A
 R9E24    1      A RES_0402-221,1.0%,1/16W,CHIP,GA    I94 @BASEBOARD_FAB2_LIB.BASEBOARD_FAB2(SCH_1):PAGE149
 DS9E1    1      A LED_A1LF-GREEN,IC,C97278-010    I98 @BASEBOARD_FAB2_LIB.BASEBOARD_FAB2(SCH_1):PAGE149

FM_HEARTBEAT_LED_K @BASEBOARD_FAB2_LIB.BASEBOARD_FAB2(SCH_1):FM_HEARTBEAT_LED_K
 DS9E1    2      C LED_A1LF-GREEN,IC,C97278-010    I98 @BASEBOARD_FAB2_LIB.BASEBOARD_FAB2(SCH_1):PAGE149
  Q9E1    3 DRAIN<0> FET_N_DUAL_SMLF-NTJD4001N,FET,A   I109 @BASEBOARD_FAB2_LIB.BASEBOARD_FAB2(SCH_1):PAGE149

FM_HSC_TIMER_EXP_N @BASEBOARD_FAB2_LIB.BASEBOARD_FAB2(SCH_1):FM_HSC_TIMER_EXP_N
  U7C1  AK9 GPP_F1_SATAXPCIE4_SATAGP4 LBG_CORE_QAT_EXT_D_BGA1-IC,H91A   I147 @BASEBOARD_FAB2_LIB.BASEBOARD_FAB2(SCH_1):PAGE120
  U8E1    5   B<0> TTL08_QFN15-74LVC08A,IC,D90404B    I11 @BASEBOARD_FAB2_LIB.BASEBOARD_FAB2(SCH_1):PAGE170
 R9P20    2      B RES_0402-2.7K,1%,1/16W,CHIP,G2A    I86 @BASEBOARD_FAB2_LIB.BASEBOARD_FAB2(SCH_1):PAGE200
  U9P2    1   OUTB TPS3700_SM-IC,H69492-001   I200 @BASEBOARD_FAB2_LIB.BASEBOARD_FAB2(SCH_1):PAGE200
 U25W4   U1 GPIOL2_NDSR1 AST2520A1-GP-GP_ASIC2-GB1-AST2A   I117 @BASEBOARD_FAB2_LIB.BASEBOARD_FAB2(SCH_1):PAGE145

FM_IE_DISABLE_N @BASEBOARD_FAB2_LIB.BASEBOARD_FAB2(SCH_1):FM_IE_DISABLE_N
  U7C1 AU13 GPP_F16_USB2_OC5_N LBG_CORE_QAT_EXT_D_BGA1-IC,H91A   I147 @BASEBOARD_FAB2_LIB.BASEBOARD_FAB2(SCH_1):PAGE120
 R8D21    2      B RES_0402-1.00K,1%,1/16W,CHIP,GA   I120 @BASEBOARD_FAB2_LIB.BASEBOARD_FAB2(SCH_1):PAGE135
  J8G2    4    IO4 CONN12_C73564003_PIP-CONN,C735A   I124 @BASEBOARD_FAB2_LIB.BASEBOARD_FAB2(SCH_1):PAGE135
  U8D7   L9  PB12D LCMXO2_A_256BGA-IC,H63395-001   I179 @BASEBOARD_FAB2_LIB.BASEBOARD_FAB2(SCH_1):PAGE190

FM_INTRUDER_HDR_PCH_N @BASEBOARD_FAB2_LIB.BASEBOARD_FAB2(SCH_1):FM_INTRUDER_HDR_PCH_N
  U7C1 AG18 INTRUDER_N LBG_CORE_QAT_EXT_D_BGA1-IC,H91A    I34 @BASEBOARD_FAB2_LIB.BASEBOARD_FAB2(SCH_1):PAGE121
 R3N10    2      B RES_0402-10.0K,1%,1/16W,CHIP,GA    I37 @BASEBOARD_FAB2_LIB.BASEBOARD_FAB2(SCH_1):PAGE121

FM_JTAG_PLD_EN_DEBUG @BASEBOARD_FAB2_LIB.BASEBOARD_FAB2(SCH_1):FM_JTAG_PLD_EN_DEBUG
 R3R15    2      B RES_0402-1.00K,1%,1/16W,CHIP,GA    I44 @BASEBOARD_FAB2_LIB.BASEBOARD_FAB2(SCH_1):PAGE189
 R3R11    1      A RES_0402-10.0K,1%,1/16W,EMPTY,A    I45 @BASEBOARD_FAB2_LIB.BASEBOARD_FAB2(SCH_1):PAGE189
  U8D7  C10 PT20C_JTAGENB LCMXO2_A_256BGA-IC,H63395-001    I59 @BASEBOARD_FAB2_LIB.BASEBOARD_FAB2(SCH_1):PAGE191

FM_M2_DET_LVC3 @BASEBOARD_FAB2_LIB.BASEBOARD_FAB2(SCH_1):FM_M2_DET_LVC3
  U2P1    4      Y TTL1G07_A_SOP-74LVC1G07,IC,C88B   I110 @BASEBOARD_FAB2_LIB.BASEBOARD_FAB2(SCH_1):PAGE185
 R2P16    2      B RES_0402-10.0K,1%,1/16W,CHIP,GA   I113 @BASEBOARD_FAB2_LIB.BASEBOARD_FAB2(SCH_1):PAGE185
 R2P14    1      A RES_0402-0.0,5%,1/16W,CHIP,G21A   I115 @BASEBOARD_FAB2_LIB.BASEBOARD_FAB2(SCH_1):PAGE185

FM_M2_SSD_PEDET @BASEBOARD_FAB2_LIB.BASEBOARD_FAB2(SCH_1):FM_M2_SSD_PEDET
  J8F1   69  PEDET SCONN75K_H17033002_SMT1-SCONN,A    I53 @BASEBOARD_FAB2_LIB.BASEBOARD_FAB2(SCH_1):PAGE185
  U2P1    2      A TTL1G07_A_SOP-74LVC1G07,IC,C88B   I110 @BASEBOARD_FAB2_LIB.BASEBOARD_FAB2(SCH_1):PAGE185
 R2P15    2      B RES_0402-10.0K,1%,1/16W,CHIP,GA   I111 @BASEBOARD_FAB2_LIB.BASEBOARD_FAB2(SCH_1):PAGE185

FM_MATED_IN_D1_N @BASEBOARD_FAB2_LIB.BASEBOARD_FAB2(SCH_1):FM_MATED_IN_D1_N
 CR1F4    1      C DIODE_SM-SDMK0340L,IC,H71799-0A   I178 @BASEBOARD_FAB2_LIB.BASEBOARD_FAB2(SCH_1):PAGE181
 CR1F3    2      A DIODE_SM-SDMK0340L,IC,H71799-0A   I180 @BASEBOARD_FAB2_LIB.BASEBOARD_FAB2(SCH_1):PAGE181

FM_MATED_IN_D2_N @BASEBOARD_FAB2_LIB.BASEBOARD_FAB2(SCH_1):FM_MATED_IN_D2_N
 CR1F3    1      C DIODE_SM-SDMK0340L,IC,H71799-0A   I180 @BASEBOARD_FAB2_LIB.BASEBOARD_FAB2(SCH_1):PAGE181
  Q9T1    1      B NPN_SM-MMBT3904,IC,C52245-001   I181 @BASEBOARD_FAB2_LIB.BASEBOARD_FAB2(SCH_1):PAGE181

FM_MATED_IN_N @BASEBOARD_FAB2_LIB.BASEBOARD_FAB2(SCH_1):FM_MATED_IN_N
  J1F1   E4   IOE4 CONN76_H22707001_THMT1-CONN,H2A   I111 @BASEBOARD_FAB2_LIB.BASEBOARD_FAB2(SCH_1):PAGE181
  R9T9    2      B RES_0402-4.75K,1%,1/16W,CHIP,GA   I177 @BASEBOARD_FAB2_LIB.BASEBOARD_FAB2(SCH_1):PAGE181
 CR1F4    2      A DIODE_SM-SDMK0340L,IC,H71799-0A   I178 @BASEBOARD_FAB2_LIB.BASEBOARD_FAB2(SCH_1):PAGE181
  J1F3    4    IO4 CONN8_H62179001_PIP-CONN,H6217A   I189 @BASEBOARD_FAB2_LIB.BASEBOARD_FAB2(SCH_1):PAGE181
  R9T8    2      B RES_0402-0.0,5%,1/16W,CHIP,G21A   I278 @BASEBOARD_FAB2_LIB.BASEBOARD_FAB2(SCH_1):PAGE181

FM_MB_SLOT_ID0 @BASEBOARD_FAB2_LIB.BASEBOARD_FAB2(SCH_1):FM_MB_SLOT_ID0
  U7C1   T4 GPP_A13_SUSWARN_N_SUSPWRDNACK LBG_CORE_QAT_EXT_D_BGA1-IC,H91A   I115 @BASEBOARD_FAB2_LIB.BASEBOARD_FAB2(SCH_1):PAGE119
  J1F1   F5  GNDF5 CONN76_H22707001_THMT1-CONN,H2A   I111 @BASEBOARD_FAB2_LIB.BASEBOARD_FAB2(SCH_1):PAGE181
  R7D5    2      B RES_0402-2.26K,1.0%,1/16W,CHIPA   I199 @BASEBOARD_FAB2_LIB.BASEBOARD_FAB2(SCH_1):PAGE181
 U25W4  F19 GPIOD0_SD2CLK AST2520A1-GP-GP_ASIC2-GB1-AST2A   I117 @BASEBOARD_FAB2_LIB.BASEBOARD_FAB2(SCH_1):PAGE145

FM_MB_SLOT_ID1 @BASEBOARD_FAB2_LIB.BASEBOARD_FAB2(SCH_1):FM_MB_SLOT_ID1
  U7C1  AB3 GPP_A14_ESPI_RESET_N LBG_CORE_QAT_EXT_D_BGA1-IC,H91A   I115 @BASEBOARD_FAB2_LIB.BASEBOARD_FAB2(SCH_1):PAGE119
  J1F1   G5   IOG5 CONN76_H22707001_THMT1-CONN,H2A   I111 @BASEBOARD_FAB2_LIB.BASEBOARD_FAB2(SCH_1):PAGE181
  R7D9    2      B RES_0402-2.26K,1.0%,1/16W,CHIPA   I200 @BASEBOARD_FAB2_LIB.BASEBOARD_FAB2(SCH_1):PAGE181
 U25W4  E21 GPIOD1_SD2CMD AST2520A1-GP-GP_ASIC2-GB1-AST2A   I117 @BASEBOARD_FAB2_LIB.BASEBOARD_FAB2(SCH_1):PAGE145

FM_MB_SLOT_ID2 @BASEBOARD_FAB2_LIB.BASEBOARD_FAB2(SCH_1):FM_MB_SLOT_ID2
  U7C1  AC4 GPP_A15_SUSACK_N LBG_CORE_QAT_EXT_D_BGA1-IC,H91A   I115 @BASEBOARD_FAB2_LIB.BASEBOARD_FAB2(SCH_1):PAGE119
  J1F1   H5   IOH5 CONN76_H22707001_THMT1-CONN,H2A   I111 @BASEBOARD_FAB2_LIB.BASEBOARD_FAB2(SCH_1):PAGE181
 R3P61    2      B RES_0402-2.26K,1.0%,1/16W,CHIPA   I201 @BASEBOARD_FAB2_LIB.BASEBOARD_FAB2(SCH_1):PAGE181
 U25W4  F20 GPIOD2_SD2DAT0 AST2520A1-GP-GP_ASIC2-GB1-AST2A   I117 @BASEBOARD_FAB2_LIB.BASEBOARD_FAB2(SCH_1):PAGE145

FM_MEM_EVENT_FUNC @BASEBOARD_FAB2_LIB.BASEBOARD_FAB2(SCH_1):FM_MEM_EVENT_FUNC
  U8D7   D2   PL2D LCMXO2_A_256BGA-IC,H63395-001   I179 @BASEBOARD_FAB2_LIB.BASEBOARD_FAB2(SCH_1):PAGE190
 R7E19    2      B RES_0402-1.00K,1%,1/16W,EMPTY,A    I57 @BASEBOARD_FAB2_LIB.BASEBOARD_FAB2(SCH_1):PAGE192
 R7E20    1      A RES_0402-1.00K,1%,1/16W,CHIP,GA    I59 @BASEBOARD_FAB2_LIB.BASEBOARD_FAB2(SCH_1):PAGE192

FM_MEM_THERM_EVENT_LVT3_N @BASEBOARD_FAB2_LIB.BASEBOARD_FAB2(SCH_1):FM_MEM_THERM_EVENT_LVT3_N
  R4U1    2      B RES_0402-4.75K,1%,1/16W,CHIP,GA    I91 @BASEBOARD_FAB2_LIB.BASEBOARD_FAB2(SCH_1):PAGE94
  Q4U1    3 DRAIN<0> FET_N_DUAL_SMLF-NTJD4001N,FET,A   I102 @BASEBOARD_FAB2_LIB.BASEBOARD_FAB2(SCH_1):PAGE94
 R8E11    1      A RES_0402-0.0,5%,1/16W,EMPTY,G2A   I279 @BASEBOARD_FAB2_LIB.BASEBOARD_FAB2(SCH_1):PAGE156
  U8D7  K13  PR11C LCMXO2_A_256BGA-IC,H63395-001    I59 @BASEBOARD_FAB2_LIB.BASEBOARD_FAB2(SCH_1):PAGE191

FM_MEM_THERM_EVENT_PCH_N @BASEBOARD_FAB2_LIB.BASEBOARD_FAB2(SCH_1):FM_MEM_THERM_EVENT_PCH_N
  U7C1 AL15 GPP_F18_USB2_OC7_N LBG_CORE_QAT_EXT_D_BGA1-IC,H91A   I147 @BASEBOARD_FAB2_LIB.BASEBOARD_FAB2(SCH_1):PAGE120
  U8D7  K12  PR11D LCMXO2_A_256BGA-IC,H63395-001    I59 @BASEBOARD_FAB2_LIB.BASEBOARD_FAB2(SCH_1):PAGE191
 U25W4   P4 GPIOL4_NDTR1_VPIVS AST2520A1-GP-GP_ASIC2-GB1-AST2A   I117 @BASEBOARD_FAB2_LIB.BASEBOARD_FAB2(SCH_1):PAGE145

FM_MEZZA_PRSNT1_N @BASEBOARD_FAB2_LIB.BASEBOARD_FAB2(SCH_1):FM_MEZZA_PRSNT1_N
  R9B7    2      B RES_0402-100.0,1%,1/16W,CHIP,GA   I222 @BASEBOARD_FAB2_LIB.BASEBOARD_FAB2(SCH_1):PAGE186
  J9B3    1    IO1 SCONN120_A28699018_SM-SCONN,A2A   I336 @BASEBOARD_FAB2_LIB.BASEBOARD_FAB2(SCH_1):PAGE186

FM_MEZZ_PRSNTB1_N @BASEBOARD_FAB2_LIB.BASEBOARD_FAB2(SCH_1):FM_MEZZ_PRSNTB1_N
  R2R8    1      A RES_0402-100.0,1%,1/16W,CHIP,GA    I18 @BASEBOARD_FAB2_LIB.BASEBOARD_FAB2(SCH_1):PAGE187
  J8E3    1    IO1 SCONN80_E67482007_SM-CONN,E674A   I119 @BASEBOARD_FAB2_LIB.BASEBOARD_FAB2(SCH_1):PAGE187

FM_ME_RECOVER_N @BASEBOARD_FAB2_LIB.BASEBOARD_FAB2(SCH_1):FM_ME_RECOVER_N
  U7C1   V3 GPP_A19 LBG_CORE_QAT_EXT_D_BGA1-IC,H91A   I115 @BASEBOARD_FAB2_LIB.BASEBOARD_FAB2(SCH_1):PAGE119
 R7G26    2      B RES_0402-10.0K,1%,1/16W,CHIP,GA   I101 @BASEBOARD_FAB2_LIB.BASEBOARD_FAB2(SCH_1):PAGE136
  J7G3    3    IO3 CONN12_C73564003_PIP-CONN,C735A   I174 @BASEBOARD_FAB2_LIB.BASEBOARD_FAB2(SCH_1):PAGE136

FM_MODPRST_HFI0_CPU0_LVT2_N @BASEBOARD_FAB2_LIB.BASEBOARD_FAB2(SCH_1):FM_MODPRST_HFI0_CPU0_LVT2_N
  U5D1 BR20 CD_HFI0_MODPRST_N SKX_EXT_B_BGA1-IC,TBD    I61 @BASEBOARD_FAB2_LIB.BASEBOARD_FAB2(SCH_1):PAGE29
  J8B1    3    IO3 SCONN24_H46321001_SM-SCONN,H46A     I1 @BASEBOARD_FAB2_LIB.BASEBOARD_FAB2(SCH_1):PAGE91
  R8B3    2      B RES_0402-4.75K,1%,1/16W,CHIP,GA    I24 @BASEBOARD_FAB2_LIB.BASEBOARD_FAB2(SCH_1):PAGE91

FM_MODPRST_HFI1_CPU0_LVT2_N @BASEBOARD_FAB2_LIB.BASEBOARD_FAB2(SCH_1):FM_MODPRST_HFI1_CPU0_LVT2_N
  U5D1 BT19 CD_HFI1_MODPRST_N SKX_EXT_B_BGA1-IC,TBD    I61 @BASEBOARD_FAB2_LIB.BASEBOARD_FAB2(SCH_1):PAGE29
  J8B1   11   IO11 SCONN24_H46321001_SM-SCONN,H46A     I1 @BASEBOARD_FAB2_LIB.BASEBOARD_FAB2(SCH_1):PAGE91
 R8B19    2      B RES_0402-4.75K,1%,1/16W,CHIP,GA    I21 @BASEBOARD_FAB2_LIB.BASEBOARD_FAB2(SCH_1):PAGE91

FM_MP_PS_FAIL_N @BASEBOARD_FAB2_LIB.BASEBOARD_FAB2(SCH_1):FM_MP_PS_FAIL_N
  U7C1 AK20 GPP_F2_SATAXPCIE5_SATAGP5 LBG_CORE_QAT_EXT_D_BGA1-IC,H91A   I147 @BASEBOARD_FAB2_LIB.BASEBOARD_FAB2(SCH_1):PAGE120
 R3N12    2      B RES_0402-4.75K,1%,1/16W,CHIP,GA   I342 @BASEBOARD_FAB2_LIB.BASEBOARD_FAB2(SCH_1):PAGE157
  J1F3    3    IO3 CONN8_H62179001_PIP-CONN,H6217A   I189 @BASEBOARD_FAB2_LIB.BASEBOARD_FAB2(SCH_1):PAGE181
  U8D7   H4   PL6C LCMXO2_A_256BGA-IC,H63395-001   I179 @BASEBOARD_FAB2_LIB.BASEBOARD_FAB2(SCH_1):PAGE190
 U25W4  L18 GPIOB2 AST2520A1-GP-GP_ASIC2-GB1-AST2A    I95 @BASEBOARD_FAB2_LIB.BASEBOARD_FAB2(SCH_1):PAGE144

FM_MP_PS_REDUNDANT_LOST_N @BASEBOARD_FAB2_LIB.BASEBOARD_FAB2(SCH_1):FM_MP_PS_REDUNDANT_LOST_N
  U7C1 AK13 GPP_F3_SATAXPCIE6_SATAGP6 LBG_CORE_QAT_EXT_D_BGA1-IC,H91A   I147 @BASEBOARD_FAB2_LIB.BASEBOARD_FAB2(SCH_1):PAGE120
 R3N11    2      B RES_0402-4.75K,1%,1/16W,CHIP,GA   I344 @BASEBOARD_FAB2_LIB.BASEBOARD_FAB2(SCH_1):PAGE157
  J1F3    2    IO2 CONN8_H62179001_PIP-CONN,H6217A   I189 @BASEBOARD_FAB2_LIB.BASEBOARD_FAB2(SCH_1):PAGE181
 U25W4   Y4 GPIOO5_TACH5_VPIR3 AST2520A1-GP-GP_ASIC2-GB1-AST2A   I106 @BASEBOARD_FAB2_LIB.BASEBOARD_FAB2(SCH_1):PAGE147

FM_NMI_EVENT_N @BASEBOARD_FAB2_LIB.BASEBOARD_FAB2(SCH_1):FM_NMI_EVENT_N
  U7C1  BE7 GPP_G18_NMI_N LBG_CORE_QAT_EXT_D_BGA1-IC,H91A   I147 @BASEBOARD_FAB2_LIB.BASEBOARD_FAB2(SCH_1):PAGE120
 R2N25    1      A RES_0402-51.1,1.0%,1/16W,CHIP,A   I302 @BASEBOARD_FAB2_LIB.BASEBOARD_FAB2(SCH_1):PAGE157

FM_OC0_USB_N @BASEBOARD_FAB2_LIB.BASEBOARD_FAB2(SCH_1):FM_OC0_USB_N
  U7C1 BL48 GPP_E9_USB2_OC0_N LBG_CORE_QAT_EXT_D_BGA1-IC,H91A   I147 @BASEBOARD_FAB2_LIB.BASEBOARD_FAB2(SCH_1):PAGE120
  U1M3    3   OC_N TPS2061_SM-IC,H66405-001   I100 @BASEBOARD_FAB2_LIB.BASEBOARD_FAB2(SCH_1):PAGE176
 R1M24    2      B RES_0402-10.0K,1%,1/16W,CHIP,GA   I105 @BASEBOARD_FAB2_LIB.BASEBOARD_FAB2(SCH_1):PAGE176

FM_OCP_MEZZA_PRES_N @BASEBOARD_FAB2_LIB.BASEBOARD_FAB2(SCH_1):FM_OCP_MEZZA_PRES_N
  U7C1  AE2 GPP_A21 LBG_CORE_QAT_EXT_D_BGA1-IC,H91A   I115 @BASEBOARD_FAB2_LIB.BASEBOARD_FAB2(SCH_1):PAGE119
 R7D12    2      B RES_0402-10.0K,1%,1/16W,CHIP,GA   I237 @BASEBOARD_FAB2_LIB.BASEBOARD_FAB2(SCH_1):PAGE133
  J9B3  120  IO120 SCONN120_A28699018_SM-SCONN,A2A   I336 @BASEBOARD_FAB2_LIB.BASEBOARD_FAB2(SCH_1):PAGE186
 U25W4  D13 GPIOA2_TIMER3_SPI1CS1# AST2520A1-GP-GP_ASIC2-GB1-AST2A   I117 @BASEBOARD_FAB2_LIB.BASEBOARD_FAB2(SCH_1):PAGE145

FM_OCP_MEZZB_PRES_N @BASEBOARD_FAB2_LIB.BASEBOARD_FAB2(SCH_1):FM_OCP_MEZZB_PRES_N
  U7C1  AD9 GPP_L8_TESTCH0_D6 LBG_CORE_QAT_EXT_D_BGA1-IC,H91A    I34 @BASEBOARD_FAB2_LIB.BASEBOARD_FAB2(SCH_1):PAGE121
 R7D44    2      B RES_0402-4.75K,1%,1/16W,CHIP,GA   I356 @BASEBOARD_FAB2_LIB.BASEBOARD_FAB2(SCH_1):PAGE133
  J8E3   80   IO80 SCONN80_E67482007_SM-CONN,E674A   I119 @BASEBOARD_FAB2_LIB.BASEBOARD_FAB2(SCH_1):PAGE187
 U25W4  H19 GPIOF5_NRTS4_LHFRAME# AST2520A1-GP-GP_ASIC2-GB1-AST2A   I117 @BASEBOARD_FAB2_LIB.BASEBOARD_FAB2(SCH_1):PAGE145

FM_OCP_MEZZC_PRES_N @BASEBOARD_FAB2_LIB.BASEBOARD_FAB2(SCH_1):FM_OCP_MEZZC_PRES_N
  U7C1 AD17 GPP_L9_TESTCH0_D7 LBG_CORE_QAT_EXT_D_BGA1-IC,H91A    I34 @BASEBOARD_FAB2_LIB.BASEBOARD_FAB2(SCH_1):PAGE121
 R3P53    2      B RES_0402-4.75K,1%,1/16W,CHIP,GA   I357 @BASEBOARD_FAB2_LIB.BASEBOARD_FAB2(SCH_1):PAGE133
  J8E4   64   IO64 SCONN64_H87568002_A_SMT-CONN,HA    I27 @BASEBOARD_FAB2_LIB.BASEBOARD_FAB2(SCH_1):PAGE188
 U25W4  H18 GPIOF7_RXD4_LHRST# AST2520A1-GP-GP_ASIC2-GB1-AST2A   I117 @BASEBOARD_FAB2_LIB.BASEBOARD_FAB2(SCH_1):PAGE145

FM_OC_DETECT_EN @BASEBOARD_FAB2_LIB.BASEBOARD_FAB2(SCH_1):FM_OC_DETECT_EN
  U1D1    1     OE TTL1G126_A_SOT-74HC1G126,IC,A7B   I103 @BASEBOARD_FAB2_LIB.BASEBOARD_FAB2(SCH_1):PAGE200
  Q1D2    3    DRN FET_N_SOT23LF-2N7002,FET,C7925A   I203 @BASEBOARD_FAB2_LIB.BASEBOARD_FAB2(SCH_1):PAGE200
 R1D21    2      B RES_0402-4.75K,1%,1/16W,CHIP,GA   I204 @BASEBOARD_FAB2_LIB.BASEBOARD_FAB2(SCH_1):PAGE200

FM_OC_DETECT_EN_N @BASEBOARD_FAB2_LIB.BASEBOARD_FAB2(SCH_1):FM_OC_DETECT_EN_N
  U7C1  BC4 GPP_H18_SML4ALERT_N_IE_N LBG_CORE_QAT_EXT_D_BGA1-IC,H91A   I147 @BASEBOARD_FAB2_LIB.BASEBOARD_FAB2(SCH_1):PAGE120
 R7D19    1      A RES_0402-1.00K,1%,1/16W,EMPTY,A     I6 @BASEBOARD_FAB2_LIB.BASEBOARD_FAB2(SCH_1):PAGE126
 R1D35    2      B RES_0402-4.75K,1%,1/16W,CHIP,GA    I12 @BASEBOARD_FAB2_LIB.BASEBOARD_FAB2(SCH_1):PAGE126
  Q1D2    1   GATE FET_N_SOT23LF-2N7002,FET,C7925A   I203 @BASEBOARD_FAB2_LIB.BASEBOARD_FAB2(SCH_1):PAGE200
 U25W4   Y2 GPIOM3_NRI2_VPIB5 AST2520A1-GP-GP_ASIC2-GB1-AST2A   I117 @BASEBOARD_FAB2_LIB.BASEBOARD_FAB2(SCH_1):PAGE145

FM_OC_DETECT_N @BASEBOARD_FAB2_LIB.BASEBOARD_FAB2(SCH_1):FM_OC_DETECT_N
  U8E1    2   B<0> TTL08_QFN15-74LVC08A,IC,D90404B    I10 @BASEBOARD_FAB2_LIB.BASEBOARD_FAB2(SCH_1):PAGE170
  U1D1    4      Y TTL1G126_A_SOT-74HC1G126,IC,A7B   I103 @BASEBOARD_FAB2_LIB.BASEBOARD_FAB2(SCH_1):PAGE200
 R1D22    2      B RES_0402-10.0K,1%,1/16W,CHIP,GA   I158 @BASEBOARD_FAB2_LIB.BASEBOARD_FAB2(SCH_1):PAGE200

FM_P12V_HOTSWAP0_EN @BASEBOARD_FAB2_LIB.BASEBOARD_FAB2(SCH_1):FM_P12V_HOTSWAP0_EN
  Q9T1    3      C NPN_SM-MMBT3904,IC,C52245-001   I181 @BASEBOARD_FAB2_LIB.BASEBOARD_FAB2(SCH_1):PAGE181
  R9T6    2      B RES_0402-15.0K,1%,1/16W,CHIP,GA   I183 @BASEBOARD_FAB2_LIB.BASEBOARD_FAB2(SCH_1):PAGE181
  R9T3    1      A RES_0402-6.19K,1%,1/16W,CHIP,GA   I185 @BASEBOARD_FAB2_LIB.BASEBOARD_FAB2(SCH_1):PAGE181
 EU1D2   12 ENABLE ADM1278_SM-IC,G99251-001    I10 @BASEBOARD_FAB2_LIB.BASEBOARD_FAB2(SCH_1):PAGE199
 C1D11    1      A CAP_A_0402V-0.1UF,16V,10%,X7R,A    I53 @BASEBOARD_FAB2_LIB.BASEBOARD_FAB2(SCH_1):PAGE199

FM_P12V_HSC_ADR1 @BASEBOARD_FAB2_LIB.BASEBOARD_FAB2(SCH_1):FM_P12V_HSC_ADR1
 EU1D2    7   ADR1 ADM1278_SM-IC,G99251-001    I10 @BASEBOARD_FAB2_LIB.BASEBOARD_FAB2(SCH_1):PAGE199
 R9P17    1      A RES_0402-150.0K,1%,1/16W,CHIP,A    I33 @BASEBOARD_FAB2_LIB.BASEBOARD_FAB2(SCH_1):PAGE199
 R1D29    2      B RES_0402-4.75K,1%,1/16W,EMPTY,A    I37 @BASEBOARD_FAB2_LIB.BASEBOARD_FAB2(SCH_1):PAGE199

FM_P12V_HSC_ADR2 @BASEBOARD_FAB2_LIB.BASEBOARD_FAB2(SCH_1):FM_P12V_HSC_ADR2
 EU1D2    8   ADR2 ADM1278_SM-IC,G99251-001    I10 @BASEBOARD_FAB2_LIB.BASEBOARD_FAB2(SCH_1):PAGE199
 R9P16    1      A RES_0402-0.0,5%,1/16W,CHIP,G21A    I36 @BASEBOARD_FAB2_LIB.BASEBOARD_FAB2(SCH_1):PAGE199
 R1D27    2      B RES_0402-4.75K,1%,1/16W,EMPTY,A    I38 @BASEBOARD_FAB2_LIB.BASEBOARD_FAB2(SCH_1):PAGE199

FM_P12V_MAIN_SW_EN @BASEBOARD_FAB2_LIB.BASEBOARD_FAB2(SCH_1):FM_P12V_MAIN_SW_EN
  U8D7  R16  PR14D LCMXO2_A_256BGA-IC,H63395-001    I59 @BASEBOARD_FAB2_LIB.BASEBOARD_FAB2(SCH_1):PAGE191
 EU7E1    2     ON SLG55021_SM-IC,G56246-001    I19 @BASEBOARD_FAB2_LIB.BASEBOARD_FAB2(SCH_1):PAGE198

FM_P1V8MCP_CPU0_EN @BASEBOARD_FAB2_LIB.BASEBOARD_FAB2(SCH_1):FM_P1V8MCP_CPU0_EN
  U8D7  E16   PR3A LCMXO2_A_256BGA-IC,H63395-001    I59 @BASEBOARD_FAB2_LIB.BASEBOARD_FAB2(SCH_1):PAGE191
  J6B1  A15  IOA15 SCONN120_H61426002_SM-CONN,H61A    I56 @BASEBOARD_FAB2_LIB.BASEBOARD_FAB2(SCH_1):PAGE194

FM_P1V8MCP_CPU1_EN @BASEBOARD_FAB2_LIB.BASEBOARD_FAB2(SCH_1):FM_P1V8MCP_CPU1_EN
  U8D7  F12   PR4C LCMXO2_A_256BGA-IC,H63395-001    I59 @BASEBOARD_FAB2_LIB.BASEBOARD_FAB2(SCH_1):PAGE191
  J4B2  A15  IOA15 SCONN120_H61426002_SM-CONN,H61A    I46 @BASEBOARD_FAB2_LIB.BASEBOARD_FAB2(SCH_1):PAGE193

FM_P3V3_CPLD_EN @BASEBOARD_FAB2_LIB.BASEBOARD_FAB2(SCH_1):FM_P3V3_CPLD_EN
  U8D7   A4  PT10A LCMXO2_A_256BGA-IC,H63395-001    I59 @BASEBOARD_FAB2_LIB.BASEBOARD_FAB2(SCH_1):PAGE191
 EU2T1    2     ON SLG55021_SM-IC,G56246-001     I1 @BASEBOARD_FAB2_LIB.BASEBOARD_FAB2(SCH_1):PAGE198

FM_PASSWORD_CLEAR_N @BASEBOARD_FAB2_LIB.BASEBOARD_FAB2(SCH_1):FM_PASSWORD_CLEAR_N
  U7C1 BW32 GPP_C8 LBG_CORE_QAT_EXT_D_BGA1-IC,H91A   I115 @BASEBOARD_FAB2_LIB.BASEBOARD_FAB2(SCH_1):PAGE119
 R2N28    2      B RES_0402-10.0K,1%,1/16W,CHIP,GA   I147 @BASEBOARD_FAB2_LIB.BASEBOARD_FAB2(SCH_1):PAGE136
  J7G3    9    IO9 CONN12_C73564003_PIP-CONN,C735A   I174 @BASEBOARD_FAB2_LIB.BASEBOARD_FAB2(SCH_1):PAGE136

FM_PCH_BMC_THERMTRIP_EXI_STRAP_ @BASEBOARD_FAB2_LIB.BASEBOARD_FAB2(SCH_1):FM_PCH_BMC_THERMTRIP_EXI_STRAP_N
  U7C1 BM20 GPP_B23_MEIE_SML1ALRT_N_PHOT_N LBG_CORE_QAT_EXT_D_BGA1-IC,H91A   I115 @BASEBOARD_FAB2_LIB.BASEBOARD_FAB2(SCH_1):PAGE119
 R2N10    2      B RES_0402-4.75K,1%,1/16W,CHIP,GA    I10 @BASEBOARD_FAB2_LIB.BASEBOARD_FAB2(SCH_1):PAGE126
  Q8D2    2    SRC FET_N_SOT23-2N7002,FET,C79254-A     I4 @BASEBOARD_FAB2_LIB.BASEBOARD_FAB2(SCH_1):PAGE134

FM_PCH_BMC_THERMTRIP_N @BASEBOARD_FAB2_LIB.BASEBOARD_FAB2(SCH_1):FM_PCH_BMC_THERMTRIP_N
  U7C1  BH2 GPP_H22_SSATAXPCIE4_SSATAGP4 LBG_CORE_QAT_EXT_D_BGA1-IC,H91A   I147 @BASEBOARD_FAB2_LIB.BASEBOARD_FAB2(SCH_1):PAGE120
 R2P17    2      B RES_0402-4.75K,1%,1/16W,CHIP,GA     I3 @BASEBOARD_FAB2_LIB.BASEBOARD_FAB2(SCH_1):PAGE134
  Q8D2    3    DRN FET_N_SOT23-2N7002,FET,C79254-A     I4 @BASEBOARD_FAB2_LIB.BASEBOARD_FAB2(SCH_1):PAGE134
 U25W4  C19 GPIOG2_SGPS1I0 AST2520A1-GP-GP_ASIC2-GB1-AST2A    I95 @BASEBOARD_FAB2_LIB.BASEBOARD_FAB2(SCH_1):PAGE144

FM_PCH_LVC1_THERMTRIP_N @BASEBOARD_FAB2_LIB.BASEBOARD_FAB2(SCH_1):FM_PCH_LVC1_THERMTRIP_N
  U7C1  V15 THRMTRIP_N LBG_CORE_QAT_EXT_D_BGA1-IC,H91A    I73 @BASEBOARD_FAB2_LIB.BASEBOARD_FAB2(SCH_1):PAGE118
 R7C21    2      B RES_0402-10.0K,1%,1/16W,CHIP,GA     I9 @BASEBOARD_FAB2_LIB.BASEBOARD_FAB2(SCH_1):PAGE134
  Q7D1    3    DRN FET_N_SOT23-2N7002,FET,C79254-A    I10 @BASEBOARD_FAB2_LIB.BASEBOARD_FAB2(SCH_1):PAGE134

FM_PCH_PLD_DATA @BASEBOARD_FAB2_LIB.BASEBOARD_FAB2(SCH_1):FM_PCH_PLD_DATA
  R2M3    2      B RES_0402-33.2,1%,1/16W,CHIP,G2A   I172 @BASEBOARD_FAB2_LIB.BASEBOARD_FAB2(SCH_1):PAGE119
  R2R5    2      B RES_0402-1.00K,1%,1/16W,CHIP,GA   I258 @BASEBOARD_FAB2_LIB.BASEBOARD_FAB2(SCH_1):PAGE133
  U8D7   C2   PL1D LCMXO2_A_256BGA-IC,H63395-001   I179 @BASEBOARD_FAB2_LIB.BASEBOARD_FAB2(SCH_1):PAGE190

FM_PCH_PLD_DATA_R @BASEBOARD_FAB2_LIB.BASEBOARD_FAB2(SCH_1):FM_PCH_PLD_DATA_R
  U7C1 BM42 GPP_D4 LBG_CORE_QAT_EXT_D_BGA1-IC,H91A   I115 @BASEBOARD_FAB2_LIB.BASEBOARD_FAB2(SCH_1):PAGE119
  R2M3    1      A RES_0402-33.2,1%,1/16W,CHIP,G2A   I172 @BASEBOARD_FAB2_LIB.BASEBOARD_FAB2(SCH_1):PAGE119

FM_PCH_PRSNT_N @BASEBOARD_FAB2_LIB.BASEBOARD_FAB2(SCH_1):FM_PCH_PRSNT_N
  U7C1  C70 CGC_DUT_DETECT_N LBG_CORE_QAT_EXT_D_BGA1-IC,H91A    I34 @BASEBOARD_FAB2_LIB.BASEBOARD_FAB2(SCH_1):PAGE121
  R7B6    2      B RES_0402-10.0K,1%,1/16W,CHIP,GA   I295 @BASEBOARD_FAB2_LIB.BASEBOARD_FAB2(SCH_1):PAGE133
  U8D7   A3  PT11C LCMXO2_A_256BGA-IC,H63395-001    I59 @BASEBOARD_FAB2_LIB.BASEBOARD_FAB2(SCH_1):PAGE191

FM_PCH_PWRBTN_N @BASEBOARD_FAB2_LIB.BASEBOARD_FAB2(SCH_1):FM_PCH_PWRBTN_N
  U7C1  C15 GPD3_PWRBTN_N LBG_CORE_QAT_EXT_D_BGA1-IC,H91A    I73 @BASEBOARD_FAB2_LIB.BASEBOARD_FAB2(SCH_1):PAGE118
 R2T28    2      B RES_0402-33.2,1%,1/16W,CHIP,G2A   I289 @BASEBOARD_FAB2_LIB.BASEBOARD_FAB2(SCH_1):PAGE156
  U8D7  B12  PT23B LCMXO2_A_256BGA-IC,H63395-001    I59 @BASEBOARD_FAB2_LIB.BASEBOARD_FAB2(SCH_1):PAGE191

FM_PCH_PWRBTN_OUT_N @BASEBOARD_FAB2_LIB.BASEBOARD_FAB2(SCH_1):FM_PCH_PWRBTN_OUT_N
  U7C1 BG15 GPP_B17 LBG_CORE_QAT_EXT_D_BGA1-IC,H91A   I115 @BASEBOARD_FAB2_LIB.BASEBOARD_FAB2(SCH_1):PAGE119
  R8G2    2      B RES_0402-4.75K,1%,1/16W,CHIP,GA   I267 @BASEBOARD_FAB2_LIB.BASEBOARD_FAB2(SCH_1):PAGE156
  U8G1    3     2A TTL2G07_SOT23LF-74LVC2G07,IC,DB   I269 @BASEBOARD_FAB2_LIB.BASEBOARD_FAB2(SCH_1):PAGE156

FM_PCH_PWRBTN_R_N @BASEBOARD_FAB2_LIB.BASEBOARD_FAB2(SCH_1):FM_PCH_PWRBTN_R_N
  U8F3    4     2Y TTL2G07_SOT23LF-74LVC2G07,IC,DB   I201 @BASEBOARD_FAB2_LIB.BASEBOARD_FAB2(SCH_1):PAGE156
 R8F26    2      B RES_0402-10.0K,1%,1/16W,CHIP,GA   I211 @BASEBOARD_FAB2_LIB.BASEBOARD_FAB2(SCH_1):PAGE156
  U8G1    4     2Y TTL2G07_SOT23LF-74LVC2G07,IC,DB   I269 @BASEBOARD_FAB2_LIB.BASEBOARD_FAB2(SCH_1):PAGE156
 R2T28    1      A RES_0402-33.2,1%,1/16W,CHIP,G2A   I289 @BASEBOARD_FAB2_LIB.BASEBOARD_FAB2(SCH_1):PAGE156

FM_PCH_SATA_RAID_KEY @BASEBOARD_FAB2_LIB.BASEBOARD_FAB2(SCH_1):FM_PCH_SATA_RAID_KEY
  U7C1 BV31 GPP_C10 LBG_CORE_QAT_EXT_D_BGA1-IC,H91A   I115 @BASEBOARD_FAB2_LIB.BASEBOARD_FAB2(SCH_1):PAGE119
 R9A13    2      B RES_0402-33.2,1%,1/16W,CHIP,G2A   I118 @BASEBOARD_FAB2_LIB.BASEBOARD_FAB2(SCH_1):PAGE135

FM_PCH_SATA_RAID_KEY_R @BASEBOARD_FAB2_LIB.BASEBOARD_FAB2(SCH_1):FM_PCH_SATA_RAID_KEY_R
 R9A12    1      A RES_0402-2.21K,1%,1/16W,CHIP,GA   I117 @BASEBOARD_FAB2_LIB.BASEBOARD_FAB2(SCH_1):PAGE135
 R9A13    1      A RES_0402-33.2,1%,1/16W,CHIP,G2A   I118 @BASEBOARD_FAB2_LIB.BASEBOARD_FAB2(SCH_1):PAGE135
  J9A1    4    IO4 CONN4_D42317002_PIP-CONN,D4231A   I131 @BASEBOARD_FAB2_LIB.BASEBOARD_FAB2(SCH_1):PAGE135

FM_PE_BMC_WAKE_N @BASEBOARD_FAB2_LIB.BASEBOARD_FAB2(SCH_1):FM_PE_BMC_WAKE_N
 R8E29    1      A RES_0402-0.0,5%,1/16W,EMPTY,G2A    I18 @BASEBOARD_FAB2_LIB.BASEBOARD_FAB2(SCH_1):PAGE142
R25W63    1      A RES_0402-100.0K,1%,1/16W,CHIP,A    I65 @BASEBOARD_FAB2_LIB.BASEBOARD_FAB2(SCH_1):PAGE146
 U25W4  N20 GPIOQ7_PEWAKE# AST2520A1-GP-GP_ASIC2-GB1-AST2A   I105 @BASEBOARD_FAB2_LIB.BASEBOARD_FAB2(SCH_1):PAGE146

FM_PE_M2_WAKE_N @BASEBOARD_FAB2_LIB.BASEBOARD_FAB2(SCH_1):FM_PE_M2_WAKE_N
 R8E27    1      A RES_0402-0.0,5%,1/16W,CHIP,G21A    I32 @BASEBOARD_FAB2_LIB.BASEBOARD_FAB2(SCH_1):PAGE142
  J8F1   54 PEWAKE_N_NC SCONN75K_H17033002_SMT1-SCONN,A    I53 @BASEBOARD_FAB2_LIB.BASEBOARD_FAB2(SCH_1):PAGE185

FM_PE_OCP_WAKE_N @BASEBOARD_FAB2_LIB.BASEBOARD_FAB2(SCH_1):FM_PE_OCP_WAKE_N
 R8E26    1      A RES_0402-0.0,5%,1/16W,CHIP,G21A    I30 @BASEBOARD_FAB2_LIB.BASEBOARD_FAB2(SCH_1):PAGE142
  J9B3   34   IO34 SCONN120_A28699018_SM-SCONN,A2A   I336 @BASEBOARD_FAB2_LIB.BASEBOARD_FAB2(SCH_1):PAGE186

FM_PE_SLOTX24_WAKE_N @BASEBOARD_FAB2_LIB.BASEBOARD_FAB2(SCH_1):FM_PE_SLOTX24_WAKE_N
  J8G1   28   IO28 SCONN200_H68296001_SM-CONN,H68A   I258 @BASEBOARD_FAB2_LIB.BASEBOARD_FAB2(SCH_1):PAGE108
 R8E36    2      B RES_0402-10.0K,1%,1/16W,CHIP,GA    I28 @BASEBOARD_FAB2_LIB.BASEBOARD_FAB2(SCH_1):PAGE142
 R8E28    1      A RES_0402-0.0,5%,1/16W,CHIP,G21A    I31 @BASEBOARD_FAB2_LIB.BASEBOARD_FAB2(SCH_1):PAGE142

FM_PE_SPRV_WAKE_N @BASEBOARD_FAB2_LIB.BASEBOARD_FAB2(SCH_1):FM_PE_SPRV_WAKE_N
 EU9E1   16 PE_WAKE_N SPRINGVILLE_SM1-IC,G47144-004    I72 @BASEBOARD_FAB2_LIB.BASEBOARD_FAB2(SCH_1):PAGE139
 R8E21    1      A RES_0402-0.0,5%,1/16W,CHIP,G21A    I33 @BASEBOARD_FAB2_LIB.BASEBOARD_FAB2(SCH_1):PAGE142

FM_PI7C9X1172_A0 @BASEBOARD_FAB2_LIB.BASEBOARD_FAB2(SCH_1):FM_PI7C9X1172_A0
 EU9F3   30 A0_CS_N PI7C9X1172_QFN-IC,H66899-001     I1 @BASEBOARD_FAB2_LIB.BASEBOARD_FAB2(SCH_1):PAGE183
 R9F51    1      A RES_0402-1.00K,1%,1/16W,CHIP,GA    I12 @BASEBOARD_FAB2_LIB.BASEBOARD_FAB2(SCH_1):PAGE183
 R9F49    2      B RES_0402-4.75K,1%,1/16W,EMPTY,A    I14 @BASEBOARD_FAB2_LIB.BASEBOARD_FAB2(SCH_1):PAGE183

FM_PI7C9X1172_A1 @BASEBOARD_FAB2_LIB.BASEBOARD_FAB2(SCH_1):FM_PI7C9X1172_A1
 EU9F3   31  A1_S1 PI7C9X1172_QFN-IC,H66899-001     I1 @BASEBOARD_FAB2_LIB.BASEBOARD_FAB2(SCH_1):PAGE183
 R9F50    1      A RES_0402-1.00K,1%,1/16W,CHIP,GA    I11 @BASEBOARD_FAB2_LIB.BASEBOARD_FAB2(SCH_1):PAGE183
 R9F48    2      B RES_0402-4.75K,1%,1/16W,EMPTY,A    I13 @BASEBOARD_FAB2_LIB.BASEBOARD_FAB2(SCH_1):PAGE183

FM_PLD_DEBUG_MODE_N @BASEBOARD_FAB2_LIB.BASEBOARD_FAB2(SCH_1):FM_PLD_DEBUG_MODE_N
  U8D7   F7  PT16A LCMXO2_A_256BGA-IC,H63395-001    I59 @BASEBOARD_FAB2_LIB.BASEBOARD_FAB2(SCH_1):PAGE191
  R2R3    2      B RES_0402-10.0K,1%,1/16W,CHIP,GA    I41 @BASEBOARD_FAB2_LIB.BASEBOARD_FAB2(SCH_1):PAGE192

FM_PMBUS_ALERT_BUF_EN @BASEBOARD_FAB2_LIB.BASEBOARD_FAB2(SCH_1):FM_PMBUS_ALERT_BUF_EN
  U8D5    1     OE TTL1G126_A_SOT-74HC1G126,IC,A7B    I38 @BASEBOARD_FAB2_LIB.BASEBOARD_FAB2(SCH_1):PAGE170
  R2P5    2      B RES_0402-4.75K,1%,1/16W,CHIP,GA    I56 @BASEBOARD_FAB2_LIB.BASEBOARD_FAB2(SCH_1):PAGE170
  Q2P1    3    DRN FET_N_SOT23LF-2N7002,FET,C7925A    I58 @BASEBOARD_FAB2_LIB.BASEBOARD_FAB2(SCH_1):PAGE170

FM_PMBUS_ALERT_BUF_EN_N @BASEBOARD_FAB2_LIB.BASEBOARD_FAB2(SCH_1):FM_PMBUS_ALERT_BUF_EN_N
  U7C1  BK9 GPP_B11 LBG_CORE_QAT_EXT_D_BGA1-IC,H91A   I115 @BASEBOARD_FAB2_LIB.BASEBOARD_FAB2(SCH_1):PAGE119
  U7C1 BY35 GPP_C18 LBG_CORE_QAT_EXT_D_BGA1-IC,H91A   I115 @BASEBOARD_FAB2_LIB.BASEBOARD_FAB2(SCH_1):PAGE119
  Q2P1    1   GATE FET_N_SOT23LF-2N7002,FET,C7925A    I58 @BASEBOARD_FAB2_LIB.BASEBOARD_FAB2(SCH_1):PAGE170
 R2P13    2      B RES_0402-4.75K,1%,1/16W,CHIP,GA    I61 @BASEBOARD_FAB2_LIB.BASEBOARD_FAB2(SCH_1):PAGE170
 R2P11    1      A RES_0402-1.00K,1%,1/16W,EMPTY,A    I63 @BASEBOARD_FAB2_LIB.BASEBOARD_FAB2(SCH_1):PAGE170
 U25W4   P3 GPIOL5_NRTS1_VPICLK AST2520A1-GP-GP_ASIC2-GB1-AST2A   I117 @BASEBOARD_FAB2_LIB.BASEBOARD_FAB2(SCH_1):PAGE145

FM_POST_CARD_PRES_BMC_N @BASEBOARD_FAB2_LIB.BASEBOARD_FAB2(SCH_1):FM_POST_CARD_PRES_BMC_N
  U7C1   W4 GPP_A20 LBG_CORE_QAT_EXT_D_BGA1-IC,H91A   I115 @BASEBOARD_FAB2_LIB.BASEBOARD_FAB2(SCH_1):PAGE119
  U7C1 BG52 GPP_E2_SATAXPCIE2_SATAGP2 LBG_CORE_QAT_EXT_D_BGA1-IC,H91A   I147 @BASEBOARD_FAB2_LIB.BASEBOARD_FAB2(SCH_1):PAGE120
  Q1L4    6 DRAIN<0> FET_N_DUAL_SMLF-2N7002DW,FET,DA    I19 @BASEBOARD_FAB2_LIB.BASEBOARD_FAB2(SCH_1):PAGE168
 R1L38    2      B RES_0402-1.00K,1%,1/16W,CHIP,GA    I22 @BASEBOARD_FAB2_LIB.BASEBOARD_FAB2(SCH_1):PAGE168
 U25W4  AB3 GPIOO4_TACH4_VPIR2 AST2520A1-GP-GP_ASIC2-GB1-AST2A   I106 @BASEBOARD_FAB2_LIB.BASEBOARD_FAB2(SCH_1):PAGE147

FM_PRSNT_2_1_N @BASEBOARD_FAB2_LIB.BASEBOARD_FAB2(SCH_1):FM_PRSNT_2_1_N
  J8G1   27   IO27 SCONN200_H68296001_SM-CONN,H68A   I258 @BASEBOARD_FAB2_LIB.BASEBOARD_FAB2(SCH_1):PAGE108
  U7C1 AE18 GPP_L2_TESTCH0_D0 LBG_CORE_QAT_EXT_D_BGA1-IC,H91A    I34 @BASEBOARD_FAB2_LIB.BASEBOARD_FAB2(SCH_1):PAGE121
  R3P7    2      B RES_0402-1.00K,1%,1/16W,CHIP,GA   I315 @BASEBOARD_FAB2_LIB.BASEBOARD_FAB2(SCH_1):PAGE133

FM_PRSNT_2_2_N @BASEBOARD_FAB2_LIB.BASEBOARD_FAB2(SCH_1):FM_PRSNT_2_2_N
  J8G1   30   IO30 SCONN200_H68296001_SM-CONN,H68A   I258 @BASEBOARD_FAB2_LIB.BASEBOARD_FAB2(SCH_1):PAGE108
  U7C1 AE15 GPP_L3_TESTCH0_D1 LBG_CORE_QAT_EXT_D_BGA1-IC,H91A    I34 @BASEBOARD_FAB2_LIB.BASEBOARD_FAB2(SCH_1):PAGE121
  R3P5    2      B RES_0402-1.00K,1%,1/16W,CHIP,GA   I316 @BASEBOARD_FAB2_LIB.BASEBOARD_FAB2(SCH_1):PAGE133

FM_PRSNT_2_3_N @BASEBOARD_FAB2_LIB.BASEBOARD_FAB2(SCH_1):FM_PRSNT_2_3_N
  J8G1   32   IO32 SCONN200_H68296001_SM-CONN,H68A   I258 @BASEBOARD_FAB2_LIB.BASEBOARD_FAB2(SCH_1):PAGE108
  U7C1 AE11 GPP_L4_TESTCH0_D2 LBG_CORE_QAT_EXT_D_BGA1-IC,H91A    I34 @BASEBOARD_FAB2_LIB.BASEBOARD_FAB2(SCH_1):PAGE121
  R3P6    2      B RES_0402-1.00K,1%,1/16W,CHIP,GA   I317 @BASEBOARD_FAB2_LIB.BASEBOARD_FAB2(SCH_1):PAGE133

FM_PRSNT_2_4_N @BASEBOARD_FAB2_LIB.BASEBOARD_FAB2(SCH_1):FM_PRSNT_2_4_N
  J8G1   63   IO63 SCONN200_H68296001_SM-CONN,H68A   I258 @BASEBOARD_FAB2_LIB.BASEBOARD_FAB2(SCH_1):PAGE108
  U7C1  Y18 GPP_L5_TESTCH0_D3 LBG_CORE_QAT_EXT_D_BGA1-IC,H91A    I34 @BASEBOARD_FAB2_LIB.BASEBOARD_FAB2(SCH_1):PAGE121
 R3N15    2      B RES_0402-1.00K,1%,1/16W,CHIP,GA   I318 @BASEBOARD_FAB2_LIB.BASEBOARD_FAB2(SCH_1):PAGE133

FM_PRSNT_2_5_N @BASEBOARD_FAB2_LIB.BASEBOARD_FAB2(SCH_1):FM_PRSNT_2_5_N
  J8G1   66   IO66 SCONN200_H68296001_SM-CONN,H68A   I258 @BASEBOARD_FAB2_LIB.BASEBOARD_FAB2(SCH_1):PAGE108
  U7C1 AA20 GPP_L6_TESTCH0_D4 LBG_CORE_QAT_EXT_D_BGA1-IC,H91A    I34 @BASEBOARD_FAB2_LIB.BASEBOARD_FAB2(SCH_1):PAGE121
 R3N16    2      B RES_0402-1.00K,1%,1/16W,CHIP,GA   I321 @BASEBOARD_FAB2_LIB.BASEBOARD_FAB2(SCH_1):PAGE133

FM_PRSNT_2_6_N @BASEBOARD_FAB2_LIB.BASEBOARD_FAB2(SCH_1):FM_PRSNT_2_6_N
  U7C1 AA17 GPP_L7_TESTCH0_D5 LBG_CORE_QAT_EXT_D_BGA1-IC,H91A    I34 @BASEBOARD_FAB2_LIB.BASEBOARD_FAB2(SCH_1):PAGE121
  R3P8    2      B RES_0402-1.00K,1%,1/16W,CHIP,GA   I322 @BASEBOARD_FAB2_LIB.BASEBOARD_FAB2(SCH_1):PAGE133
  J8G1  199  IO199 SCONN200_H68296001_SM-CONN,H68A    I78 @BASEBOARD_FAB2_LIB.BASEBOARD_FAB2(SCH_1):PAGE109

FM_PS_EN @BASEBOARD_FAB2_LIB.BASEBOARD_FAB2(SCH_1):FM_PS_EN
  C2R6    1      A CAP_0402LF-470PF,50V,10%,EMPTYA   I224 @BASEBOARD_FAB2_LIB.BASEBOARD_FAB2(SCH_1):PAGE181
  U8E1    9   A<0> TTL08_QFN15-74LVC08A,IC,D90404B   I243 @BASEBOARD_FAB2_LIB.BASEBOARD_FAB2(SCH_1):PAGE181
  U8D7   F9  PT19C LCMXO2_A_256BGA-IC,H63395-001    I59 @BASEBOARD_FAB2_LIB.BASEBOARD_FAB2(SCH_1):PAGE191

FM_PVCCIN_CPU0_PWR_IN_ALERT_N @BASEBOARD_FAB2_LIB.BASEBOARD_FAB2(SCH_1):FM_PVCCIN_CPU0_PWR_IN_ALERT_N
  U7E2    1   A<0> TTL1G08_SOTLF-NC7SZ08,IC,D1032B   I117 @BASEBOARD_FAB2_LIB.BASEBOARD_FAB2(SCH_1):PAGE95
  R4E4    2      B RES_0402-2.26K,1.0%,1/16W,CHIPA    I19 @BASEBOARD_FAB2_LIB.BASEBOARD_FAB2(SCH_1):PAGE201
 EU4D4   14 PINALRT_N PXE1610B_QFN-IC,H79206-001   I155 @BASEBOARD_FAB2_LIB.BASEBOARD_FAB2(SCH_1):PAGE201

FM_PVCCIN_CPU1_PWR_IN_ALERT_N @BASEBOARD_FAB2_LIB.BASEBOARD_FAB2(SCH_1):FM_PVCCIN_CPU1_PWR_IN_ALERT_N
  U7E3    1   A<0> TTL1G08_SOTLF-NC7SZ08,IC,D1032B   I118 @BASEBOARD_FAB2_LIB.BASEBOARD_FAB2(SCH_1):PAGE95
  R1D7    2      B RES_0402-2.26K,1.0%,1/16W,CHIPA     I7 @BASEBOARD_FAB2_LIB.BASEBOARD_FAB2(SCH_1):PAGE206
 EU1C2   14 PINALRT_N PXE1610B_QFN-IC,H79206-001   I130 @BASEBOARD_FAB2_LIB.BASEBOARD_FAB2(SCH_1):PAGE206

FM_PVCCIN_PVCCSA_CPU0_EN_LVC1 @BASEBOARD_FAB2_LIB.BASEBOARD_FAB2(SCH_1):FM_PVCCIN_PVCCSA_CPU0_EN_LVC1
  U8D7  A10  PT19B LCMXO2_A_256BGA-IC,H63395-001    I59 @BASEBOARD_FAB2_LIB.BASEBOARD_FAB2(SCH_1):PAGE191
 R6P18    1      A RES_0402-0.0,5%,1/16W,CHIP,G21A   I131 @BASEBOARD_FAB2_LIB.BASEBOARD_FAB2(SCH_1):PAGE201

FM_PVCCIN_PVCCSA_CPU1_EN_LVC1 @BASEBOARD_FAB2_LIB.BASEBOARD_FAB2(SCH_1):FM_PVCCIN_PVCCSA_CPU1_EN_LVC1
  U8D7  N16  PR14A LCMXO2_A_256BGA-IC,H63395-001    I59 @BASEBOARD_FAB2_LIB.BASEBOARD_FAB2(SCH_1):PAGE191
 R9N16    1      A RES_0402-0.0,5%,1/16W,CHIP,G21A   I119 @BASEBOARD_FAB2_LIB.BASEBOARD_FAB2(SCH_1):PAGE206

FM_PVCCIOMCP_CPU0_EN @BASEBOARD_FAB2_LIB.BASEBOARD_FAB2(SCH_1):FM_PVCCIOMCP_CPU0_EN
  U8D7   K1   PL9B LCMXO2_A_256BGA-IC,H63395-001   I179 @BASEBOARD_FAB2_LIB.BASEBOARD_FAB2(SCH_1):PAGE190
  J6B1  A16  IOA16 SCONN120_H61426002_SM-CONN,H61A    I56 @BASEBOARD_FAB2_LIB.BASEBOARD_FAB2(SCH_1):PAGE194

FM_PVCCIOMCP_CPU1_EN @BASEBOARD_FAB2_LIB.BASEBOARD_FAB2(SCH_1):FM_PVCCIOMCP_CPU1_EN
  U8D7   P7   PB9B LCMXO2_A_256BGA-IC,H63395-001   I179 @BASEBOARD_FAB2_LIB.BASEBOARD_FAB2(SCH_1):PAGE190
  J4B2  A16  IOA16 SCONN120_H61426002_SM-CONN,H61A    I46 @BASEBOARD_FAB2_LIB.BASEBOARD_FAB2(SCH_1):PAGE193

FM_PVCCIO_CPU0_EN @BASEBOARD_FAB2_LIB.BASEBOARD_FAB2(SCH_1):FM_PVCCIO_CPU0_EN
  U8D7   M7   PB9C LCMXO2_A_256BGA-IC,H63395-001   I179 @BASEBOARD_FAB2_LIB.BASEBOARD_FAB2(SCH_1):PAGE190
 R3P26    1      A RES_0402-0.0,5%,1/16W,CHIP,G21A    I87 @BASEBOARD_FAB2_LIB.BASEBOARD_FAB2(SCH_1):PAGE211

FM_PVCCIO_CPU1_EN @BASEBOARD_FAB2_LIB.BASEBOARD_FAB2(SCH_1):FM_PVCCIO_CPU1_EN
  U8D7   T7 PB11A_PCLKT2_0 LCMXO2_A_256BGA-IC,H63395-001   I179 @BASEBOARD_FAB2_LIB.BASEBOARD_FAB2(SCH_1):PAGE190
 R6P41    1      A RES_0402-0.0,5%,1/16W,CHIP,G21A    I90 @BASEBOARD_FAB2_LIB.BASEBOARD_FAB2(SCH_1):PAGE213

FM_PVCCMCP_CPU0_EN @BASEBOARD_FAB2_LIB.BASEBOARD_FAB2(SCH_1):FM_PVCCMCP_CPU0_EN
  U8D7   H2   PL6B LCMXO2_A_256BGA-IC,H63395-001   I179 @BASEBOARD_FAB2_LIB.BASEBOARD_FAB2(SCH_1):PAGE190
  J6B1  C20  IOC20 SCONN120_H61426002_SM-CONN,H61A    I56 @BASEBOARD_FAB2_LIB.BASEBOARD_FAB2(SCH_1):PAGE194

FM_PVCCMCP_CPU1_EN @BASEBOARD_FAB2_LIB.BASEBOARD_FAB2(SCH_1):FM_PVCCMCP_CPU1_EN
  U8D7   M8  PB16C LCMXO2_A_256BGA-IC,H63395-001   I179 @BASEBOARD_FAB2_LIB.BASEBOARD_FAB2(SCH_1):PAGE190
  J4B2  C20  IOC20 SCONN120_H61426002_SM-CONN,H61A    I46 @BASEBOARD_FAB2_LIB.BASEBOARD_FAB2(SCH_1):PAGE193

FM_PVDDQ_ABC_EN @BASEBOARD_FAB2_LIB.BASEBOARD_FAB2(SCH_1):FM_PVDDQ_ABC_EN
  U8D7  K14  PR10A LCMXO2_A_256BGA-IC,H63395-001    I59 @BASEBOARD_FAB2_LIB.BASEBOARD_FAB2(SCH_1):PAGE191
 R7F21    1      A RES_0402-0.0,5%,1/16W,CHIP,G21A   I343 @BASEBOARD_FAB2_LIB.BASEBOARD_FAB2(SCH_1):PAGE215

FM_PVDDQ_DEF_EN @BASEBOARD_FAB2_LIB.BASEBOARD_FAB2(SCH_1):FM_PVDDQ_DEF_EN
  U8D7  K15  PR10B LCMXO2_A_256BGA-IC,H63395-001    I59 @BASEBOARD_FAB2_LIB.BASEBOARD_FAB2(SCH_1):PAGE191
  R3M6    1      A RES_0402-0.0,5%,1/16W,CHIP,G21A    I59 @BASEBOARD_FAB2_LIB.BASEBOARD_FAB2(SCH_1):PAGE218

FM_PVDDQ_GHJ_EN @BASEBOARD_FAB2_LIB.BASEBOARD_FAB2(SCH_1):FM_PVDDQ_GHJ_EN
  U8D7  H13   PR6C LCMXO2_A_256BGA-IC,H63395-001    I59 @BASEBOARD_FAB2_LIB.BASEBOARD_FAB2(SCH_1):PAGE191
  R9U7    1      A RES_0402-0.0,5%,1/16W,CHIP,G21A    I84 @BASEBOARD_FAB2_LIB.BASEBOARD_FAB2(SCH_1):PAGE223

FM_PVDDQ_KLM_EN @BASEBOARD_FAB2_LIB.BASEBOARD_FAB2(SCH_1):FM_PVDDQ_KLM_EN
  U8D7  H15   PR6B LCMXO2_A_256BGA-IC,H63395-001    I59 @BASEBOARD_FAB2_LIB.BASEBOARD_FAB2(SCH_1):PAGE191
  R9M9    1      A RES_0402-0.0,5%,1/16W,CHIP,G21A    I84 @BASEBOARD_FAB2_LIB.BASEBOARD_FAB2(SCH_1):PAGE226

FM_PVPP_CPU0_EN @BASEBOARD_FAB2_LIB.BASEBOARD_FAB2(SCH_1):FM_PVPP_CPU0_EN
  U8D7  P15  PR14C LCMXO2_A_256BGA-IC,H63395-001    I59 @BASEBOARD_FAB2_LIB.BASEBOARD_FAB2(SCH_1):PAGE191
 R7F14    1      A RES_0402-10.0K,1%,1/16W,CHIP,GA   I136 @BASEBOARD_FAB2_LIB.BASEBOARD_FAB2(SCH_1):PAGE231
  C7F8    1      A CAP_0402LF-1000PF,50V,10%,EMPTA   I140 @BASEBOARD_FAB2_LIB.BASEBOARD_FAB2(SCH_1):PAGE231
  R7F9    1      A RES_0402-0.0,5%,1/16W,CHIP,G21A   I220 @BASEBOARD_FAB2_LIB.BASEBOARD_FAB2(SCH_1):PAGE231
  C7B9    1      A CAP_0402LF-1000PF,50V,10%,EMPTA   I185 @BASEBOARD_FAB2_LIB.BASEBOARD_FAB2(SCH_1):PAGE232
  R7B9    1      A RES_0402-0.0,5%,1/16W,CHIP,G21A   I307 @BASEBOARD_FAB2_LIB.BASEBOARD_FAB2(SCH_1):PAGE232

FM_PVPP_CPU1_EN @BASEBOARD_FAB2_LIB.BASEBOARD_FAB2(SCH_1):FM_PVPP_CPU1_EN
  U8D7  P16  PR13D LCMXO2_A_256BGA-IC,H63395-001    I59 @BASEBOARD_FAB2_LIB.BASEBOARD_FAB2(SCH_1):PAGE191
  R4G5    1      A RES_0402-10.0K,1%,1/16W,CHIP,GA   I182 @BASEBOARD_FAB2_LIB.BASEBOARD_FAB2(SCH_1):PAGE233
  C4G7    1      A CAP_0402LF-1000PF,50V,10%,EMPTA   I183 @BASEBOARD_FAB2_LIB.BASEBOARD_FAB2(SCH_1):PAGE233
  R4G4    1      A RES_0402-0.0,5%,1/16W,CHIP,G21A   I275 @BASEBOARD_FAB2_LIB.BASEBOARD_FAB2(SCH_1):PAGE233
  C4B5    1      A CAP_0402LF-1000PF,50V,10%,EMPTA   I129 @BASEBOARD_FAB2_LIB.BASEBOARD_FAB2(SCH_1):PAGE234
  R4B1    1      A RES_0402-0.0,5%,1/16W,CHIP,G21A   I220 @BASEBOARD_FAB2_LIB.BASEBOARD_FAB2(SCH_1):PAGE234

FM_PVPP_PVDDQ_CPU0_EN_ABC @BASEBOARD_FAB2_LIB.BASEBOARD_FAB2(SCH_1):FM_PVPP_PVDDQ_CPU0_EN_ABC
 EU7F1   40     EN NCP3232L_SM-IC,H86355-001   I193 @BASEBOARD_FAB2_LIB.BASEBOARD_FAB2(SCH_1):PAGE231
  R7F9    2      B RES_0402-0.0,5%,1/16W,CHIP,G21A   I220 @BASEBOARD_FAB2_LIB.BASEBOARD_FAB2(SCH_1):PAGE231

FM_PVPP_PVDDQ_CPU0_EN_DEF @BASEBOARD_FAB2_LIB.BASEBOARD_FAB2(SCH_1):FM_PVPP_PVDDQ_CPU0_EN_DEF
 EU7B1   40     EN NCP3232L_SM-IC,H86355-001   I214 @BASEBOARD_FAB2_LIB.BASEBOARD_FAB2(SCH_1):PAGE232
  R7B9    2      B RES_0402-0.0,5%,1/16W,CHIP,G21A   I307 @BASEBOARD_FAB2_LIB.BASEBOARD_FAB2(SCH_1):PAGE232

FM_PVPP_PVDDQ_CPU1_EN_GHJ @BASEBOARD_FAB2_LIB.BASEBOARD_FAB2(SCH_1):FM_PVPP_PVDDQ_CPU1_EN_GHJ
 EU4G1   40     EN NCP3232L_SM-IC,H86355-001   I225 @BASEBOARD_FAB2_LIB.BASEBOARD_FAB2(SCH_1):PAGE233
  R4G4    2      B RES_0402-0.0,5%,1/16W,CHIP,G21A   I275 @BASEBOARD_FAB2_LIB.BASEBOARD_FAB2(SCH_1):PAGE233

FM_PVPP_PVDDQ_CPU1_EN_KLM @BASEBOARD_FAB2_LIB.BASEBOARD_FAB2(SCH_1):FM_PVPP_PVDDQ_CPU1_EN_KLM
 EU4A3   40     EN NCP3232L_SM-IC,H86355-001   I184 @BASEBOARD_FAB2_LIB.BASEBOARD_FAB2(SCH_1):PAGE234
  R4B1    2      B RES_0402-0.0,5%,1/16W,CHIP,G21A   I220 @BASEBOARD_FAB2_LIB.BASEBOARD_FAB2(SCH_1):PAGE234

FM_PVTT_ABC_EN_R @BASEBOARD_FAB2_LIB.BASEBOARD_FAB2(SCH_1):FM_PVTT_ABC_EN_R
 EU4G3    7     EN MIC5166_DFN-IC,H55101-001     I1 @BASEBOARD_FAB2_LIB.BASEBOARD_FAB2(SCH_1):PAGE221
 R6U15    2      B RES_0402-1.0M,1%,1/16W,EMPTY,GA    I37 @BASEBOARD_FAB2_LIB.BASEBOARD_FAB2(SCH_1):PAGE221
 R4G23    2      B RES_0402-0.0,5%,1/16W,CHIP,G21A    I38 @BASEBOARD_FAB2_LIB.BASEBOARD_FAB2(SCH_1):PAGE221
 C4G23    1      A CAP_0402LF-1000PF,50V,10%,EMPTA    I39 @BASEBOARD_FAB2_LIB.BASEBOARD_FAB2(SCH_1):PAGE221

FM_PVTT_DEF_EN_R @BASEBOARD_FAB2_LIB.BASEBOARD_FAB2(SCH_1):FM_PVTT_DEF_EN_R
 EU4A1    7     EN MIC5166_DFN-IC,H55101-001    I31 @BASEBOARD_FAB2_LIB.BASEBOARD_FAB2(SCH_1):PAGE222
  R6L4    2      B RES_0402-1.0M,1%,1/16W,EMPTY,GA    I37 @BASEBOARD_FAB2_LIB.BASEBOARD_FAB2(SCH_1):PAGE222
  R4A2    2      B RES_0402-0.0,5%,1/16W,CHIP,G21A    I38 @BASEBOARD_FAB2_LIB.BASEBOARD_FAB2(SCH_1):PAGE222
  C4A2    1      A CAP_0402LF-1000PF,50V,10%,EMPTA    I40 @BASEBOARD_FAB2_LIB.BASEBOARD_FAB2(SCH_1):PAGE222

FM_PVTT_GHJ_EN_R @BASEBOARD_FAB2_LIB.BASEBOARD_FAB2(SCH_1):FM_PVTT_GHJ_EN_R
 EU4G2    7     EN MIC5166_DFN-IC,H55101-001    I24 @BASEBOARD_FAB2_LIB.BASEBOARD_FAB2(SCH_1):PAGE229
  R6U3    2      B RES_0402-1.0M,1%,1/16W,EMPTY,GA    I34 @BASEBOARD_FAB2_LIB.BASEBOARD_FAB2(SCH_1):PAGE229
 R4G16    2      B RES_0402-0.0,5%,1/16W,CHIP,G21A    I35 @BASEBOARD_FAB2_LIB.BASEBOARD_FAB2(SCH_1):PAGE229
 C4G12    1      A CAP_0402LF-1000PF,50V,10%,EMPTA    I36 @BASEBOARD_FAB2_LIB.BASEBOARD_FAB2(SCH_1):PAGE229

FM_PVTT_KLM_EN_R @BASEBOARD_FAB2_LIB.BASEBOARD_FAB2(SCH_1):FM_PVTT_KLM_EN_R
 EU4A2    7     EN MIC5166_DFN-IC,H55101-001    I31 @BASEBOARD_FAB2_LIB.BASEBOARD_FAB2(SCH_1):PAGE230
  R6L5    2      B RES_0402-1.0M,1%,1/16W,EMPTY,GA    I37 @BASEBOARD_FAB2_LIB.BASEBOARD_FAB2(SCH_1):PAGE230
  R4A3    2      B RES_0402-0.0,5%,1/16W,CHIP,G21A    I38 @BASEBOARD_FAB2_LIB.BASEBOARD_FAB2(SCH_1):PAGE230
  C4A6    1      A CAP_0402LF-1000PF,50V,10%,EMPTA    I39 @BASEBOARD_FAB2_LIB.BASEBOARD_FAB2(SCH_1):PAGE230

FM_PWRBRK_N @BASEBOARD_FAB2_LIB.BASEBOARD_FAB2(SCH_1):FM_PWRBRK_N
  Q7E8    3    DRN FET_N_SOT23-2N7002,FET,C79254-A   I119 @BASEBOARD_FAB2_LIB.BASEBOARD_FAB2(SCH_1):PAGE95
 R7E22    1      A RES_0402-0.0,5%,1/16W,CHIP,G21A   I341 @BASEBOARD_FAB2_LIB.BASEBOARD_FAB2(SCH_1):PAGE108
 R7E21    2      B RES_0402-4.75K,1%,1/16W,CHIP,GA   I343 @BASEBOARD_FAB2_LIB.BASEBOARD_FAB2(SCH_1):PAGE108

FM_PWRBRK_SLOT_N @BASEBOARD_FAB2_LIB.BASEBOARD_FAB2(SCH_1):FM_PWRBRK_SLOT_N
  J8G1   20   IO20 SCONN200_H68296001_SM-CONN,H68A   I258 @BASEBOARD_FAB2_LIB.BASEBOARD_FAB2(SCH_1):PAGE108
 R7E22    2      B RES_0402-0.0,5%,1/16W,CHIP,G21A   I341 @BASEBOARD_FAB2_LIB.BASEBOARD_FAB2(SCH_1):PAGE108
 R2U50    2      B RES_0402-0.0,5%,1/16W,EMPTY,G2A   I215 @BASEBOARD_FAB2_LIB.BASEBOARD_FAB2(SCH_1):PAGE119

FM_PWR_BTN_N @BASEBOARD_FAB2_LIB.BASEBOARD_FAB2(SCH_1):FM_PWR_BTN_N
  U7C1 BH20 GPP_B9_SRCCLKREQ4_N LBG_CORE_QAT_EXT_D_BGA1-IC,H91A   I115 @BASEBOARD_FAB2_LIB.BASEBOARD_FAB2(SCH_1):PAGE119
 R1L26    2      B RES_0402-33.2,1%,1/16W,CHIP,G2A    I13 @BASEBOARD_FAB2_LIB.BASEBOARD_FAB2(SCH_1):PAGE175
  U8D7   G6   PL3D LCMXO2_A_256BGA-IC,H63395-001   I179 @BASEBOARD_FAB2_LIB.BASEBOARD_FAB2(SCH_1):PAGE190
 U25W4  F18 GPIOE2_NDSR3 AST2520A1-GP-GP_ASIC2-GB1-AST2A   I117 @BASEBOARD_FAB2_LIB.BASEBOARD_FAB2(SCH_1):PAGE145

FM_PWR_BTN_R_N @BASEBOARD_FAB2_LIB.BASEBOARD_FAB2(SCH_1):FM_PWR_BTN_R_N
  U9A4    4   Y<0> TTL2G14_SMLF-74LVC2G14,IC,D184B    I10 @BASEBOARD_FAB2_LIB.BASEBOARD_FAB2(SCH_1):PAGE175
 R1L26    1      A RES_0402-33.2,1%,1/16W,CHIP,G2A    I13 @BASEBOARD_FAB2_LIB.BASEBOARD_FAB2(SCH_1):PAGE175

FM_PWR_LED @BASEBOARD_FAB2_LIB.BASEBOARD_FAB2(SCH_1):FM_PWR_LED
  Q9A2    6 DRAIN<0> FET_N_DUAL_SMLF-NTJD4001N,FET,A   I175 @BASEBOARD_FAB2_LIB.BASEBOARD_FAB2(SCH_1):PAGE119
  Q9A2    5 GATE<0> FET_N_DUAL_SMLF-NTJD4001N,FET,A   I180 @BASEBOARD_FAB2_LIB.BASEBOARD_FAB2(SCH_1):PAGE119
 R9A18    2      B RES_0402-4.75K,1%,1/16W,CHIP,GA   I183 @BASEBOARD_FAB2_LIB.BASEBOARD_FAB2(SCH_1):PAGE119

FM_PWR_LED_A @BASEBOARD_FAB2_LIB.BASEBOARD_FAB2(SCH_1):FM_PWR_LED_A
 R9A20    1      A RES_0402-221,1.0%,1/16W,CHIP,GA   I178 @BASEBOARD_FAB2_LIB.BASEBOARD_FAB2(SCH_1):PAGE119
 DS9A5    1      A LED_A1LF-GREEN,IC,C97278-010   I179 @BASEBOARD_FAB2_LIB.BASEBOARD_FAB2(SCH_1):PAGE119

FM_PWR_LED_K @BASEBOARD_FAB2_LIB.BASEBOARD_FAB2(SCH_1):FM_PWR_LED_K
 DS9A5    2      C LED_A1LF-GREEN,IC,C97278-010   I179 @BASEBOARD_FAB2_LIB.BASEBOARD_FAB2(SCH_1):PAGE119
  Q9A2    3 DRAIN<0> FET_N_DUAL_SMLF-NTJD4001N,FET,A   I180 @BASEBOARD_FAB2_LIB.BASEBOARD_FAB2(SCH_1):PAGE119

FM_PWR_LED_N @BASEBOARD_FAB2_LIB.BASEBOARD_FAB2(SCH_1):FM_PWR_LED_N
  U7C1 BK46 GPP_D1 LBG_CORE_QAT_EXT_D_BGA1-IC,H91A   I115 @BASEBOARD_FAB2_LIB.BASEBOARD_FAB2(SCH_1):PAGE119
  Q9A2    2 GATE<0> FET_N_DUAL_SMLF-NTJD4001N,FET,A   I175 @BASEBOARD_FAB2_LIB.BASEBOARD_FAB2(SCH_1):PAGE119
 R9A21    2      B RES_0402-4.75K,1%,1/16W,CHIP,GA   I186 @BASEBOARD_FAB2_LIB.BASEBOARD_FAB2(SCH_1):PAGE119

FM_QAT_EN_N @BASEBOARD_FAB2_LIB.BASEBOARD_FAB2(SCH_1):FM_QAT_EN_N
  U7C1  BR9 GPP_B3_CPU_GP2 LBG_CORE_QAT_EXT_D_BGA1-IC,H91A   I115 @BASEBOARD_FAB2_LIB.BASEBOARD_FAB2(SCH_1):PAGE119
 R2N23    2      B RES_0402-10.0K,1%,1/16W,CHIP,GA   I112 @BASEBOARD_FAB2_LIB.BASEBOARD_FAB2(SCH_1):PAGE135
 R2N24    1      A RES_0402-1.00K,1%,1/16W,EMPTY,A   I113 @BASEBOARD_FAB2_LIB.BASEBOARD_FAB2(SCH_1):PAGE135

FM_RED_LED_ANODE @BASEBOARD_FAB2_LIB.BASEBOARD_FAB2(SCH_1):FM_RED_LED_ANODE
 DS9F1    1      A LED_A1-RED,IC,D14725-005    I71 @BASEBOARD_FAB2_LIB.BASEBOARD_FAB2(SCH_1):PAGE177
 R9F28    2      B RES_0402-221,1.0%,1/16W,CHIP,GA    I72 @BASEBOARD_FAB2_LIB.BASEBOARD_FAB2(SCH_1):PAGE177

FM_RED_LED_CATHODE @BASEBOARD_FAB2_LIB.BASEBOARD_FAB2(SCH_1):FM_RED_LED_CATHODE
 DS9F1    2      C LED_A1-RED,IC,D14725-005    I71 @BASEBOARD_FAB2_LIB.BASEBOARD_FAB2(SCH_1):PAGE177
  Q9F1    3 DRAIN<0> FET_N_DUAL_SMLF-NTJD4001N,FET,A    I79 @BASEBOARD_FAB2_LIB.BASEBOARD_FAB2(SCH_1):PAGE177

FM_ROMA<0> @BASEBOARD_FAB2_LIB.BASEBOARD_FAB2(SCH_1):FM_ROMA(0)
  J9G1    3    IO3 CONN12_C73564003_PIP-CONN,C735A   I128 @BASEBOARD_FAB2_LIB.BASEBOARD_FAB2(SCH_1):PAGE137

FM_SINT_PRSNT_N @BASEBOARD_FAB2_LIB.BASEBOARD_FAB2(SCH_1):FM_SINT_PRSNT_N
  U7C1  C18 RSVD<11> LBG_CORE_QAT_EXT_D_BGA1-IC,H91A    I34 @BASEBOARD_FAB2_LIB.BASEBOARD_FAB2(SCH_1):PAGE121
  R7C5    2      B RES_0402-10.0K,1%,1/16W,CHIP,GA   I297 @BASEBOARD_FAB2_LIB.BASEBOARD_FAB2(SCH_1):PAGE133
  U8D7  B14  PT24A LCMXO2_A_256BGA-IC,H63395-001    I59 @BASEBOARD_FAB2_LIB.BASEBOARD_FAB2(SCH_1):PAGE191

FM_SLPS3_N @BASEBOARD_FAB2_LIB.BASEBOARD_FAB2(SCH_1):FM_SLPS3_N
  U7C1  D14 GPD4_SLP_S3_N LBG_CORE_QAT_EXT_D_BGA1-IC,H91A    I73 @BASEBOARD_FAB2_LIB.BASEBOARD_FAB2(SCH_1):PAGE118
  U8D7   G1   PL6A LCMXO2_A_256BGA-IC,H63395-001   I179 @BASEBOARD_FAB2_LIB.BASEBOARD_FAB2(SCH_1):PAGE190
 U25W4  R22 GPIOY0_SIOS3# AST2520A1-GP-GP_ASIC2-GB1-AST2A    I28 @BASEBOARD_FAB2_LIB.BASEBOARD_FAB2(SCH_1):PAGE148

FM_SLPS4_N @BASEBOARD_FAB2_LIB.BASEBOARD_FAB2(SCH_1):FM_SLPS4_N
  U7C1  B16 GPD5_SLP_S4_N LBG_CORE_QAT_EXT_D_BGA1-IC,H91A    I73 @BASEBOARD_FAB2_LIB.BASEBOARD_FAB2(SCH_1):PAGE118
  U8D7  C12  PT23A LCMXO2_A_256BGA-IC,H63395-001    I59 @BASEBOARD_FAB2_LIB.BASEBOARD_FAB2(SCH_1):PAGE191
 U25W4  R21 GPIOY1_SIOS5# AST2520A1-GP-GP_ASIC2-GB1-AST2A    I28 @BASEBOARD_FAB2_LIB.BASEBOARD_FAB2(SCH_1):PAGE148

FM_SLP_SUS_N @BASEBOARD_FAB2_LIB.BASEBOARD_FAB2(SCH_1):FM_SLP_SUS_N
  U7C1   P7 SLP_SUS_N LBG_CORE_QAT_EXT_D_BGA1-IC,H91A    I73 @BASEBOARD_FAB2_LIB.BASEBOARD_FAB2(SCH_1):PAGE118
  U8D7   E9  PT17D LCMXO2_A_256BGA-IC,H63395-001    I59 @BASEBOARD_FAB2_LIB.BASEBOARD_FAB2(SCH_1):PAGE191

FM_SLT_CFG0 @BASEBOARD_FAB2_LIB.BASEBOARD_FAB2(SCH_1):FM_SLT_CFG0
  J8G1   19   IO19 SCONN200_H68296001_SM-CONN,H68A   I258 @BASEBOARD_FAB2_LIB.BASEBOARD_FAB2(SCH_1):PAGE108
  U7C1 CA32 GPP_C15 LBG_CORE_QAT_EXT_D_BGA1-IC,H91A   I115 @BASEBOARD_FAB2_LIB.BASEBOARD_FAB2(SCH_1):PAGE119
  R8C7    2      B RES_0402-4.75K,1%,1/16W,CHIP,GA   I327 @BASEBOARD_FAB2_LIB.BASEBOARD_FAB2(SCH_1):PAGE133

FM_SLT_CFG1 @BASEBOARD_FAB2_LIB.BASEBOARD_FAB2(SCH_1):FM_SLT_CFG1
  J8G1   18   IO18 SCONN200_H68296001_SM-CONN,H68A   I258 @BASEBOARD_FAB2_LIB.BASEBOARD_FAB2(SCH_1):PAGE108
  U7C1 BW37 GPP_C16 LBG_CORE_QAT_EXT_D_BGA1-IC,H91A   I115 @BASEBOARD_FAB2_LIB.BASEBOARD_FAB2(SCH_1):PAGE119
  R8C1    2      B RES_0402-4.75K,1%,1/16W,CHIP,GA   I326 @BASEBOARD_FAB2_LIB.BASEBOARD_FAB2(SCH_1):PAGE133

FM_SLT_CFG2_R @BASEBOARD_FAB2_LIB.BASEBOARD_FAB2(SCH_1):FM_SLT_CFG2_R
  U7C1 BY31 GPP_C17 LBG_CORE_QAT_EXT_D_BGA1-IC,H91A   I115 @BASEBOARD_FAB2_LIB.BASEBOARD_FAB2(SCH_1):PAGE119
 R2U48    2      B RES_0402-4.75K,1%,1/16W,CHIP,GA   I213 @BASEBOARD_FAB2_LIB.BASEBOARD_FAB2(SCH_1):PAGE119
 R2U50    1      A RES_0402-0.0,5%,1/16W,EMPTY,G2A   I215 @BASEBOARD_FAB2_LIB.BASEBOARD_FAB2(SCH_1):PAGE119

FM_SOL_UART_CH_SEL @BASEBOARD_FAB2_LIB.BASEBOARD_FAB2(SCH_1):FM_SOL_UART_CH_SEL
  U7C1  BG7 GPP_G21_SSATA_DEVSLP1 LBG_CORE_QAT_EXT_D_BGA1-IC,H91A   I147 @BASEBOARD_FAB2_LIB.BASEBOARD_FAB2(SCH_1):PAGE120
  U8D7  L10  PB18D LCMXO2_A_256BGA-IC,H63395-001   I179 @BASEBOARD_FAB2_LIB.BASEBOARD_FAB2(SCH_1):PAGE190
  Q6W2    6 DRAIN<0> FET_N_DUAL_SMLF-2N7002DW,FET,DA    I30 @BASEBOARD_FAB2_LIB.BASEBOARD_FAB2(SCH_1):PAGE168
 R6W16    2      B RES_0402-10.0K,1%,1/16W,CHIP,GA    I39 @BASEBOARD_FAB2_LIB.BASEBOARD_FAB2(SCH_1):PAGE168
 U25W4  C15 GPIOI5_SPI1CK_VBCK AST2520A1-GP-GP_ASIC2-GB1-AST2A    I95 @BASEBOARD_FAB2_LIB.BASEBOARD_FAB2(SCH_1):PAGE144

FM_SPEAKER_PCH_N @BASEBOARD_FAB2_LIB.BASEBOARD_FAB2(SCH_1):FM_SPEAKER_PCH_N
 U25W4  W20 GPIOS5_VPOB7 AST2520A1-GP-GP_ASIC2-GB1-AST2A   I104 @BASEBOARD_FAB2_LIB.BASEBOARD_FAB2(SCH_1):PAGE146
 R1L45    1      1 0R2J-L-GP_SMD-RG5-0R2J-L-GP,63A    I89 @BASEBOARD_FAB2_LIB.BASEBOARD_FAB2(SCH_1):PAGE175

FM_SPEAKER_PCH_N_R @BASEBOARD_FAB2_LIB.BASEBOARD_FAB2(SCH_1):FM_SPEAKER_PCH_N_R
  Q9A3    3    DRN FET_N_SOT23LF-2N7002,FET,C7925A    I49 @BASEBOARD_FAB2_LIB.BASEBOARD_FAB2(SCH_1):PAGE175
 DS9A3    1      C LED_1NCLF-YELLOW,IC,C96565-003    I67 @BASEBOARD_FAB2_LIB.BASEBOARD_FAB2(SCH_1):PAGE175
 R1L45    2      2 0R2J-L-GP_SMD-RG5-0R2J-L-GP,63A    I89 @BASEBOARD_FAB2_LIB.BASEBOARD_FAB2(SCH_1):PAGE175

FM_SSATA_PCIE_M2_SEL @BASEBOARD_FAB2_LIB.BASEBOARD_FAB2(SCH_1):FM_SSATA_PCIE_M2_SEL
  U7C1  BH4 GPP_H23_SSATAXPCIE5_SSATAGP5 LBG_CORE_QAT_EXT_D_BGA1-IC,H91A   I147 @BASEBOARD_FAB2_LIB.BASEBOARD_FAB2(SCH_1):PAGE120
 R2P14    2      B RES_0402-0.0,5%,1/16W,CHIP,G21A   I115 @BASEBOARD_FAB2_LIB.BASEBOARD_FAB2(SCH_1):PAGE185
 U25W4  E13 GPIOA3_TIMER4 AST2520A1-GP-GP_ASIC2-GB1-AST2A   I117 @BASEBOARD_FAB2_LIB.BASEBOARD_FAB2(SCH_1):PAGE145

FM_SYS_THROTTLE_LVC3 @BASEBOARD_FAB2_LIB.BASEBOARD_FAB2(SCH_1):FM_SYS_THROTTLE_LVC3
  Q2U1    2 GATE<0> FET_N_DUAL_SMLF-NTJD4001N,FET,A    I28 @BASEBOARD_FAB2_LIB.BASEBOARD_FAB2(SCH_1):PAGE95
  Q4B2    2 GATE<0> FET_N_DUAL_SMLF-NTJD4001N,FET,A    I32 @BASEBOARD_FAB2_LIB.BASEBOARD_FAB2(SCH_1):PAGE95
  Q4B2    5 GATE<0> FET_N_DUAL_SMLF-NTJD4001N,FET,A    I33 @BASEBOARD_FAB2_LIB.BASEBOARD_FAB2(SCH_1):PAGE95
  Q7E3    5 GATE<0> FET_N_DUAL_SMLF-NTJD4001N,FET,A    I51 @BASEBOARD_FAB2_LIB.BASEBOARD_FAB2(SCH_1):PAGE95
  Q7E3    2 GATE<0> FET_N_DUAL_SMLF-NTJD4001N,FET,A    I52 @BASEBOARD_FAB2_LIB.BASEBOARD_FAB2(SCH_1):PAGE95
  Q7E4    3    DRN FET_N_SOT23-2N7002,FET,C79254-A   I104 @BASEBOARD_FAB2_LIB.BASEBOARD_FAB2(SCH_1):PAGE95
  R7E7    2      B RES_0402-4.75K,1%,1/16W,CHIP,GA   I106 @BASEBOARD_FAB2_LIB.BASEBOARD_FAB2(SCH_1):PAGE95
  Q2U1    5 GATE<0> FET_N_DUAL_SMLF-NTJD4001N,FET,A   I113 @BASEBOARD_FAB2_LIB.BASEBOARD_FAB2(SCH_1):PAGE95
  Q7E8    1   GATE FET_N_SOT23-2N7002,FET,C79254-A   I119 @BASEBOARD_FAB2_LIB.BASEBOARD_FAB2(SCH_1):PAGE95

FM_THERMTRIP_DLY @BASEBOARD_FAB2_LIB.BASEBOARD_FAB2(SCH_1):FM_THERMTRIP_DLY
 R7D18    1      A RES_0402-1.00K,1%,1/16W,CHIP,GA    I11 @BASEBOARD_FAB2_LIB.BASEBOARD_FAB2(SCH_1):PAGE134
  U8D7  L15  PR12A LCMXO2_A_256BGA-IC,H63395-001    I59 @BASEBOARD_FAB2_LIB.BASEBOARD_FAB2(SCH_1):PAGE191

FM_THERMTRIP_DLY_R @BASEBOARD_FAB2_LIB.BASEBOARD_FAB2(SCH_1):FM_THERMTRIP_DLY_R
  Q7D1    1   GATE FET_N_SOT23-2N7002,FET,C79254-A    I10 @BASEBOARD_FAB2_LIB.BASEBOARD_FAB2(SCH_1):PAGE134
 R7D18    2      B RES_0402-1.00K,1%,1/16W,CHIP,GA    I11 @BASEBOARD_FAB2_LIB.BASEBOARD_FAB2(SCH_1):PAGE134

FM_THROTTLE_N @BASEBOARD_FAB2_LIB.BASEBOARD_FAB2(SCH_1):FM_THROTTLE_N
  R7E9    1      A RES_0402-0.0,5%,1/16W,CHIP,G21A   I108 @BASEBOARD_FAB2_LIB.BASEBOARD_FAB2(SCH_1):PAGE95
  U7C1 CA39 GPP_C20 LBG_CORE_QAT_EXT_D_BGA1-IC,H91A   I115 @BASEBOARD_FAB2_LIB.BASEBOARD_FAB2(SCH_1):PAGE119
  U7C1 AY15 GPP_G7_FANTACH7_FANTACH7IE LBG_CORE_QAT_EXT_D_BGA1-IC,H91A   I147 @BASEBOARD_FAB2_LIB.BASEBOARD_FAB2(SCH_1):PAGE120
 R8B31    2      B RES_0402-4.75K,1%,1/16W,CHIP,GA   I307 @BASEBOARD_FAB2_LIB.BASEBOARD_FAB2(SCH_1):PAGE133
  R1R8    2      B RES_0402-0.0,5%,1/16W,CHIP,G21A    I51 @BASEBOARD_FAB2_LIB.BASEBOARD_FAB2(SCH_1):PAGE170
 U25W4  V20 GPIOS0_VPOB2_SPI2CS1# AST2520A1-GP-GP_ASIC2-GB1-AST2A   I104 @BASEBOARD_FAB2_LIB.BASEBOARD_FAB2(SCH_1):PAGE146

FM_THROTTLE_R1_N @BASEBOARD_FAB2_LIB.BASEBOARD_FAB2(SCH_1):FM_THROTTLE_R1_N
  U1R1    4      Y TTL1G07_A_SOP-74LVC1G07,IC,C88B    I46 @BASEBOARD_FAB2_LIB.BASEBOARD_FAB2(SCH_1):PAGE170
  R1R8    1      A RES_0402-0.0,5%,1/16W,CHIP,G21A    I51 @BASEBOARD_FAB2_LIB.BASEBOARD_FAB2(SCH_1):PAGE170

FM_THROTTLE_R_N @BASEBOARD_FAB2_LIB.BASEBOARD_FAB2(SCH_1):FM_THROTTLE_R_N
  Q7E4    1   GATE FET_N_SOT23-2N7002,FET,C79254-A   I104 @BASEBOARD_FAB2_LIB.BASEBOARD_FAB2(SCH_1):PAGE95
  R7E9    2      B RES_0402-0.0,5%,1/16W,CHIP,G21A   I108 @BASEBOARD_FAB2_LIB.BASEBOARD_FAB2(SCH_1):PAGE95

FM_TPM_PRES_N @BASEBOARD_FAB2_LIB.BASEBOARD_FAB2(SCH_1):FM_TPM_PRES_N
  U7C1  AE4 GPP_A22 LBG_CORE_QAT_EXT_D_BGA1-IC,H91A   I115 @BASEBOARD_FAB2_LIB.BASEBOARD_FAB2(SCH_1):PAGE119
  R8E3    2      B RES_0402-10.0K,1%,1/16W,CHIP,GA   I355 @BASEBOARD_FAB2_LIB.BASEBOARD_FAB2(SCH_1):PAGE133
  Q9W4    4    OUT LMV331IDCKRG4-GP_DISCRET-G-LMVA    I15 @BASEBOARD_FAB2_LIB.BASEBOARD_FAB2(SCH_1):PAGE249
 U25W4   V6 GPIOP7_TACH15 AST2520A1-GP-GP_ASIC2-GB1-AST2A   I106 @BASEBOARD_FAB2_LIB.BASEBOARD_FAB2(SCH_1):PAGE147

FM_TPM_PRES_RST @BASEBOARD_FAB2_LIB.BASEBOARD_FAB2(SCH_1):FM_TPM_PRES_RST
  Q9W3    1      B NPN_SM-MMBT3904,IC,C52245-001    I26 @BASEBOARD_FAB2_LIB.BASEBOARD_FAB2(SCH_1):PAGE249
  Q9W2    3      C NPN_SM-MMBT3904,IC,C52245-001    I29 @BASEBOARD_FAB2_LIB.BASEBOARD_FAB2(SCH_1):PAGE249
  R3W5    2      2 82K5R2F-GP_SMD-RG-82K5R2F-GP,6A    I33 @BASEBOARD_FAB2_LIB.BASEBOARD_FAB2(SCH_1):PAGE249

FM_TPM_PRES_RST_N @BASEBOARD_FAB2_LIB.BASEBOARD_FAB2(SCH_1):FM_TPM_PRES_RST_N
 R9E14    1      A RES_0402-0.0,5%,1/16W,CHIP,G21A   I379 @BASEBOARD_FAB2_LIB.BASEBOARD_FAB2(SCH_1):PAGE157
 R8D22    2      B RES_0402-33.2,1%,1/16W,CHIP,G2A   I386 @BASEBOARD_FAB2_LIB.BASEBOARD_FAB2(SCH_1):PAGE157
  J8E1    8    IO8 SCONN11_H67026001_SM-CONN,H670A    I87 @BASEBOARD_FAB2_LIB.BASEBOARD_FAB2(SCH_1):PAGE184
  Q9W4    1    +IN LMV331IDCKRG4-GP_DISCRET-G-LMVA    I15 @BASEBOARD_FAB2_LIB.BASEBOARD_FAB2(SCH_1):PAGE249
  R3W3    2      B RES_0402-10.0K,1%,1/16W,CHIP,GA    I17 @BASEBOARD_FAB2_LIB.BASEBOARD_FAB2(SCH_1):PAGE249
  Q9W1    3    DRN FET_N_SOT23LF-2N7002,FET,C7925A    I30 @BASEBOARD_FAB2_LIB.BASEBOARD_FAB2(SCH_1):PAGE249
  R3W4    1      1 47KR2F-GP_RCL_GP-47KR2F-GP,64.A    I31 @BASEBOARD_FAB2_LIB.BASEBOARD_FAB2(SCH_1):PAGE249

FM_TPM_PRES_RST_N_R @BASEBOARD_FAB2_LIB.BASEBOARD_FAB2(SCH_1):FM_TPM_PRES_RST_N_R
  Q9W2    1      B NPN_SM-MMBT3904,IC,C52245-001    I29 @BASEBOARD_FAB2_LIB.BASEBOARD_FAB2(SCH_1):PAGE249
  R3W4    2      2 47KR2F-GP_RCL_GP-47KR2F-GP,64.A    I31 @BASEBOARD_FAB2_LIB.BASEBOARD_FAB2(SCH_1):PAGE249

FM_UARTSW_LSB_N @BASEBOARD_FAB2_LIB.BASEBOARD_FAB2(SCH_1):FM_UARTSW_LSB_N
  U7C1  AT4 GPP_H0_SRCCLKREQ6_N LBG_CORE_QAT_EXT_D_BGA1-IC,H91A   I147 @BASEBOARD_FAB2_LIB.BASEBOARD_FAB2(SCH_1):PAGE120
  U9F2    6     S1 FSA3357_SM-IC,C63273-001    I74 @BASEBOARD_FAB2_LIB.BASEBOARD_FAB2(SCH_1):PAGE158
  U9F1    6     S1 FSA3357_SM-IC,C63273-001    I75 @BASEBOARD_FAB2_LIB.BASEBOARD_FAB2(SCH_1):PAGE158
 DS9A4    2      C LED_A1LF-GREEN,IC,D14725-022   I130 @BASEBOARD_FAB2_LIB.BASEBOARD_FAB2(SCH_1):PAGE158
  U8D7   R9  PB18A LCMXO2_A_256BGA-IC,H63395-001   I179 @BASEBOARD_FAB2_LIB.BASEBOARD_FAB2(SCH_1):PAGE190
 U25W4   Y3 GPION6_PWM6_VPIG6 AST2520A1-GP-GP_ASIC2-GB1-AST2A   I106 @BASEBOARD_FAB2_LIB.BASEBOARD_FAB2(SCH_1):PAGE147

FM_UARTSW_LSB_R_N @BASEBOARD_FAB2_LIB.BASEBOARD_FAB2(SCH_1):FM_UARTSW_LSB_R_N
 DS9A4    1      A LED_A1LF-GREEN,IC,D14725-022   I130 @BASEBOARD_FAB2_LIB.BASEBOARD_FAB2(SCH_1):PAGE158
 R1L43    1      A RES_0402-330,5%,1/16W,CHIP,G21A   I131 @BASEBOARD_FAB2_LIB.BASEBOARD_FAB2(SCH_1):PAGE158

FM_UARTSW_MSB_N @BASEBOARD_FAB2_LIB.BASEBOARD_FAB2(SCH_1):FM_UARTSW_MSB_N
  U7C1 BA13 GPP_G23_SSATAXPCIE0_SSATAGP0 LBG_CORE_QAT_EXT_D_BGA1-IC,H91A   I147 @BASEBOARD_FAB2_LIB.BASEBOARD_FAB2(SCH_1):PAGE120
  U9F2    5     S2 FSA3357_SM-IC,C63273-001    I74 @BASEBOARD_FAB2_LIB.BASEBOARD_FAB2(SCH_1):PAGE158
  U9F1    5     S2 FSA3357_SM-IC,C63273-001    I75 @BASEBOARD_FAB2_LIB.BASEBOARD_FAB2(SCH_1):PAGE158
 DS9A7    2      C LED_A1LF-GREEN,IC,D14725-022   I134 @BASEBOARD_FAB2_LIB.BASEBOARD_FAB2(SCH_1):PAGE158
  U8D7  P11  PB21B LCMXO2_A_256BGA-IC,H63395-001   I179 @BASEBOARD_FAB2_LIB.BASEBOARD_FAB2(SCH_1):PAGE190
 U25W4   T4 GPION7_PWM7_VPIG7 AST2520A1-GP-GP_ASIC2-GB1-AST2A   I106 @BASEBOARD_FAB2_LIB.BASEBOARD_FAB2(SCH_1):PAGE147

FM_UARTSW_MSB_R_N @BASEBOARD_FAB2_LIB.BASEBOARD_FAB2(SCH_1):FM_UARTSW_MSB_R_N
 DS9A7    1      A LED_A1LF-GREEN,IC,D14725-022   I134 @BASEBOARD_FAB2_LIB.BASEBOARD_FAB2(SCH_1):PAGE158
 R1L44    1      A RES_0402-330,5%,1/16W,CHIP,G21A   I136 @BASEBOARD_FAB2_LIB.BASEBOARD_FAB2(SCH_1):PAGE158

FM_UART_ALERT_N @BASEBOARD_FAB2_LIB.BASEBOARD_FAB2(SCH_1):FM_UART_ALERT_N
  U7C1 BK13 GPP_B15 LBG_CORE_QAT_EXT_D_BGA1-IC,H91A   I115 @BASEBOARD_FAB2_LIB.BASEBOARD_FAB2(SCH_1):PAGE119
 EU9F3   20  IRQ_N PI7C9X1172_QFN-IC,H66899-001     I1 @BASEBOARD_FAB2_LIB.BASEBOARD_FAB2(SCH_1):PAGE183
 R9F55    2      B RES_0402-4.75K,1%,1/16W,CHIP,GA    I30 @BASEBOARD_FAB2_LIB.BASEBOARD_FAB2(SCH_1):PAGE183
  U8D7   P2  PL14D LCMXO2_A_256BGA-IC,H63395-001   I179 @BASEBOARD_FAB2_LIB.BASEBOARD_FAB2(SCH_1):PAGE190

FM_UART_PRES_N @BASEBOARD_FAB2_LIB.BASEBOARD_FAB2(SCH_1):FM_UART_PRES_N
  U7C1   T2 GPP_A16_CLKOUT_LPC2 LBG_CORE_QAT_EXT_D_BGA1-IC,H91A   I115 @BASEBOARD_FAB2_LIB.BASEBOARD_FAB2(SCH_1):PAGE119
 R7C13    2      B RES_0402-10.0K,1%,1/16W,CHIP,GA    I67 @BASEBOARD_FAB2_LIB.BASEBOARD_FAB2(SCH_1):PAGE137
  J9G1    9    IO9 CONN12_C73564003_PIP-CONN,C735A   I128 @BASEBOARD_FAB2_LIB.BASEBOARD_FAB2(SCH_1):PAGE137

FM_UART_SEL_N @BASEBOARD_FAB2_LIB.BASEBOARD_FAB2(SCH_1):FM_UART_SEL_N
  Q6W2    2 GATE<0> FET_N_DUAL_SMLF-2N7002DW,FET,DA    I30 @BASEBOARD_FAB2_LIB.BASEBOARD_FAB2(SCH_1):PAGE168
  Q6W3    3      C NPN_SM-MMBT3904,IC,C52245-001    I37 @BASEBOARD_FAB2_LIB.BASEBOARD_FAB2(SCH_1):PAGE168
 R6W15    2      B RES_0402-10.0K,1%,1/16W,CHIP,GA    I40 @BASEBOARD_FAB2_LIB.BASEBOARD_FAB2(SCH_1):PAGE168

FM_UART_SWITCH_N @BASEBOARD_FAB2_LIB.BASEBOARD_FAB2(SCH_1):FM_UART_SWITCH_N
  J9A2   12   IO12 CONN14_H54902001_PIP-CONN,H549A   I171 @BASEBOARD_FAB2_LIB.BASEBOARD_FAB2(SCH_1):PAGE155
  R1L6    1      A RES_0402-0.0,5%,1/16W,CHIP,G21A     I6 @BASEBOARD_FAB2_LIB.BASEBOARD_FAB2(SCH_1):PAGE168
  J9B1    7 GND_DRAIN CONN9_H51826001_PIP2-CONN,H518A    I69 @BASEBOARD_FAB2_LIB.BASEBOARD_FAB2(SCH_1):PAGE176
  Q6W3    2      E NPN_SM-MMBT3904,IC,C52245-001    I37 @BASEBOARD_FAB2_LIB.BASEBOARD_FAB2(SCH_1):PAGE168
  R9A5    2      B RES_0402-15.0K,1%,1/16W,CHIP,GA   I195 @BASEBOARD_FAB2_LIB.BASEBOARD_FAB2(SCH_1):PAGE155

FM_USB_P0_EN_BOOT_BIOS_STRAP_N @BASEBOARD_FAB2_LIB.BASEBOARD_FAB2(SCH_1):FM_USB_P0_EN_BOOT_BIOS_STRAP_N
  U7C1 BR17 GPP_B22 LBG_CORE_QAT_EXT_D_BGA1-IC,H91A   I115 @BASEBOARD_FAB2_LIB.BASEBOARD_FAB2(SCH_1):PAGE119
 R2N14    2      B RES_0402-1.00K,1%,1/16W,EMPTY,A    I83 @BASEBOARD_FAB2_LIB.BASEBOARD_FAB2(SCH_1):PAGE125
  U1M3    4   EN_N TPS2061_SM-IC,H66405-001   I100 @BASEBOARD_FAB2_LIB.BASEBOARD_FAB2(SCH_1):PAGE176
 R1M25    1      A RES_0402-10.0K,1%,1/16W,CHIP,GA   I111 @BASEBOARD_FAB2_LIB.BASEBOARD_FAB2(SCH_1):PAGE176

FM_UV_ADR_TRIGGER_EN @BASEBOARD_FAB2_LIB.BASEBOARD_FAB2(SCH_1):FM_UV_ADR_TRIGGER_EN
  U7C1 BL15 GPP_B18 LBG_CORE_QAT_EXT_D_BGA1-IC,H91A   I115 @BASEBOARD_FAB2_LIB.BASEBOARD_FAB2(SCH_1):PAGE119
 R2U30    2      B RES_0402-4.75K,1%,1/16W,CHIP,GA    I76 @BASEBOARD_FAB2_LIB.BASEBOARD_FAB2(SCH_1):PAGE125
  U8D7  H12   PR5D LCMXO2_A_256BGA-IC,H63395-001    I59 @BASEBOARD_FAB2_LIB.BASEBOARD_FAB2(SCH_1):PAGE191
 U25W4  B13 GPIOA7_TIMER8_MDIO2 AST2520A1-GP-GP_ASIC2-GB1-AST2A   I106 @BASEBOARD_FAB2_LIB.BASEBOARD_FAB2(SCH_1):PAGE147

FM_UV_ADR_TRIGGER_N @BASEBOARD_FAB2_LIB.BASEBOARD_FAB2(SCH_1):FM_UV_ADR_TRIGGER_N
  U8D7  G15   PR5A LCMXO2_A_256BGA-IC,H63395-001    I59 @BASEBOARD_FAB2_LIB.BASEBOARD_FAB2(SCH_1):PAGE191
  R9P6    2      B RES_0402-10.0K,1%,1/16W,CHIP,GA   I149 @BASEBOARD_FAB2_LIB.BASEBOARD_FAB2(SCH_1):PAGE200
  U9P1    6   OUTA TPS3700_SM-IC,H69492-001   I163 @BASEBOARD_FAB2_LIB.BASEBOARD_FAB2(SCH_1):PAGE200
 CR9P2    1      C DIODE_SMLF-BAT54WS,IC,C73510-0A   I213 @BASEBOARD_FAB2_LIB.BASEBOARD_FAB2(SCH_1):PAGE200

FM_WBG_PRSNT_N @BASEBOARD_FAB2_LIB.BASEBOARD_FAB2(SCH_1):FM_WBG_PRSNT_N
  U7C1   D8 RSVD<10> LBG_CORE_QAT_EXT_D_BGA1-IC,H91A    I34 @BASEBOARD_FAB2_LIB.BASEBOARD_FAB2(SCH_1):PAGE121
  R7C8    2      B RES_0402-10.0K,1%,1/16W,CHIP,GA   I296 @BASEBOARD_FAB2_LIB.BASEBOARD_FAB2(SCH_1):PAGE133
  U8D7  G11   PR5C LCMXO2_A_256BGA-IC,H63395-001    I59 @BASEBOARD_FAB2_LIB.BASEBOARD_FAB2(SCH_1):PAGE191

FM_XRC_PRESENT_N @BASEBOARD_FAB2_LIB.BASEBOARD_FAB2(SCH_1):FM_XRC_PRESENT_N
  U7C1 BW48 GPP_D17 LBG_CORE_QAT_EXT_D_BGA1-IC,H91A   I115 @BASEBOARD_FAB2_LIB.BASEBOARD_FAB2(SCH_1):PAGE119
 R8B23    2      B RES_0402-1.00K,1%,1/16W,CHIP,GA   I280 @BASEBOARD_FAB2_LIB.BASEBOARD_FAB2(SCH_1):PAGE133
  J1C1   G5   IOG5 CONN76_H22707001_THMT1-CONN,H2A    I18 @BASEBOARD_FAB2_LIB.BASEBOARD_FAB2(SCH_1):PAGE182
 U25W4  AA4 GPIOO6_TACH6_VPIR4 AST2520A1-GP-GP_ASIC2-GB1-AST2A   I106 @BASEBOARD_FAB2_LIB.BASEBOARD_FAB2(SCH_1):PAGE147

FM_XRC_READY_N @BASEBOARD_FAB2_LIB.BASEBOARD_FAB2(SCH_1):FM_XRC_READY_N
  U7C1 CA41 GPP_D18 LBG_CORE_QAT_EXT_D_BGA1-IC,H91A   I115 @BASEBOARD_FAB2_LIB.BASEBOARD_FAB2(SCH_1):PAGE119
 R8B30    2      B RES_0402-1.00K,1%,1/16W,CHIP,GA   I282 @BASEBOARD_FAB2_LIB.BASEBOARD_FAB2(SCH_1):PAGE133
  J1C1   H5   IOH5 CONN76_H22707001_THMT1-CONN,H2A    I18 @BASEBOARD_FAB2_LIB.BASEBOARD_FAB2(SCH_1):PAGE182
 R1C31    1      A RES_0402-0.0,5%,1/16W,EMPTY,G2A   I110 @BASEBOARD_FAB2_LIB.BASEBOARD_FAB2(SCH_1):PAGE182
 U25W4   W4 GPIOO7_TACH7_VPIR5 AST2520A1-GP-GP_ASIC2-GB1-AST2A   I106 @BASEBOARD_FAB2_LIB.BASEBOARD_FAB2(SCH_1):PAGE147

FP_ID_LED_P5V_STBY_N @BASEBOARD_FAB2_LIB.BASEBOARD_FAB2(SCH_1):FP_ID_LED_P5V_STBY_N
 DS9A1    1      C LED_1NC-BLUE,IC,C96565-012    I50 @BASEBOARD_FAB2_LIB.BASEBOARD_FAB2(SCH_1):PAGE175
  U1L2    4      Y TTL1G86_SOTLF-74AHCT1G86,IC,D3B    I57 @BASEBOARD_FAB2_LIB.BASEBOARD_FAB2(SCH_1):PAGE175

FP_ID_LED_XOR_R @BASEBOARD_FAB2_LIB.BASEBOARD_FAB2(SCH_1):FP_ID_LED_XOR_R
 DS9A1    2      A LED_1NC-BLUE,IC,C96565-012    I50 @BASEBOARD_FAB2_LIB.BASEBOARD_FAB2(SCH_1):PAGE175
  R1L8    2      B RES_0402-470.0,5%,1/16W,CHIP,GA    I58 @BASEBOARD_FAB2_LIB.BASEBOARD_FAB2(SCH_1):PAGE175

FP_LED_HDD_ACTIVITY_AND_N @BASEBOARD_FAB2_LIB.BASEBOARD_FAB2(SCH_1):FP_LED_HDD_ACTIVITY_AND_N
 DS9A2    1      C LED_1NCLF-GREEN,IC,C96565-011    I42 @BASEBOARD_FAB2_LIB.BASEBOARD_FAB2(SCH_1):PAGE177
  U1M1    4   Y<0> TTL1G08_SOTLF-NC7SZ08,IC,D1032C    I70 @BASEBOARD_FAB2_LIB.BASEBOARD_FAB2(SCH_1):PAGE177

FP_LED_HDD_ACTIVITY_AND_R_N @BASEBOARD_FAB2_LIB.BASEBOARD_FAB2(SCH_1):FP_LED_HDD_ACTIVITY_AND_R_N
 DS9A2    2      A LED_1NCLF-GREEN,IC,C96565-011    I42 @BASEBOARD_FAB2_LIB.BASEBOARD_FAB2(SCH_1):PAGE177
 R1L21    2      B RES_0402-64.9,1.0%,1/16W,CHIP,A    I43 @BASEBOARD_FAB2_LIB.BASEBOARD_FAB2(SCH_1):PAGE177

FP_NMI_BTN @BASEBOARD_FAB2_LIB.BASEBOARD_FAB2(SCH_1):FP_NMI_BTN
  U2R1    4   Y<0> TTL2G14_SMLF-74LVC2G14,IC,D184B   I356 @BASEBOARD_FAB2_LIB.BASEBOARD_FAB2(SCH_1):PAGE157
  U2R1    1   A<0> TTL2G14_SMLF-74LVC2G14,IC,D184B   I357 @BASEBOARD_FAB2_LIB.BASEBOARD_FAB2(SCH_1):PAGE157

FP_NMI_BTN_N @BASEBOARD_FAB2_LIB.BASEBOARD_FAB2(SCH_1):FP_NMI_BTN_N
  U7C1 BN11 GPP_B8_SRCCLKREQ3_N LBG_CORE_QAT_EXT_D_BGA1-IC,H91A   I115 @BASEBOARD_FAB2_LIB.BASEBOARD_FAB2(SCH_1):PAGE119
 R8F24    2      B RES_0402-4.75K,1%,1/16W,CHIP,GA   I316 @BASEBOARD_FAB2_LIB.BASEBOARD_FAB2(SCH_1):PAGE157
 R2R10    2      B RES_0402-33.2,1%,1/16W,CHIP,G2A   I358 @BASEBOARD_FAB2_LIB.BASEBOARD_FAB2(SCH_1):PAGE157
 U25W4  E18 GPIOE4_NDTR3 AST2520A1-GP-GP_ASIC2-GB1-AST2A   I117 @BASEBOARD_FAB2_LIB.BASEBOARD_FAB2(SCH_1):PAGE145

FP_NMI_BTN_OUT_N @BASEBOARD_FAB2_LIB.BASEBOARD_FAB2(SCH_1):FP_NMI_BTN_OUT_N
  R2R9    2      B RES_0402-200.0,1%,1/16W,CHIP,GA   I352 @BASEBOARD_FAB2_LIB.BASEBOARD_FAB2(SCH_1):PAGE157
 C2R12    1      A CAP_A_0402V-1.0UF,6.3V,10%,X6SA   I353 @BASEBOARD_FAB2_LIB.BASEBOARD_FAB2(SCH_1):PAGE157
  U2R1    3   A<0> TTL2G14_SMLF-74LVC2G14,IC,D184B   I356 @BASEBOARD_FAB2_LIB.BASEBOARD_FAB2(SCH_1):PAGE157

FP_NMI_BTN_OUT_R_N @BASEBOARD_FAB2_LIB.BASEBOARD_FAB2(SCH_1):FP_NMI_BTN_OUT_R_N
  S8E1    2      B SWITCH_D90553001_SMLF-IC,D9055A   I351 @BASEBOARD_FAB2_LIB.BASEBOARD_FAB2(SCH_1):PAGE157
  R2R9    1      A RES_0402-200.0,1%,1/16W,CHIP,GA   I352 @BASEBOARD_FAB2_LIB.BASEBOARD_FAB2(SCH_1):PAGE157
 R8E32    2      B RES_0402-4.75K,1%,1/16W,CHIP,GA   I385 @BASEBOARD_FAB2_LIB.BASEBOARD_FAB2(SCH_1):PAGE157

FP_NMI_BTN_R_N @BASEBOARD_FAB2_LIB.BASEBOARD_FAB2(SCH_1):FP_NMI_BTN_R_N
  U2R1    6   Y<0> TTL2G14_SMLF-74LVC2G14,IC,D184B   I357 @BASEBOARD_FAB2_LIB.BASEBOARD_FAB2(SCH_1):PAGE157
 R2R10    1      A RES_0402-33.2,1%,1/16W,CHIP,G2A   I358 @BASEBOARD_FAB2_LIB.BASEBOARD_FAB2(SCH_1):PAGE157

FP_PWR_BTN_BUF1_N @BASEBOARD_FAB2_LIB.BASEBOARD_FAB2(SCH_1):FP_PWR_BTN_BUF1_N
  U9A4    6   Y<0> TTL2G14_SMLF-74LVC2G14,IC,D184B     I9 @BASEBOARD_FAB2_LIB.BASEBOARD_FAB2(SCH_1):PAGE175
  U9A4    3   A<0> TTL2G14_SMLF-74LVC2G14,IC,D184B    I10 @BASEBOARD_FAB2_LIB.BASEBOARD_FAB2(SCH_1):PAGE175

FP_PWR_BTN_R1_N @BASEBOARD_FAB2_LIB.BASEBOARD_FAB2(SCH_1):FP_PWR_BTN_R1_N
 R1L31    2      B RES_0402-200.0,1%,1/16W,CHIP,GA     I4 @BASEBOARD_FAB2_LIB.BASEBOARD_FAB2(SCH_1):PAGE175
  U9A4    1   A<0> TTL2G14_SMLF-74LVC2G14,IC,D184B     I9 @BASEBOARD_FAB2_LIB.BASEBOARD_FAB2(SCH_1):PAGE175
 C1L18    1      A CAP_A_0402V-1.0UF,6.3V,10%,X6SA    I11 @BASEBOARD_FAB2_LIB.BASEBOARD_FAB2(SCH_1):PAGE175

FP_PWR_BTN_R_N @BASEBOARD_FAB2_LIB.BASEBOARD_FAB2(SCH_1):FP_PWR_BTN_R_N
 R1L31    1      A RES_0402-200.0,1%,1/16W,CHIP,GA     I4 @BASEBOARD_FAB2_LIB.BASEBOARD_FAB2(SCH_1):PAGE175
 R1L27    2      B RES_0402-4.75K,1%,1/16W,CHIP,GA     I5 @BASEBOARD_FAB2_LIB.BASEBOARD_FAB2(SCH_1):PAGE175
  S9A2    1    IO1 SW_H67881001_SM-IC,H67881-001    I84 @BASEBOARD_FAB2_LIB.BASEBOARD_FAB2(SCH_1):PAGE175
  S9A2    2    IO2 SW_H67881001_SM-IC,H67881-001    I84 @BASEBOARD_FAB2_LIB.BASEBOARD_FAB2(SCH_1):PAGE175
  U6W1   14    P11 PCA9555PWRG4-GP_DISCRET-G5-PCAA    I97 @BASEBOARD_FAB2_LIB.BASEBOARD_FAB2(SCH_1):PAGE247

FP_PWR_ID_LED_N @BASEBOARD_FAB2_LIB.BASEBOARD_FAB2(SCH_1):FP_PWR_ID_LED_N
  U7C1  BD3 GPP_H19_SSATAXPCIE1_SSATAGP1 LBG_CORE_QAT_EXT_D_BGA1-IC,H91A   I147 @BASEBOARD_FAB2_LIB.BASEBOARD_FAB2(SCH_1):PAGE120
 R8D14    2      B RES_0402-4.75K,1%,1/16W,CHIP,GA   I301 @BASEBOARD_FAB2_LIB.BASEBOARD_FAB2(SCH_1):PAGE133
  U1L2    2      B TTL1G86_SOTLF-74AHCT1G86,IC,D3B    I57 @BASEBOARD_FAB2_LIB.BASEBOARD_FAB2(SCH_1):PAGE175
R25W99    2      B RES_0402-4.75K,1%,1/16W,EMPTY,A    I14 @BASEBOARD_FAB2_LIB.BASEBOARD_FAB2(SCH_1):PAGE151
 U25W4  U20 GPIOS6_VPOB8 AST2520A1-GP-GP_ASIC2-GB1-AST2A   I104 @BASEBOARD_FAB2_LIB.BASEBOARD_FAB2(SCH_1):PAGE146

FP_RST_BTN_BUF1_N @BASEBOARD_FAB2_LIB.BASEBOARD_FAB2(SCH_1):FP_RST_BTN_BUF1_N
  U9A3    3   A<0> TTL2G14_SMLF-74LVC2G14,IC,D184B    I15 @BASEBOARD_FAB2_LIB.BASEBOARD_FAB2(SCH_1):PAGE175
  U9A3    6   Y<0> TTL2G14_SMLF-74LVC2G14,IC,D184B    I18 @BASEBOARD_FAB2_LIB.BASEBOARD_FAB2(SCH_1):PAGE175

FP_RST_BTN_R_N @BASEBOARD_FAB2_LIB.BASEBOARD_FAB2(SCH_1):FP_RST_BTN_R_N
  U9A3    1   A<0> TTL2G14_SMLF-74LVC2G14,IC,D184B    I18 @BASEBOARD_FAB2_LIB.BASEBOARD_FAB2(SCH_1):PAGE175
 C1L10    1      A CAP_A_0402V-1.0UF,6.3V,10%,X6SA    I19 @BASEBOARD_FAB2_LIB.BASEBOARD_FAB2(SCH_1):PAGE175
 R1L22    2      B RES_0402-200.0,1%,1/16W,CHIP,GA    I22 @BASEBOARD_FAB2_LIB.BASEBOARD_FAB2(SCH_1):PAGE175

GND @BASEBOARD_FAB2_LIB.BASEBOARD_FAB2(SCH_1):GND
  R5D1    2      B RES_0402-90.9,1%,1/16W,CHIP,G2A   I177 @BASEBOARD_FAB2_LIB.BASEBOARD_FAB2(SCH_1):PAGE21
  R5D2    2      B RES_0402-90.9,1%,1/16W,CHIP,G2A   I178 @BASEBOARD_FAB2_LIB.BASEBOARD_FAB2(SCH_1):PAGE21
  R6D1    2      B RES_0402-100.0,1%,1/16W,CHIP,GA   I179 @BASEBOARD_FAB2_LIB.BASEBOARD_FAB2(SCH_1):PAGE21
  R4P8    2      B RES_0402-90.9,1%,1/16W,CHIP,G2A   I180 @BASEBOARD_FAB2_LIB.BASEBOARD_FAB2(SCH_1):PAGE21
 R4P10    2      B RES_0402-90.9,1%,1/16W,CHIP,G2A   I181 @BASEBOARD_FAB2_LIB.BASEBOARD_FAB2(SCH_1):PAGE21
 R4P11    2      B RES_0402-100.0,1%,1/16W,CHIP,GA   I182 @BASEBOARD_FAB2_LIB.BASEBOARD_FAB2(SCH_1):PAGE21
 R6D11    2      B RES_0402-49.9,1%,1/16W,CHIP,G2A   I184 @BASEBOARD_FAB2_LIB.BASEBOARD_FAB2(SCH_1):PAGE21
  R4P3    2      B RES_0402-49.9,1%,1/16W,CHIP,G2A   I186 @BASEBOARD_FAB2_LIB.BASEBOARD_FAB2(SCH_1):PAGE21
  R4P2    2      B RES_0402-49.9,1%,1/16W,CHIP,G2A   I188 @BASEBOARD_FAB2_LIB.BASEBOARD_FAB2(SCH_1):PAGE21
  R4P4    2      B RES_0402-49.9,1%,1/16W,CHIP,G2A   I189 @BASEBOARD_FAB2_LIB.BASEBOARD_FAB2(SCH_1):PAGE21
  R6D2    2      B RES_0402-49.9,1%,1/16W,CHIP,G2A   I204 @BASEBOARD_FAB2_LIB.BASEBOARD_FAB2(SCH_1):PAGE21
  R5R1    2      B RES_0402-49.9,1%,1/16W,CHIP,G2A   I188 @BASEBOARD_FAB2_LIB.BASEBOARD_FAB2(SCH_1):PAGE22
  R5P4    2      B RES_0402-49.9,1%,1/16W,CHIP,G2A   I190 @BASEBOARD_FAB2_LIB.BASEBOARD_FAB2(SCH_1):PAGE22
  U5D1 DF23 UPI2_RX_DN<0> SKX_EXT_B_BGA1-IC,TBD     I3 @BASEBOARD_FAB2_LIB.BASEBOARD_FAB2(SCH_1):PAGE35
  U5D1 DE22 UPI2_RX_DN<1> SKX_EXT_B_BGA1-IC,TBD     I3 @BASEBOARD_FAB2_LIB.BASEBOARD_FAB2(SCH_1):PAGE35
  U5D1 DC22 UPI2_RX_DN<2> SKX_EXT_B_BGA1-IC,TBD     I3 @BASEBOARD_FAB2_LIB.BASEBOARD_FAB2(SCH_1):PAGE35
  U5D1 DB21 UPI2_RX_DN<3> SKX_EXT_B_BGA1-IC,TBD     I3 @BASEBOARD_FAB2_LIB.BASEBOARD_FAB2(SCH_1):PAGE35
  U5D1 DD19 UPI2_RX_DN<4> SKX_EXT_B_BGA1-IC,TBD     I3 @BASEBOARD_FAB2_LIB.BASEBOARD_FAB2(SCH_1):PAGE35
  U5D1 DA20 UPI2_RX_DN<5> SKX_EXT_B_BGA1-IC,TBD     I3 @BASEBOARD_FAB2_LIB.BASEBOARD_FAB2(SCH_1):PAGE35
  U5D1 CW20 UPI2_RX_DN<6> SKX_EXT_B_BGA1-IC,TBD     I3 @BASEBOARD_FAB2_LIB.BASEBOARD_FAB2(SCH_1):PAGE35
  U5D1 CV19 UPI2_RX_DN<7> SKX_EXT_B_BGA1-IC,TBD     I3 @BASEBOARD_FAB2_LIB.BASEBOARD_FAB2(SCH_1):PAGE35
  U5D1 CT21 UPI2_RX_DN<8> SKX_EXT_B_BGA1-IC,TBD     I3 @BASEBOARD_FAB2_LIB.BASEBOARD_FAB2(SCH_1):PAGE35
  U5D1 CR18 UPI2_RX_DN<9> SKX_EXT_B_BGA1-IC,TBD     I3 @BASEBOARD_FAB2_LIB.BASEBOARD_FAB2(SCH_1):PAGE35
  U5D1 CN20 UPI2_RX_DN<10> SKX_EXT_B_BGA1-IC,TBD     I3 @BASEBOARD_FAB2_LIB.BASEBOARD_FAB2(SCH_1):PAGE35
  U5D1 CP21 UPI2_RX_DN<11> SKX_EXT_B_BGA1-IC,TBD     I3 @BASEBOARD_FAB2_LIB.BASEBOARD_FAB2(SCH_1):PAGE35
  U5D1 CL16 UPI2_RX_DN<12> SKX_EXT_B_BGA1-IC,TBD     I3 @BASEBOARD_FAB2_LIB.BASEBOARD_FAB2(SCH_1):PAGE35
  U5D1 CJ18 UPI2_RX_DN<13> SKX_EXT_B_BGA1-IC,TBD     I3 @BASEBOARD_FAB2_LIB.BASEBOARD_FAB2(SCH_1):PAGE35
  U5D1 CH17 UPI2_RX_DN<14> SKX_EXT_B_BGA1-IC,TBD     I3 @BASEBOARD_FAB2_LIB.BASEBOARD_FAB2(SCH_1):PAGE35
  U5D1 CE16 UPI2_RX_DN<15> SKX_EXT_B_BGA1-IC,TBD     I3 @BASEBOARD_FAB2_LIB.BASEBOARD_FAB2(SCH_1):PAGE35
  U5D1 CD15 UPI2_RX_DN<16> SKX_EXT_B_BGA1-IC,TBD     I3 @BASEBOARD_FAB2_LIB.BASEBOARD_FAB2(SCH_1):PAGE35
  U5D1 CF17 UPI2_RX_DN<17> SKX_EXT_B_BGA1-IC,TBD     I3 @BASEBOARD_FAB2_LIB.BASEBOARD_FAB2(SCH_1):PAGE35
  U5D1 CB15 UPI2_RX_DN<18> SKX_EXT_B_BGA1-IC,TBD     I3 @BASEBOARD_FAB2_LIB.BASEBOARD_FAB2(SCH_1):PAGE35
  U5D1 BY17 UPI2_RX_DN<19> SKX_EXT_B_BGA1-IC,TBD     I3 @BASEBOARD_FAB2_LIB.BASEBOARD_FAB2(SCH_1):PAGE35
  U5D1 DG22 UPI2_RX_DP<0> SKX_EXT_B_BGA1-IC,TBD     I3 @BASEBOARD_FAB2_LIB.BASEBOARD_FAB2(SCH_1):PAGE35
  U5D1 DD21 UPI2_RX_DP<1> SKX_EXT_B_BGA1-IC,TBD     I3 @BASEBOARD_FAB2_LIB.BASEBOARD_FAB2(SCH_1):PAGE35
  U5D1 DA22 UPI2_RX_DP<2> SKX_EXT_B_BGA1-IC,TBD     I3 @BASEBOARD_FAB2_LIB.BASEBOARD_FAB2(SCH_1):PAGE35
  U5D1 DC20 UPI2_RX_DP<3> SKX_EXT_B_BGA1-IC,TBD     I3 @BASEBOARD_FAB2_LIB.BASEBOARD_FAB2(SCH_1):PAGE35
  U5D1 DB19 UPI2_RX_DP<4> SKX_EXT_B_BGA1-IC,TBD     I3 @BASEBOARD_FAB2_LIB.BASEBOARD_FAB2(SCH_1):PAGE35
  U5D1 CY19 UPI2_RX_DP<5> SKX_EXT_B_BGA1-IC,TBD     I3 @BASEBOARD_FAB2_LIB.BASEBOARD_FAB2(SCH_1):PAGE35
  U5D1 CU20 UPI2_RX_DP<6> SKX_EXT_B_BGA1-IC,TBD     I3 @BASEBOARD_FAB2_LIB.BASEBOARD_FAB2(SCH_1):PAGE35
  U5D1 CW18 UPI2_RX_DP<7> SKX_EXT_B_BGA1-IC,TBD     I3 @BASEBOARD_FAB2_LIB.BASEBOARD_FAB2(SCH_1):PAGE35
  U5D1 CR20 UPI2_RX_DP<8> SKX_EXT_B_BGA1-IC,TBD     I3 @BASEBOARD_FAB2_LIB.BASEBOARD_FAB2(SCH_1):PAGE35
  U5D1 CN18 UPI2_RX_DP<9> SKX_EXT_B_BGA1-IC,TBD     I3 @BASEBOARD_FAB2_LIB.BASEBOARD_FAB2(SCH_1):PAGE35
  U5D1 CP19 UPI2_RX_DP<10> SKX_EXT_B_BGA1-IC,TBD     I3 @BASEBOARD_FAB2_LIB.BASEBOARD_FAB2(SCH_1):PAGE35
  U5D1 CM21 UPI2_RX_DP<11> SKX_EXT_B_BGA1-IC,TBD     I3 @BASEBOARD_FAB2_LIB.BASEBOARD_FAB2(SCH_1):PAGE35
  U5D1 CJ16 UPI2_RX_DP<12> SKX_EXT_B_BGA1-IC,TBD     I3 @BASEBOARD_FAB2_LIB.BASEBOARD_FAB2(SCH_1):PAGE35
  U5D1 CK17 UPI2_RX_DP<13> SKX_EXT_B_BGA1-IC,TBD     I3 @BASEBOARD_FAB2_LIB.BASEBOARD_FAB2(SCH_1):PAGE35
  U5D1 CG16 UPI2_RX_DP<14> SKX_EXT_B_BGA1-IC,TBD     I3 @BASEBOARD_FAB2_LIB.BASEBOARD_FAB2(SCH_1):PAGE35
  U5D1 CF15 UPI2_RX_DP<15> SKX_EXT_B_BGA1-IC,TBD     I3 @BASEBOARD_FAB2_LIB.BASEBOARD_FAB2(SCH_1):PAGE35
  U5D1 CC14 UPI2_RX_DP<16> SKX_EXT_B_BGA1-IC,TBD     I3 @BASEBOARD_FAB2_LIB.BASEBOARD_FAB2(SCH_1):PAGE35
  U5D1 CD17 UPI2_RX_DP<17> SKX_EXT_B_BGA1-IC,TBD     I3 @BASEBOARD_FAB2_LIB.BASEBOARD_FAB2(SCH_1):PAGE35
  U5D1 BY15 UPI2_RX_DP<18> SKX_EXT_B_BGA1-IC,TBD     I3 @BASEBOARD_FAB2_LIB.BASEBOARD_FAB2(SCH_1):PAGE35
  U5D1 CA16 UPI2_RX_DP<19> SKX_EXT_B_BGA1-IC,TBD     I3 @BASEBOARD_FAB2_LIB.BASEBOARD_FAB2(SCH_1):PAGE35
  R5D5    2      B RES_0402-249,0.1%,1/16W,CHIP,GA   I303 @BASEBOARD_FAB2_LIB.BASEBOARD_FAB2(SCH_1):PAGE37
  C6D1    2      B CAP_0603LF-10UF,4V,20%,X6S,E15A    I19 @BASEBOARD_FAB2_LIB.BASEBOARD_FAB2(SCH_1):PAGE38
  U5D1  J74 VSS<1094> SKX_EXT_B_BGA1-IC,TBD    I20 @BASEBOARD_FAB2_LIB.BASEBOARD_FAB2(SCH_1):PAGE40
  U5D1  J72 VSS<1095> SKX_EXT_B_BGA1-IC,TBD    I20 @BASEBOARD_FAB2_LIB.BASEBOARD_FAB2(SCH_1):PAGE40
  U5D1  J40 VSS<1096> SKX_EXT_B_BGA1-IC,TBD    I20 @BASEBOARD_FAB2_LIB.BASEBOARD_FAB2(SCH_1):PAGE40
  U5D1  J38 VSS<1097> SKX_EXT_B_BGA1-IC,TBD    I20 @BASEBOARD_FAB2_LIB.BASEBOARD_FAB2(SCH_1):PAGE40
  U5D1  J34 VSS<1098> SKX_EXT_B_BGA1-IC,TBD    I20 @BASEBOARD_FAB2_LIB.BASEBOARD_FAB2(SCH_1):PAGE40
  U5D1  J32 VSS<1099> SKX_EXT_B_BGA1-IC,TBD    I20 @BASEBOARD_FAB2_LIB.BASEBOARD_FAB2(SCH_1):PAGE40
  U5D1  J28 VSS<1100> SKX_EXT_B_BGA1-IC,TBD    I20 @BASEBOARD_FAB2_LIB.BASEBOARD_FAB2(SCH_1):PAGE40
  U5D1  J26 VSS<1101> SKX_EXT_B_BGA1-IC,TBD    I20 @BASEBOARD_FAB2_LIB.BASEBOARD_FAB2(SCH_1):PAGE40
  U5D1  J22 VSS<1102> SKX_EXT_B_BGA1-IC,TBD    I20 @BASEBOARD_FAB2_LIB.BASEBOARD_FAB2(SCH_1):PAGE40
  U5D1  J14 VSS<1103> SKX_EXT_B_BGA1-IC,TBD    I20 @BASEBOARD_FAB2_LIB.BASEBOARD_FAB2(SCH_1):PAGE40
  U5D1  J12 VSS<1104> SKX_EXT_B_BGA1-IC,TBD    I20 @BASEBOARD_FAB2_LIB.BASEBOARD_FAB2(SCH_1):PAGE40
  U5D1   J4 VSS<1105> SKX_EXT_B_BGA1-IC,TBD    I20 @BASEBOARD_FAB2_LIB.BASEBOARD_FAB2(SCH_1):PAGE40
  U5D1 DN44 VSS<1106> SKX_EXT_B_BGA1-IC,TBD    I20 @BASEBOARD_FAB2_LIB.BASEBOARD_FAB2(SCH_1):PAGE40
  U5D1  H75 VSS<1107> SKX_EXT_B_BGA1-IC,TBD    I20 @BASEBOARD_FAB2_LIB.BASEBOARD_FAB2(SCH_1):PAGE40
  U5D1  H71 VSS<1108> SKX_EXT_B_BGA1-IC,TBD    I20 @BASEBOARD_FAB2_LIB.BASEBOARD_FAB2(SCH_1):PAGE40
  U5D1  H65 VSS<1109> SKX_EXT_B_BGA1-IC,TBD    I20 @BASEBOARD_FAB2_LIB.BASEBOARD_FAB2(SCH_1):PAGE40
  U5D1  H41 VSS<1110> SKX_EXT_B_BGA1-IC,TBD    I20 @BASEBOARD_FAB2_LIB.BASEBOARD_FAB2(SCH_1):PAGE40
  U5D1  H39 VSS<1111> SKX_EXT_B_BGA1-IC,TBD    I20 @BASEBOARD_FAB2_LIB.BASEBOARD_FAB2(SCH_1):PAGE40
  U5D1  H37 VSS<1112> SKX_EXT_B_BGA1-IC,TBD    I20 @BASEBOARD_FAB2_LIB.BASEBOARD_FAB2(SCH_1):PAGE40
  U5D1  H35 VSS<1113> SKX_EXT_B_BGA1-IC,TBD    I20 @BASEBOARD_FAB2_LIB.BASEBOARD_FAB2(SCH_1):PAGE40
  U5D1  H33 VSS<1114> SKX_EXT_B_BGA1-IC,TBD    I20 @BASEBOARD_FAB2_LIB.BASEBOARD_FAB2(SCH_1):PAGE40
  U5D1  H31 VSS<1115> SKX_EXT_B_BGA1-IC,TBD    I20 @BASEBOARD_FAB2_LIB.BASEBOARD_FAB2(SCH_1):PAGE40
  U5D1  H29 VSS<1116> SKX_EXT_B_BGA1-IC,TBD    I20 @BASEBOARD_FAB2_LIB.BASEBOARD_FAB2(SCH_1):PAGE40
  U5D1  H27 VSS<1117> SKX_EXT_B_BGA1-IC,TBD    I20 @BASEBOARD_FAB2_LIB.BASEBOARD_FAB2(SCH_1):PAGE40
  U5D1  H25 VSS<1118> SKX_EXT_B_BGA1-IC,TBD    I20 @BASEBOARD_FAB2_LIB.BASEBOARD_FAB2(SCH_1):PAGE40
  U5D1  H11 VSS<1119> SKX_EXT_B_BGA1-IC,TBD    I20 @BASEBOARD_FAB2_LIB.BASEBOARD_FAB2(SCH_1):PAGE40
  U5D1   H3 VSS<1120> SKX_EXT_B_BGA1-IC,TBD    I20 @BASEBOARD_FAB2_LIB.BASEBOARD_FAB2(SCH_1):PAGE40
  U5D1  G82 VSS<1121> SKX_EXT_B_BGA1-IC,TBD    I20 @BASEBOARD_FAB2_LIB.BASEBOARD_FAB2(SCH_1):PAGE40
  U5D1  G80 VSS<1122> SKX_EXT_B_BGA1-IC,TBD    I20 @BASEBOARD_FAB2_LIB.BASEBOARD_FAB2(SCH_1):PAGE40
  U5D1  G78 VSS<1123> SKX_EXT_B_BGA1-IC,TBD    I20 @BASEBOARD_FAB2_LIB.BASEBOARD_FAB2(SCH_1):PAGE40
  U5D1  G76 VSS<1124> SKX_EXT_B_BGA1-IC,TBD    I20 @BASEBOARD_FAB2_LIB.BASEBOARD_FAB2(SCH_1):PAGE40
  U5D1  G70 VSS<1125> SKX_EXT_B_BGA1-IC,TBD    I20 @BASEBOARD_FAB2_LIB.BASEBOARD_FAB2(SCH_1):PAGE40
  U5D1  G66 VSS<1126> SKX_EXT_B_BGA1-IC,TBD    I20 @BASEBOARD_FAB2_LIB.BASEBOARD_FAB2(SCH_1):PAGE40
  U5D1  G42 VSS<1127> SKX_EXT_B_BGA1-IC,TBD    I20 @BASEBOARD_FAB2_LIB.BASEBOARD_FAB2(SCH_1):PAGE40
  U5D1  G38 VSS<1128> SKX_EXT_B_BGA1-IC,TBD    I20 @BASEBOARD_FAB2_LIB.BASEBOARD_FAB2(SCH_1):PAGE40
  U5D1  G36 VSS<1129> SKX_EXT_B_BGA1-IC,TBD    I20 @BASEBOARD_FAB2_LIB.BASEBOARD_FAB2(SCH_1):PAGE40
  U5D1  G32 VSS<1130> SKX_EXT_B_BGA1-IC,TBD    I20 @BASEBOARD_FAB2_LIB.BASEBOARD_FAB2(SCH_1):PAGE40
  U5D1  G30 VSS<1131> SKX_EXT_B_BGA1-IC,TBD    I20 @BASEBOARD_FAB2_LIB.BASEBOARD_FAB2(SCH_1):PAGE40
  U5D1  G26 VSS<1132> SKX_EXT_B_BGA1-IC,TBD    I20 @BASEBOARD_FAB2_LIB.BASEBOARD_FAB2(SCH_1):PAGE40
  U5D1  G24 VSS<1133> SKX_EXT_B_BGA1-IC,TBD    I20 @BASEBOARD_FAB2_LIB.BASEBOARD_FAB2(SCH_1):PAGE40
  U5D1  G22 VSS<1134> SKX_EXT_B_BGA1-IC,TBD    I20 @BASEBOARD_FAB2_LIB.BASEBOARD_FAB2(SCH_1):PAGE40
  U5D1   G8 VSS<1135> SKX_EXT_B_BGA1-IC,TBD    I20 @BASEBOARD_FAB2_LIB.BASEBOARD_FAB2(SCH_1):PAGE40
  U5D1   G4 VSS<1136> SKX_EXT_B_BGA1-IC,TBD    I20 @BASEBOARD_FAB2_LIB.BASEBOARD_FAB2(SCH_1):PAGE40
  U5D1  F69 VSS<1137> SKX_EXT_B_BGA1-IC,TBD    I20 @BASEBOARD_FAB2_LIB.BASEBOARD_FAB2(SCH_1):PAGE40
  U5D1  F67 VSS<1138> SKX_EXT_B_BGA1-IC,TBD    I20 @BASEBOARD_FAB2_LIB.BASEBOARD_FAB2(SCH_1):PAGE40
  U5D1  F43 VSS<1139> SKX_EXT_B_BGA1-IC,TBD    I20 @BASEBOARD_FAB2_LIB.BASEBOARD_FAB2(SCH_1):PAGE40
  U5D1  F37 VSS<1140> SKX_EXT_B_BGA1-IC,TBD    I20 @BASEBOARD_FAB2_LIB.BASEBOARD_FAB2(SCH_1):PAGE40
  U5D1  F31 VSS<1141> SKX_EXT_B_BGA1-IC,TBD    I20 @BASEBOARD_FAB2_LIB.BASEBOARD_FAB2(SCH_1):PAGE40
  U5D1  F25 VSS<1142> SKX_EXT_B_BGA1-IC,TBD    I20 @BASEBOARD_FAB2_LIB.BASEBOARD_FAB2(SCH_1):PAGE40
  U5D1  F19 VSS<1143> SKX_EXT_B_BGA1-IC,TBD    I20 @BASEBOARD_FAB2_LIB.BASEBOARD_FAB2(SCH_1):PAGE40
  U5D1  F17 VSS<1144> SKX_EXT_B_BGA1-IC,TBD    I20 @BASEBOARD_FAB2_LIB.BASEBOARD_FAB2(SCH_1):PAGE40
  U5D1   F5 VSS<1145> SKX_EXT_B_BGA1-IC,TBD    I20 @BASEBOARD_FAB2_LIB.BASEBOARD_FAB2(SCH_1):PAGE40
  U5D1  E76 VSS<1146> SKX_EXT_B_BGA1-IC,TBD    I20 @BASEBOARD_FAB2_LIB.BASEBOARD_FAB2(SCH_1):PAGE40
  U5D1  E74 VSS<1147> SKX_EXT_B_BGA1-IC,TBD    I20 @BASEBOARD_FAB2_LIB.BASEBOARD_FAB2(SCH_1):PAGE40
  U5D1  E72 VSS<1148> SKX_EXT_B_BGA1-IC,TBD    I20 @BASEBOARD_FAB2_LIB.BASEBOARD_FAB2(SCH_1):PAGE40
  U5D1  E22 VSS<1149> SKX_EXT_B_BGA1-IC,TBD    I20 @BASEBOARD_FAB2_LIB.BASEBOARD_FAB2(SCH_1):PAGE40
  U5D1  E20 VSS<1150> SKX_EXT_B_BGA1-IC,TBD    I20 @BASEBOARD_FAB2_LIB.BASEBOARD_FAB2(SCH_1):PAGE40
  U5D1  E18 VSS<1151> SKX_EXT_B_BGA1-IC,TBD    I20 @BASEBOARD_FAB2_LIB.BASEBOARD_FAB2(SCH_1):PAGE40
  U5D1  E16 VSS<1152> SKX_EXT_B_BGA1-IC,TBD    I20 @BASEBOARD_FAB2_LIB.BASEBOARD_FAB2(SCH_1):PAGE40
  U5D1   E8 VSS<1153> SKX_EXT_B_BGA1-IC,TBD    I20 @BASEBOARD_FAB2_LIB.BASEBOARD_FAB2(SCH_1):PAGE40
  U5D1   E6 VSS<1154> SKX_EXT_B_BGA1-IC,TBD    I20 @BASEBOARD_FAB2_LIB.BASEBOARD_FAB2(SCH_1):PAGE40
  U5D1  D77 VSS<1155> SKX_EXT_B_BGA1-IC,TBD    I20 @BASEBOARD_FAB2_LIB.BASEBOARD_FAB2(SCH_1):PAGE40
  U5D1  D43 VSS<1156> SKX_EXT_B_BGA1-IC,TBD    I20 @BASEBOARD_FAB2_LIB.BASEBOARD_FAB2(SCH_1):PAGE40
  U5D1  D41 VSS<1157> SKX_EXT_B_BGA1-IC,TBD    I20 @BASEBOARD_FAB2_LIB.BASEBOARD_FAB2(SCH_1):PAGE40
  U5D1  D39 VSS<1158> SKX_EXT_B_BGA1-IC,TBD    I20 @BASEBOARD_FAB2_LIB.BASEBOARD_FAB2(SCH_1):PAGE40
  U5D1  D37 VSS<1159> SKX_EXT_B_BGA1-IC,TBD    I20 @BASEBOARD_FAB2_LIB.BASEBOARD_FAB2(SCH_1):PAGE40
  U5D1  D35 VSS<1160> SKX_EXT_B_BGA1-IC,TBD    I20 @BASEBOARD_FAB2_LIB.BASEBOARD_FAB2(SCH_1):PAGE40
  U5D1  D33 VSS<1161> SKX_EXT_B_BGA1-IC,TBD    I20 @BASEBOARD_FAB2_LIB.BASEBOARD_FAB2(SCH_1):PAGE40
  U5D1  D31 VSS<1162> SKX_EXT_B_BGA1-IC,TBD    I20 @BASEBOARD_FAB2_LIB.BASEBOARD_FAB2(SCH_1):PAGE40
  U5D1  D29 VSS<1163> SKX_EXT_B_BGA1-IC,TBD    I20 @BASEBOARD_FAB2_LIB.BASEBOARD_FAB2(SCH_1):PAGE40
  U5D1  D27 VSS<1164> SKX_EXT_B_BGA1-IC,TBD    I20 @BASEBOARD_FAB2_LIB.BASEBOARD_FAB2(SCH_1):PAGE40
  U5D1  D25 VSS<1165> SKX_EXT_B_BGA1-IC,TBD    I20 @BASEBOARD_FAB2_LIB.BASEBOARD_FAB2(SCH_1):PAGE40
  U5D1  D13 VSS<1166> SKX_EXT_B_BGA1-IC,TBD    I20 @BASEBOARD_FAB2_LIB.BASEBOARD_FAB2(SCH_1):PAGE40
  U5D1  D11 VSS<1167> SKX_EXT_B_BGA1-IC,TBD    I20 @BASEBOARD_FAB2_LIB.BASEBOARD_FAB2(SCH_1):PAGE40
  U5D1 CM27 VSS<1168> SKX_EXT_B_BGA1-IC,TBD    I20 @BASEBOARD_FAB2_LIB.BASEBOARD_FAB2(SCH_1):PAGE40
  U5D1  C78 VSS<1169> SKX_EXT_B_BGA1-IC,TBD    I20 @BASEBOARD_FAB2_LIB.BASEBOARD_FAB2(SCH_1):PAGE40
  U5D1  C76 VSS<1170> SKX_EXT_B_BGA1-IC,TBD    I20 @BASEBOARD_FAB2_LIB.BASEBOARD_FAB2(SCH_1):PAGE40
  U5D1  C16 VSS<1171> SKX_EXT_B_BGA1-IC,TBD    I20 @BASEBOARD_FAB2_LIB.BASEBOARD_FAB2(SCH_1):PAGE40
  U5D1  C14 VSS<1172> SKX_EXT_B_BGA1-IC,TBD    I20 @BASEBOARD_FAB2_LIB.BASEBOARD_FAB2(SCH_1):PAGE40
  U5D1  C12 VSS<1173> SKX_EXT_B_BGA1-IC,TBD    I20 @BASEBOARD_FAB2_LIB.BASEBOARD_FAB2(SCH_1):PAGE40
  U5D1  C10 VSS<1174> SKX_EXT_B_BGA1-IC,TBD    I20 @BASEBOARD_FAB2_LIB.BASEBOARD_FAB2(SCH_1):PAGE40
  U5D1   C8 VSS<1175> SKX_EXT_B_BGA1-IC,TBD    I20 @BASEBOARD_FAB2_LIB.BASEBOARD_FAB2(SCH_1):PAGE40
  U5D1  B75 VSS<1176> SKX_EXT_B_BGA1-IC,TBD    I20 @BASEBOARD_FAB2_LIB.BASEBOARD_FAB2(SCH_1):PAGE40
  U5D1  B71 VSS<1177> SKX_EXT_B_BGA1-IC,TBD    I20 @BASEBOARD_FAB2_LIB.BASEBOARD_FAB2(SCH_1):PAGE40
  U5D1  B37 VSS<1178> SKX_EXT_B_BGA1-IC,TBD    I20 @BASEBOARD_FAB2_LIB.BASEBOARD_FAB2(SCH_1):PAGE40
  U5D1  B31 VSS<1179> SKX_EXT_B_BGA1-IC,TBD    I20 @BASEBOARD_FAB2_LIB.BASEBOARD_FAB2(SCH_1):PAGE40
  U5D1  B25 VSS<1180> SKX_EXT_B_BGA1-IC,TBD    I20 @BASEBOARD_FAB2_LIB.BASEBOARD_FAB2(SCH_1):PAGE40
  U5D1  A38 VSS<1181> SKX_EXT_B_BGA1-IC,TBD    I20 @BASEBOARD_FAB2_LIB.BASEBOARD_FAB2(SCH_1):PAGE40
  U5D1  A36 VSS<1182> SKX_EXT_B_BGA1-IC,TBD    I20 @BASEBOARD_FAB2_LIB.BASEBOARD_FAB2(SCH_1):PAGE40
  U5D1  A32 VSS<1183> SKX_EXT_B_BGA1-IC,TBD    I20 @BASEBOARD_FAB2_LIB.BASEBOARD_FAB2(SCH_1):PAGE40
  U5D1  A30 VSS<1184> SKX_EXT_B_BGA1-IC,TBD    I20 @BASEBOARD_FAB2_LIB.BASEBOARD_FAB2(SCH_1):PAGE40
  U5D1  A26 VSS<1185> SKX_EXT_B_BGA1-IC,TBD    I20 @BASEBOARD_FAB2_LIB.BASEBOARD_FAB2(SCH_1):PAGE40
  U5D1 AC58 VSS<1186> SKX_EXT_B_BGA1-IC,TBD    I20 @BASEBOARD_FAB2_LIB.BASEBOARD_FAB2(SCH_1):PAGE40
  U5D1 AC60 VSS<1187> SKX_EXT_B_BGA1-IC,TBD    I20 @BASEBOARD_FAB2_LIB.BASEBOARD_FAB2(SCH_1):PAGE40
  U5D1 AC62 VSS<1188> SKX_EXT_B_BGA1-IC,TBD    I20 @BASEBOARD_FAB2_LIB.BASEBOARD_FAB2(SCH_1):PAGE40
  U5D1  AJ4 VSS<1189> SKX_EXT_B_BGA1-IC,TBD    I20 @BASEBOARD_FAB2_LIB.BASEBOARD_FAB2(SCH_1):PAGE40
  U5D1  AR6 VSS<1190> SKX_EXT_B_BGA1-IC,TBD    I20 @BASEBOARD_FAB2_LIB.BASEBOARD_FAB2(SCH_1):PAGE40
  U5D1  CG6 VSS<1191> SKX_EXT_B_BGA1-IC,TBD    I20 @BASEBOARD_FAB2_LIB.BASEBOARD_FAB2(SCH_1):PAGE40
  U5D1  CW6 VSS<1192> SKX_EXT_B_BGA1-IC,TBD    I20 @BASEBOARD_FAB2_LIB.BASEBOARD_FAB2(SCH_1):PAGE40
  U5D1 DE48 VSS<1193> SKX_EXT_B_BGA1-IC,TBD    I20 @BASEBOARD_FAB2_LIB.BASEBOARD_FAB2(SCH_1):PAGE40
  U5D1 DE50 VSS<1194> SKX_EXT_B_BGA1-IC,TBD    I20 @BASEBOARD_FAB2_LIB.BASEBOARD_FAB2(SCH_1):PAGE40
  U5D1 DE52 VSS<1195> SKX_EXT_B_BGA1-IC,TBD    I20 @BASEBOARD_FAB2_LIB.BASEBOARD_FAB2(SCH_1):PAGE40
  U5D1 DE54 VSS<1196> SKX_EXT_B_BGA1-IC,TBD    I20 @BASEBOARD_FAB2_LIB.BASEBOARD_FAB2(SCH_1):PAGE40
  U5D1 DE56 VSS<1197> SKX_EXT_B_BGA1-IC,TBD    I20 @BASEBOARD_FAB2_LIB.BASEBOARD_FAB2(SCH_1):PAGE40
  U5D1 DE58 VSS<1198> SKX_EXT_B_BGA1-IC,TBD    I20 @BASEBOARD_FAB2_LIB.BASEBOARD_FAB2(SCH_1):PAGE40
  U5D1 DE60 VSS<1199> SKX_EXT_B_BGA1-IC,TBD    I20 @BASEBOARD_FAB2_LIB.BASEBOARD_FAB2(SCH_1):PAGE40
  U5D1 DE62 VSS<1200> SKX_EXT_B_BGA1-IC,TBD    I20 @BASEBOARD_FAB2_LIB.BASEBOARD_FAB2(SCH_1):PAGE40
  U5D1  DL8 VSS<1201> SKX_EXT_B_BGA1-IC,TBD    I20 @BASEBOARD_FAB2_LIB.BASEBOARD_FAB2(SCH_1):PAGE40
  U5D1 DN18 VSS<1202> SKX_EXT_B_BGA1-IC,TBD    I20 @BASEBOARD_FAB2_LIB.BASEBOARD_FAB2(SCH_1):PAGE40
  U5D1 DP45 VSS<1203> SKX_EXT_B_BGA1-IC,TBD    I20 @BASEBOARD_FAB2_LIB.BASEBOARD_FAB2(SCH_1):PAGE40
  U5D1 DP47 VSS<1204> SKX_EXT_B_BGA1-IC,TBD    I20 @BASEBOARD_FAB2_LIB.BASEBOARD_FAB2(SCH_1):PAGE40
  U5D1 DP49 VSS<1205> SKX_EXT_B_BGA1-IC,TBD    I20 @BASEBOARD_FAB2_LIB.BASEBOARD_FAB2(SCH_1):PAGE40
  U5D1 DP51 VSS<1206> SKX_EXT_B_BGA1-IC,TBD    I20 @BASEBOARD_FAB2_LIB.BASEBOARD_FAB2(SCH_1):PAGE40
  U5D1 DP53 VSS<1207> SKX_EXT_B_BGA1-IC,TBD    I20 @BASEBOARD_FAB2_LIB.BASEBOARD_FAB2(SCH_1):PAGE40
  U5D1 DP55 VSS<1208> SKX_EXT_B_BGA1-IC,TBD    I20 @BASEBOARD_FAB2_LIB.BASEBOARD_FAB2(SCH_1):PAGE40
  U5D1 DP57 VSS<1209> SKX_EXT_B_BGA1-IC,TBD    I20 @BASEBOARD_FAB2_LIB.BASEBOARD_FAB2(SCH_1):PAGE40
  U5D1 DP59 VSS<1210> SKX_EXT_B_BGA1-IC,TBD    I20 @BASEBOARD_FAB2_LIB.BASEBOARD_FAB2(SCH_1):PAGE40
  U5D1 DP61 VSS<1211> SKX_EXT_B_BGA1-IC,TBD    I20 @BASEBOARD_FAB2_LIB.BASEBOARD_FAB2(SCH_1):PAGE40
  U5D1 DP63 VSS<1212> SKX_EXT_B_BGA1-IC,TBD    I20 @BASEBOARD_FAB2_LIB.BASEBOARD_FAB2(SCH_1):PAGE40
  U5D1  DP9 VSS<1213> SKX_EXT_B_BGA1-IC,TBD    I20 @BASEBOARD_FAB2_LIB.BASEBOARD_FAB2(SCH_1):PAGE40
  U5D1 DV19 VSS<1214> SKX_EXT_B_BGA1-IC,TBD    I20 @BASEBOARD_FAB2_LIB.BASEBOARD_FAB2(SCH_1):PAGE40
  U5D1 DY45 VSS<1215> SKX_EXT_B_BGA1-IC,TBD    I20 @BASEBOARD_FAB2_LIB.BASEBOARD_FAB2(SCH_1):PAGE40
  U5D1 DY47 VSS<1216> SKX_EXT_B_BGA1-IC,TBD    I20 @BASEBOARD_FAB2_LIB.BASEBOARD_FAB2(SCH_1):PAGE40
  U5D1 DY49 VSS<1217> SKX_EXT_B_BGA1-IC,TBD    I20 @BASEBOARD_FAB2_LIB.BASEBOARD_FAB2(SCH_1):PAGE40
  U5D1 DY51 VSS<1218> SKX_EXT_B_BGA1-IC,TBD    I20 @BASEBOARD_FAB2_LIB.BASEBOARD_FAB2(SCH_1):PAGE40
  U5D1 DY53 VSS<1219> SKX_EXT_B_BGA1-IC,TBD    I20 @BASEBOARD_FAB2_LIB.BASEBOARD_FAB2(SCH_1):PAGE40
  U5D1 DY55 VSS<1220> SKX_EXT_B_BGA1-IC,TBD    I20 @BASEBOARD_FAB2_LIB.BASEBOARD_FAB2(SCH_1):PAGE40
  U5D1 DY57 VSS<1221> SKX_EXT_B_BGA1-IC,TBD    I20 @BASEBOARD_FAB2_LIB.BASEBOARD_FAB2(SCH_1):PAGE40
  U5D1 DY59 VSS<1222> SKX_EXT_B_BGA1-IC,TBD    I20 @BASEBOARD_FAB2_LIB.BASEBOARD_FAB2(SCH_1):PAGE40
  U5D1 DY61 VSS<1223> SKX_EXT_B_BGA1-IC,TBD    I20 @BASEBOARD_FAB2_LIB.BASEBOARD_FAB2(SCH_1):PAGE40
  U5D1 DY63 VSS<1224> SKX_EXT_B_BGA1-IC,TBD    I20 @BASEBOARD_FAB2_LIB.BASEBOARD_FAB2(SCH_1):PAGE40
  U5D1 EA14 VSS<1225> SKX_EXT_B_BGA1-IC,TBD    I20 @BASEBOARD_FAB2_LIB.BASEBOARD_FAB2(SCH_1):PAGE40
  U5D1   L8 VSS<1226> SKX_EXT_B_BGA1-IC,TBD    I20 @BASEBOARD_FAB2_LIB.BASEBOARD_FAB2(SCH_1):PAGE40
  U5D1  V11 VSS<1227> SKX_EXT_B_BGA1-IC,TBD    I20 @BASEBOARD_FAB2_LIB.BASEBOARD_FAB2(SCH_1):PAGE40
  U5D1  E66 VSS<1228> SKX_EXT_B_BGA1-IC,TBD    I20 @BASEBOARD_FAB2_LIB.BASEBOARD_FAB2(SCH_1):PAGE40
  U5D1 ED69 VSS<1229> SKX_EXT_B_BGA1-IC,TBD    I20 @BASEBOARD_FAB2_LIB.BASEBOARD_FAB2(SCH_1):PAGE40
  U5D1 EE80 VSS<1230> SKX_EXT_B_BGA1-IC,TBD    I20 @BASEBOARD_FAB2_LIB.BASEBOARD_FAB2(SCH_1):PAGE40
  U5D1  EE8 VSS<1231> SKX_EXT_B_BGA1-IC,TBD    I20 @BASEBOARD_FAB2_LIB.BASEBOARD_FAB2(SCH_1):PAGE40
  U5D1 EE40 VSS<1232> SKX_EXT_B_BGA1-IC,TBD    I20 @BASEBOARD_FAB2_LIB.BASEBOARD_FAB2(SCH_1):PAGE40
  U5D1 ED81 VSS<1233> SKX_EXT_B_BGA1-IC,TBD    I20 @BASEBOARD_FAB2_LIB.BASEBOARD_FAB2(SCH_1):PAGE40
  U5D1  ED7 VSS<1234> SKX_EXT_B_BGA1-IC,TBD    I20 @BASEBOARD_FAB2_LIB.BASEBOARD_FAB2(SCH_1):PAGE40
  U5D1 ED41 VSS<1235> SKX_EXT_B_BGA1-IC,TBD    I20 @BASEBOARD_FAB2_LIB.BASEBOARD_FAB2(SCH_1):PAGE40
  U5D1 EC82 VSS<1236> SKX_EXT_B_BGA1-IC,TBD    I20 @BASEBOARD_FAB2_LIB.BASEBOARD_FAB2(SCH_1):PAGE40
  U5D1  EC6 VSS<1237> SKX_EXT_B_BGA1-IC,TBD    I20 @BASEBOARD_FAB2_LIB.BASEBOARD_FAB2(SCH_1):PAGE40
  U5D1 EC42 VSS<1238> SKX_EXT_B_BGA1-IC,TBD    I20 @BASEBOARD_FAB2_LIB.BASEBOARD_FAB2(SCH_1):PAGE40
  U5D1  DW2 VSS<1239> SKX_EXT_B_BGA1-IC,TBD    I20 @BASEBOARD_FAB2_LIB.BASEBOARD_FAB2(SCH_1):PAGE40
  U5D1 EB83 VSS<1240> SKX_EXT_B_BGA1-IC,TBD    I20 @BASEBOARD_FAB2_LIB.BASEBOARD_FAB2(SCH_1):PAGE40
  U5D1 EA84 VSS<1241> SKX_EXT_B_BGA1-IC,TBD    I20 @BASEBOARD_FAB2_LIB.BASEBOARD_FAB2(SCH_1):PAGE40
  U5D1 DY85 VSS<1242> SKX_EXT_B_BGA1-IC,TBD    I20 @BASEBOARD_FAB2_LIB.BASEBOARD_FAB2(SCH_1):PAGE40
  U5D1  J86 VSS<1243> SKX_EXT_B_BGA1-IC,TBD    I20 @BASEBOARD_FAB2_LIB.BASEBOARD_FAB2(SCH_1):PAGE40
  U5D1  E82 VSS<1244> SKX_EXT_B_BGA1-IC,TBD    I20 @BASEBOARD_FAB2_LIB.BASEBOARD_FAB2(SCH_1):PAGE40
  U5D1  D81 VSS<1245> SKX_EXT_B_BGA1-IC,TBD    I20 @BASEBOARD_FAB2_LIB.BASEBOARD_FAB2(SCH_1):PAGE40
  U5D1   D3 VSS<1246> SKX_EXT_B_BGA1-IC,TBD    I20 @BASEBOARD_FAB2_LIB.BASEBOARD_FAB2(SCH_1):PAGE40
  U5D1  C80 VSS<1247> SKX_EXT_B_BGA1-IC,TBD    I20 @BASEBOARD_FAB2_LIB.BASEBOARD_FAB2(SCH_1):PAGE40
  U5D1   C4 VSS<1248> SKX_EXT_B_BGA1-IC,TBD    I20 @BASEBOARD_FAB2_LIB.BASEBOARD_FAB2(SCH_1):PAGE40
  U5D1  B79 VSS<1249> SKX_EXT_B_BGA1-IC,TBD    I20 @BASEBOARD_FAB2_LIB.BASEBOARD_FAB2(SCH_1):PAGE40
  U5D1   B5 VSS<1250> SKX_EXT_B_BGA1-IC,TBD    I20 @BASEBOARD_FAB2_LIB.BASEBOARD_FAB2(SCH_1):PAGE40
  U5D1  B43 VSS<1251> SKX_EXT_B_BGA1-IC,TBD    I20 @BASEBOARD_FAB2_LIB.BASEBOARD_FAB2(SCH_1):PAGE40
  U5D1  A42 VSS<1252> SKX_EXT_B_BGA1-IC,TBD    I20 @BASEBOARD_FAB2_LIB.BASEBOARD_FAB2(SCH_1):PAGE40
  U5D1   B9 VSS<1253> SKX_EXT_B_BGA1-IC,TBD    I20 @BASEBOARD_FAB2_LIB.BASEBOARD_FAB2(SCH_1):PAGE40
  U5D1 AA16 VSS<934> SKX_EXT_B_BGA1-IC,TBD    I21 @BASEBOARD_FAB2_LIB.BASEBOARD_FAB2(SCH_1):PAGE40
  U5D1  AA4 VSS<935> SKX_EXT_B_BGA1-IC,TBD    I21 @BASEBOARD_FAB2_LIB.BASEBOARD_FAB2(SCH_1):PAGE40
  U5D1  Y85 VSS<936> SKX_EXT_B_BGA1-IC,TBD    I21 @BASEBOARD_FAB2_LIB.BASEBOARD_FAB2(SCH_1):PAGE40
  U5D1  Y83 VSS<937> SKX_EXT_B_BGA1-IC,TBD    I21 @BASEBOARD_FAB2_LIB.BASEBOARD_FAB2(SCH_1):PAGE40
  U5D1  Y81 VSS<938> SKX_EXT_B_BGA1-IC,TBD    I21 @BASEBOARD_FAB2_LIB.BASEBOARD_FAB2(SCH_1):PAGE40
  U5D1  Y79 VSS<939> SKX_EXT_B_BGA1-IC,TBD    I21 @BASEBOARD_FAB2_LIB.BASEBOARD_FAB2(SCH_1):PAGE40
  U5D1  Y73 VSS<940> SKX_EXT_B_BGA1-IC,TBD    I21 @BASEBOARD_FAB2_LIB.BASEBOARD_FAB2(SCH_1):PAGE40
  U5D1  Y71 VSS<941> SKX_EXT_B_BGA1-IC,TBD    I21 @BASEBOARD_FAB2_LIB.BASEBOARD_FAB2(SCH_1):PAGE40
  U5D1   Y9 VSS<942> SKX_EXT_B_BGA1-IC,TBD    I21 @BASEBOARD_FAB2_LIB.BASEBOARD_FAB2(SCH_1):PAGE40
  U5D1   Y7 VSS<943> SKX_EXT_B_BGA1-IC,TBD    I21 @BASEBOARD_FAB2_LIB.BASEBOARD_FAB2(SCH_1):PAGE40
  U5D1  Y67 VSS<944> SKX_EXT_B_BGA1-IC,TBD    I21 @BASEBOARD_FAB2_LIB.BASEBOARD_FAB2(SCH_1):PAGE40
  U5D1   Y5 VSS<945> SKX_EXT_B_BGA1-IC,TBD    I21 @BASEBOARD_FAB2_LIB.BASEBOARD_FAB2(SCH_1):PAGE40
  U5D1  Y17 VSS<946> SKX_EXT_B_BGA1-IC,TBD    I21 @BASEBOARD_FAB2_LIB.BASEBOARD_FAB2(SCH_1):PAGE40
  U5D1  Y15 VSS<947> SKX_EXT_B_BGA1-IC,TBD    I21 @BASEBOARD_FAB2_LIB.BASEBOARD_FAB2(SCH_1):PAGE40
  U5D1  W82 VSS<948> SKX_EXT_B_BGA1-IC,TBD    I21 @BASEBOARD_FAB2_LIB.BASEBOARD_FAB2(SCH_1):PAGE40
  U5D1  W78 VSS<949> SKX_EXT_B_BGA1-IC,TBD    I21 @BASEBOARD_FAB2_LIB.BASEBOARD_FAB2(SCH_1):PAGE40
  U5D1  W74 VSS<950> SKX_EXT_B_BGA1-IC,TBD    I21 @BASEBOARD_FAB2_LIB.BASEBOARD_FAB2(SCH_1):PAGE40
  U5D1  W68 VSS<951> SKX_EXT_B_BGA1-IC,TBD    I21 @BASEBOARD_FAB2_LIB.BASEBOARD_FAB2(SCH_1):PAGE40
  U5D1  W42 VSS<952> SKX_EXT_B_BGA1-IC,TBD    I21 @BASEBOARD_FAB2_LIB.BASEBOARD_FAB2(SCH_1):PAGE40
  U5D1  W40 VSS<953> SKX_EXT_B_BGA1-IC,TBD    I21 @BASEBOARD_FAB2_LIB.BASEBOARD_FAB2(SCH_1):PAGE40
  U5D1  W38 VSS<954> SKX_EXT_B_BGA1-IC,TBD    I21 @BASEBOARD_FAB2_LIB.BASEBOARD_FAB2(SCH_1):PAGE40
  U5D1  W36 VSS<955> SKX_EXT_B_BGA1-IC,TBD    I21 @BASEBOARD_FAB2_LIB.BASEBOARD_FAB2(SCH_1):PAGE40
  U5D1  W34 VSS<956> SKX_EXT_B_BGA1-IC,TBD    I21 @BASEBOARD_FAB2_LIB.BASEBOARD_FAB2(SCH_1):PAGE40
  U5D1  W32 VSS<957> SKX_EXT_B_BGA1-IC,TBD    I21 @BASEBOARD_FAB2_LIB.BASEBOARD_FAB2(SCH_1):PAGE40
  U5D1  W30 VSS<958> SKX_EXT_B_BGA1-IC,TBD    I21 @BASEBOARD_FAB2_LIB.BASEBOARD_FAB2(SCH_1):PAGE40
  U5D1  W28 VSS<959> SKX_EXT_B_BGA1-IC,TBD    I21 @BASEBOARD_FAB2_LIB.BASEBOARD_FAB2(SCH_1):PAGE40
  U5D1  W26 VSS<960> SKX_EXT_B_BGA1-IC,TBD    I21 @BASEBOARD_FAB2_LIB.BASEBOARD_FAB2(SCH_1):PAGE40
  U5D1  W24 VSS<961> SKX_EXT_B_BGA1-IC,TBD    I21 @BASEBOARD_FAB2_LIB.BASEBOARD_FAB2(SCH_1):PAGE40
  U5D1  W22 VSS<962> SKX_EXT_B_BGA1-IC,TBD    I21 @BASEBOARD_FAB2_LIB.BASEBOARD_FAB2(SCH_1):PAGE40
  U5D1  W12 VSS<963> SKX_EXT_B_BGA1-IC,TBD    I21 @BASEBOARD_FAB2_LIB.BASEBOARD_FAB2(SCH_1):PAGE40
  U5D1 AC56 VSS<964> SKX_EXT_B_BGA1-IC,TBD    I21 @BASEBOARD_FAB2_LIB.BASEBOARD_FAB2(SCH_1):PAGE40
  U5D1   W8 VSS<965> SKX_EXT_B_BGA1-IC,TBD    I21 @BASEBOARD_FAB2_LIB.BASEBOARD_FAB2(SCH_1):PAGE40
  U5D1  V83 VSS<966> SKX_EXT_B_BGA1-IC,TBD    I21 @BASEBOARD_FAB2_LIB.BASEBOARD_FAB2(SCH_1):PAGE40
  U5D1  V77 VSS<967> SKX_EXT_B_BGA1-IC,TBD    I21 @BASEBOARD_FAB2_LIB.BASEBOARD_FAB2(SCH_1):PAGE40
  U5D1  V75 VSS<968> SKX_EXT_B_BGA1-IC,TBD    I21 @BASEBOARD_FAB2_LIB.BASEBOARD_FAB2(SCH_1):PAGE40
  U5D1  V73 VSS<969> SKX_EXT_B_BGA1-IC,TBD    I21 @BASEBOARD_FAB2_LIB.BASEBOARD_FAB2(SCH_1):PAGE40
  U5D1  V43 VSS<970> SKX_EXT_B_BGA1-IC,TBD    I21 @BASEBOARD_FAB2_LIB.BASEBOARD_FAB2(SCH_1):PAGE40
  U5D1  V23 VSS<971> SKX_EXT_B_BGA1-IC,TBD    I21 @BASEBOARD_FAB2_LIB.BASEBOARD_FAB2(SCH_1):PAGE40
  U5D1  V21 VSS<972> SKX_EXT_B_BGA1-IC,TBD    I21 @BASEBOARD_FAB2_LIB.BASEBOARD_FAB2(SCH_1):PAGE40
  U5D1  V15 VSS<973> SKX_EXT_B_BGA1-IC,TBD    I21 @BASEBOARD_FAB2_LIB.BASEBOARD_FAB2(SCH_1):PAGE40
  U5D1  V13 VSS<974> SKX_EXT_B_BGA1-IC,TBD    I21 @BASEBOARD_FAB2_LIB.BASEBOARD_FAB2(SCH_1):PAGE40
  U5D1   V9 VSS<975> SKX_EXT_B_BGA1-IC,TBD    I21 @BASEBOARD_FAB2_LIB.BASEBOARD_FAB2(SCH_1):PAGE40
  U5D1   V5 VSS<976> SKX_EXT_B_BGA1-IC,TBD    I21 @BASEBOARD_FAB2_LIB.BASEBOARD_FAB2(SCH_1):PAGE40
  U5D1   V1 VSS<977> SKX_EXT_B_BGA1-IC,TBD    I21 @BASEBOARD_FAB2_LIB.BASEBOARD_FAB2(SCH_1):PAGE40
  U5D1  U86 VSS<978> SKX_EXT_B_BGA1-IC,TBD    I21 @BASEBOARD_FAB2_LIB.BASEBOARD_FAB2(SCH_1):PAGE40
  U5D1  U80 VSS<979> SKX_EXT_B_BGA1-IC,TBD    I21 @BASEBOARD_FAB2_LIB.BASEBOARD_FAB2(SCH_1):PAGE40
  U5D1  U78 VSS<980> SKX_EXT_B_BGA1-IC,TBD    I21 @BASEBOARD_FAB2_LIB.BASEBOARD_FAB2(SCH_1):PAGE40
  U5D1  U76 VSS<981> SKX_EXT_B_BGA1-IC,TBD    I21 @BASEBOARD_FAB2_LIB.BASEBOARD_FAB2(SCH_1):PAGE40
  U5D1  U74 VSS<982> SKX_EXT_B_BGA1-IC,TBD    I21 @BASEBOARD_FAB2_LIB.BASEBOARD_FAB2(SCH_1):PAGE40
  U5D1  U70 VSS<983> SKX_EXT_B_BGA1-IC,TBD    I21 @BASEBOARD_FAB2_LIB.BASEBOARD_FAB2(SCH_1):PAGE40
  U5D1  U68 VSS<984> SKX_EXT_B_BGA1-IC,TBD    I21 @BASEBOARD_FAB2_LIB.BASEBOARD_FAB2(SCH_1):PAGE40
  U5D1  U42 VSS<985> SKX_EXT_B_BGA1-IC,TBD    I21 @BASEBOARD_FAB2_LIB.BASEBOARD_FAB2(SCH_1):PAGE40
  U5D1  U36 VSS<986> SKX_EXT_B_BGA1-IC,TBD    I21 @BASEBOARD_FAB2_LIB.BASEBOARD_FAB2(SCH_1):PAGE40
  U5D1  U30 VSS<987> SKX_EXT_B_BGA1-IC,TBD    I21 @BASEBOARD_FAB2_LIB.BASEBOARD_FAB2(SCH_1):PAGE40
  U5D1  U24 VSS<988> SKX_EXT_B_BGA1-IC,TBD    I21 @BASEBOARD_FAB2_LIB.BASEBOARD_FAB2(SCH_1):PAGE40
  U5D1  U22 VSS<989> SKX_EXT_B_BGA1-IC,TBD    I21 @BASEBOARD_FAB2_LIB.BASEBOARD_FAB2(SCH_1):PAGE40
  U5D1  U20 VSS<990> SKX_EXT_B_BGA1-IC,TBD    I21 @BASEBOARD_FAB2_LIB.BASEBOARD_FAB2(SCH_1):PAGE40
  U5D1   U6 VSS<991> SKX_EXT_B_BGA1-IC,TBD    I21 @BASEBOARD_FAB2_LIB.BASEBOARD_FAB2(SCH_1):PAGE40
  U5D1   U4 VSS<992> SKX_EXT_B_BGA1-IC,TBD    I21 @BASEBOARD_FAB2_LIB.BASEBOARD_FAB2(SCH_1):PAGE40
  U5D1   U2 VSS<993> SKX_EXT_B_BGA1-IC,TBD    I21 @BASEBOARD_FAB2_LIB.BASEBOARD_FAB2(SCH_1):PAGE40
  U5D1  T85 VSS<994> SKX_EXT_B_BGA1-IC,TBD    I21 @BASEBOARD_FAB2_LIB.BASEBOARD_FAB2(SCH_1):PAGE40
  U5D1  T83 VSS<995> SKX_EXT_B_BGA1-IC,TBD    I21 @BASEBOARD_FAB2_LIB.BASEBOARD_FAB2(SCH_1):PAGE40
  U5D1  T77 VSS<996> SKX_EXT_B_BGA1-IC,TBD    I21 @BASEBOARD_FAB2_LIB.BASEBOARD_FAB2(SCH_1):PAGE40
  U5D1  T73 VSS<997> SKX_EXT_B_BGA1-IC,TBD    I21 @BASEBOARD_FAB2_LIB.BASEBOARD_FAB2(SCH_1):PAGE40
  U5D1  T65 VSS<998> SKX_EXT_B_BGA1-IC,TBD    I21 @BASEBOARD_FAB2_LIB.BASEBOARD_FAB2(SCH_1):PAGE40
  U5D1  T41 VSS<999> SKX_EXT_B_BGA1-IC,TBD    I21 @BASEBOARD_FAB2_LIB.BASEBOARD_FAB2(SCH_1):PAGE40
  U5D1  T37 VSS<1000> SKX_EXT_B_BGA1-IC,TBD    I21 @BASEBOARD_FAB2_LIB.BASEBOARD_FAB2(SCH_1):PAGE40
  U5D1  T35 VSS<1001> SKX_EXT_B_BGA1-IC,TBD    I21 @BASEBOARD_FAB2_LIB.BASEBOARD_FAB2(SCH_1):PAGE40
  U5D1  T31 VSS<1002> SKX_EXT_B_BGA1-IC,TBD    I21 @BASEBOARD_FAB2_LIB.BASEBOARD_FAB2(SCH_1):PAGE40
  U5D1  T29 VSS<1003> SKX_EXT_B_BGA1-IC,TBD    I21 @BASEBOARD_FAB2_LIB.BASEBOARD_FAB2(SCH_1):PAGE40
  U5D1  T25 VSS<1004> SKX_EXT_B_BGA1-IC,TBD    I21 @BASEBOARD_FAB2_LIB.BASEBOARD_FAB2(SCH_1):PAGE40
  U5D1  T17 VSS<1005> SKX_EXT_B_BGA1-IC,TBD    I21 @BASEBOARD_FAB2_LIB.BASEBOARD_FAB2(SCH_1):PAGE40
  U5D1  T13 VSS<1006> SKX_EXT_B_BGA1-IC,TBD    I21 @BASEBOARD_FAB2_LIB.BASEBOARD_FAB2(SCH_1):PAGE40
  U5D1  R86 VSS<1007> SKX_EXT_B_BGA1-IC,TBD    I21 @BASEBOARD_FAB2_LIB.BASEBOARD_FAB2(SCH_1):PAGE40
  U5D1  R78 VSS<1008> SKX_EXT_B_BGA1-IC,TBD    I21 @BASEBOARD_FAB2_LIB.BASEBOARD_FAB2(SCH_1):PAGE40
  U5D1  R72 VSS<1009> SKX_EXT_B_BGA1-IC,TBD    I21 @BASEBOARD_FAB2_LIB.BASEBOARD_FAB2(SCH_1):PAGE40
  U5D1  R68 VSS<1010> SKX_EXT_B_BGA1-IC,TBD    I21 @BASEBOARD_FAB2_LIB.BASEBOARD_FAB2(SCH_1):PAGE40
  U5D1  R40 VSS<1011> SKX_EXT_B_BGA1-IC,TBD    I21 @BASEBOARD_FAB2_LIB.BASEBOARD_FAB2(SCH_1):PAGE40
  U5D1  R38 VSS<1012> SKX_EXT_B_BGA1-IC,TBD    I21 @BASEBOARD_FAB2_LIB.BASEBOARD_FAB2(SCH_1):PAGE40
  U5D1  R34 VSS<1013> SKX_EXT_B_BGA1-IC,TBD    I21 @BASEBOARD_FAB2_LIB.BASEBOARD_FAB2(SCH_1):PAGE40
  U5D1  R32 VSS<1014> SKX_EXT_B_BGA1-IC,TBD    I21 @BASEBOARD_FAB2_LIB.BASEBOARD_FAB2(SCH_1):PAGE40
  U5D1  R28 VSS<1015> SKX_EXT_B_BGA1-IC,TBD    I21 @BASEBOARD_FAB2_LIB.BASEBOARD_FAB2(SCH_1):PAGE40
  U5D1  R26 VSS<1016> SKX_EXT_B_BGA1-IC,TBD    I21 @BASEBOARD_FAB2_LIB.BASEBOARD_FAB2(SCH_1):PAGE40
  U5D1  R22 VSS<1017> SKX_EXT_B_BGA1-IC,TBD    I21 @BASEBOARD_FAB2_LIB.BASEBOARD_FAB2(SCH_1):PAGE40
  U5D1   R4 VSS<1018> SKX_EXT_B_BGA1-IC,TBD    I21 @BASEBOARD_FAB2_LIB.BASEBOARD_FAB2(SCH_1):PAGE40
  U5D1   R2 VSS<1019> SKX_EXT_B_BGA1-IC,TBD    I21 @BASEBOARD_FAB2_LIB.BASEBOARD_FAB2(SCH_1):PAGE40
  U5D1  R18 VSS<1020> SKX_EXT_B_BGA1-IC,TBD    I21 @BASEBOARD_FAB2_LIB.BASEBOARD_FAB2(SCH_1):PAGE40
  U5D1  R14 VSS<1021> SKX_EXT_B_BGA1-IC,TBD    I21 @BASEBOARD_FAB2_LIB.BASEBOARD_FAB2(SCH_1):PAGE40
  U5D1  P83 VSS<1022> SKX_EXT_B_BGA1-IC,TBD    I21 @BASEBOARD_FAB2_LIB.BASEBOARD_FAB2(SCH_1):PAGE40
  U5D1  P81 VSS<1023> SKX_EXT_B_BGA1-IC,TBD    I21 @BASEBOARD_FAB2_LIB.BASEBOARD_FAB2(SCH_1):PAGE40
  U5D1  P71 VSS<1024> SKX_EXT_B_BGA1-IC,TBD    I21 @BASEBOARD_FAB2_LIB.BASEBOARD_FAB2(SCH_1):PAGE40
  U5D1  P69 VSS<1025> SKX_EXT_B_BGA1-IC,TBD    I21 @BASEBOARD_FAB2_LIB.BASEBOARD_FAB2(SCH_1):PAGE40
  U5D1  P67 VSS<1026> SKX_EXT_B_BGA1-IC,TBD    I21 @BASEBOARD_FAB2_LIB.BASEBOARD_FAB2(SCH_1):PAGE40
  U5D1  P39 VSS<1027> SKX_EXT_B_BGA1-IC,TBD    I21 @BASEBOARD_FAB2_LIB.BASEBOARD_FAB2(SCH_1):PAGE40
  U5D1  P33 VSS<1028> SKX_EXT_B_BGA1-IC,TBD    I21 @BASEBOARD_FAB2_LIB.BASEBOARD_FAB2(SCH_1):PAGE40
  U5D1  P27 VSS<1029> SKX_EXT_B_BGA1-IC,TBD    I21 @BASEBOARD_FAB2_LIB.BASEBOARD_FAB2(SCH_1):PAGE40
  U5D1  P15 VSS<1030> SKX_EXT_B_BGA1-IC,TBD    I21 @BASEBOARD_FAB2_LIB.BASEBOARD_FAB2(SCH_1):PAGE40
  U5D1  P11 VSS<1031> SKX_EXT_B_BGA1-IC,TBD    I21 @BASEBOARD_FAB2_LIB.BASEBOARD_FAB2(SCH_1):PAGE40
  U5D1   N8 VSS<1032> SKX_EXT_B_BGA1-IC,TBD    I21 @BASEBOARD_FAB2_LIB.BASEBOARD_FAB2(SCH_1):PAGE40
  U5D1   N4 VSS<1033> SKX_EXT_B_BGA1-IC,TBD    I21 @BASEBOARD_FAB2_LIB.BASEBOARD_FAB2(SCH_1):PAGE40
  U5D1  N78 VSS<1034> SKX_EXT_B_BGA1-IC,TBD    I21 @BASEBOARD_FAB2_LIB.BASEBOARD_FAB2(SCH_1):PAGE40
  U5D1  N76 VSS<1035> SKX_EXT_B_BGA1-IC,TBD    I21 @BASEBOARD_FAB2_LIB.BASEBOARD_FAB2(SCH_1):PAGE40
  U5D1  N74 VSS<1036> SKX_EXT_B_BGA1-IC,TBD    I21 @BASEBOARD_FAB2_LIB.BASEBOARD_FAB2(SCH_1):PAGE40
  U5D1  N72 VSS<1037> SKX_EXT_B_BGA1-IC,TBD    I21 @BASEBOARD_FAB2_LIB.BASEBOARD_FAB2(SCH_1):PAGE40
  U5D1  N70 VSS<1038> SKX_EXT_B_BGA1-IC,TBD    I21 @BASEBOARD_FAB2_LIB.BASEBOARD_FAB2(SCH_1):PAGE40
  U5D1  N66 VSS<1039> SKX_EXT_B_BGA1-IC,TBD    I21 @BASEBOARD_FAB2_LIB.BASEBOARD_FAB2(SCH_1):PAGE40
  U5D1   N6 VSS<1040> SKX_EXT_B_BGA1-IC,TBD    I21 @BASEBOARD_FAB2_LIB.BASEBOARD_FAB2(SCH_1):PAGE40
  U5D1  N22 VSS<1041> SKX_EXT_B_BGA1-IC,TBD    I21 @BASEBOARD_FAB2_LIB.BASEBOARD_FAB2(SCH_1):PAGE40
  U5D1  N20 VSS<1042> SKX_EXT_B_BGA1-IC,TBD    I21 @BASEBOARD_FAB2_LIB.BASEBOARD_FAB2(SCH_1):PAGE40
  U5D1 DM19 VSS<1043> SKX_EXT_B_BGA1-IC,TBD    I21 @BASEBOARD_FAB2_LIB.BASEBOARD_FAB2(SCH_1):PAGE40
  U5D1  M85 VSS<1044> SKX_EXT_B_BGA1-IC,TBD    I21 @BASEBOARD_FAB2_LIB.BASEBOARD_FAB2(SCH_1):PAGE40
  U5D1  M83 VSS<1045> SKX_EXT_B_BGA1-IC,TBD    I21 @BASEBOARD_FAB2_LIB.BASEBOARD_FAB2(SCH_1):PAGE40
  U5D1  M79 VSS<1046> SKX_EXT_B_BGA1-IC,TBD    I21 @BASEBOARD_FAB2_LIB.BASEBOARD_FAB2(SCH_1):PAGE40
  U5D1  M71 VSS<1047> SKX_EXT_B_BGA1-IC,TBD    I21 @BASEBOARD_FAB2_LIB.BASEBOARD_FAB2(SCH_1):PAGE40
  U5D1  M65 VSS<1048> SKX_EXT_B_BGA1-IC,TBD    I21 @BASEBOARD_FAB2_LIB.BASEBOARD_FAB2(SCH_1):PAGE40
  U5D1  M43 VSS<1049> SKX_EXT_B_BGA1-IC,TBD    I21 @BASEBOARD_FAB2_LIB.BASEBOARD_FAB2(SCH_1):PAGE40
  U5D1  M41 VSS<1050> SKX_EXT_B_BGA1-IC,TBD    I21 @BASEBOARD_FAB2_LIB.BASEBOARD_FAB2(SCH_1):PAGE40
  U5D1  M39 VSS<1051> SKX_EXT_B_BGA1-IC,TBD    I21 @BASEBOARD_FAB2_LIB.BASEBOARD_FAB2(SCH_1):PAGE40
  U5D1  M37 VSS<1052> SKX_EXT_B_BGA1-IC,TBD    I21 @BASEBOARD_FAB2_LIB.BASEBOARD_FAB2(SCH_1):PAGE40
  U5D1  M35 VSS<1053> SKX_EXT_B_BGA1-IC,TBD    I21 @BASEBOARD_FAB2_LIB.BASEBOARD_FAB2(SCH_1):PAGE40
  U5D1  M33 VSS<1054> SKX_EXT_B_BGA1-IC,TBD    I21 @BASEBOARD_FAB2_LIB.BASEBOARD_FAB2(SCH_1):PAGE40
  U5D1  M31 VSS<1055> SKX_EXT_B_BGA1-IC,TBD    I21 @BASEBOARD_FAB2_LIB.BASEBOARD_FAB2(SCH_1):PAGE40
  U5D1  M29 VSS<1056> SKX_EXT_B_BGA1-IC,TBD    I21 @BASEBOARD_FAB2_LIB.BASEBOARD_FAB2(SCH_1):PAGE40
  U5D1  M27 VSS<1057> SKX_EXT_B_BGA1-IC,TBD    I21 @BASEBOARD_FAB2_LIB.BASEBOARD_FAB2(SCH_1):PAGE40
  U5D1  M25 VSS<1058> SKX_EXT_B_BGA1-IC,TBD    I21 @BASEBOARD_FAB2_LIB.BASEBOARD_FAB2(SCH_1):PAGE40
  U5D1  M23 VSS<1059> SKX_EXT_B_BGA1-IC,TBD    I21 @BASEBOARD_FAB2_LIB.BASEBOARD_FAB2(SCH_1):PAGE40
  U5D1  M19 VSS<1060> SKX_EXT_B_BGA1-IC,TBD    I21 @BASEBOARD_FAB2_LIB.BASEBOARD_FAB2(SCH_1):PAGE40
  U5D1  M17 VSS<1061> SKX_EXT_B_BGA1-IC,TBD    I21 @BASEBOARD_FAB2_LIB.BASEBOARD_FAB2(SCH_1):PAGE40
  U5D1  M15 VSS<1062> SKX_EXT_B_BGA1-IC,TBD    I21 @BASEBOARD_FAB2_LIB.BASEBOARD_FAB2(SCH_1):PAGE40
  U5D1  CT7 VSS<1063> SKX_EXT_B_BGA1-IC,TBD    I21 @BASEBOARD_FAB2_LIB.BASEBOARD_FAB2(SCH_1):PAGE40
  U5D1  BT9 VSS<1064> SKX_EXT_B_BGA1-IC,TBD    I21 @BASEBOARD_FAB2_LIB.BASEBOARD_FAB2(SCH_1):PAGE40
  U5D1  L82 VSS<1065> SKX_EXT_B_BGA1-IC,TBD    I21 @BASEBOARD_FAB2_LIB.BASEBOARD_FAB2(SCH_1):PAGE40
  U5D1  L80 VSS<1066> SKX_EXT_B_BGA1-IC,TBD    I21 @BASEBOARD_FAB2_LIB.BASEBOARD_FAB2(SCH_1):PAGE40
  U5D1  L78 VSS<1067> SKX_EXT_B_BGA1-IC,TBD    I21 @BASEBOARD_FAB2_LIB.BASEBOARD_FAB2(SCH_1):PAGE40
  U5D1  L72 VSS<1068> SKX_EXT_B_BGA1-IC,TBD    I21 @BASEBOARD_FAB2_LIB.BASEBOARD_FAB2(SCH_1):PAGE40
  U5D1  L22 VSS<1069> SKX_EXT_B_BGA1-IC,TBD    I21 @BASEBOARD_FAB2_LIB.BASEBOARD_FAB2(SCH_1):PAGE40
  U5D1  L20 VSS<1070> SKX_EXT_B_BGA1-IC,TBD    I21 @BASEBOARD_FAB2_LIB.BASEBOARD_FAB2(SCH_1):PAGE40
  U5D1   L6 VSS<1071> SKX_EXT_B_BGA1-IC,TBD    I21 @BASEBOARD_FAB2_LIB.BASEBOARD_FAB2(SCH_1):PAGE40
  U5D1   L2 VSS<1072> SKX_EXT_B_BGA1-IC,TBD    I21 @BASEBOARD_FAB2_LIB.BASEBOARD_FAB2(SCH_1):PAGE40
  U5D1  L10 VSS<1073> SKX_EXT_B_BGA1-IC,TBD    I21 @BASEBOARD_FAB2_LIB.BASEBOARD_FAB2(SCH_1):PAGE40
  U5D1  K85 VSS<1074> SKX_EXT_B_BGA1-IC,TBD    I21 @BASEBOARD_FAB2_LIB.BASEBOARD_FAB2(SCH_1):PAGE40
  U5D1  K83 VSS<1075> SKX_EXT_B_BGA1-IC,TBD    I21 @BASEBOARD_FAB2_LIB.BASEBOARD_FAB2(SCH_1):PAGE40
  U5D1  K81 VSS<1076> SKX_EXT_B_BGA1-IC,TBD    I21 @BASEBOARD_FAB2_LIB.BASEBOARD_FAB2(SCH_1):PAGE40
  U5D1  K77 VSS<1077> SKX_EXT_B_BGA1-IC,TBD    I21 @BASEBOARD_FAB2_LIB.BASEBOARD_FAB2(SCH_1):PAGE40
  U5D1  K73 VSS<1078> SKX_EXT_B_BGA1-IC,TBD    I21 @BASEBOARD_FAB2_LIB.BASEBOARD_FAB2(SCH_1):PAGE40
  U5D1  K71 VSS<1079> SKX_EXT_B_BGA1-IC,TBD    I21 @BASEBOARD_FAB2_LIB.BASEBOARD_FAB2(SCH_1):PAGE40
  U5D1  K69 VSS<1080> SKX_EXT_B_BGA1-IC,TBD    I21 @BASEBOARD_FAB2_LIB.BASEBOARD_FAB2(SCH_1):PAGE40
  U5D1  K67 VSS<1081> SKX_EXT_B_BGA1-IC,TBD    I21 @BASEBOARD_FAB2_LIB.BASEBOARD_FAB2(SCH_1):PAGE40
  U5D1  K65 VSS<1082> SKX_EXT_B_BGA1-IC,TBD    I21 @BASEBOARD_FAB2_LIB.BASEBOARD_FAB2(SCH_1):PAGE40
  U5D1  K39 VSS<1083> SKX_EXT_B_BGA1-IC,TBD    I21 @BASEBOARD_FAB2_LIB.BASEBOARD_FAB2(SCH_1):PAGE40
  U5D1  K33 VSS<1084> SKX_EXT_B_BGA1-IC,TBD    I21 @BASEBOARD_FAB2_LIB.BASEBOARD_FAB2(SCH_1):PAGE40
  U5D1  K27 VSS<1085> SKX_EXT_B_BGA1-IC,TBD    I21 @BASEBOARD_FAB2_LIB.BASEBOARD_FAB2(SCH_1):PAGE40
  U5D1  DB7 VSS<1086> SKX_EXT_B_BGA1-IC,TBD    I21 @BASEBOARD_FAB2_LIB.BASEBOARD_FAB2(SCH_1):PAGE40
  U5D1  K17 VSS<1087> SKX_EXT_B_BGA1-IC,TBD    I21 @BASEBOARD_FAB2_LIB.BASEBOARD_FAB2(SCH_1):PAGE40
  U5D1  K13 VSS<1088> SKX_EXT_B_BGA1-IC,TBD    I21 @BASEBOARD_FAB2_LIB.BASEBOARD_FAB2(SCH_1):PAGE40
  U5D1  K11 VSS<1089> SKX_EXT_B_BGA1-IC,TBD    I21 @BASEBOARD_FAB2_LIB.BASEBOARD_FAB2(SCH_1):PAGE40
  U5D1   K1 VSS<1090> SKX_EXT_B_BGA1-IC,TBD    I21 @BASEBOARD_FAB2_LIB.BASEBOARD_FAB2(SCH_1):PAGE40
  U5D1  J84 VSS<1091> SKX_EXT_B_BGA1-IC,TBD    I21 @BASEBOARD_FAB2_LIB.BASEBOARD_FAB2(SCH_1):PAGE40
  U5D1  J82 VSS<1092> SKX_EXT_B_BGA1-IC,TBD    I21 @BASEBOARD_FAB2_LIB.BASEBOARD_FAB2(SCH_1):PAGE40
  U5D1  J76 VSS<1093> SKX_EXT_B_BGA1-IC,TBD    I21 @BASEBOARD_FAB2_LIB.BASEBOARD_FAB2(SCH_1):PAGE40
  U5D1 AL68 VSS<774> SKX_EXT_B_BGA1-IC,TBD    I22 @BASEBOARD_FAB2_LIB.BASEBOARD_FAB2(SCH_1):PAGE40
  U5D1 AL64 VSS<775> SKX_EXT_B_BGA1-IC,TBD    I22 @BASEBOARD_FAB2_LIB.BASEBOARD_FAB2(SCH_1):PAGE40
  U5D1 AL56 VSS<776> SKX_EXT_B_BGA1-IC,TBD    I22 @BASEBOARD_FAB2_LIB.BASEBOARD_FAB2(SCH_1):PAGE40
  U5D1 AL32 VSS<777> SKX_EXT_B_BGA1-IC,TBD    I22 @BASEBOARD_FAB2_LIB.BASEBOARD_FAB2(SCH_1):PAGE40
  U5D1 AL30 VSS<778> SKX_EXT_B_BGA1-IC,TBD    I22 @BASEBOARD_FAB2_LIB.BASEBOARD_FAB2(SCH_1):PAGE40
  U5D1 AL24 VSS<779> SKX_EXT_B_BGA1-IC,TBD    I22 @BASEBOARD_FAB2_LIB.BASEBOARD_FAB2(SCH_1):PAGE40
  U5D1 AL10 VSS<780> SKX_EXT_B_BGA1-IC,TBD    I22 @BASEBOARD_FAB2_LIB.BASEBOARD_FAB2(SCH_1):PAGE40
  U5D1  AL4 VSS<781> SKX_EXT_B_BGA1-IC,TBD    I22 @BASEBOARD_FAB2_LIB.BASEBOARD_FAB2(SCH_1):PAGE40
  U5D1 AK85 VSS<782> SKX_EXT_B_BGA1-IC,TBD    I22 @BASEBOARD_FAB2_LIB.BASEBOARD_FAB2(SCH_1):PAGE40
  U5D1 AK83 VSS<783> SKX_EXT_B_BGA1-IC,TBD    I22 @BASEBOARD_FAB2_LIB.BASEBOARD_FAB2(SCH_1):PAGE40
  U5D1 AK81 VSS<784> SKX_EXT_B_BGA1-IC,TBD    I22 @BASEBOARD_FAB2_LIB.BASEBOARD_FAB2(SCH_1):PAGE40
  U5D1 AK79 VSS<785> SKX_EXT_B_BGA1-IC,TBD    I22 @BASEBOARD_FAB2_LIB.BASEBOARD_FAB2(SCH_1):PAGE40
  U5D1 AK73 VSS<786> SKX_EXT_B_BGA1-IC,TBD    I22 @BASEBOARD_FAB2_LIB.BASEBOARD_FAB2(SCH_1):PAGE40
  U5D1 AK67 VSS<787> SKX_EXT_B_BGA1-IC,TBD    I22 @BASEBOARD_FAB2_LIB.BASEBOARD_FAB2(SCH_1):PAGE40
  U5D1 AK65 VSS<788> SKX_EXT_B_BGA1-IC,TBD    I22 @BASEBOARD_FAB2_LIB.BASEBOARD_FAB2(SCH_1):PAGE40
  U5D1 AK55 VSS<789> SKX_EXT_B_BGA1-IC,TBD    I22 @BASEBOARD_FAB2_LIB.BASEBOARD_FAB2(SCH_1):PAGE40
  U5D1 AK33 VSS<790> SKX_EXT_B_BGA1-IC,TBD    I22 @BASEBOARD_FAB2_LIB.BASEBOARD_FAB2(SCH_1):PAGE40
  U5D1 AK31 VSS<791> SKX_EXT_B_BGA1-IC,TBD    I22 @BASEBOARD_FAB2_LIB.BASEBOARD_FAB2(SCH_1):PAGE40
  U5D1 AK29 VSS<792> SKX_EXT_B_BGA1-IC,TBD    I22 @BASEBOARD_FAB2_LIB.BASEBOARD_FAB2(SCH_1):PAGE40
  U5D1 AK25 VSS<793> SKX_EXT_B_BGA1-IC,TBD    I22 @BASEBOARD_FAB2_LIB.BASEBOARD_FAB2(SCH_1):PAGE40
  U5D1 AK23 VSS<794> SKX_EXT_B_BGA1-IC,TBD    I22 @BASEBOARD_FAB2_LIB.BASEBOARD_FAB2(SCH_1):PAGE40
  U5D1 AK19 VSS<795> SKX_EXT_B_BGA1-IC,TBD    I22 @BASEBOARD_FAB2_LIB.BASEBOARD_FAB2(SCH_1):PAGE40
  U5D1 AK13 VSS<796> SKX_EXT_B_BGA1-IC,TBD    I22 @BASEBOARD_FAB2_LIB.BASEBOARD_FAB2(SCH_1):PAGE40
  U5D1  AK9 VSS<797> SKX_EXT_B_BGA1-IC,TBD    I22 @BASEBOARD_FAB2_LIB.BASEBOARD_FAB2(SCH_1):PAGE40
  U5D1 AJ86 VSS<798> SKX_EXT_B_BGA1-IC,TBD    I22 @BASEBOARD_FAB2_LIB.BASEBOARD_FAB2(SCH_1):PAGE40
  U5D1 AJ82 VSS<799> SKX_EXT_B_BGA1-IC,TBD    I22 @BASEBOARD_FAB2_LIB.BASEBOARD_FAB2(SCH_1):PAGE40
  U5D1 AJ78 VSS<800> SKX_EXT_B_BGA1-IC,TBD    I22 @BASEBOARD_FAB2_LIB.BASEBOARD_FAB2(SCH_1):PAGE40
  U5D1 AJ74 VSS<801> SKX_EXT_B_BGA1-IC,TBD    I22 @BASEBOARD_FAB2_LIB.BASEBOARD_FAB2(SCH_1):PAGE40
  U5D1 AJ68 VSS<802> SKX_EXT_B_BGA1-IC,TBD    I22 @BASEBOARD_FAB2_LIB.BASEBOARD_FAB2(SCH_1):PAGE40
  U5D1 AJ66 VSS<803> SKX_EXT_B_BGA1-IC,TBD    I22 @BASEBOARD_FAB2_LIB.BASEBOARD_FAB2(SCH_1):PAGE40
  U5D1 AJ54 VSS<804> SKX_EXT_B_BGA1-IC,TBD    I22 @BASEBOARD_FAB2_LIB.BASEBOARD_FAB2(SCH_1):PAGE40
  U5D1 AJ52 VSS<805> SKX_EXT_B_BGA1-IC,TBD    I22 @BASEBOARD_FAB2_LIB.BASEBOARD_FAB2(SCH_1):PAGE40
  U5D1 AJ50 VSS<806> SKX_EXT_B_BGA1-IC,TBD    I22 @BASEBOARD_FAB2_LIB.BASEBOARD_FAB2(SCH_1):PAGE40
  U5D1 AJ48 VSS<807> SKX_EXT_B_BGA1-IC,TBD    I22 @BASEBOARD_FAB2_LIB.BASEBOARD_FAB2(SCH_1):PAGE40
  U5D1 AJ46 VSS<808> SKX_EXT_B_BGA1-IC,TBD    I22 @BASEBOARD_FAB2_LIB.BASEBOARD_FAB2(SCH_1):PAGE40
  U5D1 AJ34 VSS<809> SKX_EXT_B_BGA1-IC,TBD    I22 @BASEBOARD_FAB2_LIB.BASEBOARD_FAB2(SCH_1):PAGE40
  U5D1 AJ32 VSS<810> SKX_EXT_B_BGA1-IC,TBD    I22 @BASEBOARD_FAB2_LIB.BASEBOARD_FAB2(SCH_1):PAGE40
  U5D1 AJ28 VSS<811> SKX_EXT_B_BGA1-IC,TBD    I22 @BASEBOARD_FAB2_LIB.BASEBOARD_FAB2(SCH_1):PAGE40
  U5D1 AJ26 VSS<812> SKX_EXT_B_BGA1-IC,TBD    I22 @BASEBOARD_FAB2_LIB.BASEBOARD_FAB2(SCH_1):PAGE40
  U5D1 AJ22 VSS<813> SKX_EXT_B_BGA1-IC,TBD    I22 @BASEBOARD_FAB2_LIB.BASEBOARD_FAB2(SCH_1):PAGE40
  U5D1  AJ8 VSS<814> SKX_EXT_B_BGA1-IC,TBD    I22 @BASEBOARD_FAB2_LIB.BASEBOARD_FAB2(SCH_1):PAGE40
  U5D1 AH83 VSS<815> SKX_EXT_B_BGA1-IC,TBD    I22 @BASEBOARD_FAB2_LIB.BASEBOARD_FAB2(SCH_1):PAGE40
  U5D1 AH77 VSS<816> SKX_EXT_B_BGA1-IC,TBD    I22 @BASEBOARD_FAB2_LIB.BASEBOARD_FAB2(SCH_1):PAGE40
  U5D1 AH75 VSS<817> SKX_EXT_B_BGA1-IC,TBD    I22 @BASEBOARD_FAB2_LIB.BASEBOARD_FAB2(SCH_1):PAGE40
  U5D1 AH69 VSS<818> SKX_EXT_B_BGA1-IC,TBD    I22 @BASEBOARD_FAB2_LIB.BASEBOARD_FAB2(SCH_1):PAGE40
  U5D1 AH65 VSS<819> SKX_EXT_B_BGA1-IC,TBD    I22 @BASEBOARD_FAB2_LIB.BASEBOARD_FAB2(SCH_1):PAGE40
  U5D1 AH61 VSS<820> SKX_EXT_B_BGA1-IC,TBD    I22 @BASEBOARD_FAB2_LIB.BASEBOARD_FAB2(SCH_1):PAGE40
  U5D1 AH59 VSS<821> SKX_EXT_B_BGA1-IC,TBD    I22 @BASEBOARD_FAB2_LIB.BASEBOARD_FAB2(SCH_1):PAGE40
  U5D1 AH53 VSS<822> SKX_EXT_B_BGA1-IC,TBD    I22 @BASEBOARD_FAB2_LIB.BASEBOARD_FAB2(SCH_1):PAGE40
  U5D1 AH51 VSS<823> SKX_EXT_B_BGA1-IC,TBD    I22 @BASEBOARD_FAB2_LIB.BASEBOARD_FAB2(SCH_1):PAGE40
  U5D1 AH49 VSS<824> SKX_EXT_B_BGA1-IC,TBD    I22 @BASEBOARD_FAB2_LIB.BASEBOARD_FAB2(SCH_1):PAGE40
  U5D1 AH47 VSS<825> SKX_EXT_B_BGA1-IC,TBD    I22 @BASEBOARD_FAB2_LIB.BASEBOARD_FAB2(SCH_1):PAGE40
  U5D1 AH45 VSS<826> SKX_EXT_B_BGA1-IC,TBD    I22 @BASEBOARD_FAB2_LIB.BASEBOARD_FAB2(SCH_1):PAGE40
  U5D1 AH35 VSS<827> SKX_EXT_B_BGA1-IC,TBD    I22 @BASEBOARD_FAB2_LIB.BASEBOARD_FAB2(SCH_1):PAGE40
  U5D1 AH33 VSS<828> SKX_EXT_B_BGA1-IC,TBD    I22 @BASEBOARD_FAB2_LIB.BASEBOARD_FAB2(SCH_1):PAGE40
  U5D1 AH27 VSS<829> SKX_EXT_B_BGA1-IC,TBD    I22 @BASEBOARD_FAB2_LIB.BASEBOARD_FAB2(SCH_1):PAGE40
  U5D1 AH21 VSS<830> SKX_EXT_B_BGA1-IC,TBD    I22 @BASEBOARD_FAB2_LIB.BASEBOARD_FAB2(SCH_1):PAGE40
  U5D1  AH5 VSS<831> SKX_EXT_B_BGA1-IC,TBD    I22 @BASEBOARD_FAB2_LIB.BASEBOARD_FAB2(SCH_1):PAGE40
  U5D1  AH1 VSS<832> SKX_EXT_B_BGA1-IC,TBD    I22 @BASEBOARD_FAB2_LIB.BASEBOARD_FAB2(SCH_1):PAGE40
  U5D1 AG80 VSS<833> SKX_EXT_B_BGA1-IC,TBD    I22 @BASEBOARD_FAB2_LIB.BASEBOARD_FAB2(SCH_1):PAGE40
  U5D1 AG78 VSS<834> SKX_EXT_B_BGA1-IC,TBD    I22 @BASEBOARD_FAB2_LIB.BASEBOARD_FAB2(SCH_1):PAGE40
  U5D1 AG76 VSS<835> SKX_EXT_B_BGA1-IC,TBD    I22 @BASEBOARD_FAB2_LIB.BASEBOARD_FAB2(SCH_1):PAGE40
  U5D1 AG74 VSS<836> SKX_EXT_B_BGA1-IC,TBD    I22 @BASEBOARD_FAB2_LIB.BASEBOARD_FAB2(SCH_1):PAGE40
  U5D1 AG70 VSS<837> SKX_EXT_B_BGA1-IC,TBD    I22 @BASEBOARD_FAB2_LIB.BASEBOARD_FAB2(SCH_1):PAGE40
  U5D1 AG64 VSS<838> SKX_EXT_B_BGA1-IC,TBD    I22 @BASEBOARD_FAB2_LIB.BASEBOARD_FAB2(SCH_1):PAGE40
  U5D1 AG36 VSS<839> SKX_EXT_B_BGA1-IC,TBD    I22 @BASEBOARD_FAB2_LIB.BASEBOARD_FAB2(SCH_1):PAGE40
  U5D1 AG18 VSS<840> SKX_EXT_B_BGA1-IC,TBD    I22 @BASEBOARD_FAB2_LIB.BASEBOARD_FAB2(SCH_1):PAGE40
  U5D1 AG14 VSS<841> SKX_EXT_B_BGA1-IC,TBD    I22 @BASEBOARD_FAB2_LIB.BASEBOARD_FAB2(SCH_1):PAGE40
  U5D1 AG12 VSS<842> SKX_EXT_B_BGA1-IC,TBD    I22 @BASEBOARD_FAB2_LIB.BASEBOARD_FAB2(SCH_1):PAGE40
  U5D1 AF85 VSS<843> SKX_EXT_B_BGA1-IC,TBD    I22 @BASEBOARD_FAB2_LIB.BASEBOARD_FAB2(SCH_1):PAGE40
  U5D1 AF83 VSS<844> SKX_EXT_B_BGA1-IC,TBD    I22 @BASEBOARD_FAB2_LIB.BASEBOARD_FAB2(SCH_1):PAGE40
  U5D1 AF77 VSS<845> SKX_EXT_B_BGA1-IC,TBD    I22 @BASEBOARD_FAB2_LIB.BASEBOARD_FAB2(SCH_1):PAGE40
  U5D1 AF73 VSS<846> SKX_EXT_B_BGA1-IC,TBD    I22 @BASEBOARD_FAB2_LIB.BASEBOARD_FAB2(SCH_1):PAGE40
  U5D1 AF41 VSS<847> SKX_EXT_B_BGA1-IC,TBD    I22 @BASEBOARD_FAB2_LIB.BASEBOARD_FAB2(SCH_1):PAGE40
  U5D1 AF39 VSS<848> SKX_EXT_B_BGA1-IC,TBD    I22 @BASEBOARD_FAB2_LIB.BASEBOARD_FAB2(SCH_1):PAGE40
  U5D1 AF37 VSS<849> SKX_EXT_B_BGA1-IC,TBD    I22 @BASEBOARD_FAB2_LIB.BASEBOARD_FAB2(SCH_1):PAGE40
  U5D1 AF33 VSS<850> SKX_EXT_B_BGA1-IC,TBD    I22 @BASEBOARD_FAB2_LIB.BASEBOARD_FAB2(SCH_1):PAGE40
  U5D1 AF31 VSS<851> SKX_EXT_B_BGA1-IC,TBD    I22 @BASEBOARD_FAB2_LIB.BASEBOARD_FAB2(SCH_1):PAGE40
  U5D1 AF29 VSS<852> SKX_EXT_B_BGA1-IC,TBD    I22 @BASEBOARD_FAB2_LIB.BASEBOARD_FAB2(SCH_1):PAGE40
  U5D1 AF27 VSS<853> SKX_EXT_B_BGA1-IC,TBD    I22 @BASEBOARD_FAB2_LIB.BASEBOARD_FAB2(SCH_1):PAGE40
  U5D1 AF25 VSS<854> SKX_EXT_B_BGA1-IC,TBD    I22 @BASEBOARD_FAB2_LIB.BASEBOARD_FAB2(SCH_1):PAGE40
  U5D1 AF23 VSS<855> SKX_EXT_B_BGA1-IC,TBD    I22 @BASEBOARD_FAB2_LIB.BASEBOARD_FAB2(SCH_1):PAGE40
  U5D1 AF21 VSS<856> SKX_EXT_B_BGA1-IC,TBD    I22 @BASEBOARD_FAB2_LIB.BASEBOARD_FAB2(SCH_1):PAGE40
  U5D1  AF9 VSS<857> SKX_EXT_B_BGA1-IC,TBD    I22 @BASEBOARD_FAB2_LIB.BASEBOARD_FAB2(SCH_1):PAGE40
  U5D1 AC52 VSS<858> SKX_EXT_B_BGA1-IC,TBD    I22 @BASEBOARD_FAB2_LIB.BASEBOARD_FAB2(SCH_1):PAGE40
  U5D1  AF1 VSS<859> SKX_EXT_B_BGA1-IC,TBD    I22 @BASEBOARD_FAB2_LIB.BASEBOARD_FAB2(SCH_1):PAGE40
  U5D1 AE78 VSS<860> SKX_EXT_B_BGA1-IC,TBD    I22 @BASEBOARD_FAB2_LIB.BASEBOARD_FAB2(SCH_1):PAGE40
  U5D1 AE70 VSS<861> SKX_EXT_B_BGA1-IC,TBD    I22 @BASEBOARD_FAB2_LIB.BASEBOARD_FAB2(SCH_1):PAGE40
  U5D1 AE68 VSS<862> SKX_EXT_B_BGA1-IC,TBD    I22 @BASEBOARD_FAB2_LIB.BASEBOARD_FAB2(SCH_1):PAGE40
  U5D1 AE66 VSS<863> SKX_EXT_B_BGA1-IC,TBD    I22 @BASEBOARD_FAB2_LIB.BASEBOARD_FAB2(SCH_1):PAGE40
  U5D1 AE64 VSS<864> SKX_EXT_B_BGA1-IC,TBD    I22 @BASEBOARD_FAB2_LIB.BASEBOARD_FAB2(SCH_1):PAGE40
  U5D1 AE42 VSS<865> SKX_EXT_B_BGA1-IC,TBD    I22 @BASEBOARD_FAB2_LIB.BASEBOARD_FAB2(SCH_1):PAGE40
  U5D1 AE40 VSS<866> SKX_EXT_B_BGA1-IC,TBD    I22 @BASEBOARD_FAB2_LIB.BASEBOARD_FAB2(SCH_1):PAGE40
  U5D1 AE38 VSS<867> SKX_EXT_B_BGA1-IC,TBD    I22 @BASEBOARD_FAB2_LIB.BASEBOARD_FAB2(SCH_1):PAGE40
  U5D1 AE16 VSS<868> SKX_EXT_B_BGA1-IC,TBD    I22 @BASEBOARD_FAB2_LIB.BASEBOARD_FAB2(SCH_1):PAGE40
  U5D1 AC54 VSS<869> SKX_EXT_B_BGA1-IC,TBD    I22 @BASEBOARD_FAB2_LIB.BASEBOARD_FAB2(SCH_1):PAGE40
  U5D1  AE8 VSS<870> SKX_EXT_B_BGA1-IC,TBD    I22 @BASEBOARD_FAB2_LIB.BASEBOARD_FAB2(SCH_1):PAGE40
  U5D1  AE4 VSS<871> SKX_EXT_B_BGA1-IC,TBD    I22 @BASEBOARD_FAB2_LIB.BASEBOARD_FAB2(SCH_1):PAGE40
  U5D1 AD85 VSS<872> SKX_EXT_B_BGA1-IC,TBD    I22 @BASEBOARD_FAB2_LIB.BASEBOARD_FAB2(SCH_1):PAGE40
  U5D1 AD83 VSS<873> SKX_EXT_B_BGA1-IC,TBD    I22 @BASEBOARD_FAB2_LIB.BASEBOARD_FAB2(SCH_1):PAGE40
  U5D1 AD81 VSS<874> SKX_EXT_B_BGA1-IC,TBD    I22 @BASEBOARD_FAB2_LIB.BASEBOARD_FAB2(SCH_1):PAGE40
  U5D1 AD75 VSS<875> SKX_EXT_B_BGA1-IC,TBD    I22 @BASEBOARD_FAB2_LIB.BASEBOARD_FAB2(SCH_1):PAGE40
  U5D1 AD73 VSS<876> SKX_EXT_B_BGA1-IC,TBD    I22 @BASEBOARD_FAB2_LIB.BASEBOARD_FAB2(SCH_1):PAGE40
  U5D1 AD71 VSS<877> SKX_EXT_B_BGA1-IC,TBD    I22 @BASEBOARD_FAB2_LIB.BASEBOARD_FAB2(SCH_1):PAGE40
  U5D1 AD43 VSS<878> SKX_EXT_B_BGA1-IC,TBD    I22 @BASEBOARD_FAB2_LIB.BASEBOARD_FAB2(SCH_1):PAGE40
  U5D1 AD39 VSS<879> SKX_EXT_B_BGA1-IC,TBD    I22 @BASEBOARD_FAB2_LIB.BASEBOARD_FAB2(SCH_1):PAGE40
  U5D1 AD33 VSS<880> SKX_EXT_B_BGA1-IC,TBD    I22 @BASEBOARD_FAB2_LIB.BASEBOARD_FAB2(SCH_1):PAGE40
  U5D1 AD27 VSS<881> SKX_EXT_B_BGA1-IC,TBD    I22 @BASEBOARD_FAB2_LIB.BASEBOARD_FAB2(SCH_1):PAGE40
  U5D1 AD21 VSS<882> SKX_EXT_B_BGA1-IC,TBD    I22 @BASEBOARD_FAB2_LIB.BASEBOARD_FAB2(SCH_1):PAGE40
  U5D1 AD19 VSS<883> SKX_EXT_B_BGA1-IC,TBD    I22 @BASEBOARD_FAB2_LIB.BASEBOARD_FAB2(SCH_1):PAGE40
  U5D1 AD15 VSS<884> SKX_EXT_B_BGA1-IC,TBD    I22 @BASEBOARD_FAB2_LIB.BASEBOARD_FAB2(SCH_1):PAGE40
  U5D1 AD13 VSS<885> SKX_EXT_B_BGA1-IC,TBD    I22 @BASEBOARD_FAB2_LIB.BASEBOARD_FAB2(SCH_1):PAGE40
  U5D1 AD11 VSS<886> SKX_EXT_B_BGA1-IC,TBD    I22 @BASEBOARD_FAB2_LIB.BASEBOARD_FAB2(SCH_1):PAGE40
  U5D1  AD9 VSS<887> SKX_EXT_B_BGA1-IC,TBD    I22 @BASEBOARD_FAB2_LIB.BASEBOARD_FAB2(SCH_1):PAGE40
  U5D1  AD7 VSS<888> SKX_EXT_B_BGA1-IC,TBD    I22 @BASEBOARD_FAB2_LIB.BASEBOARD_FAB2(SCH_1):PAGE40
  U5D1  AD3 VSS<889> SKX_EXT_B_BGA1-IC,TBD    I22 @BASEBOARD_FAB2_LIB.BASEBOARD_FAB2(SCH_1):PAGE40
  U5D1 AC86 VSS<890> SKX_EXT_B_BGA1-IC,TBD    I22 @BASEBOARD_FAB2_LIB.BASEBOARD_FAB2(SCH_1):PAGE40
  U5D1 AC84 VSS<891> SKX_EXT_B_BGA1-IC,TBD    I22 @BASEBOARD_FAB2_LIB.BASEBOARD_FAB2(SCH_1):PAGE40
  U5D1 AC78 VSS<892> SKX_EXT_B_BGA1-IC,TBD    I22 @BASEBOARD_FAB2_LIB.BASEBOARD_FAB2(SCH_1):PAGE40
  U5D1 AC72 VSS<893> SKX_EXT_B_BGA1-IC,TBD    I22 @BASEBOARD_FAB2_LIB.BASEBOARD_FAB2(SCH_1):PAGE40
  U5D1 AC70 VSS<894> SKX_EXT_B_BGA1-IC,TBD    I22 @BASEBOARD_FAB2_LIB.BASEBOARD_FAB2(SCH_1):PAGE40
  U5D1 AC64 VSS<895> SKX_EXT_B_BGA1-IC,TBD    I22 @BASEBOARD_FAB2_LIB.BASEBOARD_FAB2(SCH_1):PAGE40
  U5D1 AC40 VSS<896> SKX_EXT_B_BGA1-IC,TBD    I22 @BASEBOARD_FAB2_LIB.BASEBOARD_FAB2(SCH_1):PAGE40
  U5D1 AC38 VSS<897> SKX_EXT_B_BGA1-IC,TBD    I22 @BASEBOARD_FAB2_LIB.BASEBOARD_FAB2(SCH_1):PAGE40
  U5D1 AC34 VSS<898> SKX_EXT_B_BGA1-IC,TBD    I22 @BASEBOARD_FAB2_LIB.BASEBOARD_FAB2(SCH_1):PAGE40
  U5D1 AC32 VSS<899> SKX_EXT_B_BGA1-IC,TBD    I22 @BASEBOARD_FAB2_LIB.BASEBOARD_FAB2(SCH_1):PAGE40
  U5D1 AC28 VSS<900> SKX_EXT_B_BGA1-IC,TBD    I22 @BASEBOARD_FAB2_LIB.BASEBOARD_FAB2(SCH_1):PAGE40
  U5D1 AC26 VSS<901> SKX_EXT_B_BGA1-IC,TBD    I22 @BASEBOARD_FAB2_LIB.BASEBOARD_FAB2(SCH_1):PAGE40
  U5D1 AC22 VSS<902> SKX_EXT_B_BGA1-IC,TBD    I22 @BASEBOARD_FAB2_LIB.BASEBOARD_FAB2(SCH_1):PAGE40
  U5D1 AC18 VSS<903> SKX_EXT_B_BGA1-IC,TBD    I22 @BASEBOARD_FAB2_LIB.BASEBOARD_FAB2(SCH_1):PAGE40
  U5D1 AB85 VSS<904> SKX_EXT_B_BGA1-IC,TBD    I22 @BASEBOARD_FAB2_LIB.BASEBOARD_FAB2(SCH_1):PAGE40
  U5D1 AB83 VSS<905> SKX_EXT_B_BGA1-IC,TBD    I22 @BASEBOARD_FAB2_LIB.BASEBOARD_FAB2(SCH_1):PAGE40
  U5D1 AB79 VSS<906> SKX_EXT_B_BGA1-IC,TBD    I22 @BASEBOARD_FAB2_LIB.BASEBOARD_FAB2(SCH_1):PAGE40
  U5D1 AB73 VSS<907> SKX_EXT_B_BGA1-IC,TBD    I22 @BASEBOARD_FAB2_LIB.BASEBOARD_FAB2(SCH_1):PAGE40
  U5D1 AB69 VSS<908> SKX_EXT_B_BGA1-IC,TBD    I22 @BASEBOARD_FAB2_LIB.BASEBOARD_FAB2(SCH_1):PAGE40
  U5D1 AB65 VSS<909> SKX_EXT_B_BGA1-IC,TBD    I22 @BASEBOARD_FAB2_LIB.BASEBOARD_FAB2(SCH_1):PAGE40
  U5D1 AB41 VSS<910> SKX_EXT_B_BGA1-IC,TBD    I22 @BASEBOARD_FAB2_LIB.BASEBOARD_FAB2(SCH_1):PAGE40
  U5D1 AB37 VSS<911> SKX_EXT_B_BGA1-IC,TBD    I22 @BASEBOARD_FAB2_LIB.BASEBOARD_FAB2(SCH_1):PAGE40
  U5D1 AB35 VSS<912> SKX_EXT_B_BGA1-IC,TBD    I22 @BASEBOARD_FAB2_LIB.BASEBOARD_FAB2(SCH_1):PAGE40
  U5D1 AB31 VSS<913> SKX_EXT_B_BGA1-IC,TBD    I22 @BASEBOARD_FAB2_LIB.BASEBOARD_FAB2(SCH_1):PAGE40
  U5D1 AB29 VSS<914> SKX_EXT_B_BGA1-IC,TBD    I22 @BASEBOARD_FAB2_LIB.BASEBOARD_FAB2(SCH_1):PAGE40
  U5D1 AB25 VSS<915> SKX_EXT_B_BGA1-IC,TBD    I22 @BASEBOARD_FAB2_LIB.BASEBOARD_FAB2(SCH_1):PAGE40
  U5D1 AB23 VSS<916> SKX_EXT_B_BGA1-IC,TBD    I22 @BASEBOARD_FAB2_LIB.BASEBOARD_FAB2(SCH_1):PAGE40
  U5D1 AB21 VSS<917> SKX_EXT_B_BGA1-IC,TBD    I22 @BASEBOARD_FAB2_LIB.BASEBOARD_FAB2(SCH_1):PAGE40
  U5D1 AB11 VSS<918> SKX_EXT_B_BGA1-IC,TBD    I22 @BASEBOARD_FAB2_LIB.BASEBOARD_FAB2(SCH_1):PAGE40
  U5D1  AB5 VSS<919> SKX_EXT_B_BGA1-IC,TBD    I22 @BASEBOARD_FAB2_LIB.BASEBOARD_FAB2(SCH_1):PAGE40
  U5D1  AB1 VSS<920> SKX_EXT_B_BGA1-IC,TBD    I22 @BASEBOARD_FAB2_LIB.BASEBOARD_FAB2(SCH_1):PAGE40
  U5D1 AA82 VSS<921> SKX_EXT_B_BGA1-IC,TBD    I22 @BASEBOARD_FAB2_LIB.BASEBOARD_FAB2(SCH_1):PAGE40
  U5D1 AA80 VSS<922> SKX_EXT_B_BGA1-IC,TBD    I22 @BASEBOARD_FAB2_LIB.BASEBOARD_FAB2(SCH_1):PAGE40
  U5D1 AA78 VSS<923> SKX_EXT_B_BGA1-IC,TBD    I22 @BASEBOARD_FAB2_LIB.BASEBOARD_FAB2(SCH_1):PAGE40
  U5D1 AA76 VSS<924> SKX_EXT_B_BGA1-IC,TBD    I22 @BASEBOARD_FAB2_LIB.BASEBOARD_FAB2(SCH_1):PAGE40
  U5D1 AA68 VSS<925> SKX_EXT_B_BGA1-IC,TBD    I22 @BASEBOARD_FAB2_LIB.BASEBOARD_FAB2(SCH_1):PAGE40
  U5D1 AA66 VSS<926> SKX_EXT_B_BGA1-IC,TBD    I22 @BASEBOARD_FAB2_LIB.BASEBOARD_FAB2(SCH_1):PAGE40
  U5D1 AA64 VSS<927> SKX_EXT_B_BGA1-IC,TBD    I22 @BASEBOARD_FAB2_LIB.BASEBOARD_FAB2(SCH_1):PAGE40
  U5D1 AA42 VSS<928> SKX_EXT_B_BGA1-IC,TBD    I22 @BASEBOARD_FAB2_LIB.BASEBOARD_FAB2(SCH_1):PAGE40
  U5D1 AA36 VSS<929> SKX_EXT_B_BGA1-IC,TBD    I22 @BASEBOARD_FAB2_LIB.BASEBOARD_FAB2(SCH_1):PAGE40
  U5D1 AA30 VSS<930> SKX_EXT_B_BGA1-IC,TBD    I22 @BASEBOARD_FAB2_LIB.BASEBOARD_FAB2(SCH_1):PAGE40
  U5D1 AA24 VSS<931> SKX_EXT_B_BGA1-IC,TBD    I22 @BASEBOARD_FAB2_LIB.BASEBOARD_FAB2(SCH_1):PAGE40
  U5D1 AA22 VSS<932> SKX_EXT_B_BGA1-IC,TBD    I22 @BASEBOARD_FAB2_LIB.BASEBOARD_FAB2(SCH_1):PAGE40
  U5D1 AA18 VSS<933> SKX_EXT_B_BGA1-IC,TBD    I22 @BASEBOARD_FAB2_LIB.BASEBOARD_FAB2(SCH_1):PAGE40
  U5D1 BG72 VSS<614> SKX_EXT_B_BGA1-IC,TBD    I23 @BASEBOARD_FAB2_LIB.BASEBOARD_FAB2(SCH_1):PAGE40
  U5D1 BG24 VSS<615> SKX_EXT_B_BGA1-IC,TBD    I23 @BASEBOARD_FAB2_LIB.BASEBOARD_FAB2(SCH_1):PAGE40
  U5D1 BG22 VSS<616> SKX_EXT_B_BGA1-IC,TBD    I23 @BASEBOARD_FAB2_LIB.BASEBOARD_FAB2(SCH_1):PAGE40
  U5D1 BG10 VSS<617> SKX_EXT_B_BGA1-IC,TBD    I23 @BASEBOARD_FAB2_LIB.BASEBOARD_FAB2(SCH_1):PAGE40
  U5D1  BG8 VSS<618> SKX_EXT_B_BGA1-IC,TBD    I23 @BASEBOARD_FAB2_LIB.BASEBOARD_FAB2(SCH_1):PAGE40
  U5D1  BG6 VSS<619> SKX_EXT_B_BGA1-IC,TBD    I23 @BASEBOARD_FAB2_LIB.BASEBOARD_FAB2(SCH_1):PAGE40
  U5D1 BF71 VSS<620> SKX_EXT_B_BGA1-IC,TBD    I23 @BASEBOARD_FAB2_LIB.BASEBOARD_FAB2(SCH_1):PAGE40
  U5D1 BF69 VSS<621> SKX_EXT_B_BGA1-IC,TBD    I23 @BASEBOARD_FAB2_LIB.BASEBOARD_FAB2(SCH_1):PAGE40
  U5D1 BF67 VSS<622> SKX_EXT_B_BGA1-IC,TBD    I23 @BASEBOARD_FAB2_LIB.BASEBOARD_FAB2(SCH_1):PAGE40
  U5D1 BF65 VSS<623> SKX_EXT_B_BGA1-IC,TBD    I23 @BASEBOARD_FAB2_LIB.BASEBOARD_FAB2(SCH_1):PAGE40
  U5D1 BF63 VSS<624> SKX_EXT_B_BGA1-IC,TBD    I23 @BASEBOARD_FAB2_LIB.BASEBOARD_FAB2(SCH_1):PAGE40
  U5D1 BF25 VSS<625> SKX_EXT_B_BGA1-IC,TBD    I23 @BASEBOARD_FAB2_LIB.BASEBOARD_FAB2(SCH_1):PAGE40
  U5D1 BF19 VSS<626> SKX_EXT_B_BGA1-IC,TBD    I23 @BASEBOARD_FAB2_LIB.BASEBOARD_FAB2(SCH_1):PAGE40
  U5D1 BF17 VSS<627> SKX_EXT_B_BGA1-IC,TBD    I23 @BASEBOARD_FAB2_LIB.BASEBOARD_FAB2(SCH_1):PAGE40
  U5D1 BF15 VSS<628> SKX_EXT_B_BGA1-IC,TBD    I23 @BASEBOARD_FAB2_LIB.BASEBOARD_FAB2(SCH_1):PAGE40
  U5D1  BF9 VSS<629> SKX_EXT_B_BGA1-IC,TBD    I23 @BASEBOARD_FAB2_LIB.BASEBOARD_FAB2(SCH_1):PAGE40
  U5D1 BE70 VSS<630> SKX_EXT_B_BGA1-IC,TBD    I23 @BASEBOARD_FAB2_LIB.BASEBOARD_FAB2(SCH_1):PAGE40
  U5D1 BE68 VSS<631> SKX_EXT_B_BGA1-IC,TBD    I23 @BASEBOARD_FAB2_LIB.BASEBOARD_FAB2(SCH_1):PAGE40
  U5D1 BE66 VSS<632> SKX_EXT_B_BGA1-IC,TBD    I23 @BASEBOARD_FAB2_LIB.BASEBOARD_FAB2(SCH_1):PAGE40
  U5D1 BE64 VSS<633> SKX_EXT_B_BGA1-IC,TBD    I23 @BASEBOARD_FAB2_LIB.BASEBOARD_FAB2(SCH_1):PAGE40
  U5D1 BE26 VSS<634> SKX_EXT_B_BGA1-IC,TBD    I23 @BASEBOARD_FAB2_LIB.BASEBOARD_FAB2(SCH_1):PAGE40
  U5D1 BE10 VSS<635> SKX_EXT_B_BGA1-IC,TBD    I23 @BASEBOARD_FAB2_LIB.BASEBOARD_FAB2(SCH_1):PAGE40
  U5D1  BE8 VSS<636> SKX_EXT_B_BGA1-IC,TBD    I23 @BASEBOARD_FAB2_LIB.BASEBOARD_FAB2(SCH_1):PAGE40
  U5D1  BE6 VSS<637> SKX_EXT_B_BGA1-IC,TBD    I23 @BASEBOARD_FAB2_LIB.BASEBOARD_FAB2(SCH_1):PAGE40
  U5D1  BE4 VSS<638> SKX_EXT_B_BGA1-IC,TBD    I23 @BASEBOARD_FAB2_LIB.BASEBOARD_FAB2(SCH_1):PAGE40
  U5D1 BD71 VSS<639> SKX_EXT_B_BGA1-IC,TBD    I23 @BASEBOARD_FAB2_LIB.BASEBOARD_FAB2(SCH_1):PAGE40
  U5D1 BD63 VSS<640> SKX_EXT_B_BGA1-IC,TBD    I23 @BASEBOARD_FAB2_LIB.BASEBOARD_FAB2(SCH_1):PAGE40
  U5D1 BD27 VSS<641> SKX_EXT_B_BGA1-IC,TBD    I23 @BASEBOARD_FAB2_LIB.BASEBOARD_FAB2(SCH_1):PAGE40
  U5D1 BD21 VSS<642> SKX_EXT_B_BGA1-IC,TBD    I23 @BASEBOARD_FAB2_LIB.BASEBOARD_FAB2(SCH_1):PAGE40
  U5D1 BD15 VSS<643> SKX_EXT_B_BGA1-IC,TBD    I23 @BASEBOARD_FAB2_LIB.BASEBOARD_FAB2(SCH_1):PAGE40
  U5D1 BD11 VSS<644> SKX_EXT_B_BGA1-IC,TBD    I23 @BASEBOARD_FAB2_LIB.BASEBOARD_FAB2(SCH_1):PAGE40
  U5D1  BD5 VSS<645> SKX_EXT_B_BGA1-IC,TBD    I23 @BASEBOARD_FAB2_LIB.BASEBOARD_FAB2(SCH_1):PAGE40
  U5D1 BC82 VSS<646> SKX_EXT_B_BGA1-IC,TBD    I23 @BASEBOARD_FAB2_LIB.BASEBOARD_FAB2(SCH_1):PAGE40
  U5D1 BC80 VSS<647> SKX_EXT_B_BGA1-IC,TBD    I23 @BASEBOARD_FAB2_LIB.BASEBOARD_FAB2(SCH_1):PAGE40
  U5D1 BC78 VSS<648> SKX_EXT_B_BGA1-IC,TBD    I23 @BASEBOARD_FAB2_LIB.BASEBOARD_FAB2(SCH_1):PAGE40
  U5D1 BC76 VSS<649> SKX_EXT_B_BGA1-IC,TBD    I23 @BASEBOARD_FAB2_LIB.BASEBOARD_FAB2(SCH_1):PAGE40
  U5D1 BC74 VSS<650> SKX_EXT_B_BGA1-IC,TBD    I23 @BASEBOARD_FAB2_LIB.BASEBOARD_FAB2(SCH_1):PAGE40
  U5D1 BC72 VSS<651> SKX_EXT_B_BGA1-IC,TBD    I23 @BASEBOARD_FAB2_LIB.BASEBOARD_FAB2(SCH_1):PAGE40
  U5D1 BC70 VSS<652> SKX_EXT_B_BGA1-IC,TBD    I23 @BASEBOARD_FAB2_LIB.BASEBOARD_FAB2(SCH_1):PAGE40
  U5D1 BC16 VSS<653> SKX_EXT_B_BGA1-IC,TBD    I23 @BASEBOARD_FAB2_LIB.BASEBOARD_FAB2(SCH_1):PAGE40
  U5D1 BC12 VSS<654> SKX_EXT_B_BGA1-IC,TBD    I23 @BASEBOARD_FAB2_LIB.BASEBOARD_FAB2(SCH_1):PAGE40
  U5D1  BC8 VSS<655> SKX_EXT_B_BGA1-IC,TBD    I23 @BASEBOARD_FAB2_LIB.BASEBOARD_FAB2(SCH_1):PAGE40
  U5D1  BC4 VSS<656> SKX_EXT_B_BGA1-IC,TBD    I23 @BASEBOARD_FAB2_LIB.BASEBOARD_FAB2(SCH_1):PAGE40
  U5D1 BB83 VSS<657> SKX_EXT_B_BGA1-IC,TBD    I23 @BASEBOARD_FAB2_LIB.BASEBOARD_FAB2(SCH_1):PAGE40
  U5D1 BB81 VSS<658> SKX_EXT_B_BGA1-IC,TBD    I23 @BASEBOARD_FAB2_LIB.BASEBOARD_FAB2(SCH_1):PAGE40
  U5D1 BB79 VSS<659> SKX_EXT_B_BGA1-IC,TBD    I23 @BASEBOARD_FAB2_LIB.BASEBOARD_FAB2(SCH_1):PAGE40
  U5D1 BB77 VSS<660> SKX_EXT_B_BGA1-IC,TBD    I23 @BASEBOARD_FAB2_LIB.BASEBOARD_FAB2(SCH_1):PAGE40
  U5D1 BB75 VSS<661> SKX_EXT_B_BGA1-IC,TBD    I23 @BASEBOARD_FAB2_LIB.BASEBOARD_FAB2(SCH_1):PAGE40
  U5D1 BB73 VSS<662> SKX_EXT_B_BGA1-IC,TBD    I23 @BASEBOARD_FAB2_LIB.BASEBOARD_FAB2(SCH_1):PAGE40
  U5D1 BB69 VSS<663> SKX_EXT_B_BGA1-IC,TBD    I23 @BASEBOARD_FAB2_LIB.BASEBOARD_FAB2(SCH_1):PAGE40
  U5D1 BB63 VSS<664> SKX_EXT_B_BGA1-IC,TBD    I23 @BASEBOARD_FAB2_LIB.BASEBOARD_FAB2(SCH_1):PAGE40
  U5D1 BB23 VSS<665> SKX_EXT_B_BGA1-IC,TBD    I23 @BASEBOARD_FAB2_LIB.BASEBOARD_FAB2(SCH_1):PAGE40
  U5D1 BB19 VSS<666> SKX_EXT_B_BGA1-IC,TBD    I23 @BASEBOARD_FAB2_LIB.BASEBOARD_FAB2(SCH_1):PAGE40
  U5D1 BA84 VSS<667> SKX_EXT_B_BGA1-IC,TBD    I23 @BASEBOARD_FAB2_LIB.BASEBOARD_FAB2(SCH_1):PAGE40
  U5D1 BA80 VSS<668> SKX_EXT_B_BGA1-IC,TBD    I23 @BASEBOARD_FAB2_LIB.BASEBOARD_FAB2(SCH_1):PAGE40
  U5D1 BA74 VSS<669> SKX_EXT_B_BGA1-IC,TBD    I23 @BASEBOARD_FAB2_LIB.BASEBOARD_FAB2(SCH_1):PAGE40
  U5D1 BA68 VSS<670> SKX_EXT_B_BGA1-IC,TBD    I23 @BASEBOARD_FAB2_LIB.BASEBOARD_FAB2(SCH_1):PAGE40
  U5D1 BA62 VSS<671> SKX_EXT_B_BGA1-IC,TBD    I23 @BASEBOARD_FAB2_LIB.BASEBOARD_FAB2(SCH_1):PAGE40
  U5D1 BA12 VSS<672> SKX_EXT_B_BGA1-IC,TBD    I23 @BASEBOARD_FAB2_LIB.BASEBOARD_FAB2(SCH_1):PAGE40
  U5D1  BA6 VSS<673> SKX_EXT_B_BGA1-IC,TBD    I23 @BASEBOARD_FAB2_LIB.BASEBOARD_FAB2(SCH_1):PAGE40
  U5D1  BA2 VSS<674> SKX_EXT_B_BGA1-IC,TBD    I23 @BASEBOARD_FAB2_LIB.BASEBOARD_FAB2(SCH_1):PAGE40
  U5D1 AY81 VSS<675> SKX_EXT_B_BGA1-IC,TBD    I23 @BASEBOARD_FAB2_LIB.BASEBOARD_FAB2(SCH_1):PAGE40
  U5D1 AY79 VSS<676> SKX_EXT_B_BGA1-IC,TBD    I23 @BASEBOARD_FAB2_LIB.BASEBOARD_FAB2(SCH_1):PAGE40
  U5D1 AY63 VSS<677> SKX_EXT_B_BGA1-IC,TBD    I23 @BASEBOARD_FAB2_LIB.BASEBOARD_FAB2(SCH_1):PAGE40
  U5D1 AY25 VSS<678> SKX_EXT_B_BGA1-IC,TBD    I23 @BASEBOARD_FAB2_LIB.BASEBOARD_FAB2(SCH_1):PAGE40
  U5D1 AY23 VSS<679> SKX_EXT_B_BGA1-IC,TBD    I23 @BASEBOARD_FAB2_LIB.BASEBOARD_FAB2(SCH_1):PAGE40
  U5D1 AY21 VSS<680> SKX_EXT_B_BGA1-IC,TBD    I23 @BASEBOARD_FAB2_LIB.BASEBOARD_FAB2(SCH_1):PAGE40
  U5D1 AY17 VSS<681> SKX_EXT_B_BGA1-IC,TBD    I23 @BASEBOARD_FAB2_LIB.BASEBOARD_FAB2(SCH_1):PAGE40
  U5D1 AY15 VSS<682> SKX_EXT_B_BGA1-IC,TBD    I23 @BASEBOARD_FAB2_LIB.BASEBOARD_FAB2(SCH_1):PAGE40
  U5D1  AY5 VSS<683> SKX_EXT_B_BGA1-IC,TBD    I23 @BASEBOARD_FAB2_LIB.BASEBOARD_FAB2(SCH_1):PAGE40
  U5D1 AW84 VSS<684> SKX_EXT_B_BGA1-IC,TBD    I23 @BASEBOARD_FAB2_LIB.BASEBOARD_FAB2(SCH_1):PAGE40
  U5D1 AW82 VSS<685> SKX_EXT_B_BGA1-IC,TBD    I23 @BASEBOARD_FAB2_LIB.BASEBOARD_FAB2(SCH_1):PAGE40
  U5D1 AW78 VSS<686> SKX_EXT_B_BGA1-IC,TBD    I23 @BASEBOARD_FAB2_LIB.BASEBOARD_FAB2(SCH_1):PAGE40
  U5D1 AW74 VSS<687> SKX_EXT_B_BGA1-IC,TBD    I23 @BASEBOARD_FAB2_LIB.BASEBOARD_FAB2(SCH_1):PAGE40
  U5D1 AW72 VSS<688> SKX_EXT_B_BGA1-IC,TBD    I23 @BASEBOARD_FAB2_LIB.BASEBOARD_FAB2(SCH_1):PAGE40
  U5D1 AW70 VSS<689> SKX_EXT_B_BGA1-IC,TBD    I23 @BASEBOARD_FAB2_LIB.BASEBOARD_FAB2(SCH_1):PAGE40
  U5D1 AW68 VSS<690> SKX_EXT_B_BGA1-IC,TBD    I23 @BASEBOARD_FAB2_LIB.BASEBOARD_FAB2(SCH_1):PAGE40
  U5D1 AW66 VSS<691> SKX_EXT_B_BGA1-IC,TBD    I23 @BASEBOARD_FAB2_LIB.BASEBOARD_FAB2(SCH_1):PAGE40
  U5D1 AW62 VSS<692> SKX_EXT_B_BGA1-IC,TBD    I23 @BASEBOARD_FAB2_LIB.BASEBOARD_FAB2(SCH_1):PAGE40
  U5D1 AW10 VSS<693> SKX_EXT_B_BGA1-IC,TBD    I23 @BASEBOARD_FAB2_LIB.BASEBOARD_FAB2(SCH_1):PAGE40
  U5D1  AW2 VSS<694> SKX_EXT_B_BGA1-IC,TBD    I23 @BASEBOARD_FAB2_LIB.BASEBOARD_FAB2(SCH_1):PAGE40
  U5D1 AV83 VSS<695> SKX_EXT_B_BGA1-IC,TBD    I23 @BASEBOARD_FAB2_LIB.BASEBOARD_FAB2(SCH_1):PAGE40
  U5D1 AV75 VSS<696> SKX_EXT_B_BGA1-IC,TBD    I23 @BASEBOARD_FAB2_LIB.BASEBOARD_FAB2(SCH_1):PAGE40
  U5D1 AV67 VSS<697> SKX_EXT_B_BGA1-IC,TBD    I23 @BASEBOARD_FAB2_LIB.BASEBOARD_FAB2(SCH_1):PAGE40
  U5D1 AV65 VSS<698> SKX_EXT_B_BGA1-IC,TBD    I23 @BASEBOARD_FAB2_LIB.BASEBOARD_FAB2(SCH_1):PAGE40
  U5D1 AV63 VSS<699> SKX_EXT_B_BGA1-IC,TBD    I23 @BASEBOARD_FAB2_LIB.BASEBOARD_FAB2(SCH_1):PAGE40
  U5D1 AV25 VSS<700> SKX_EXT_B_BGA1-IC,TBD    I23 @BASEBOARD_FAB2_LIB.BASEBOARD_FAB2(SCH_1):PAGE40
  U5D1 AV23 VSS<701> SKX_EXT_B_BGA1-IC,TBD    I23 @BASEBOARD_FAB2_LIB.BASEBOARD_FAB2(SCH_1):PAGE40
  U5D1 AV19 VSS<702> SKX_EXT_B_BGA1-IC,TBD    I23 @BASEBOARD_FAB2_LIB.BASEBOARD_FAB2(SCH_1):PAGE40
  U5D1 AV13 VSS<703> SKX_EXT_B_BGA1-IC,TBD    I23 @BASEBOARD_FAB2_LIB.BASEBOARD_FAB2(SCH_1):PAGE40
  U5D1 AV11 VSS<704> SKX_EXT_B_BGA1-IC,TBD    I23 @BASEBOARD_FAB2_LIB.BASEBOARD_FAB2(SCH_1):PAGE40
  U5D1  AV7 VSS<705> SKX_EXT_B_BGA1-IC,TBD    I23 @BASEBOARD_FAB2_LIB.BASEBOARD_FAB2(SCH_1):PAGE40
  U5D1  AV3 VSS<706> SKX_EXT_B_BGA1-IC,TBD    I23 @BASEBOARD_FAB2_LIB.BASEBOARD_FAB2(SCH_1):PAGE40
  U5D1  AV1 VSS<707> SKX_EXT_B_BGA1-IC,TBD    I23 @BASEBOARD_FAB2_LIB.BASEBOARD_FAB2(SCH_1):PAGE40
  U5D1 AU86 VSS<708> SKX_EXT_B_BGA1-IC,TBD    I23 @BASEBOARD_FAB2_LIB.BASEBOARD_FAB2(SCH_1):PAGE40
  U5D1 AU84 VSS<709> SKX_EXT_B_BGA1-IC,TBD    I23 @BASEBOARD_FAB2_LIB.BASEBOARD_FAB2(SCH_1):PAGE40
  U5D1 AU80 VSS<710> SKX_EXT_B_BGA1-IC,TBD    I23 @BASEBOARD_FAB2_LIB.BASEBOARD_FAB2(SCH_1):PAGE40
  U5D1 AU78 VSS<711> SKX_EXT_B_BGA1-IC,TBD    I23 @BASEBOARD_FAB2_LIB.BASEBOARD_FAB2(SCH_1):PAGE40
  U5D1 AU76 VSS<712> SKX_EXT_B_BGA1-IC,TBD    I23 @BASEBOARD_FAB2_LIB.BASEBOARD_FAB2(SCH_1):PAGE40
  U5D1 AU74 VSS<713> SKX_EXT_B_BGA1-IC,TBD    I23 @BASEBOARD_FAB2_LIB.BASEBOARD_FAB2(SCH_1):PAGE40
  U5D1 AU68 VSS<714> SKX_EXT_B_BGA1-IC,TBD    I23 @BASEBOARD_FAB2_LIB.BASEBOARD_FAB2(SCH_1):PAGE40
  U5D1 AU64 VSS<715> SKX_EXT_B_BGA1-IC,TBD    I23 @BASEBOARD_FAB2_LIB.BASEBOARD_FAB2(SCH_1):PAGE40
  U5D1 AU62 VSS<716> SKX_EXT_B_BGA1-IC,TBD    I23 @BASEBOARD_FAB2_LIB.BASEBOARD_FAB2(SCH_1):PAGE40
  U5D1 AU28 VSS<717> SKX_EXT_B_BGA1-IC,TBD    I23 @BASEBOARD_FAB2_LIB.BASEBOARD_FAB2(SCH_1):PAGE40
  U5D1 AU26 VSS<718> SKX_EXT_B_BGA1-IC,TBD    I23 @BASEBOARD_FAB2_LIB.BASEBOARD_FAB2(SCH_1):PAGE40
  U5D1  AU6 VSS<719> SKX_EXT_B_BGA1-IC,TBD    I23 @BASEBOARD_FAB2_LIB.BASEBOARD_FAB2(SCH_1):PAGE40
  U5D1  AU2 VSS<720> SKX_EXT_B_BGA1-IC,TBD    I23 @BASEBOARD_FAB2_LIB.BASEBOARD_FAB2(SCH_1):PAGE40
  U5D1 AT85 VSS<721> SKX_EXT_B_BGA1-IC,TBD    I23 @BASEBOARD_FAB2_LIB.BASEBOARD_FAB2(SCH_1):PAGE40
  U5D1 AT83 VSS<722> SKX_EXT_B_BGA1-IC,TBD    I23 @BASEBOARD_FAB2_LIB.BASEBOARD_FAB2(SCH_1):PAGE40
  U5D1 AT77 VSS<723> SKX_EXT_B_BGA1-IC,TBD    I23 @BASEBOARD_FAB2_LIB.BASEBOARD_FAB2(SCH_1):PAGE40
  U5D1 AT73 VSS<724> SKX_EXT_B_BGA1-IC,TBD    I23 @BASEBOARD_FAB2_LIB.BASEBOARD_FAB2(SCH_1):PAGE40
  U5D1 AT69 VSS<725> SKX_EXT_B_BGA1-IC,TBD    I23 @BASEBOARD_FAB2_LIB.BASEBOARD_FAB2(SCH_1):PAGE40
  U5D1 AT63 VSS<726> SKX_EXT_B_BGA1-IC,TBD    I23 @BASEBOARD_FAB2_LIB.BASEBOARD_FAB2(SCH_1):PAGE40
  U5D1 AT61 VSS<727> SKX_EXT_B_BGA1-IC,TBD    I23 @BASEBOARD_FAB2_LIB.BASEBOARD_FAB2(SCH_1):PAGE40
  U5D1 AT27 VSS<728> SKX_EXT_B_BGA1-IC,TBD    I23 @BASEBOARD_FAB2_LIB.BASEBOARD_FAB2(SCH_1):PAGE40
  U5D1 AT21 VSS<729> SKX_EXT_B_BGA1-IC,TBD    I23 @BASEBOARD_FAB2_LIB.BASEBOARD_FAB2(SCH_1):PAGE40
  U5D1 AT17 VSS<730> SKX_EXT_B_BGA1-IC,TBD    I23 @BASEBOARD_FAB2_LIB.BASEBOARD_FAB2(SCH_1):PAGE40
  U5D1 AT15 VSS<731> SKX_EXT_B_BGA1-IC,TBD    I23 @BASEBOARD_FAB2_LIB.BASEBOARD_FAB2(SCH_1):PAGE40
  U5D1  P63 VSS<732> SKX_EXT_B_BGA1-IC,TBD    I23 @BASEBOARD_FAB2_LIB.BASEBOARD_FAB2(SCH_1):PAGE40
  U5D1 AC48 VSS<733> SKX_EXT_B_BGA1-IC,TBD    I23 @BASEBOARD_FAB2_LIB.BASEBOARD_FAB2(SCH_1):PAGE40
  U5D1 AR78 VSS<734> SKX_EXT_B_BGA1-IC,TBD    I23 @BASEBOARD_FAB2_LIB.BASEBOARD_FAB2(SCH_1):PAGE40
  U5D1 AR72 VSS<735> SKX_EXT_B_BGA1-IC,TBD    I23 @BASEBOARD_FAB2_LIB.BASEBOARD_FAB2(SCH_1):PAGE40
  U5D1 AR60 VSS<736> SKX_EXT_B_BGA1-IC,TBD    I23 @BASEBOARD_FAB2_LIB.BASEBOARD_FAB2(SCH_1):PAGE40
  U5D1 AR30 VSS<737> SKX_EXT_B_BGA1-IC,TBD    I23 @BASEBOARD_FAB2_LIB.BASEBOARD_FAB2(SCH_1):PAGE40
  U5D1 AR24 VSS<738> SKX_EXT_B_BGA1-IC,TBD    I23 @BASEBOARD_FAB2_LIB.BASEBOARD_FAB2(SCH_1):PAGE40
  U5D1 AR10 VSS<739> SKX_EXT_B_BGA1-IC,TBD    I23 @BASEBOARD_FAB2_LIB.BASEBOARD_FAB2(SCH_1):PAGE40
  U5D1 AP85 VSS<740> SKX_EXT_B_BGA1-IC,TBD    I23 @BASEBOARD_FAB2_LIB.BASEBOARD_FAB2(SCH_1):PAGE40
  U5D1 AP83 VSS<741> SKX_EXT_B_BGA1-IC,TBD    I23 @BASEBOARD_FAB2_LIB.BASEBOARD_FAB2(SCH_1):PAGE40
  U5D1 AP81 VSS<742> SKX_EXT_B_BGA1-IC,TBD    I23 @BASEBOARD_FAB2_LIB.BASEBOARD_FAB2(SCH_1):PAGE40
  U5D1 AP75 VSS<743> SKX_EXT_B_BGA1-IC,TBD    I23 @BASEBOARD_FAB2_LIB.BASEBOARD_FAB2(SCH_1):PAGE40
  U5D1 AP73 VSS<744> SKX_EXT_B_BGA1-IC,TBD    I23 @BASEBOARD_FAB2_LIB.BASEBOARD_FAB2(SCH_1):PAGE40
  U5D1 AP69 VSS<745> SKX_EXT_B_BGA1-IC,TBD    I23 @BASEBOARD_FAB2_LIB.BASEBOARD_FAB2(SCH_1):PAGE40
  U5D1 AP67 VSS<746> SKX_EXT_B_BGA1-IC,TBD    I23 @BASEBOARD_FAB2_LIB.BASEBOARD_FAB2(SCH_1):PAGE40
  U5D1 AP65 VSS<747> SKX_EXT_B_BGA1-IC,TBD    I23 @BASEBOARD_FAB2_LIB.BASEBOARD_FAB2(SCH_1):PAGE40
  U5D1 AP63 VSS<748> SKX_EXT_B_BGA1-IC,TBD    I23 @BASEBOARD_FAB2_LIB.BASEBOARD_FAB2(SCH_1):PAGE40
  U5D1 AP59 VSS<749> SKX_EXT_B_BGA1-IC,TBD    I23 @BASEBOARD_FAB2_LIB.BASEBOARD_FAB2(SCH_1):PAGE40
  U5D1 AP31 VSS<750> SKX_EXT_B_BGA1-IC,TBD    I23 @BASEBOARD_FAB2_LIB.BASEBOARD_FAB2(SCH_1):PAGE40
  U5D1 AP19 VSS<751> SKX_EXT_B_BGA1-IC,TBD    I23 @BASEBOARD_FAB2_LIB.BASEBOARD_FAB2(SCH_1):PAGE40
  U5D1 AP13 VSS<752> SKX_EXT_B_BGA1-IC,TBD    I23 @BASEBOARD_FAB2_LIB.BASEBOARD_FAB2(SCH_1):PAGE40
  U5D1  AP9 VSS<753> SKX_EXT_B_BGA1-IC,TBD    I23 @BASEBOARD_FAB2_LIB.BASEBOARD_FAB2(SCH_1):PAGE40
  U5D1  AP5 VSS<754> SKX_EXT_B_BGA1-IC,TBD    I23 @BASEBOARD_FAB2_LIB.BASEBOARD_FAB2(SCH_1):PAGE40
  U5D1 AN78 VSS<755> SKX_EXT_B_BGA1-IC,TBD    I23 @BASEBOARD_FAB2_LIB.BASEBOARD_FAB2(SCH_1):PAGE40
  U5D1 AN58 VSS<756> SKX_EXT_B_BGA1-IC,TBD    I23 @BASEBOARD_FAB2_LIB.BASEBOARD_FAB2(SCH_1):PAGE40
  U5D1 AN28 VSS<757> SKX_EXT_B_BGA1-IC,TBD    I23 @BASEBOARD_FAB2_LIB.BASEBOARD_FAB2(SCH_1):PAGE40
  U5D1  AN6 VSS<758> SKX_EXT_B_BGA1-IC,TBD    I23 @BASEBOARD_FAB2_LIB.BASEBOARD_FAB2(SCH_1):PAGE40
  U5D1  AN2 VSS<759> SKX_EXT_B_BGA1-IC,TBD    I23 @BASEBOARD_FAB2_LIB.BASEBOARD_FAB2(SCH_1):PAGE40
  U5D1 AM83 VSS<760> SKX_EXT_B_BGA1-IC,TBD    I23 @BASEBOARD_FAB2_LIB.BASEBOARD_FAB2(SCH_1):PAGE40
  U5D1 AM79 VSS<761> SKX_EXT_B_BGA1-IC,TBD    I23 @BASEBOARD_FAB2_LIB.BASEBOARD_FAB2(SCH_1):PAGE40
  U5D1 AM73 VSS<762> SKX_EXT_B_BGA1-IC,TBD    I23 @BASEBOARD_FAB2_LIB.BASEBOARD_FAB2(SCH_1):PAGE40
  U5D1 AM69 VSS<763> SKX_EXT_B_BGA1-IC,TBD    I23 @BASEBOARD_FAB2_LIB.BASEBOARD_FAB2(SCH_1):PAGE40
  U5D1 AM63 VSS<764> SKX_EXT_B_BGA1-IC,TBD    I23 @BASEBOARD_FAB2_LIB.BASEBOARD_FAB2(SCH_1):PAGE40
  U5D1 AM57 VSS<765> SKX_EXT_B_BGA1-IC,TBD    I23 @BASEBOARD_FAB2_LIB.BASEBOARD_FAB2(SCH_1):PAGE40
  U5D1 AM31 VSS<766> SKX_EXT_B_BGA1-IC,TBD    I23 @BASEBOARD_FAB2_LIB.BASEBOARD_FAB2(SCH_1):PAGE40
  U5D1 AC50 VSS<767> SKX_EXT_B_BGA1-IC,TBD    I23 @BASEBOARD_FAB2_LIB.BASEBOARD_FAB2(SCH_1):PAGE40
  U5D1  AM1 VSS<768> SKX_EXT_B_BGA1-IC,TBD    I23 @BASEBOARD_FAB2_LIB.BASEBOARD_FAB2(SCH_1):PAGE40
  U5D1 AL86 VSS<769> SKX_EXT_B_BGA1-IC,TBD    I23 @BASEBOARD_FAB2_LIB.BASEBOARD_FAB2(SCH_1):PAGE40
  U5D1 AL82 VSS<770> SKX_EXT_B_BGA1-IC,TBD    I23 @BASEBOARD_FAB2_LIB.BASEBOARD_FAB2(SCH_1):PAGE40
  U5D1 AL80 VSS<771> SKX_EXT_B_BGA1-IC,TBD    I23 @BASEBOARD_FAB2_LIB.BASEBOARD_FAB2(SCH_1):PAGE40
  U5D1 AL78 VSS<772> SKX_EXT_B_BGA1-IC,TBD    I23 @BASEBOARD_FAB2_LIB.BASEBOARD_FAB2(SCH_1):PAGE40
  U5D1 AL76 VSS<773> SKX_EXT_B_BGA1-IC,TBD    I23 @BASEBOARD_FAB2_LIB.BASEBOARD_FAB2(SCH_1):PAGE40
  U5D1  P49 VSS<454> SKX_EXT_B_BGA1-IC,TBD   I283 @BASEBOARD_FAB2_LIB.BASEBOARD_FAB2(SCH_1):PAGE41
  U5D1 CJ12 VSS<455> SKX_EXT_B_BGA1-IC,TBD   I283 @BASEBOARD_FAB2_LIB.BASEBOARD_FAB2(SCH_1):PAGE41
  U5D1 CJ10 VSS<456> SKX_EXT_B_BGA1-IC,TBD   I283 @BASEBOARD_FAB2_LIB.BASEBOARD_FAB2(SCH_1):PAGE41
  U5D1  CJ8 VSS<457> SKX_EXT_B_BGA1-IC,TBD   I283 @BASEBOARD_FAB2_LIB.BASEBOARD_FAB2(SCH_1):PAGE41
  U5D1  CJ6 VSS<458> SKX_EXT_B_BGA1-IC,TBD   I283 @BASEBOARD_FAB2_LIB.BASEBOARD_FAB2(SCH_1):PAGE41
  U5D1  CJ2 VSS<459> SKX_EXT_B_BGA1-IC,TBD   I283 @BASEBOARD_FAB2_LIB.BASEBOARD_FAB2(SCH_1):PAGE41
  U5D1 CH83 VSS<460> SKX_EXT_B_BGA1-IC,TBD   I283 @BASEBOARD_FAB2_LIB.BASEBOARD_FAB2(SCH_1):PAGE41
  U5D1 CH81 VSS<461> SKX_EXT_B_BGA1-IC,TBD   I283 @BASEBOARD_FAB2_LIB.BASEBOARD_FAB2(SCH_1):PAGE41
  U5D1 CH79 VSS<462> SKX_EXT_B_BGA1-IC,TBD   I283 @BASEBOARD_FAB2_LIB.BASEBOARD_FAB2(SCH_1):PAGE41
  U5D1 CH73 VSS<463> SKX_EXT_B_BGA1-IC,TBD   I283 @BASEBOARD_FAB2_LIB.BASEBOARD_FAB2(SCH_1):PAGE41
  U5D1 CH67 VSS<464> SKX_EXT_B_BGA1-IC,TBD   I283 @BASEBOARD_FAB2_LIB.BASEBOARD_FAB2(SCH_1):PAGE41
  U5D1 CH63 VSS<465> SKX_EXT_B_BGA1-IC,TBD   I283 @BASEBOARD_FAB2_LIB.BASEBOARD_FAB2(SCH_1):PAGE41
  U5D1 CH19 VSS<466> SKX_EXT_B_BGA1-IC,TBD   I283 @BASEBOARD_FAB2_LIB.BASEBOARD_FAB2(SCH_1):PAGE41
  U5D1 CH15 VSS<467> SKX_EXT_B_BGA1-IC,TBD   I283 @BASEBOARD_FAB2_LIB.BASEBOARD_FAB2(SCH_1):PAGE41
  U5D1  CH3 VSS<468> SKX_EXT_B_BGA1-IC,TBD   I283 @BASEBOARD_FAB2_LIB.BASEBOARD_FAB2(SCH_1):PAGE41
  U5D1  CH1 VSS<469> SKX_EXT_B_BGA1-IC,TBD   I283 @BASEBOARD_FAB2_LIB.BASEBOARD_FAB2(SCH_1):PAGE41
  U5D1 CG80 VSS<470> SKX_EXT_B_BGA1-IC,TBD   I283 @BASEBOARD_FAB2_LIB.BASEBOARD_FAB2(SCH_1):PAGE41
  U5D1 CG72 VSS<471> SKX_EXT_B_BGA1-IC,TBD   I283 @BASEBOARD_FAB2_LIB.BASEBOARD_FAB2(SCH_1):PAGE41
  U5D1 CG68 VSS<472> SKX_EXT_B_BGA1-IC,TBD   I283 @BASEBOARD_FAB2_LIB.BASEBOARD_FAB2(SCH_1):PAGE41
  U5D1 CG62 VSS<473> SKX_EXT_B_BGA1-IC,TBD   I283 @BASEBOARD_FAB2_LIB.BASEBOARD_FAB2(SCH_1):PAGE41
  U5D1 CG22 VSS<474> SKX_EXT_B_BGA1-IC,TBD   I283 @BASEBOARD_FAB2_LIB.BASEBOARD_FAB2(SCH_1):PAGE41
  U5D1 CG18 VSS<475> SKX_EXT_B_BGA1-IC,TBD   I283 @BASEBOARD_FAB2_LIB.BASEBOARD_FAB2(SCH_1):PAGE41
  U5D1  P51 VSS<476> SKX_EXT_B_BGA1-IC,TBD   I283 @BASEBOARD_FAB2_LIB.BASEBOARD_FAB2(SCH_1):PAGE41
  U5D1 CF83 VSS<477> SKX_EXT_B_BGA1-IC,TBD   I283 @BASEBOARD_FAB2_LIB.BASEBOARD_FAB2(SCH_1):PAGE41
  U5D1 CF77 VSS<478> SKX_EXT_B_BGA1-IC,TBD   I283 @BASEBOARD_FAB2_LIB.BASEBOARD_FAB2(SCH_1):PAGE41
  U5D1 CF71 VSS<479> SKX_EXT_B_BGA1-IC,TBD   I283 @BASEBOARD_FAB2_LIB.BASEBOARD_FAB2(SCH_1):PAGE41
  U5D1 CF69 VSS<480> SKX_EXT_B_BGA1-IC,TBD   I283 @BASEBOARD_FAB2_LIB.BASEBOARD_FAB2(SCH_1):PAGE41
  U5D1 CF63 VSS<481> SKX_EXT_B_BGA1-IC,TBD   I283 @BASEBOARD_FAB2_LIB.BASEBOARD_FAB2(SCH_1):PAGE41
  U5D1  CF9 VSS<482> SKX_EXT_B_BGA1-IC,TBD   I283 @BASEBOARD_FAB2_LIB.BASEBOARD_FAB2(SCH_1):PAGE41
  U5D1  P53 VSS<483> SKX_EXT_B_BGA1-IC,TBD   I283 @BASEBOARD_FAB2_LIB.BASEBOARD_FAB2(SCH_1):PAGE41
  U5D1 CE82 VSS<484> SKX_EXT_B_BGA1-IC,TBD   I283 @BASEBOARD_FAB2_LIB.BASEBOARD_FAB2(SCH_1):PAGE41
  U5D1 CE70 VSS<485> SKX_EXT_B_BGA1-IC,TBD   I283 @BASEBOARD_FAB2_LIB.BASEBOARD_FAB2(SCH_1):PAGE41
  U5D1 CE62 VSS<486> SKX_EXT_B_BGA1-IC,TBD   I283 @BASEBOARD_FAB2_LIB.BASEBOARD_FAB2(SCH_1):PAGE41
  U5D1 CE26 VSS<487> SKX_EXT_B_BGA1-IC,TBD   I283 @BASEBOARD_FAB2_LIB.BASEBOARD_FAB2(SCH_1):PAGE41
  U5D1 CE20 VSS<488> SKX_EXT_B_BGA1-IC,TBD   I283 @BASEBOARD_FAB2_LIB.BASEBOARD_FAB2(SCH_1):PAGE41
  U5D1 CE14 VSS<489> SKX_EXT_B_BGA1-IC,TBD   I283 @BASEBOARD_FAB2_LIB.BASEBOARD_FAB2(SCH_1):PAGE41
  U5D1 CE10 VSS<490> SKX_EXT_B_BGA1-IC,TBD   I283 @BASEBOARD_FAB2_LIB.BASEBOARD_FAB2(SCH_1):PAGE41
  U5D1 CD81 VSS<491> SKX_EXT_B_BGA1-IC,TBD   I283 @BASEBOARD_FAB2_LIB.BASEBOARD_FAB2(SCH_1):PAGE41
  U5D1 CD79 VSS<492> SKX_EXT_B_BGA1-IC,TBD   I283 @BASEBOARD_FAB2_LIB.BASEBOARD_FAB2(SCH_1):PAGE41
  U5D1 CD77 VSS<493> SKX_EXT_B_BGA1-IC,TBD   I283 @BASEBOARD_FAB2_LIB.BASEBOARD_FAB2(SCH_1):PAGE41
  U5D1 CD75 VSS<494> SKX_EXT_B_BGA1-IC,TBD   I283 @BASEBOARD_FAB2_LIB.BASEBOARD_FAB2(SCH_1):PAGE41
  U5D1 CD73 VSS<495> SKX_EXT_B_BGA1-IC,TBD   I283 @BASEBOARD_FAB2_LIB.BASEBOARD_FAB2(SCH_1):PAGE41
  U5D1 CD63 VSS<496> SKX_EXT_B_BGA1-IC,TBD   I283 @BASEBOARD_FAB2_LIB.BASEBOARD_FAB2(SCH_1):PAGE41
  U5D1 CD13 VSS<497> SKX_EXT_B_BGA1-IC,TBD   I283 @BASEBOARD_FAB2_LIB.BASEBOARD_FAB2(SCH_1):PAGE41
  U5D1  CD5 VSS<498> SKX_EXT_B_BGA1-IC,TBD   I283 @BASEBOARD_FAB2_LIB.BASEBOARD_FAB2(SCH_1):PAGE41
  U5D1 CC82 VSS<499> SKX_EXT_B_BGA1-IC,TBD   I283 @BASEBOARD_FAB2_LIB.BASEBOARD_FAB2(SCH_1):PAGE41
  U5D1 CC80 VSS<500> SKX_EXT_B_BGA1-IC,TBD   I283 @BASEBOARD_FAB2_LIB.BASEBOARD_FAB2(SCH_1):PAGE41
  U5D1 CC78 VSS<501> SKX_EXT_B_BGA1-IC,TBD   I283 @BASEBOARD_FAB2_LIB.BASEBOARD_FAB2(SCH_1):PAGE41
  U5D1 CC76 VSS<502> SKX_EXT_B_BGA1-IC,TBD   I283 @BASEBOARD_FAB2_LIB.BASEBOARD_FAB2(SCH_1):PAGE41
  U5D1 CC74 VSS<503> SKX_EXT_B_BGA1-IC,TBD   I283 @BASEBOARD_FAB2_LIB.BASEBOARD_FAB2(SCH_1):PAGE41
  U5D1 CC72 VSS<504> SKX_EXT_B_BGA1-IC,TBD   I283 @BASEBOARD_FAB2_LIB.BASEBOARD_FAB2(SCH_1):PAGE41
  U5D1 CC64 VSS<505> SKX_EXT_B_BGA1-IC,TBD   I283 @BASEBOARD_FAB2_LIB.BASEBOARD_FAB2(SCH_1):PAGE41
  U5D1 CC24 VSS<506> SKX_EXT_B_BGA1-IC,TBD   I283 @BASEBOARD_FAB2_LIB.BASEBOARD_FAB2(SCH_1):PAGE41
  U5D1 CC18 VSS<507> SKX_EXT_B_BGA1-IC,TBD   I283 @BASEBOARD_FAB2_LIB.BASEBOARD_FAB2(SCH_1):PAGE41
  U5D1 CC16 VSS<508> SKX_EXT_B_BGA1-IC,TBD   I283 @BASEBOARD_FAB2_LIB.BASEBOARD_FAB2(SCH_1):PAGE41
  U5D1  CC4 VSS<509> SKX_EXT_B_BGA1-IC,TBD   I283 @BASEBOARD_FAB2_LIB.BASEBOARD_FAB2(SCH_1):PAGE41
  U5D1 CB71 VSS<510> SKX_EXT_B_BGA1-IC,TBD   I283 @BASEBOARD_FAB2_LIB.BASEBOARD_FAB2(SCH_1):PAGE41
  U5D1 CB63 VSS<511> SKX_EXT_B_BGA1-IC,TBD   I283 @BASEBOARD_FAB2_LIB.BASEBOARD_FAB2(SCH_1):PAGE41
  U5D1 CB27 VSS<512> SKX_EXT_B_BGA1-IC,TBD   I283 @BASEBOARD_FAB2_LIB.BASEBOARD_FAB2(SCH_1):PAGE41
  U5D1  CB9 VSS<513> SKX_EXT_B_BGA1-IC,TBD   I283 @BASEBOARD_FAB2_LIB.BASEBOARD_FAB2(SCH_1):PAGE41
  U5D1  CB7 VSS<514> SKX_EXT_B_BGA1-IC,TBD   I283 @BASEBOARD_FAB2_LIB.BASEBOARD_FAB2(SCH_1):PAGE41
  U5D1 CA70 VSS<515> SKX_EXT_B_BGA1-IC,TBD   I283 @BASEBOARD_FAB2_LIB.BASEBOARD_FAB2(SCH_1):PAGE41
  U5D1 CA68 VSS<516> SKX_EXT_B_BGA1-IC,TBD   I283 @BASEBOARD_FAB2_LIB.BASEBOARD_FAB2(SCH_1):PAGE41
  U5D1 CA66 VSS<517> SKX_EXT_B_BGA1-IC,TBD   I283 @BASEBOARD_FAB2_LIB.BASEBOARD_FAB2(SCH_1):PAGE41
  U5D1 CA64 VSS<518> SKX_EXT_B_BGA1-IC,TBD   I283 @BASEBOARD_FAB2_LIB.BASEBOARD_FAB2(SCH_1):PAGE41
  U5D1 CA26 VSS<519> SKX_EXT_B_BGA1-IC,TBD   I283 @BASEBOARD_FAB2_LIB.BASEBOARD_FAB2(SCH_1):PAGE41
  U5D1 CA18 VSS<520> SKX_EXT_B_BGA1-IC,TBD   I283 @BASEBOARD_FAB2_LIB.BASEBOARD_FAB2(SCH_1):PAGE41
  U5D1 CA14 VSS<521> SKX_EXT_B_BGA1-IC,TBD   I283 @BASEBOARD_FAB2_LIB.BASEBOARD_FAB2(SCH_1):PAGE41
  U5D1 CA10 VSS<522> SKX_EXT_B_BGA1-IC,TBD   I283 @BASEBOARD_FAB2_LIB.BASEBOARD_FAB2(SCH_1):PAGE41
  U5D1  CA8 VSS<523> SKX_EXT_B_BGA1-IC,TBD   I283 @BASEBOARD_FAB2_LIB.BASEBOARD_FAB2(SCH_1):PAGE41
  U5D1  CA6 VSS<524> SKX_EXT_B_BGA1-IC,TBD   I283 @BASEBOARD_FAB2_LIB.BASEBOARD_FAB2(SCH_1):PAGE41
  U5D1  CA2 VSS<525> SKX_EXT_B_BGA1-IC,TBD   I283 @BASEBOARD_FAB2_LIB.BASEBOARD_FAB2(SCH_1):PAGE41
  U5D1 BY71 VSS<526> SKX_EXT_B_BGA1-IC,TBD   I283 @BASEBOARD_FAB2_LIB.BASEBOARD_FAB2(SCH_1):PAGE41
  U5D1 BY69 VSS<527> SKX_EXT_B_BGA1-IC,TBD   I283 @BASEBOARD_FAB2_LIB.BASEBOARD_FAB2(SCH_1):PAGE41
  U5D1 BY67 VSS<528> SKX_EXT_B_BGA1-IC,TBD   I283 @BASEBOARD_FAB2_LIB.BASEBOARD_FAB2(SCH_1):PAGE41
  U5D1 BY65 VSS<529> SKX_EXT_B_BGA1-IC,TBD   I283 @BASEBOARD_FAB2_LIB.BASEBOARD_FAB2(SCH_1):PAGE41
  U5D1 BY63 VSS<530> SKX_EXT_B_BGA1-IC,TBD   I283 @BASEBOARD_FAB2_LIB.BASEBOARD_FAB2(SCH_1):PAGE41
  U5D1 BY23 VSS<531> SKX_EXT_B_BGA1-IC,TBD   I283 @BASEBOARD_FAB2_LIB.BASEBOARD_FAB2(SCH_1):PAGE41
  U5D1 BY13 VSS<532> SKX_EXT_B_BGA1-IC,TBD   I283 @BASEBOARD_FAB2_LIB.BASEBOARD_FAB2(SCH_1):PAGE41
  U5D1 BY11 VSS<533> SKX_EXT_B_BGA1-IC,TBD   I283 @BASEBOARD_FAB2_LIB.BASEBOARD_FAB2(SCH_1):PAGE41
  U5D1 BW82 VSS<534> SKX_EXT_B_BGA1-IC,TBD   I283 @BASEBOARD_FAB2_LIB.BASEBOARD_FAB2(SCH_1):PAGE41
  U5D1 BW80 VSS<535> SKX_EXT_B_BGA1-IC,TBD   I283 @BASEBOARD_FAB2_LIB.BASEBOARD_FAB2(SCH_1):PAGE41
  U5D1 BW78 VSS<536> SKX_EXT_B_BGA1-IC,TBD   I283 @BASEBOARD_FAB2_LIB.BASEBOARD_FAB2(SCH_1):PAGE41
  U5D1 BW76 VSS<537> SKX_EXT_B_BGA1-IC,TBD   I283 @BASEBOARD_FAB2_LIB.BASEBOARD_FAB2(SCH_1):PAGE41
  U5D1 BW74 VSS<538> SKX_EXT_B_BGA1-IC,TBD   I283 @BASEBOARD_FAB2_LIB.BASEBOARD_FAB2(SCH_1):PAGE41
  U5D1 BW72 VSS<539> SKX_EXT_B_BGA1-IC,TBD   I283 @BASEBOARD_FAB2_LIB.BASEBOARD_FAB2(SCH_1):PAGE41
  U5D1 BW26 VSS<540> SKX_EXT_B_BGA1-IC,TBD   I283 @BASEBOARD_FAB2_LIB.BASEBOARD_FAB2(SCH_1):PAGE41
  U5D1 BW18 VSS<541> SKX_EXT_B_BGA1-IC,TBD   I283 @BASEBOARD_FAB2_LIB.BASEBOARD_FAB2(SCH_1):PAGE41
  U5D1 BW16 VSS<542> SKX_EXT_B_BGA1-IC,TBD   I283 @BASEBOARD_FAB2_LIB.BASEBOARD_FAB2(SCH_1):PAGE41
  U5D1 BW14 VSS<543> SKX_EXT_B_BGA1-IC,TBD   I283 @BASEBOARD_FAB2_LIB.BASEBOARD_FAB2(SCH_1):PAGE41
  U5D1 BW12 VSS<544> SKX_EXT_B_BGA1-IC,TBD   I283 @BASEBOARD_FAB2_LIB.BASEBOARD_FAB2(SCH_1):PAGE41
  U5D1  P55 VSS<545> SKX_EXT_B_BGA1-IC,TBD   I283 @BASEBOARD_FAB2_LIB.BASEBOARD_FAB2(SCH_1):PAGE41
  U5D1  BW6 VSS<546> SKX_EXT_B_BGA1-IC,TBD   I283 @BASEBOARD_FAB2_LIB.BASEBOARD_FAB2(SCH_1):PAGE41
  U5D1 BV25 VSS<547> SKX_EXT_B_BGA1-IC,TBD   I283 @BASEBOARD_FAB2_LIB.BASEBOARD_FAB2(SCH_1):PAGE41
  U5D1 BV17 VSS<548> SKX_EXT_B_BGA1-IC,TBD   I283 @BASEBOARD_FAB2_LIB.BASEBOARD_FAB2(SCH_1):PAGE41
  U5D1 BU10 VSS<549> SKX_EXT_B_BGA1-IC,TBD   I283 @BASEBOARD_FAB2_LIB.BASEBOARD_FAB2(SCH_1):PAGE41
  U5D1  BV5 VSS<550> SKX_EXT_B_BGA1-IC,TBD   I283 @BASEBOARD_FAB2_LIB.BASEBOARD_FAB2(SCH_1):PAGE41
  U5D1  BU8 VSS<551> SKX_EXT_B_BGA1-IC,TBD   I283 @BASEBOARD_FAB2_LIB.BASEBOARD_FAB2(SCH_1):PAGE41
  U5D1 BT25 VSS<552> SKX_EXT_B_BGA1-IC,TBD   I283 @BASEBOARD_FAB2_LIB.BASEBOARD_FAB2(SCH_1):PAGE41
  U5D1 BT23 VSS<553> SKX_EXT_B_BGA1-IC,TBD   I283 @BASEBOARD_FAB2_LIB.BASEBOARD_FAB2(SCH_1):PAGE41
  U5D1 BT21 VSS<554> SKX_EXT_B_BGA1-IC,TBD   I283 @BASEBOARD_FAB2_LIB.BASEBOARD_FAB2(SCH_1):PAGE41
  U5D1  BT5 VSS<555> SKX_EXT_B_BGA1-IC,TBD   I283 @BASEBOARD_FAB2_LIB.BASEBOARD_FAB2(SCH_1):PAGE41
  U5D1  BT3 VSS<556> SKX_EXT_B_BGA1-IC,TBD   I283 @BASEBOARD_FAB2_LIB.BASEBOARD_FAB2(SCH_1):PAGE41
  U5D1 BR82 VSS<557> SKX_EXT_B_BGA1-IC,TBD   I283 @BASEBOARD_FAB2_LIB.BASEBOARD_FAB2(SCH_1):PAGE41
  U5D1 BR80 VSS<558> SKX_EXT_B_BGA1-IC,TBD   I283 @BASEBOARD_FAB2_LIB.BASEBOARD_FAB2(SCH_1):PAGE41
  U5D1 BR78 VSS<559> SKX_EXT_B_BGA1-IC,TBD   I283 @BASEBOARD_FAB2_LIB.BASEBOARD_FAB2(SCH_1):PAGE41
  U5D1 BR76 VSS<560> SKX_EXT_B_BGA1-IC,TBD   I283 @BASEBOARD_FAB2_LIB.BASEBOARD_FAB2(SCH_1):PAGE41
  U5D1 BR74 VSS<561> SKX_EXT_B_BGA1-IC,TBD   I283 @BASEBOARD_FAB2_LIB.BASEBOARD_FAB2(SCH_1):PAGE41
  U5D1 BR72 VSS<562> SKX_EXT_B_BGA1-IC,TBD   I283 @BASEBOARD_FAB2_LIB.BASEBOARD_FAB2(SCH_1):PAGE41
  U5D1 BR70 VSS<563> SKX_EXT_B_BGA1-IC,TBD   I283 @BASEBOARD_FAB2_LIB.BASEBOARD_FAB2(SCH_1):PAGE41
  U5D1 BR68 VSS<564> SKX_EXT_B_BGA1-IC,TBD   I283 @BASEBOARD_FAB2_LIB.BASEBOARD_FAB2(SCH_1):PAGE41
  U5D1 BR66 VSS<565> SKX_EXT_B_BGA1-IC,TBD   I283 @BASEBOARD_FAB2_LIB.BASEBOARD_FAB2(SCH_1):PAGE41
  U5D1 BR64 VSS<566> SKX_EXT_B_BGA1-IC,TBD   I283 @BASEBOARD_FAB2_LIB.BASEBOARD_FAB2(SCH_1):PAGE41
  U5D1  P57 VSS<567> SKX_EXT_B_BGA1-IC,TBD   I283 @BASEBOARD_FAB2_LIB.BASEBOARD_FAB2(SCH_1):PAGE41
  U5D1 BR16 VSS<568> SKX_EXT_B_BGA1-IC,TBD   I283 @BASEBOARD_FAB2_LIB.BASEBOARD_FAB2(SCH_1):PAGE41
  U5D1 BR10 VSS<569> SKX_EXT_B_BGA1-IC,TBD   I283 @BASEBOARD_FAB2_LIB.BASEBOARD_FAB2(SCH_1):PAGE41
  U5D1  BR6 VSS<570> SKX_EXT_B_BGA1-IC,TBD   I283 @BASEBOARD_FAB2_LIB.BASEBOARD_FAB2(SCH_1):PAGE41
  U5D1 BP27 VSS<571> SKX_EXT_B_BGA1-IC,TBD   I283 @BASEBOARD_FAB2_LIB.BASEBOARD_FAB2(SCH_1):PAGE41
  U5D1  BP3 VSS<572> SKX_EXT_B_BGA1-IC,TBD   I283 @BASEBOARD_FAB2_LIB.BASEBOARD_FAB2(SCH_1):PAGE41
  U5D1 BN26 VSS<573> SKX_EXT_B_BGA1-IC,TBD   I283 @BASEBOARD_FAB2_LIB.BASEBOARD_FAB2(SCH_1):PAGE41
  U5D1 BN20 VSS<574> SKX_EXT_B_BGA1-IC,TBD   I283 @BASEBOARD_FAB2_LIB.BASEBOARD_FAB2(SCH_1):PAGE41
  U5D1 BN10 VSS<575> SKX_EXT_B_BGA1-IC,TBD   I283 @BASEBOARD_FAB2_LIB.BASEBOARD_FAB2(SCH_1):PAGE41
  U5D1  BN6 VSS<576> SKX_EXT_B_BGA1-IC,TBD   I283 @BASEBOARD_FAB2_LIB.BASEBOARD_FAB2(SCH_1):PAGE41
  U5D1 BM25 VSS<577> SKX_EXT_B_BGA1-IC,TBD   I283 @BASEBOARD_FAB2_LIB.BASEBOARD_FAB2(SCH_1):PAGE41
  U5D1  P59 VSS<578> SKX_EXT_B_BGA1-IC,TBD   I283 @BASEBOARD_FAB2_LIB.BASEBOARD_FAB2(SCH_1):PAGE41
  U5D1 BM15 VSS<579> SKX_EXT_B_BGA1-IC,TBD   I283 @BASEBOARD_FAB2_LIB.BASEBOARD_FAB2(SCH_1):PAGE41
  U5D1 BM13 VSS<580> SKX_EXT_B_BGA1-IC,TBD   I283 @BASEBOARD_FAB2_LIB.BASEBOARD_FAB2(SCH_1):PAGE41
  U5D1  BM9 VSS<581> SKX_EXT_B_BGA1-IC,TBD   I283 @BASEBOARD_FAB2_LIB.BASEBOARD_FAB2(SCH_1):PAGE41
  U5D1 BL82 VSS<582> SKX_EXT_B_BGA1-IC,TBD   I283 @BASEBOARD_FAB2_LIB.BASEBOARD_FAB2(SCH_1):PAGE41
  U5D1 BL80 VSS<583> SKX_EXT_B_BGA1-IC,TBD   I283 @BASEBOARD_FAB2_LIB.BASEBOARD_FAB2(SCH_1):PAGE41
  U5D1 BL78 VSS<584> SKX_EXT_B_BGA1-IC,TBD   I283 @BASEBOARD_FAB2_LIB.BASEBOARD_FAB2(SCH_1):PAGE41
  U5D1 BL76 VSS<585> SKX_EXT_B_BGA1-IC,TBD   I283 @BASEBOARD_FAB2_LIB.BASEBOARD_FAB2(SCH_1):PAGE41
  U5D1 BL74 VSS<586> SKX_EXT_B_BGA1-IC,TBD   I283 @BASEBOARD_FAB2_LIB.BASEBOARD_FAB2(SCH_1):PAGE41
  U5D1 BL72 VSS<587> SKX_EXT_B_BGA1-IC,TBD   I283 @BASEBOARD_FAB2_LIB.BASEBOARD_FAB2(SCH_1):PAGE41
  U5D1 BL70 VSS<588> SKX_EXT_B_BGA1-IC,TBD   I283 @BASEBOARD_FAB2_LIB.BASEBOARD_FAB2(SCH_1):PAGE41
  U5D1 BL68 VSS<589> SKX_EXT_B_BGA1-IC,TBD   I283 @BASEBOARD_FAB2_LIB.BASEBOARD_FAB2(SCH_1):PAGE41
  U5D1 BL66 VSS<590> SKX_EXT_B_BGA1-IC,TBD   I283 @BASEBOARD_FAB2_LIB.BASEBOARD_FAB2(SCH_1):PAGE41
  U5D1 BL64 VSS<591> SKX_EXT_B_BGA1-IC,TBD   I283 @BASEBOARD_FAB2_LIB.BASEBOARD_FAB2(SCH_1):PAGE41
  U5D1 BL24 VSS<592> SKX_EXT_B_BGA1-IC,TBD   I283 @BASEBOARD_FAB2_LIB.BASEBOARD_FAB2(SCH_1):PAGE41
  U5D1 BL22 VSS<593> SKX_EXT_B_BGA1-IC,TBD   I283 @BASEBOARD_FAB2_LIB.BASEBOARD_FAB2(SCH_1):PAGE41
  U5D1  P61 VSS<594> SKX_EXT_B_BGA1-IC,TBD   I283 @BASEBOARD_FAB2_LIB.BASEBOARD_FAB2(SCH_1):PAGE41
  U5D1 BL12 VSS<595> SKX_EXT_B_BGA1-IC,TBD   I283 @BASEBOARD_FAB2_LIB.BASEBOARD_FAB2(SCH_1):PAGE41
  U5D1 BL10 VSS<596> SKX_EXT_B_BGA1-IC,TBD   I283 @BASEBOARD_FAB2_LIB.BASEBOARD_FAB2(SCH_1):PAGE41
  U5D1  BL6 VSS<597> SKX_EXT_B_BGA1-IC,TBD   I283 @BASEBOARD_FAB2_LIB.BASEBOARD_FAB2(SCH_1):PAGE41
  U5D1 BK19 VSS<598> SKX_EXT_B_BGA1-IC,TBD   I283 @BASEBOARD_FAB2_LIB.BASEBOARD_FAB2(SCH_1):PAGE41
  U5D1 BK11 VSS<599> SKX_EXT_B_BGA1-IC,TBD   I283 @BASEBOARD_FAB2_LIB.BASEBOARD_FAB2(SCH_1):PAGE41
  U5D1  BK7 VSS<600> SKX_EXT_B_BGA1-IC,TBD   I283 @BASEBOARD_FAB2_LIB.BASEBOARD_FAB2(SCH_1):PAGE41
  U5D1  BK3 VSS<601> SKX_EXT_B_BGA1-IC,TBD   I283 @BASEBOARD_FAB2_LIB.BASEBOARD_FAB2(SCH_1):PAGE41
  U5D1  BJ6 VSS<602> SKX_EXT_B_BGA1-IC,TBD   I283 @BASEBOARD_FAB2_LIB.BASEBOARD_FAB2(SCH_1):PAGE41
  U5D1  BJ4 VSS<603> SKX_EXT_B_BGA1-IC,TBD   I283 @BASEBOARD_FAB2_LIB.BASEBOARD_FAB2(SCH_1):PAGE41
  U5D1 BH21 VSS<604> SKX_EXT_B_BGA1-IC,TBD   I283 @BASEBOARD_FAB2_LIB.BASEBOARD_FAB2(SCH_1):PAGE41
  U5D1 BH15 VSS<605> SKX_EXT_B_BGA1-IC,TBD   I283 @BASEBOARD_FAB2_LIB.BASEBOARD_FAB2(SCH_1):PAGE41
  U5D1 BH11 VSS<606> SKX_EXT_B_BGA1-IC,TBD   I283 @BASEBOARD_FAB2_LIB.BASEBOARD_FAB2(SCH_1):PAGE41
  U5D1  BH9 VSS<607> SKX_EXT_B_BGA1-IC,TBD   I283 @BASEBOARD_FAB2_LIB.BASEBOARD_FAB2(SCH_1):PAGE41
  U5D1  BH7 VSS<608> SKX_EXT_B_BGA1-IC,TBD   I283 @BASEBOARD_FAB2_LIB.BASEBOARD_FAB2(SCH_1):PAGE41
  U5D1 BG82 VSS<609> SKX_EXT_B_BGA1-IC,TBD   I283 @BASEBOARD_FAB2_LIB.BASEBOARD_FAB2(SCH_1):PAGE41
  U5D1 BG80 VSS<610> SKX_EXT_B_BGA1-IC,TBD   I283 @BASEBOARD_FAB2_LIB.BASEBOARD_FAB2(SCH_1):PAGE41
  U5D1 BG78 VSS<611> SKX_EXT_B_BGA1-IC,TBD   I283 @BASEBOARD_FAB2_LIB.BASEBOARD_FAB2(SCH_1):PAGE41
  U5D1 BG76 VSS<612> SKX_EXT_B_BGA1-IC,TBD   I283 @BASEBOARD_FAB2_LIB.BASEBOARD_FAB2(SCH_1):PAGE41
  U5D1 BG74 VSS<613> SKX_EXT_B_BGA1-IC,TBD   I283 @BASEBOARD_FAB2_LIB.BASEBOARD_FAB2(SCH_1):PAGE41
  U5D1 DA46 VSS<294> SKX_EXT_B_BGA1-IC,TBD   I284 @BASEBOARD_FAB2_LIB.BASEBOARD_FAB2(SCH_1):PAGE41
  U5D1 DA44 VSS<295> SKX_EXT_B_BGA1-IC,TBD   I284 @BASEBOARD_FAB2_LIB.BASEBOARD_FAB2(SCH_1):PAGE41
  U5D1 DA38 VSS<296> SKX_EXT_B_BGA1-IC,TBD   I284 @BASEBOARD_FAB2_LIB.BASEBOARD_FAB2(SCH_1):PAGE41
  U5D1 DA36 VSS<297> SKX_EXT_B_BGA1-IC,TBD   I284 @BASEBOARD_FAB2_LIB.BASEBOARD_FAB2(SCH_1):PAGE41
  U5D1 DA34 VSS<298> SKX_EXT_B_BGA1-IC,TBD   I284 @BASEBOARD_FAB2_LIB.BASEBOARD_FAB2(SCH_1):PAGE41
  U5D1 DA32 VSS<299> SKX_EXT_B_BGA1-IC,TBD   I284 @BASEBOARD_FAB2_LIB.BASEBOARD_FAB2(SCH_1):PAGE41
  U5D1 DA30 VSS<300> SKX_EXT_B_BGA1-IC,TBD   I284 @BASEBOARD_FAB2_LIB.BASEBOARD_FAB2(SCH_1):PAGE41
  U5D1 DA28 VSS<301> SKX_EXT_B_BGA1-IC,TBD   I284 @BASEBOARD_FAB2_LIB.BASEBOARD_FAB2(SCH_1):PAGE41
  U5D1 DA26 VSS<302> SKX_EXT_B_BGA1-IC,TBD   I284 @BASEBOARD_FAB2_LIB.BASEBOARD_FAB2(SCH_1):PAGE41
  U5D1 DA18 VSS<303> SKX_EXT_B_BGA1-IC,TBD   I284 @BASEBOARD_FAB2_LIB.BASEBOARD_FAB2(SCH_1):PAGE41
  U5D1  H53 VSS<304> SKX_EXT_B_BGA1-IC,TBD   I284 @BASEBOARD_FAB2_LIB.BASEBOARD_FAB2(SCH_1):PAGE41
  U5D1  DA6 VSS<305> SKX_EXT_B_BGA1-IC,TBD   I284 @BASEBOARD_FAB2_LIB.BASEBOARD_FAB2(SCH_1):PAGE41
  U5D1 CY85 VSS<306> SKX_EXT_B_BGA1-IC,TBD   I284 @BASEBOARD_FAB2_LIB.BASEBOARD_FAB2(SCH_1):PAGE41
  U5D1 CY83 VSS<307> SKX_EXT_B_BGA1-IC,TBD   I284 @BASEBOARD_FAB2_LIB.BASEBOARD_FAB2(SCH_1):PAGE41
  U5D1 CY77 VSS<308> SKX_EXT_B_BGA1-IC,TBD   I284 @BASEBOARD_FAB2_LIB.BASEBOARD_FAB2(SCH_1):PAGE41
  U5D1 CY75 VSS<309> SKX_EXT_B_BGA1-IC,TBD   I284 @BASEBOARD_FAB2_LIB.BASEBOARD_FAB2(SCH_1):PAGE41
  U5D1 CY69 VSS<310> SKX_EXT_B_BGA1-IC,TBD   I284 @BASEBOARD_FAB2_LIB.BASEBOARD_FAB2(SCH_1):PAGE41
  U5D1 CY65 VSS<311> SKX_EXT_B_BGA1-IC,TBD   I284 @BASEBOARD_FAB2_LIB.BASEBOARD_FAB2(SCH_1):PAGE41
  U5D1 CY61 VSS<312> SKX_EXT_B_BGA1-IC,TBD   I284 @BASEBOARD_FAB2_LIB.BASEBOARD_FAB2(SCH_1):PAGE41
  U5D1 CY59 VSS<313> SKX_EXT_B_BGA1-IC,TBD   I284 @BASEBOARD_FAB2_LIB.BASEBOARD_FAB2(SCH_1):PAGE41
  U5D1 CY51 VSS<314> SKX_EXT_B_BGA1-IC,TBD   I284 @BASEBOARD_FAB2_LIB.BASEBOARD_FAB2(SCH_1):PAGE41
  U5D1 CY45 VSS<315> SKX_EXT_B_BGA1-IC,TBD   I284 @BASEBOARD_FAB2_LIB.BASEBOARD_FAB2(SCH_1):PAGE41
  U5D1 CY41 VSS<316> SKX_EXT_B_BGA1-IC,TBD   I284 @BASEBOARD_FAB2_LIB.BASEBOARD_FAB2(SCH_1):PAGE41
  U5D1 CY21 VSS<317> SKX_EXT_B_BGA1-IC,TBD   I284 @BASEBOARD_FAB2_LIB.BASEBOARD_FAB2(SCH_1):PAGE41
  U5D1 CY15 VSS<318> SKX_EXT_B_BGA1-IC,TBD   I284 @BASEBOARD_FAB2_LIB.BASEBOARD_FAB2(SCH_1):PAGE41
  U5D1 CY13 VSS<319> SKX_EXT_B_BGA1-IC,TBD   I284 @BASEBOARD_FAB2_LIB.BASEBOARD_FAB2(SCH_1):PAGE41
  U5D1  CY9 VSS<320> SKX_EXT_B_BGA1-IC,TBD   I284 @BASEBOARD_FAB2_LIB.BASEBOARD_FAB2(SCH_1):PAGE41
  U5D1  CY1 VSS<321> SKX_EXT_B_BGA1-IC,TBD   I284 @BASEBOARD_FAB2_LIB.BASEBOARD_FAB2(SCH_1):PAGE41
  U5D1 CW82 VSS<322> SKX_EXT_B_BGA1-IC,TBD   I284 @BASEBOARD_FAB2_LIB.BASEBOARD_FAB2(SCH_1):PAGE41
  U5D1 CW78 VSS<323> SKX_EXT_B_BGA1-IC,TBD   I284 @BASEBOARD_FAB2_LIB.BASEBOARD_FAB2(SCH_1):PAGE41
  U5D1 CW74 VSS<324> SKX_EXT_B_BGA1-IC,TBD   I284 @BASEBOARD_FAB2_LIB.BASEBOARD_FAB2(SCH_1):PAGE41
  U5D1 CW68 VSS<325> SKX_EXT_B_BGA1-IC,TBD   I284 @BASEBOARD_FAB2_LIB.BASEBOARD_FAB2(SCH_1):PAGE41
  U5D1 CW66 VSS<326> SKX_EXT_B_BGA1-IC,TBD   I284 @BASEBOARD_FAB2_LIB.BASEBOARD_FAB2(SCH_1):PAGE41
  U5D1 CW64 VSS<327> SKX_EXT_B_BGA1-IC,TBD   I284 @BASEBOARD_FAB2_LIB.BASEBOARD_FAB2(SCH_1):PAGE41
  U5D1 CW54 VSS<328> SKX_EXT_B_BGA1-IC,TBD   I284 @BASEBOARD_FAB2_LIB.BASEBOARD_FAB2(SCH_1):PAGE41
  U5D1 CW52 VSS<329> SKX_EXT_B_BGA1-IC,TBD   I284 @BASEBOARD_FAB2_LIB.BASEBOARD_FAB2(SCH_1):PAGE41
  U5D1 CW42 VSS<330> SKX_EXT_B_BGA1-IC,TBD   I284 @BASEBOARD_FAB2_LIB.BASEBOARD_FAB2(SCH_1):PAGE41
  U5D1 CW40 VSS<331> SKX_EXT_B_BGA1-IC,TBD   I284 @BASEBOARD_FAB2_LIB.BASEBOARD_FAB2(SCH_1):PAGE41
  U5D1 CW38 VSS<332> SKX_EXT_B_BGA1-IC,TBD   I284 @BASEBOARD_FAB2_LIB.BASEBOARD_FAB2(SCH_1):PAGE41
  U5D1 CW32 VSS<333> SKX_EXT_B_BGA1-IC,TBD   I284 @BASEBOARD_FAB2_LIB.BASEBOARD_FAB2(SCH_1):PAGE41
  U5D1 CW26 VSS<334> SKX_EXT_B_BGA1-IC,TBD   I284 @BASEBOARD_FAB2_LIB.BASEBOARD_FAB2(SCH_1):PAGE41
  U5D1 CW12 VSS<335> SKX_EXT_B_BGA1-IC,TBD   I284 @BASEBOARD_FAB2_LIB.BASEBOARD_FAB2(SCH_1):PAGE41
  U5D1 CV83 VSS<336> SKX_EXT_B_BGA1-IC,TBD   I284 @BASEBOARD_FAB2_LIB.BASEBOARD_FAB2(SCH_1):PAGE41
  U5D1 CV81 VSS<337> SKX_EXT_B_BGA1-IC,TBD   I284 @BASEBOARD_FAB2_LIB.BASEBOARD_FAB2(SCH_1):PAGE41
  U5D1 CV79 VSS<338> SKX_EXT_B_BGA1-IC,TBD   I284 @BASEBOARD_FAB2_LIB.BASEBOARD_FAB2(SCH_1):PAGE41
  U5D1 CV73 VSS<339> SKX_EXT_B_BGA1-IC,TBD   I284 @BASEBOARD_FAB2_LIB.BASEBOARD_FAB2(SCH_1):PAGE41
  U5D1 CV67 VSS<340> SKX_EXT_B_BGA1-IC,TBD   I284 @BASEBOARD_FAB2_LIB.BASEBOARD_FAB2(SCH_1):PAGE41
  U5D1 CV63 VSS<341> SKX_EXT_B_BGA1-IC,TBD   I284 @BASEBOARD_FAB2_LIB.BASEBOARD_FAB2(SCH_1):PAGE41
  U5D1 CV55 VSS<342> SKX_EXT_B_BGA1-IC,TBD   I284 @BASEBOARD_FAB2_LIB.BASEBOARD_FAB2(SCH_1):PAGE41
  U5D1 CV53 VSS<343> SKX_EXT_B_BGA1-IC,TBD   I284 @BASEBOARD_FAB2_LIB.BASEBOARD_FAB2(SCH_1):PAGE41
  U5D1 CV41 VSS<344> SKX_EXT_B_BGA1-IC,TBD   I284 @BASEBOARD_FAB2_LIB.BASEBOARD_FAB2(SCH_1):PAGE41
  U5D1 CV39 VSS<345> SKX_EXT_B_BGA1-IC,TBD   I284 @BASEBOARD_FAB2_LIB.BASEBOARD_FAB2(SCH_1):PAGE41
  U5D1 CV37 VSS<346> SKX_EXT_B_BGA1-IC,TBD   I284 @BASEBOARD_FAB2_LIB.BASEBOARD_FAB2(SCH_1):PAGE41
  U5D1 CV33 VSS<347> SKX_EXT_B_BGA1-IC,TBD   I284 @BASEBOARD_FAB2_LIB.BASEBOARD_FAB2(SCH_1):PAGE41
  U5D1 CV31 VSS<348> SKX_EXT_B_BGA1-IC,TBD   I284 @BASEBOARD_FAB2_LIB.BASEBOARD_FAB2(SCH_1):PAGE41
  U5D1 CV27 VSS<349> SKX_EXT_B_BGA1-IC,TBD   I284 @BASEBOARD_FAB2_LIB.BASEBOARD_FAB2(SCH_1):PAGE41
  U5D1 CV25 VSS<350> SKX_EXT_B_BGA1-IC,TBD   I284 @BASEBOARD_FAB2_LIB.BASEBOARD_FAB2(SCH_1):PAGE41
  U5D1 CV17 VSS<351> SKX_EXT_B_BGA1-IC,TBD   I284 @BASEBOARD_FAB2_LIB.BASEBOARD_FAB2(SCH_1):PAGE41
  U5D1  H55 VSS<352> SKX_EXT_B_BGA1-IC,TBD   I284 @BASEBOARD_FAB2_LIB.BASEBOARD_FAB2(SCH_1):PAGE41
  U5D1  CV1 VSS<353> SKX_EXT_B_BGA1-IC,TBD   I284 @BASEBOARD_FAB2_LIB.BASEBOARD_FAB2(SCH_1):PAGE41
  U5D1 CU86 VSS<354> SKX_EXT_B_BGA1-IC,TBD   I284 @BASEBOARD_FAB2_LIB.BASEBOARD_FAB2(SCH_1):PAGE41
  U5D1 CU82 VSS<355> SKX_EXT_B_BGA1-IC,TBD   I284 @BASEBOARD_FAB2_LIB.BASEBOARD_FAB2(SCH_1):PAGE41
  U5D1 CU80 VSS<356> SKX_EXT_B_BGA1-IC,TBD   I284 @BASEBOARD_FAB2_LIB.BASEBOARD_FAB2(SCH_1):PAGE41
  U5D1 CU78 VSS<357> SKX_EXT_B_BGA1-IC,TBD   I284 @BASEBOARD_FAB2_LIB.BASEBOARD_FAB2(SCH_1):PAGE41
  U5D1 CU76 VSS<358> SKX_EXT_B_BGA1-IC,TBD   I284 @BASEBOARD_FAB2_LIB.BASEBOARD_FAB2(SCH_1):PAGE41
  U5D1 CU68 VSS<359> SKX_EXT_B_BGA1-IC,TBD   I284 @BASEBOARD_FAB2_LIB.BASEBOARD_FAB2(SCH_1):PAGE41
  U5D1 CU62 VSS<360> SKX_EXT_B_BGA1-IC,TBD   I284 @BASEBOARD_FAB2_LIB.BASEBOARD_FAB2(SCH_1):PAGE41
  U5D1 CU56 VSS<361> SKX_EXT_B_BGA1-IC,TBD   I284 @BASEBOARD_FAB2_LIB.BASEBOARD_FAB2(SCH_1):PAGE41
  U5D1 CU36 VSS<362> SKX_EXT_B_BGA1-IC,TBD   I284 @BASEBOARD_FAB2_LIB.BASEBOARD_FAB2(SCH_1):PAGE41
  U5D1 CU34 VSS<363> SKX_EXT_B_BGA1-IC,TBD   I284 @BASEBOARD_FAB2_LIB.BASEBOARD_FAB2(SCH_1):PAGE41
  U5D1 CU30 VSS<364> SKX_EXT_B_BGA1-IC,TBD   I284 @BASEBOARD_FAB2_LIB.BASEBOARD_FAB2(SCH_1):PAGE41
  U5D1 CU28 VSS<365> SKX_EXT_B_BGA1-IC,TBD   I284 @BASEBOARD_FAB2_LIB.BASEBOARD_FAB2(SCH_1):PAGE41
  U5D1 CU22 VSS<366> SKX_EXT_B_BGA1-IC,TBD   I284 @BASEBOARD_FAB2_LIB.BASEBOARD_FAB2(SCH_1):PAGE41
  U5D1  CU4 VSS<367> SKX_EXT_B_BGA1-IC,TBD   I284 @BASEBOARD_FAB2_LIB.BASEBOARD_FAB2(SCH_1):PAGE41
  U5D1 CT85 VSS<368> SKX_EXT_B_BGA1-IC,TBD   I284 @BASEBOARD_FAB2_LIB.BASEBOARD_FAB2(SCH_1):PAGE41
  U5D1 CT83 VSS<369> SKX_EXT_B_BGA1-IC,TBD   I284 @BASEBOARD_FAB2_LIB.BASEBOARD_FAB2(SCH_1):PAGE41
  U5D1 CT79 VSS<370> SKX_EXT_B_BGA1-IC,TBD   I284 @BASEBOARD_FAB2_LIB.BASEBOARD_FAB2(SCH_1):PAGE41
  U5D1 CT73 VSS<371> SKX_EXT_B_BGA1-IC,TBD   I284 @BASEBOARD_FAB2_LIB.BASEBOARD_FAB2(SCH_1):PAGE41
  U5D1 CT57 VSS<372> SKX_EXT_B_BGA1-IC,TBD   I284 @BASEBOARD_FAB2_LIB.BASEBOARD_FAB2(SCH_1):PAGE41
  U5D1 CT35 VSS<373> SKX_EXT_B_BGA1-IC,TBD   I284 @BASEBOARD_FAB2_LIB.BASEBOARD_FAB2(SCH_1):PAGE41
  U5D1 CT33 VSS<374> SKX_EXT_B_BGA1-IC,TBD   I284 @BASEBOARD_FAB2_LIB.BASEBOARD_FAB2(SCH_1):PAGE41
  U5D1 CT29 VSS<375> SKX_EXT_B_BGA1-IC,TBD   I284 @BASEBOARD_FAB2_LIB.BASEBOARD_FAB2(SCH_1):PAGE41
  U5D1 CT27 VSS<376> SKX_EXT_B_BGA1-IC,TBD   I284 @BASEBOARD_FAB2_LIB.BASEBOARD_FAB2(SCH_1):PAGE41
  U5D1 CT19 VSS<377> SKX_EXT_B_BGA1-IC,TBD   I284 @BASEBOARD_FAB2_LIB.BASEBOARD_FAB2(SCH_1):PAGE41
  U5D1 CT13 VSS<378> SKX_EXT_B_BGA1-IC,TBD   I284 @BASEBOARD_FAB2_LIB.BASEBOARD_FAB2(SCH_1):PAGE41
  U5D1  H57 VSS<379> SKX_EXT_B_BGA1-IC,TBD   I284 @BASEBOARD_FAB2_LIB.BASEBOARD_FAB2(SCH_1):PAGE41
  U5D1 CR86 VSS<380> SKX_EXT_B_BGA1-IC,TBD   I284 @BASEBOARD_FAB2_LIB.BASEBOARD_FAB2(SCH_1):PAGE41
  U5D1 CR78 VSS<381> SKX_EXT_B_BGA1-IC,TBD   I284 @BASEBOARD_FAB2_LIB.BASEBOARD_FAB2(SCH_1):PAGE41
  U5D1 CR68 VSS<382> SKX_EXT_B_BGA1-IC,TBD   I284 @BASEBOARD_FAB2_LIB.BASEBOARD_FAB2(SCH_1):PAGE41
  U5D1 CR66 VSS<383> SKX_EXT_B_BGA1-IC,TBD   I284 @BASEBOARD_FAB2_LIB.BASEBOARD_FAB2(SCH_1):PAGE41
  U5D1 CR64 VSS<384> SKX_EXT_B_BGA1-IC,TBD   I284 @BASEBOARD_FAB2_LIB.BASEBOARD_FAB2(SCH_1):PAGE41
  U5D1 CR62 VSS<385> SKX_EXT_B_BGA1-IC,TBD   I284 @BASEBOARD_FAB2_LIB.BASEBOARD_FAB2(SCH_1):PAGE41
  U5D1 CR58 VSS<386> SKX_EXT_B_BGA1-IC,TBD   I284 @BASEBOARD_FAB2_LIB.BASEBOARD_FAB2(SCH_1):PAGE41
  U5D1 CR32 VSS<387> SKX_EXT_B_BGA1-IC,TBD   I284 @BASEBOARD_FAB2_LIB.BASEBOARD_FAB2(SCH_1):PAGE41
  U5D1 CR24 VSS<388> SKX_EXT_B_BGA1-IC,TBD   I284 @BASEBOARD_FAB2_LIB.BASEBOARD_FAB2(SCH_1):PAGE41
  U5D1 CR22 VSS<389> SKX_EXT_B_BGA1-IC,TBD   I284 @BASEBOARD_FAB2_LIB.BASEBOARD_FAB2(SCH_1):PAGE41
  U5D1 CR10 VSS<390> SKX_EXT_B_BGA1-IC,TBD   I284 @BASEBOARD_FAB2_LIB.BASEBOARD_FAB2(SCH_1):PAGE41
  U5D1  CR6 VSS<391> SKX_EXT_B_BGA1-IC,TBD   I284 @BASEBOARD_FAB2_LIB.BASEBOARD_FAB2(SCH_1):PAGE41
  U5D1 CP83 VSS<392> SKX_EXT_B_BGA1-IC,TBD   I284 @BASEBOARD_FAB2_LIB.BASEBOARD_FAB2(SCH_1):PAGE41
  U5D1 CP81 VSS<393> SKX_EXT_B_BGA1-IC,TBD   I284 @BASEBOARD_FAB2_LIB.BASEBOARD_FAB2(SCH_1):PAGE41
  U5D1 CP75 VSS<394> SKX_EXT_B_BGA1-IC,TBD   I284 @BASEBOARD_FAB2_LIB.BASEBOARD_FAB2(SCH_1):PAGE41
  U5D1 CP73 VSS<395> SKX_EXT_B_BGA1-IC,TBD   I284 @BASEBOARD_FAB2_LIB.BASEBOARD_FAB2(SCH_1):PAGE41
  U5D1 CP69 VSS<396> SKX_EXT_B_BGA1-IC,TBD   I284 @BASEBOARD_FAB2_LIB.BASEBOARD_FAB2(SCH_1):PAGE41
  U5D1 CP59 VSS<397> SKX_EXT_B_BGA1-IC,TBD   I284 @BASEBOARD_FAB2_LIB.BASEBOARD_FAB2(SCH_1):PAGE41
  U5D1 CP25 VSS<398> SKX_EXT_B_BGA1-IC,TBD   I284 @BASEBOARD_FAB2_LIB.BASEBOARD_FAB2(SCH_1):PAGE41
  U5D1  H59 VSS<399> SKX_EXT_B_BGA1-IC,TBD   I284 @BASEBOARD_FAB2_LIB.BASEBOARD_FAB2(SCH_1):PAGE41
  U5D1  CP1 VSS<400> SKX_EXT_B_BGA1-IC,TBD   I284 @BASEBOARD_FAB2_LIB.BASEBOARD_FAB2(SCH_1):PAGE41
  U5D1 CN78 VSS<401> SKX_EXT_B_BGA1-IC,TBD   I284 @BASEBOARD_FAB2_LIB.BASEBOARD_FAB2(SCH_1):PAGE41
  U5D1 CN68 VSS<402> SKX_EXT_B_BGA1-IC,TBD   I284 @BASEBOARD_FAB2_LIB.BASEBOARD_FAB2(SCH_1):PAGE41
  U5D1 CN62 VSS<403> SKX_EXT_B_BGA1-IC,TBD   I284 @BASEBOARD_FAB2_LIB.BASEBOARD_FAB2(SCH_1):PAGE41
  U5D1 CN60 VSS<404> SKX_EXT_B_BGA1-IC,TBD   I284 @BASEBOARD_FAB2_LIB.BASEBOARD_FAB2(SCH_1):PAGE41
  U5D1 CN32 VSS<405> SKX_EXT_B_BGA1-IC,TBD   I284 @BASEBOARD_FAB2_LIB.BASEBOARD_FAB2(SCH_1):PAGE41
  U5D1 CN26 VSS<406> SKX_EXT_B_BGA1-IC,TBD   I284 @BASEBOARD_FAB2_LIB.BASEBOARD_FAB2(SCH_1):PAGE41
  U5D1  H61 VSS<407> SKX_EXT_B_BGA1-IC,TBD   I284 @BASEBOARD_FAB2_LIB.BASEBOARD_FAB2(SCH_1):PAGE41
  U5D1 CN12 VSS<408> SKX_EXT_B_BGA1-IC,TBD   I284 @BASEBOARD_FAB2_LIB.BASEBOARD_FAB2(SCH_1):PAGE41
  U5D1  CN2 VSS<409> SKX_EXT_B_BGA1-IC,TBD   I284 @BASEBOARD_FAB2_LIB.BASEBOARD_FAB2(SCH_1):PAGE41
  U5D1 CM85 VSS<410> SKX_EXT_B_BGA1-IC,TBD   I284 @BASEBOARD_FAB2_LIB.BASEBOARD_FAB2(SCH_1):PAGE41
  U5D1 CM83 VSS<411> SKX_EXT_B_BGA1-IC,TBD   I284 @BASEBOARD_FAB2_LIB.BASEBOARD_FAB2(SCH_1):PAGE41
  U5D1 CM77 VSS<412> SKX_EXT_B_BGA1-IC,TBD   I284 @BASEBOARD_FAB2_LIB.BASEBOARD_FAB2(SCH_1):PAGE41
  U5D1 CM73 VSS<413> SKX_EXT_B_BGA1-IC,TBD   I284 @BASEBOARD_FAB2_LIB.BASEBOARD_FAB2(SCH_1):PAGE41
  U5D1 CM67 VSS<414> SKX_EXT_B_BGA1-IC,TBD   I284 @BASEBOARD_FAB2_LIB.BASEBOARD_FAB2(SCH_1):PAGE41
  U5D1 CM63 VSS<415> SKX_EXT_B_BGA1-IC,TBD   I284 @BASEBOARD_FAB2_LIB.BASEBOARD_FAB2(SCH_1):PAGE41
  U5D1 CM61 VSS<416> SKX_EXT_B_BGA1-IC,TBD   I284 @BASEBOARD_FAB2_LIB.BASEBOARD_FAB2(SCH_1):PAGE41
  U5D1 CM31 VSS<417> SKX_EXT_B_BGA1-IC,TBD   I284 @BASEBOARD_FAB2_LIB.BASEBOARD_FAB2(SCH_1):PAGE41
  U5D1  CM5 VSS<418> SKX_EXT_B_BGA1-IC,TBD   I284 @BASEBOARD_FAB2_LIB.BASEBOARD_FAB2(SCH_1):PAGE41
  U5D1 CM29 VSS<419> SKX_EXT_B_BGA1-IC,TBD   I284 @BASEBOARD_FAB2_LIB.BASEBOARD_FAB2(SCH_1):PAGE41
  U5D1 CM19 VSS<420> SKX_EXT_B_BGA1-IC,TBD   I284 @BASEBOARD_FAB2_LIB.BASEBOARD_FAB2(SCH_1):PAGE41
  U5D1 CL80 VSS<421> SKX_EXT_B_BGA1-IC,TBD   I284 @BASEBOARD_FAB2_LIB.BASEBOARD_FAB2(SCH_1):PAGE41
  U5D1 CL78 VSS<422> SKX_EXT_B_BGA1-IC,TBD   I284 @BASEBOARD_FAB2_LIB.BASEBOARD_FAB2(SCH_1):PAGE41
  U5D1 CL76 VSS<423> SKX_EXT_B_BGA1-IC,TBD   I284 @BASEBOARD_FAB2_LIB.BASEBOARD_FAB2(SCH_1):PAGE41
  U5D1 CL74 VSS<424> SKX_EXT_B_BGA1-IC,TBD   I284 @BASEBOARD_FAB2_LIB.BASEBOARD_FAB2(SCH_1):PAGE41
  U5D1 CL66 VSS<425> SKX_EXT_B_BGA1-IC,TBD   I284 @BASEBOARD_FAB2_LIB.BASEBOARD_FAB2(SCH_1):PAGE41
  U5D1 CL64 VSS<426> SKX_EXT_B_BGA1-IC,TBD   I284 @BASEBOARD_FAB2_LIB.BASEBOARD_FAB2(SCH_1):PAGE41
  U5D1 CL62 VSS<427> SKX_EXT_B_BGA1-IC,TBD   I284 @BASEBOARD_FAB2_LIB.BASEBOARD_FAB2(SCH_1):PAGE41
  U5D1  H63 VSS<428> SKX_EXT_B_BGA1-IC,TBD   I284 @BASEBOARD_FAB2_LIB.BASEBOARD_FAB2(SCH_1):PAGE41
  U5D1  P45 VSS<429> SKX_EXT_B_BGA1-IC,TBD   I284 @BASEBOARD_FAB2_LIB.BASEBOARD_FAB2(SCH_1):PAGE41
  U5D1 CL18 VSS<430> SKX_EXT_B_BGA1-IC,TBD   I284 @BASEBOARD_FAB2_LIB.BASEBOARD_FAB2(SCH_1):PAGE41
  U5D1 CL14 VSS<431> SKX_EXT_B_BGA1-IC,TBD   I284 @BASEBOARD_FAB2_LIB.BASEBOARD_FAB2(SCH_1):PAGE41
  U5D1  CL8 VSS<432> SKX_EXT_B_BGA1-IC,TBD   I284 @BASEBOARD_FAB2_LIB.BASEBOARD_FAB2(SCH_1):PAGE41
  U5D1 CK85 VSS<433> SKX_EXT_B_BGA1-IC,TBD   I284 @BASEBOARD_FAB2_LIB.BASEBOARD_FAB2(SCH_1):PAGE41
  U5D1 CK83 VSS<434> SKX_EXT_B_BGA1-IC,TBD   I284 @BASEBOARD_FAB2_LIB.BASEBOARD_FAB2(SCH_1):PAGE41
  U5D1 CK75 VSS<435> SKX_EXT_B_BGA1-IC,TBD   I284 @BASEBOARD_FAB2_LIB.BASEBOARD_FAB2(SCH_1):PAGE41
  U5D1 CK73 VSS<436> SKX_EXT_B_BGA1-IC,TBD   I284 @BASEBOARD_FAB2_LIB.BASEBOARD_FAB2(SCH_1):PAGE41
  U5D1 CK71 VSS<437> SKX_EXT_B_BGA1-IC,TBD   I284 @BASEBOARD_FAB2_LIB.BASEBOARD_FAB2(SCH_1):PAGE41
  U5D1 CK69 VSS<438> SKX_EXT_B_BGA1-IC,TBD   I284 @BASEBOARD_FAB2_LIB.BASEBOARD_FAB2(SCH_1):PAGE41
  U5D1 CK67 VSS<439> SKX_EXT_B_BGA1-IC,TBD   I284 @BASEBOARD_FAB2_LIB.BASEBOARD_FAB2(SCH_1):PAGE41
  U5D1 CK65 VSS<440> SKX_EXT_B_BGA1-IC,TBD   I284 @BASEBOARD_FAB2_LIB.BASEBOARD_FAB2(SCH_1):PAGE41
  U5D1 CK63 VSS<441> SKX_EXT_B_BGA1-IC,TBD   I284 @BASEBOARD_FAB2_LIB.BASEBOARD_FAB2(SCH_1):PAGE41
  U5D1 CK27 VSS<442> SKX_EXT_B_BGA1-IC,TBD   I284 @BASEBOARD_FAB2_LIB.BASEBOARD_FAB2(SCH_1):PAGE41
  U5D1 CK21 VSS<443> SKX_EXT_B_BGA1-IC,TBD   I284 @BASEBOARD_FAB2_LIB.BASEBOARD_FAB2(SCH_1):PAGE41
  U5D1 CK15 VSS<444> SKX_EXT_B_BGA1-IC,TBD   I284 @BASEBOARD_FAB2_LIB.BASEBOARD_FAB2(SCH_1):PAGE41
  U5D1 CK11 VSS<445> SKX_EXT_B_BGA1-IC,TBD   I284 @BASEBOARD_FAB2_LIB.BASEBOARD_FAB2(SCH_1):PAGE41
  U5D1 CJ86 VSS<446> SKX_EXT_B_BGA1-IC,TBD   I284 @BASEBOARD_FAB2_LIB.BASEBOARD_FAB2(SCH_1):PAGE41
  U5D1 CJ84 VSS<447> SKX_EXT_B_BGA1-IC,TBD   I284 @BASEBOARD_FAB2_LIB.BASEBOARD_FAB2(SCH_1):PAGE41
  U5D1 CJ82 VSS<448> SKX_EXT_B_BGA1-IC,TBD   I284 @BASEBOARD_FAB2_LIB.BASEBOARD_FAB2(SCH_1):PAGE41
  U5D1 CJ78 VSS<449> SKX_EXT_B_BGA1-IC,TBD   I284 @BASEBOARD_FAB2_LIB.BASEBOARD_FAB2(SCH_1):PAGE41
  U5D1 CJ76 VSS<450> SKX_EXT_B_BGA1-IC,TBD   I284 @BASEBOARD_FAB2_LIB.BASEBOARD_FAB2(SCH_1):PAGE41
  U5D1 CJ74 VSS<451> SKX_EXT_B_BGA1-IC,TBD   I284 @BASEBOARD_FAB2_LIB.BASEBOARD_FAB2(SCH_1):PAGE41
  U5D1 CJ62 VSS<452> SKX_EXT_B_BGA1-IC,TBD   I284 @BASEBOARD_FAB2_LIB.BASEBOARD_FAB2(SCH_1):PAGE41
  U5D1  P47 VSS<453> SKX_EXT_B_BGA1-IC,TBD   I284 @BASEBOARD_FAB2_LIB.BASEBOARD_FAB2(SCH_1):PAGE41
  U5D1 DN72 VSS<134> SKX_EXT_B_BGA1-IC,TBD   I285 @BASEBOARD_FAB2_LIB.BASEBOARD_FAB2(SCH_1):PAGE41
  U5D1 DN68 VSS<135> SKX_EXT_B_BGA1-IC,TBD   I285 @BASEBOARD_FAB2_LIB.BASEBOARD_FAB2(SCH_1):PAGE41
  U5D1 DN38 VSS<136> SKX_EXT_B_BGA1-IC,TBD   I285 @BASEBOARD_FAB2_LIB.BASEBOARD_FAB2(SCH_1):PAGE41
  U5D1 DN32 VSS<137> SKX_EXT_B_BGA1-IC,TBD   I285 @BASEBOARD_FAB2_LIB.BASEBOARD_FAB2(SCH_1):PAGE41
  U5D1 DN26 VSS<138> SKX_EXT_B_BGA1-IC,TBD   I285 @BASEBOARD_FAB2_LIB.BASEBOARD_FAB2(SCH_1):PAGE41
  U5D1 DN22 VSS<139> SKX_EXT_B_BGA1-IC,TBD   I285 @BASEBOARD_FAB2_LIB.BASEBOARD_FAB2(SCH_1):PAGE41
  U5D1 DN12 VSS<140> SKX_EXT_B_BGA1-IC,TBD   I285 @BASEBOARD_FAB2_LIB.BASEBOARD_FAB2(SCH_1):PAGE41
  U5D1 BH17 VSS<141> SKX_EXT_B_BGA1-IC,TBD   I285 @BASEBOARD_FAB2_LIB.BASEBOARD_FAB2(SCH_1):PAGE41
  U5D1  DN2 VSS<142> SKX_EXT_B_BGA1-IC,TBD   I285 @BASEBOARD_FAB2_LIB.BASEBOARD_FAB2(SCH_1):PAGE41
  U5D1 DM83 VSS<143> SKX_EXT_B_BGA1-IC,TBD   I285 @BASEBOARD_FAB2_LIB.BASEBOARD_FAB2(SCH_1):PAGE41
  U5D1 DM77 VSS<144> SKX_EXT_B_BGA1-IC,TBD   I285 @BASEBOARD_FAB2_LIB.BASEBOARD_FAB2(SCH_1):PAGE41
  U5D1 DM73 VSS<145> SKX_EXT_B_BGA1-IC,TBD   I285 @BASEBOARD_FAB2_LIB.BASEBOARD_FAB2(SCH_1):PAGE41
  U5D1 DM65 VSS<146> SKX_EXT_B_BGA1-IC,TBD   I285 @BASEBOARD_FAB2_LIB.BASEBOARD_FAB2(SCH_1):PAGE41
  U5D1 DM39 VSS<147> SKX_EXT_B_BGA1-IC,TBD   I285 @BASEBOARD_FAB2_LIB.BASEBOARD_FAB2(SCH_1):PAGE41
  U5D1 DM37 VSS<148> SKX_EXT_B_BGA1-IC,TBD   I285 @BASEBOARD_FAB2_LIB.BASEBOARD_FAB2(SCH_1):PAGE41
  U5D1 DM33 VSS<149> SKX_EXT_B_BGA1-IC,TBD   I285 @BASEBOARD_FAB2_LIB.BASEBOARD_FAB2(SCH_1):PAGE41
  U5D1 DM31 VSS<150> SKX_EXT_B_BGA1-IC,TBD   I285 @BASEBOARD_FAB2_LIB.BASEBOARD_FAB2(SCH_1):PAGE41
  U5D1 DM27 VSS<151> SKX_EXT_B_BGA1-IC,TBD   I285 @BASEBOARD_FAB2_LIB.BASEBOARD_FAB2(SCH_1):PAGE41
  U5D1 DM25 VSS<152> SKX_EXT_B_BGA1-IC,TBD   I285 @BASEBOARD_FAB2_LIB.BASEBOARD_FAB2(SCH_1):PAGE41
  U5D1  H45 VSS<153> SKX_EXT_B_BGA1-IC,TBD   I285 @BASEBOARD_FAB2_LIB.BASEBOARD_FAB2(SCH_1):PAGE41
  U5D1 DM15 VSS<154> SKX_EXT_B_BGA1-IC,TBD   I285 @BASEBOARD_FAB2_LIB.BASEBOARD_FAB2(SCH_1):PAGE41
  U5D1 DL80 VSS<155> SKX_EXT_B_BGA1-IC,TBD   I285 @BASEBOARD_FAB2_LIB.BASEBOARD_FAB2(SCH_1):PAGE41
  U5D1 DL78 VSS<156> SKX_EXT_B_BGA1-IC,TBD   I285 @BASEBOARD_FAB2_LIB.BASEBOARD_FAB2(SCH_1):PAGE41
  U5D1 DL76 VSS<157> SKX_EXT_B_BGA1-IC,TBD   I285 @BASEBOARD_FAB2_LIB.BASEBOARD_FAB2(SCH_1):PAGE41
  U5D1 DL74 VSS<158> SKX_EXT_B_BGA1-IC,TBD   I285 @BASEBOARD_FAB2_LIB.BASEBOARD_FAB2(SCH_1):PAGE41
  U5D1 DL70 VSS<159> SKX_EXT_B_BGA1-IC,TBD   I285 @BASEBOARD_FAB2_LIB.BASEBOARD_FAB2(SCH_1):PAGE41
  U5D1 DL68 VSS<160> SKX_EXT_B_BGA1-IC,TBD   I285 @BASEBOARD_FAB2_LIB.BASEBOARD_FAB2(SCH_1):PAGE41
  U5D1 DL40 VSS<161> SKX_EXT_B_BGA1-IC,TBD   I285 @BASEBOARD_FAB2_LIB.BASEBOARD_FAB2(SCH_1):PAGE41
  U5D1 DL36 VSS<162> SKX_EXT_B_BGA1-IC,TBD   I285 @BASEBOARD_FAB2_LIB.BASEBOARD_FAB2(SCH_1):PAGE41
  U5D1 DL34 VSS<163> SKX_EXT_B_BGA1-IC,TBD   I285 @BASEBOARD_FAB2_LIB.BASEBOARD_FAB2(SCH_1):PAGE41
  U5D1 DL30 VSS<164> SKX_EXT_B_BGA1-IC,TBD   I285 @BASEBOARD_FAB2_LIB.BASEBOARD_FAB2(SCH_1):PAGE41
  U5D1 DL28 VSS<165> SKX_EXT_B_BGA1-IC,TBD   I285 @BASEBOARD_FAB2_LIB.BASEBOARD_FAB2(SCH_1):PAGE41
  U5D1 DL24 VSS<166> SKX_EXT_B_BGA1-IC,TBD   I285 @BASEBOARD_FAB2_LIB.BASEBOARD_FAB2(SCH_1):PAGE41
  U5D1 DL22 VSS<167> SKX_EXT_B_BGA1-IC,TBD   I285 @BASEBOARD_FAB2_LIB.BASEBOARD_FAB2(SCH_1):PAGE41
  U5D1  DL4 VSS<168> SKX_EXT_B_BGA1-IC,TBD   I285 @BASEBOARD_FAB2_LIB.BASEBOARD_FAB2(SCH_1):PAGE41
  U5D1 DL18 VSS<169> SKX_EXT_B_BGA1-IC,TBD   I285 @BASEBOARD_FAB2_LIB.BASEBOARD_FAB2(SCH_1):PAGE41
  U5D1 DL16 VSS<170> SKX_EXT_B_BGA1-IC,TBD   I285 @BASEBOARD_FAB2_LIB.BASEBOARD_FAB2(SCH_1):PAGE41
  U5D1 DK85 VSS<171> SKX_EXT_B_BGA1-IC,TBD   I285 @BASEBOARD_FAB2_LIB.BASEBOARD_FAB2(SCH_1):PAGE41
  U5D1 DK83 VSS<172> SKX_EXT_B_BGA1-IC,TBD   I285 @BASEBOARD_FAB2_LIB.BASEBOARD_FAB2(SCH_1):PAGE41
  U5D1 DK77 VSS<173> SKX_EXT_B_BGA1-IC,TBD   I285 @BASEBOARD_FAB2_LIB.BASEBOARD_FAB2(SCH_1):PAGE41
  U5D1 DK75 VSS<174> SKX_EXT_B_BGA1-IC,TBD   I285 @BASEBOARD_FAB2_LIB.BASEBOARD_FAB2(SCH_1):PAGE41
  U5D1 DK73 VSS<175> SKX_EXT_B_BGA1-IC,TBD   I285 @BASEBOARD_FAB2_LIB.BASEBOARD_FAB2(SCH_1):PAGE41
  U5D1 DK41 VSS<176> SKX_EXT_B_BGA1-IC,TBD   I285 @BASEBOARD_FAB2_LIB.BASEBOARD_FAB2(SCH_1):PAGE41
  U5D1 DK39 VSS<177> SKX_EXT_B_BGA1-IC,TBD   I285 @BASEBOARD_FAB2_LIB.BASEBOARD_FAB2(SCH_1):PAGE41
  U5D1 DK35 VSS<178> SKX_EXT_B_BGA1-IC,TBD   I285 @BASEBOARD_FAB2_LIB.BASEBOARD_FAB2(SCH_1):PAGE41
  U5D1 DK29 VSS<179> SKX_EXT_B_BGA1-IC,TBD   I285 @BASEBOARD_FAB2_LIB.BASEBOARD_FAB2(SCH_1):PAGE41
  U5D1 DK23 VSS<180> SKX_EXT_B_BGA1-IC,TBD   I285 @BASEBOARD_FAB2_LIB.BASEBOARD_FAB2(SCH_1):PAGE41
  U5D1  DK7 VSS<181> SKX_EXT_B_BGA1-IC,TBD   I285 @BASEBOARD_FAB2_LIB.BASEBOARD_FAB2(SCH_1):PAGE41
  U5D1 DJ84 VSS<182> SKX_EXT_B_BGA1-IC,TBD   I285 @BASEBOARD_FAB2_LIB.BASEBOARD_FAB2(SCH_1):PAGE41
  U5D1 DJ82 VSS<183> SKX_EXT_B_BGA1-IC,TBD   I285 @BASEBOARD_FAB2_LIB.BASEBOARD_FAB2(SCH_1):PAGE41
  U5D1 DJ78 VSS<184> SKX_EXT_B_BGA1-IC,TBD   I285 @BASEBOARD_FAB2_LIB.BASEBOARD_FAB2(SCH_1):PAGE41
  U5D1 DJ74 VSS<185> SKX_EXT_B_BGA1-IC,TBD   I285 @BASEBOARD_FAB2_LIB.BASEBOARD_FAB2(SCH_1):PAGE41
  U5D1 DJ68 VSS<186> SKX_EXT_B_BGA1-IC,TBD   I285 @BASEBOARD_FAB2_LIB.BASEBOARD_FAB2(SCH_1):PAGE41
  U5D1 DJ42 VSS<187> SKX_EXT_B_BGA1-IC,TBD   I285 @BASEBOARD_FAB2_LIB.BASEBOARD_FAB2(SCH_1):PAGE41
  U5D1 DJ38 VSS<188> SKX_EXT_B_BGA1-IC,TBD   I285 @BASEBOARD_FAB2_LIB.BASEBOARD_FAB2(SCH_1):PAGE41
  U5D1 DJ22 VSS<189> SKX_EXT_B_BGA1-IC,TBD   I285 @BASEBOARD_FAB2_LIB.BASEBOARD_FAB2(SCH_1):PAGE41
  U5D1  H47 VSS<190> SKX_EXT_B_BGA1-IC,TBD   I285 @BASEBOARD_FAB2_LIB.BASEBOARD_FAB2(SCH_1):PAGE41
  U5D1 DJ10 VSS<191> SKX_EXT_B_BGA1-IC,TBD   I285 @BASEBOARD_FAB2_LIB.BASEBOARD_FAB2(SCH_1):PAGE41
  U5D1  DJ2 VSS<192> SKX_EXT_B_BGA1-IC,TBD   I285 @BASEBOARD_FAB2_LIB.BASEBOARD_FAB2(SCH_1):PAGE41
  U5D1 DH83 VSS<193> SKX_EXT_B_BGA1-IC,TBD   I285 @BASEBOARD_FAB2_LIB.BASEBOARD_FAB2(SCH_1):PAGE41
  U5D1 DH81 VSS<194> SKX_EXT_B_BGA1-IC,TBD   I285 @BASEBOARD_FAB2_LIB.BASEBOARD_FAB2(SCH_1):PAGE41
  U5D1 DH79 VSS<195> SKX_EXT_B_BGA1-IC,TBD   I285 @BASEBOARD_FAB2_LIB.BASEBOARD_FAB2(SCH_1):PAGE41
  U5D1 DH73 VSS<196> SKX_EXT_B_BGA1-IC,TBD   I285 @BASEBOARD_FAB2_LIB.BASEBOARD_FAB2(SCH_1):PAGE41
  U5D1 DH71 VSS<197> SKX_EXT_B_BGA1-IC,TBD   I285 @BASEBOARD_FAB2_LIB.BASEBOARD_FAB2(SCH_1):PAGE41
  U5D1 DH67 VSS<198> SKX_EXT_B_BGA1-IC,TBD   I285 @BASEBOARD_FAB2_LIB.BASEBOARD_FAB2(SCH_1):PAGE41
  U5D1 DH41 VSS<199> SKX_EXT_B_BGA1-IC,TBD   I285 @BASEBOARD_FAB2_LIB.BASEBOARD_FAB2(SCH_1):PAGE41
  U5D1 DH37 VSS<200> SKX_EXT_B_BGA1-IC,TBD   I285 @BASEBOARD_FAB2_LIB.BASEBOARD_FAB2(SCH_1):PAGE41
  U5D1 DH35 VSS<201> SKX_EXT_B_BGA1-IC,TBD   I285 @BASEBOARD_FAB2_LIB.BASEBOARD_FAB2(SCH_1):PAGE41
  U5D1 DH33 VSS<202> SKX_EXT_B_BGA1-IC,TBD   I285 @BASEBOARD_FAB2_LIB.BASEBOARD_FAB2(SCH_1):PAGE41
  U5D1 DH31 VSS<203> SKX_EXT_B_BGA1-IC,TBD   I285 @BASEBOARD_FAB2_LIB.BASEBOARD_FAB2(SCH_1):PAGE41
  U5D1 DH29 VSS<204> SKX_EXT_B_BGA1-IC,TBD   I285 @BASEBOARD_FAB2_LIB.BASEBOARD_FAB2(SCH_1):PAGE41
  U5D1 DH27 VSS<205> SKX_EXT_B_BGA1-IC,TBD   I285 @BASEBOARD_FAB2_LIB.BASEBOARD_FAB2(SCH_1):PAGE41
  U5D1 DH25 VSS<206> SKX_EXT_B_BGA1-IC,TBD   I285 @BASEBOARD_FAB2_LIB.BASEBOARD_FAB2(SCH_1):PAGE41
  U5D1 DH23 VSS<207> SKX_EXT_B_BGA1-IC,TBD   I285 @BASEBOARD_FAB2_LIB.BASEBOARD_FAB2(SCH_1):PAGE41
  U5D1 DH15 VSS<208> SKX_EXT_B_BGA1-IC,TBD   I285 @BASEBOARD_FAB2_LIB.BASEBOARD_FAB2(SCH_1):PAGE41
  U5D1 DH13 VSS<209> SKX_EXT_B_BGA1-IC,TBD   I285 @BASEBOARD_FAB2_LIB.BASEBOARD_FAB2(SCH_1):PAGE41
  U5D1 DG82 VSS<210> SKX_EXT_B_BGA1-IC,TBD   I285 @BASEBOARD_FAB2_LIB.BASEBOARD_FAB2(SCH_1):PAGE41
  U5D1 DG80 VSS<211> SKX_EXT_B_BGA1-IC,TBD   I285 @BASEBOARD_FAB2_LIB.BASEBOARD_FAB2(SCH_1):PAGE41
  U5D1 DG78 VSS<212> SKX_EXT_B_BGA1-IC,TBD   I285 @BASEBOARD_FAB2_LIB.BASEBOARD_FAB2(SCH_1):PAGE41
  U5D1 DG76 VSS<213> SKX_EXT_B_BGA1-IC,TBD   I285 @BASEBOARD_FAB2_LIB.BASEBOARD_FAB2(SCH_1):PAGE41
  U5D1 DG68 VSS<214> SKX_EXT_B_BGA1-IC,TBD   I285 @BASEBOARD_FAB2_LIB.BASEBOARD_FAB2(SCH_1):PAGE41
  U5D1 DG66 VSS<215> SKX_EXT_B_BGA1-IC,TBD   I285 @BASEBOARD_FAB2_LIB.BASEBOARD_FAB2(SCH_1):PAGE41
  U5D1 DG24 VSS<216> SKX_EXT_B_BGA1-IC,TBD   I285 @BASEBOARD_FAB2_LIB.BASEBOARD_FAB2(SCH_1):PAGE41
  U5D1 DG16 VSS<217> SKX_EXT_B_BGA1-IC,TBD   I285 @BASEBOARD_FAB2_LIB.BASEBOARD_FAB2(SCH_1):PAGE41
  U5D1 DG14 VSS<218> SKX_EXT_B_BGA1-IC,TBD   I285 @BASEBOARD_FAB2_LIB.BASEBOARD_FAB2(SCH_1):PAGE41
  U5D1  H49 VSS<219> SKX_EXT_B_BGA1-IC,TBD   I285 @BASEBOARD_FAB2_LIB.BASEBOARD_FAB2(SCH_1):PAGE41
  U5D1  DG2 VSS<220> SKX_EXT_B_BGA1-IC,TBD   I285 @BASEBOARD_FAB2_LIB.BASEBOARD_FAB2(SCH_1):PAGE41
  U5D1 DF85 VSS<221> SKX_EXT_B_BGA1-IC,TBD   I285 @BASEBOARD_FAB2_LIB.BASEBOARD_FAB2(SCH_1):PAGE41
  U5D1 DF83 VSS<222> SKX_EXT_B_BGA1-IC,TBD   I285 @BASEBOARD_FAB2_LIB.BASEBOARD_FAB2(SCH_1):PAGE41
  U5D1 DF79 VSS<223> SKX_EXT_B_BGA1-IC,TBD   I285 @BASEBOARD_FAB2_LIB.BASEBOARD_FAB2(SCH_1):PAGE41
  U5D1 DF73 VSS<224> SKX_EXT_B_BGA1-IC,TBD   I285 @BASEBOARD_FAB2_LIB.BASEBOARD_FAB2(SCH_1):PAGE41
  U5D1 DF69 VSS<225> SKX_EXT_B_BGA1-IC,TBD   I285 @BASEBOARD_FAB2_LIB.BASEBOARD_FAB2(SCH_1):PAGE41
  U5D1 DF65 VSS<226> SKX_EXT_B_BGA1-IC,TBD   I285 @BASEBOARD_FAB2_LIB.BASEBOARD_FAB2(SCH_1):PAGE41
  U5D1 DF41 VSS<227> SKX_EXT_B_BGA1-IC,TBD   I285 @BASEBOARD_FAB2_LIB.BASEBOARD_FAB2(SCH_1):PAGE41
  U5D1 DF39 VSS<228> SKX_EXT_B_BGA1-IC,TBD   I285 @BASEBOARD_FAB2_LIB.BASEBOARD_FAB2(SCH_1):PAGE41
  U5D1 DF37 VSS<229> SKX_EXT_B_BGA1-IC,TBD   I285 @BASEBOARD_FAB2_LIB.BASEBOARD_FAB2(SCH_1):PAGE41
  U5D1 DF35 VSS<230> SKX_EXT_B_BGA1-IC,TBD   I285 @BASEBOARD_FAB2_LIB.BASEBOARD_FAB2(SCH_1):PAGE41
  U5D1 DF29 VSS<231> SKX_EXT_B_BGA1-IC,TBD   I285 @BASEBOARD_FAB2_LIB.BASEBOARD_FAB2(SCH_1):PAGE41
  U5D1 DF19 VSS<232> SKX_EXT_B_BGA1-IC,TBD   I285 @BASEBOARD_FAB2_LIB.BASEBOARD_FAB2(SCH_1):PAGE41
  U5D1  H51 VSS<233> SKX_EXT_B_BGA1-IC,TBD   I285 @BASEBOARD_FAB2_LIB.BASEBOARD_FAB2(SCH_1):PAGE41
  U5D1  DF7 VSS<234> SKX_EXT_B_BGA1-IC,TBD   I285 @BASEBOARD_FAB2_LIB.BASEBOARD_FAB2(SCH_1):PAGE41
  U5D1  DF5 VSS<235> SKX_EXT_B_BGA1-IC,TBD   I285 @BASEBOARD_FAB2_LIB.BASEBOARD_FAB2(SCH_1):PAGE41
  U5D1 DE78 VSS<236> SKX_EXT_B_BGA1-IC,TBD   I285 @BASEBOARD_FAB2_LIB.BASEBOARD_FAB2(SCH_1):PAGE41
  U5D1 DE72 VSS<237> SKX_EXT_B_BGA1-IC,TBD   I285 @BASEBOARD_FAB2_LIB.BASEBOARD_FAB2(SCH_1):PAGE41
  U5D1 DE70 VSS<238> SKX_EXT_B_BGA1-IC,TBD   I285 @BASEBOARD_FAB2_LIB.BASEBOARD_FAB2(SCH_1):PAGE41
  U5D1 DE64 VSS<239> SKX_EXT_B_BGA1-IC,TBD   I285 @BASEBOARD_FAB2_LIB.BASEBOARD_FAB2(SCH_1):PAGE41
  U5D1 DE36 VSS<240> SKX_EXT_B_BGA1-IC,TBD   I285 @BASEBOARD_FAB2_LIB.BASEBOARD_FAB2(SCH_1):PAGE41
  U5D1 DE34 VSS<241> SKX_EXT_B_BGA1-IC,TBD   I285 @BASEBOARD_FAB2_LIB.BASEBOARD_FAB2(SCH_1):PAGE41
  U5D1 DE30 VSS<242> SKX_EXT_B_BGA1-IC,TBD   I285 @BASEBOARD_FAB2_LIB.BASEBOARD_FAB2(SCH_1):PAGE41
  U5D1 DE28 VSS<243> SKX_EXT_B_BGA1-IC,TBD   I285 @BASEBOARD_FAB2_LIB.BASEBOARD_FAB2(SCH_1):PAGE41
  U5D1 DE24 VSS<244> SKX_EXT_B_BGA1-IC,TBD   I285 @BASEBOARD_FAB2_LIB.BASEBOARD_FAB2(SCH_1):PAGE41
  U5D1 DE20 VSS<245> SKX_EXT_B_BGA1-IC,TBD   I285 @BASEBOARD_FAB2_LIB.BASEBOARD_FAB2(SCH_1):PAGE41
  U5D1 DE18 VSS<246> SKX_EXT_B_BGA1-IC,TBD   I285 @BASEBOARD_FAB2_LIB.BASEBOARD_FAB2(SCH_1):PAGE41
  U5D1  DE8 VSS<247> SKX_EXT_B_BGA1-IC,TBD   I285 @BASEBOARD_FAB2_LIB.BASEBOARD_FAB2(SCH_1):PAGE41
  U5D1  DE6 VSS<248> SKX_EXT_B_BGA1-IC,TBD   I285 @BASEBOARD_FAB2_LIB.BASEBOARD_FAB2(SCH_1):PAGE41
  U5D1 DD83 VSS<249> SKX_EXT_B_BGA1-IC,TBD   I285 @BASEBOARD_FAB2_LIB.BASEBOARD_FAB2(SCH_1):PAGE41
  U5D1 DD81 VSS<250> SKX_EXT_B_BGA1-IC,TBD   I285 @BASEBOARD_FAB2_LIB.BASEBOARD_FAB2(SCH_1):PAGE41
  U5D1 DD75 VSS<251> SKX_EXT_B_BGA1-IC,TBD   I285 @BASEBOARD_FAB2_LIB.BASEBOARD_FAB2(SCH_1):PAGE41
  U5D1 DD73 VSS<252> SKX_EXT_B_BGA1-IC,TBD   I285 @BASEBOARD_FAB2_LIB.BASEBOARD_FAB2(SCH_1):PAGE41
  U5D1 DD71 VSS<253> SKX_EXT_B_BGA1-IC,TBD   I285 @BASEBOARD_FAB2_LIB.BASEBOARD_FAB2(SCH_1):PAGE41
  U5D1 DD37 VSS<254> SKX_EXT_B_BGA1-IC,TBD   I285 @BASEBOARD_FAB2_LIB.BASEBOARD_FAB2(SCH_1):PAGE41
  U5D1 DD33 VSS<255> SKX_EXT_B_BGA1-IC,TBD   I285 @BASEBOARD_FAB2_LIB.BASEBOARD_FAB2(SCH_1):PAGE41
  U5D1 DD31 VSS<256> SKX_EXT_B_BGA1-IC,TBD   I285 @BASEBOARD_FAB2_LIB.BASEBOARD_FAB2(SCH_1):PAGE41
  U5D1 DD27 VSS<257> SKX_EXT_B_BGA1-IC,TBD   I285 @BASEBOARD_FAB2_LIB.BASEBOARD_FAB2(SCH_1):PAGE41
  U5D1 DD23 VSS<258> SKX_EXT_B_BGA1-IC,TBD   I285 @BASEBOARD_FAB2_LIB.BASEBOARD_FAB2(SCH_1):PAGE41
  U5D1 DD11 VSS<259> SKX_EXT_B_BGA1-IC,TBD   I285 @BASEBOARD_FAB2_LIB.BASEBOARD_FAB2(SCH_1):PAGE41
  U5D1 DC86 VSS<260> SKX_EXT_B_BGA1-IC,TBD   I285 @BASEBOARD_FAB2_LIB.BASEBOARD_FAB2(SCH_1):PAGE41
  U5D1 DC84 VSS<261> SKX_EXT_B_BGA1-IC,TBD   I285 @BASEBOARD_FAB2_LIB.BASEBOARD_FAB2(SCH_1):PAGE41
  U5D1 DC78 VSS<262> SKX_EXT_B_BGA1-IC,TBD   I285 @BASEBOARD_FAB2_LIB.BASEBOARD_FAB2(SCH_1):PAGE41
  U5D1 DC70 VSS<263> SKX_EXT_B_BGA1-IC,TBD   I285 @BASEBOARD_FAB2_LIB.BASEBOARD_FAB2(SCH_1):PAGE41
  U5D1 DC68 VSS<264> SKX_EXT_B_BGA1-IC,TBD   I285 @BASEBOARD_FAB2_LIB.BASEBOARD_FAB2(SCH_1):PAGE41
  U5D1 DC66 VSS<265> SKX_EXT_B_BGA1-IC,TBD   I285 @BASEBOARD_FAB2_LIB.BASEBOARD_FAB2(SCH_1):PAGE41
  U5D1 DC64 VSS<266> SKX_EXT_B_BGA1-IC,TBD   I285 @BASEBOARD_FAB2_LIB.BASEBOARD_FAB2(SCH_1):PAGE41
  U5D1 DC42 VSS<267> SKX_EXT_B_BGA1-IC,TBD   I285 @BASEBOARD_FAB2_LIB.BASEBOARD_FAB2(SCH_1):PAGE41
  U5D1 DC38 VSS<268> SKX_EXT_B_BGA1-IC,TBD   I285 @BASEBOARD_FAB2_LIB.BASEBOARD_FAB2(SCH_1):PAGE41
  U5D1 DC32 VSS<269> SKX_EXT_B_BGA1-IC,TBD   I285 @BASEBOARD_FAB2_LIB.BASEBOARD_FAB2(SCH_1):PAGE41
  U5D1 DC26 VSS<270> SKX_EXT_B_BGA1-IC,TBD   I285 @BASEBOARD_FAB2_LIB.BASEBOARD_FAB2(SCH_1):PAGE41
  U5D1 DC24 VSS<271> SKX_EXT_B_BGA1-IC,TBD   I285 @BASEBOARD_FAB2_LIB.BASEBOARD_FAB2(SCH_1):PAGE41
  U5D1 DC14 VSS<272> SKX_EXT_B_BGA1-IC,TBD   I285 @BASEBOARD_FAB2_LIB.BASEBOARD_FAB2(SCH_1):PAGE41
  U5D1 DB85 VSS<273> SKX_EXT_B_BGA1-IC,TBD   I285 @BASEBOARD_FAB2_LIB.BASEBOARD_FAB2(SCH_1):PAGE41
  U5D1 DB83 VSS<274> SKX_EXT_B_BGA1-IC,TBD   I285 @BASEBOARD_FAB2_LIB.BASEBOARD_FAB2(SCH_1):PAGE41
  U5D1 DB77 VSS<275> SKX_EXT_B_BGA1-IC,TBD   I285 @BASEBOARD_FAB2_LIB.BASEBOARD_FAB2(SCH_1):PAGE41
  U5D1 DB73 VSS<276> SKX_EXT_B_BGA1-IC,TBD   I285 @BASEBOARD_FAB2_LIB.BASEBOARD_FAB2(SCH_1):PAGE41
  U5D1 DB49 VSS<277> SKX_EXT_B_BGA1-IC,TBD   I285 @BASEBOARD_FAB2_LIB.BASEBOARD_FAB2(SCH_1):PAGE41
  U5D1 DB47 VSS<278> SKX_EXT_B_BGA1-IC,TBD   I285 @BASEBOARD_FAB2_LIB.BASEBOARD_FAB2(SCH_1):PAGE41
  U5D1 DB41 VSS<279> SKX_EXT_B_BGA1-IC,TBD   I285 @BASEBOARD_FAB2_LIB.BASEBOARD_FAB2(SCH_1):PAGE41
  U5D1 DB39 VSS<280> SKX_EXT_B_BGA1-IC,TBD   I285 @BASEBOARD_FAB2_LIB.BASEBOARD_FAB2(SCH_1):PAGE41
  U5D1 DB25 VSS<281> SKX_EXT_B_BGA1-IC,TBD   I285 @BASEBOARD_FAB2_LIB.BASEBOARD_FAB2(SCH_1):PAGE41
  U5D1 DB23 VSS<282> SKX_EXT_B_BGA1-IC,TBD   I285 @BASEBOARD_FAB2_LIB.BASEBOARD_FAB2(SCH_1):PAGE41
  U5D1 DB17 VSS<283> SKX_EXT_B_BGA1-IC,TBD   I285 @BASEBOARD_FAB2_LIB.BASEBOARD_FAB2(SCH_1):PAGE41
  U5D1 DB13 VSS<284> SKX_EXT_B_BGA1-IC,TBD   I285 @BASEBOARD_FAB2_LIB.BASEBOARD_FAB2(SCH_1):PAGE41
  U5D1  DB3 VSS<285> SKX_EXT_B_BGA1-IC,TBD   I285 @BASEBOARD_FAB2_LIB.BASEBOARD_FAB2(SCH_1):PAGE41
  U5D1 DA80 VSS<286> SKX_EXT_B_BGA1-IC,TBD   I285 @BASEBOARD_FAB2_LIB.BASEBOARD_FAB2(SCH_1):PAGE41
  U5D1 DA78 VSS<287> SKX_EXT_B_BGA1-IC,TBD   I285 @BASEBOARD_FAB2_LIB.BASEBOARD_FAB2(SCH_1):PAGE41
  U5D1 DA76 VSS<288> SKX_EXT_B_BGA1-IC,TBD   I285 @BASEBOARD_FAB2_LIB.BASEBOARD_FAB2(SCH_1):PAGE41
  U5D1 DA74 VSS<289> SKX_EXT_B_BGA1-IC,TBD   I285 @BASEBOARD_FAB2_LIB.BASEBOARD_FAB2(SCH_1):PAGE41
  U5D1 DA70 VSS<290> SKX_EXT_B_BGA1-IC,TBD   I285 @BASEBOARD_FAB2_LIB.BASEBOARD_FAB2(SCH_1):PAGE41
  U5D1 DA64 VSS<291> SKX_EXT_B_BGA1-IC,TBD   I285 @BASEBOARD_FAB2_LIB.BASEBOARD_FAB2(SCH_1):PAGE41
  U5D1 DA50 VSS<292> SKX_EXT_B_BGA1-IC,TBD   I285 @BASEBOARD_FAB2_LIB.BASEBOARD_FAB2(SCH_1):PAGE41
  U5D1 DA48 VSS<293> SKX_EXT_B_BGA1-IC,TBD   I285 @BASEBOARD_FAB2_LIB.BASEBOARD_FAB2(SCH_1):PAGE41
  U5D1 EF79 VSS<0> SKX_EXT_B_BGA1-IC,TBD   I286 @BASEBOARD_FAB2_LIB.BASEBOARD_FAB2(SCH_1):PAGE41
  U5D1 EF75 VSS<1> SKX_EXT_B_BGA1-IC,TBD   I286 @BASEBOARD_FAB2_LIB.BASEBOARD_FAB2(SCH_1):PAGE41
  U5D1 EF71 VSS<2> SKX_EXT_B_BGA1-IC,TBD   I286 @BASEBOARD_FAB2_LIB.BASEBOARD_FAB2(SCH_1):PAGE41
  U5D1 EE78 VSS<3> SKX_EXT_B_BGA1-IC,TBD   I286 @BASEBOARD_FAB2_LIB.BASEBOARD_FAB2(SCH_1):PAGE41
  U5D1 EE76 VSS<4> SKX_EXT_B_BGA1-IC,TBD   I286 @BASEBOARD_FAB2_LIB.BASEBOARD_FAB2(SCH_1):PAGE41
  U5D1 EE70 VSS<5> SKX_EXT_B_BGA1-IC,TBD   I286 @BASEBOARD_FAB2_LIB.BASEBOARD_FAB2(SCH_1):PAGE41
  U5D1 EE36 VSS<6> SKX_EXT_B_BGA1-IC,TBD   I286 @BASEBOARD_FAB2_LIB.BASEBOARD_FAB2(SCH_1):PAGE41
  U5D1 EE34 VSS<7> SKX_EXT_B_BGA1-IC,TBD   I286 @BASEBOARD_FAB2_LIB.BASEBOARD_FAB2(SCH_1):PAGE41
  U5D1 EE30 VSS<8> SKX_EXT_B_BGA1-IC,TBD   I286 @BASEBOARD_FAB2_LIB.BASEBOARD_FAB2(SCH_1):PAGE41
  U5D1 EE28 VSS<9> SKX_EXT_B_BGA1-IC,TBD   I286 @BASEBOARD_FAB2_LIB.BASEBOARD_FAB2(SCH_1):PAGE41
  U5D1 EE24 VSS<10> SKX_EXT_B_BGA1-IC,TBD   I286 @BASEBOARD_FAB2_LIB.BASEBOARD_FAB2(SCH_1):PAGE41
  U5D1 ED77 VSS<11> SKX_EXT_B_BGA1-IC,TBD   I286 @BASEBOARD_FAB2_LIB.BASEBOARD_FAB2(SCH_1):PAGE41
  U5D1 ED35 VSS<12> SKX_EXT_B_BGA1-IC,TBD   I286 @BASEBOARD_FAB2_LIB.BASEBOARD_FAB2(SCH_1):PAGE41
  U5D1 ED29 VSS<13> SKX_EXT_B_BGA1-IC,TBD   I286 @BASEBOARD_FAB2_LIB.BASEBOARD_FAB2(SCH_1):PAGE41
  U5D1 ED23 VSS<14> SKX_EXT_B_BGA1-IC,TBD   I286 @BASEBOARD_FAB2_LIB.BASEBOARD_FAB2(SCH_1):PAGE41
  U5D1 ED15 VSS<15> SKX_EXT_B_BGA1-IC,TBD   I286 @BASEBOARD_FAB2_LIB.BASEBOARD_FAB2(SCH_1):PAGE41
  U5D1 ED11 VSS<16> SKX_EXT_B_BGA1-IC,TBD   I286 @BASEBOARD_FAB2_LIB.BASEBOARD_FAB2(SCH_1):PAGE41
  U5D1 EC76 VSS<17> SKX_EXT_B_BGA1-IC,TBD   I286 @BASEBOARD_FAB2_LIB.BASEBOARD_FAB2(SCH_1):PAGE41
  U5D1 EC74 VSS<18> SKX_EXT_B_BGA1-IC,TBD   I286 @BASEBOARD_FAB2_LIB.BASEBOARD_FAB2(SCH_1):PAGE41
  U5D1 EC72 VSS<19> SKX_EXT_B_BGA1-IC,TBD   I286 @BASEBOARD_FAB2_LIB.BASEBOARD_FAB2(SCH_1):PAGE41
  U5D1 EC70 VSS<20> SKX_EXT_B_BGA1-IC,TBD   I286 @BASEBOARD_FAB2_LIB.BASEBOARD_FAB2(SCH_1):PAGE41
  U5D1 EC10 VSS<21> SKX_EXT_B_BGA1-IC,TBD   I286 @BASEBOARD_FAB2_LIB.BASEBOARD_FAB2(SCH_1):PAGE41
  U5D1 EB69 VSS<22> SKX_EXT_B_BGA1-IC,TBD   I286 @BASEBOARD_FAB2_LIB.BASEBOARD_FAB2(SCH_1):PAGE41
  U5D1 EB65 VSS<23> SKX_EXT_B_BGA1-IC,TBD   I286 @BASEBOARD_FAB2_LIB.BASEBOARD_FAB2(SCH_1):PAGE41
  U5D1 EB41 VSS<24> SKX_EXT_B_BGA1-IC,TBD   I286 @BASEBOARD_FAB2_LIB.BASEBOARD_FAB2(SCH_1):PAGE41
  U5D1 EB39 VSS<25> SKX_EXT_B_BGA1-IC,TBD   I286 @BASEBOARD_FAB2_LIB.BASEBOARD_FAB2(SCH_1):PAGE41
  U5D1 EB37 VSS<26> SKX_EXT_B_BGA1-IC,TBD   I286 @BASEBOARD_FAB2_LIB.BASEBOARD_FAB2(SCH_1):PAGE41
  U5D1 EB35 VSS<27> SKX_EXT_B_BGA1-IC,TBD   I286 @BASEBOARD_FAB2_LIB.BASEBOARD_FAB2(SCH_1):PAGE41
  U5D1 EB33 VSS<28> SKX_EXT_B_BGA1-IC,TBD   I286 @BASEBOARD_FAB2_LIB.BASEBOARD_FAB2(SCH_1):PAGE41
  U5D1 EB31 VSS<29> SKX_EXT_B_BGA1-IC,TBD   I286 @BASEBOARD_FAB2_LIB.BASEBOARD_FAB2(SCH_1):PAGE41
  U5D1 EB29 VSS<30> SKX_EXT_B_BGA1-IC,TBD   I286 @BASEBOARD_FAB2_LIB.BASEBOARD_FAB2(SCH_1):PAGE41
  U5D1 EB27 VSS<31> SKX_EXT_B_BGA1-IC,TBD   I286 @BASEBOARD_FAB2_LIB.BASEBOARD_FAB2(SCH_1):PAGE41
  U5D1 EB25 VSS<32> SKX_EXT_B_BGA1-IC,TBD   I286 @BASEBOARD_FAB2_LIB.BASEBOARD_FAB2(SCH_1):PAGE41
  U5D1 EB23 VSS<33> SKX_EXT_B_BGA1-IC,TBD   I286 @BASEBOARD_FAB2_LIB.BASEBOARD_FAB2(SCH_1):PAGE41
  U5D1 BR18 VSS<34> SKX_EXT_B_BGA1-IC,TBD   I286 @BASEBOARD_FAB2_LIB.BASEBOARD_FAB2(SCH_1):PAGE41
  U5D1 EB13 VSS<35> SKX_EXT_B_BGA1-IC,TBD   I286 @BASEBOARD_FAB2_LIB.BASEBOARD_FAB2(SCH_1):PAGE41
  U5D1 EA82 VSS<36> SKX_EXT_B_BGA1-IC,TBD   I286 @BASEBOARD_FAB2_LIB.BASEBOARD_FAB2(SCH_1):PAGE41
  U5D1 EA80 VSS<37> SKX_EXT_B_BGA1-IC,TBD   I286 @BASEBOARD_FAB2_LIB.BASEBOARD_FAB2(SCH_1):PAGE41
  U5D1 EA78 VSS<38> SKX_EXT_B_BGA1-IC,TBD   I286 @BASEBOARD_FAB2_LIB.BASEBOARD_FAB2(SCH_1):PAGE41
  U5D1 EA76 VSS<39> SKX_EXT_B_BGA1-IC,TBD   I286 @BASEBOARD_FAB2_LIB.BASEBOARD_FAB2(SCH_1):PAGE41
  U5D1 EA70 VSS<40> SKX_EXT_B_BGA1-IC,TBD   I286 @BASEBOARD_FAB2_LIB.BASEBOARD_FAB2(SCH_1):PAGE41
  U5D1 EA64 VSS<41> SKX_EXT_B_BGA1-IC,TBD   I286 @BASEBOARD_FAB2_LIB.BASEBOARD_FAB2(SCH_1):PAGE41
  U5D1 EA42 VSS<42> SKX_EXT_B_BGA1-IC,TBD   I286 @BASEBOARD_FAB2_LIB.BASEBOARD_FAB2(SCH_1):PAGE41
  U5D1 EA22 VSS<43> SKX_EXT_B_BGA1-IC,TBD   I286 @BASEBOARD_FAB2_LIB.BASEBOARD_FAB2(SCH_1):PAGE41
  U5D1 EA20 VSS<44> SKX_EXT_B_BGA1-IC,TBD   I286 @BASEBOARD_FAB2_LIB.BASEBOARD_FAB2(SCH_1):PAGE41
  U5D1 EA16 VSS<45> SKX_EXT_B_BGA1-IC,TBD   I286 @BASEBOARD_FAB2_LIB.BASEBOARD_FAB2(SCH_1):PAGE41
  U5D1  J16 VSS<46> SKX_EXT_B_BGA1-IC,TBD   I286 @BASEBOARD_FAB2_LIB.BASEBOARD_FAB2(SCH_1):PAGE41
  U5D1  EA6 VSS<47> SKX_EXT_B_BGA1-IC,TBD   I286 @BASEBOARD_FAB2_LIB.BASEBOARD_FAB2(SCH_1):PAGE41
  U5D1 DY75 VSS<48> SKX_EXT_B_BGA1-IC,TBD   I286 @BASEBOARD_FAB2_LIB.BASEBOARD_FAB2(SCH_1):PAGE41
  U5D1 DY71 VSS<49> SKX_EXT_B_BGA1-IC,TBD   I286 @BASEBOARD_FAB2_LIB.BASEBOARD_FAB2(SCH_1):PAGE41
  U5D1 DY41 VSS<50> SKX_EXT_B_BGA1-IC,TBD   I286 @BASEBOARD_FAB2_LIB.BASEBOARD_FAB2(SCH_1):PAGE41
  U5D1 DY35 VSS<51> SKX_EXT_B_BGA1-IC,TBD   I286 @BASEBOARD_FAB2_LIB.BASEBOARD_FAB2(SCH_1):PAGE41
  U5D1 DY29 VSS<52> SKX_EXT_B_BGA1-IC,TBD   I286 @BASEBOARD_FAB2_LIB.BASEBOARD_FAB2(SCH_1):PAGE41
  U5D1 DY23 VSS<53> SKX_EXT_B_BGA1-IC,TBD   I286 @BASEBOARD_FAB2_LIB.BASEBOARD_FAB2(SCH_1):PAGE41
  U5D1 DY19 VSS<54> SKX_EXT_B_BGA1-IC,TBD   I286 @BASEBOARD_FAB2_LIB.BASEBOARD_FAB2(SCH_1):PAGE41
  U5D1  DY5 VSS<55> SKX_EXT_B_BGA1-IC,TBD   I286 @BASEBOARD_FAB2_LIB.BASEBOARD_FAB2(SCH_1):PAGE41
  U5D1 DW84 VSS<56> SKX_EXT_B_BGA1-IC,TBD   I286 @BASEBOARD_FAB2_LIB.BASEBOARD_FAB2(SCH_1):PAGE41
  U5D1 DW82 VSS<57> SKX_EXT_B_BGA1-IC,TBD   I286 @BASEBOARD_FAB2_LIB.BASEBOARD_FAB2(SCH_1):PAGE41
  U5D1  DW8 VSS<58> SKX_EXT_B_BGA1-IC,TBD   I286 @BASEBOARD_FAB2_LIB.BASEBOARD_FAB2(SCH_1):PAGE41
  U5D1 DW76 VSS<59> SKX_EXT_B_BGA1-IC,TBD   I286 @BASEBOARD_FAB2_LIB.BASEBOARD_FAB2(SCH_1):PAGE41
  U5D1 DW74 VSS<60> SKX_EXT_B_BGA1-IC,TBD   I286 @BASEBOARD_FAB2_LIB.BASEBOARD_FAB2(SCH_1):PAGE41
  U5D1 DW72 VSS<61> SKX_EXT_B_BGA1-IC,TBD   I286 @BASEBOARD_FAB2_LIB.BASEBOARD_FAB2(SCH_1):PAGE41
  U5D1 DW70 VSS<62> SKX_EXT_B_BGA1-IC,TBD   I286 @BASEBOARD_FAB2_LIB.BASEBOARD_FAB2(SCH_1):PAGE41
  U5D1 DW68 VSS<63> SKX_EXT_B_BGA1-IC,TBD   I286 @BASEBOARD_FAB2_LIB.BASEBOARD_FAB2(SCH_1):PAGE41
  U5D1 DW66 VSS<64> SKX_EXT_B_BGA1-IC,TBD   I286 @BASEBOARD_FAB2_LIB.BASEBOARD_FAB2(SCH_1):PAGE41
  U5D1 DW64 VSS<65> SKX_EXT_B_BGA1-IC,TBD   I286 @BASEBOARD_FAB2_LIB.BASEBOARD_FAB2(SCH_1):PAGE41
  U5D1 DW40 VSS<66> SKX_EXT_B_BGA1-IC,TBD   I286 @BASEBOARD_FAB2_LIB.BASEBOARD_FAB2(SCH_1):PAGE41
  U5D1 DW36 VSS<67> SKX_EXT_B_BGA1-IC,TBD   I286 @BASEBOARD_FAB2_LIB.BASEBOARD_FAB2(SCH_1):PAGE41
  U5D1 DW34 VSS<68> SKX_EXT_B_BGA1-IC,TBD   I286 @BASEBOARD_FAB2_LIB.BASEBOARD_FAB2(SCH_1):PAGE41
  U5D1 DW30 VSS<69> SKX_EXT_B_BGA1-IC,TBD   I286 @BASEBOARD_FAB2_LIB.BASEBOARD_FAB2(SCH_1):PAGE41
  U5D1 DW28 VSS<70> SKX_EXT_B_BGA1-IC,TBD   I286 @BASEBOARD_FAB2_LIB.BASEBOARD_FAB2(SCH_1):PAGE41
  U5D1 DW24 VSS<71> SKX_EXT_B_BGA1-IC,TBD   I286 @BASEBOARD_FAB2_LIB.BASEBOARD_FAB2(SCH_1):PAGE41
  U5D1 DW20 VSS<72> SKX_EXT_B_BGA1-IC,TBD   I286 @BASEBOARD_FAB2_LIB.BASEBOARD_FAB2(SCH_1):PAGE41
  U5D1 DW12 VSS<73> SKX_EXT_B_BGA1-IC,TBD   I286 @BASEBOARD_FAB2_LIB.BASEBOARD_FAB2(SCH_1):PAGE41
  U5D1 DV81 VSS<74> SKX_EXT_B_BGA1-IC,TBD   I286 @BASEBOARD_FAB2_LIB.BASEBOARD_FAB2(SCH_1):PAGE41
  U5D1 DV77 VSS<75> SKX_EXT_B_BGA1-IC,TBD   I286 @BASEBOARD_FAB2_LIB.BASEBOARD_FAB2(SCH_1):PAGE41
  U5D1 DV73 VSS<76> SKX_EXT_B_BGA1-IC,TBD   I286 @BASEBOARD_FAB2_LIB.BASEBOARD_FAB2(SCH_1):PAGE41
  U5D1 DV39 VSS<77> SKX_EXT_B_BGA1-IC,TBD   I286 @BASEBOARD_FAB2_LIB.BASEBOARD_FAB2(SCH_1):PAGE41
  U5D1 DV37 VSS<78> SKX_EXT_B_BGA1-IC,TBD   I286 @BASEBOARD_FAB2_LIB.BASEBOARD_FAB2(SCH_1):PAGE41
  U5D1 DV33 VSS<79> SKX_EXT_B_BGA1-IC,TBD   I286 @BASEBOARD_FAB2_LIB.BASEBOARD_FAB2(SCH_1):PAGE41
  U5D1 DV31 VSS<80> SKX_EXT_B_BGA1-IC,TBD   I286 @BASEBOARD_FAB2_LIB.BASEBOARD_FAB2(SCH_1):PAGE41
  U5D1 DV27 VSS<81> SKX_EXT_B_BGA1-IC,TBD   I286 @BASEBOARD_FAB2_LIB.BASEBOARD_FAB2(SCH_1):PAGE41
  U5D1 DV25 VSS<82> SKX_EXT_B_BGA1-IC,TBD   I286 @BASEBOARD_FAB2_LIB.BASEBOARD_FAB2(SCH_1):PAGE41
  U5D1 DV21 VSS<83> SKX_EXT_B_BGA1-IC,TBD   I286 @BASEBOARD_FAB2_LIB.BASEBOARD_FAB2(SCH_1):PAGE41
  U5D1 DU84 VSS<84> SKX_EXT_B_BGA1-IC,TBD   I286 @BASEBOARD_FAB2_LIB.BASEBOARD_FAB2(SCH_1):PAGE41
  U5D1 DU82 VSS<85> SKX_EXT_B_BGA1-IC,TBD   I286 @BASEBOARD_FAB2_LIB.BASEBOARD_FAB2(SCH_1):PAGE41
  U5D1 DU80 VSS<86> SKX_EXT_B_BGA1-IC,TBD   I286 @BASEBOARD_FAB2_LIB.BASEBOARD_FAB2(SCH_1):PAGE41
  U5D1 DU78 VSS<87> SKX_EXT_B_BGA1-IC,TBD   I286 @BASEBOARD_FAB2_LIB.BASEBOARD_FAB2(SCH_1):PAGE41
  U5D1 DU72 VSS<88> SKX_EXT_B_BGA1-IC,TBD   I286 @BASEBOARD_FAB2_LIB.BASEBOARD_FAB2(SCH_1):PAGE41
  U5D1 DU70 VSS<89> SKX_EXT_B_BGA1-IC,TBD   I286 @BASEBOARD_FAB2_LIB.BASEBOARD_FAB2(SCH_1):PAGE41
  U5D1 DU38 VSS<90> SKX_EXT_B_BGA1-IC,TBD   I286 @BASEBOARD_FAB2_LIB.BASEBOARD_FAB2(SCH_1):PAGE41
  U5D1 DU32 VSS<91> SKX_EXT_B_BGA1-IC,TBD   I286 @BASEBOARD_FAB2_LIB.BASEBOARD_FAB2(SCH_1):PAGE41
  U5D1 DU26 VSS<92> SKX_EXT_B_BGA1-IC,TBD   I286 @BASEBOARD_FAB2_LIB.BASEBOARD_FAB2(SCH_1):PAGE41
  U5D1 DU22 VSS<93> SKX_EXT_B_BGA1-IC,TBD   I286 @BASEBOARD_FAB2_LIB.BASEBOARD_FAB2(SCH_1):PAGE41
  U5D1 CN14 VSS<94> SKX_EXT_B_BGA1-IC,TBD   I286 @BASEBOARD_FAB2_LIB.BASEBOARD_FAB2(SCH_1):PAGE41
  U5D1 DU14 VSS<95> SKX_EXT_B_BGA1-IC,TBD   I286 @BASEBOARD_FAB2_LIB.BASEBOARD_FAB2(SCH_1):PAGE41
  U5D1 DU10 VSS<96> SKX_EXT_B_BGA1-IC,TBD   I286 @BASEBOARD_FAB2_LIB.BASEBOARD_FAB2(SCH_1):PAGE41
  U5D1 DT85 VSS<97> SKX_EXT_B_BGA1-IC,TBD   I286 @BASEBOARD_FAB2_LIB.BASEBOARD_FAB2(SCH_1):PAGE41
  U5D1 DT83 VSS<98> SKX_EXT_B_BGA1-IC,TBD   I286 @BASEBOARD_FAB2_LIB.BASEBOARD_FAB2(SCH_1):PAGE41
  U5D1 DT79 VSS<99> SKX_EXT_B_BGA1-IC,TBD   I286 @BASEBOARD_FAB2_LIB.BASEBOARD_FAB2(SCH_1):PAGE41
  U5D1 DT69 VSS<100> SKX_EXT_B_BGA1-IC,TBD   I286 @BASEBOARD_FAB2_LIB.BASEBOARD_FAB2(SCH_1):PAGE41
  U5D1 DT65 VSS<101> SKX_EXT_B_BGA1-IC,TBD   I286 @BASEBOARD_FAB2_LIB.BASEBOARD_FAB2(SCH_1):PAGE41
  U5D1 DH21 VSS<102> SKX_EXT_B_BGA1-IC,TBD   I286 @BASEBOARD_FAB2_LIB.BASEBOARD_FAB2(SCH_1):PAGE41
  U5D1 DT17 VSS<103> SKX_EXT_B_BGA1-IC,TBD   I286 @BASEBOARD_FAB2_LIB.BASEBOARD_FAB2(SCH_1):PAGE41
  U5D1  DT3 VSS<104> SKX_EXT_B_BGA1-IC,TBD   I286 @BASEBOARD_FAB2_LIB.BASEBOARD_FAB2(SCH_1):PAGE41
  U5D1 DR78 VSS<105> SKX_EXT_B_BGA1-IC,TBD   I286 @BASEBOARD_FAB2_LIB.BASEBOARD_FAB2(SCH_1):PAGE41
  U5D1 DR76 VSS<106> SKX_EXT_B_BGA1-IC,TBD   I286 @BASEBOARD_FAB2_LIB.BASEBOARD_FAB2(SCH_1):PAGE41
  U5D1 DR74 VSS<107> SKX_EXT_B_BGA1-IC,TBD   I286 @BASEBOARD_FAB2_LIB.BASEBOARD_FAB2(SCH_1):PAGE41
  U5D1 DR72 VSS<108> SKX_EXT_B_BGA1-IC,TBD   I286 @BASEBOARD_FAB2_LIB.BASEBOARD_FAB2(SCH_1):PAGE41
  U5D1 DR70 VSS<109> SKX_EXT_B_BGA1-IC,TBD   I286 @BASEBOARD_FAB2_LIB.BASEBOARD_FAB2(SCH_1):PAGE41
  U5D1 DR68 VSS<110> SKX_EXT_B_BGA1-IC,TBD   I286 @BASEBOARD_FAB2_LIB.BASEBOARD_FAB2(SCH_1):PAGE41
  U5D1 DR66 VSS<111> SKX_EXT_B_BGA1-IC,TBD   I286 @BASEBOARD_FAB2_LIB.BASEBOARD_FAB2(SCH_1):PAGE41
  U5D1 DR42 VSS<112> SKX_EXT_B_BGA1-IC,TBD   I286 @BASEBOARD_FAB2_LIB.BASEBOARD_FAB2(SCH_1):PAGE41
  U5D1 DR40 VSS<113> SKX_EXT_B_BGA1-IC,TBD   I286 @BASEBOARD_FAB2_LIB.BASEBOARD_FAB2(SCH_1):PAGE41
  U5D1 DR38 VSS<114> SKX_EXT_B_BGA1-IC,TBD   I286 @BASEBOARD_FAB2_LIB.BASEBOARD_FAB2(SCH_1):PAGE41
  U5D1 DR36 VSS<115> SKX_EXT_B_BGA1-IC,TBD   I286 @BASEBOARD_FAB2_LIB.BASEBOARD_FAB2(SCH_1):PAGE41
  U5D1 DR34 VSS<116> SKX_EXT_B_BGA1-IC,TBD   I286 @BASEBOARD_FAB2_LIB.BASEBOARD_FAB2(SCH_1):PAGE41
  U5D1 DR32 VSS<117> SKX_EXT_B_BGA1-IC,TBD   I286 @BASEBOARD_FAB2_LIB.BASEBOARD_FAB2(SCH_1):PAGE41
  U5D1 DR30 VSS<118> SKX_EXT_B_BGA1-IC,TBD   I286 @BASEBOARD_FAB2_LIB.BASEBOARD_FAB2(SCH_1):PAGE41
  U5D1 DR28 VSS<119> SKX_EXT_B_BGA1-IC,TBD   I286 @BASEBOARD_FAB2_LIB.BASEBOARD_FAB2(SCH_1):PAGE41
  U5D1 DR26 VSS<120> SKX_EXT_B_BGA1-IC,TBD   I286 @BASEBOARD_FAB2_LIB.BASEBOARD_FAB2(SCH_1):PAGE41
  U5D1 DR24 VSS<121> SKX_EXT_B_BGA1-IC,TBD   I286 @BASEBOARD_FAB2_LIB.BASEBOARD_FAB2(SCH_1):PAGE41
  U5D1 DR22 VSS<122> SKX_EXT_B_BGA1-IC,TBD   I286 @BASEBOARD_FAB2_LIB.BASEBOARD_FAB2(SCH_1):PAGE41
  U5D1 DR20 VSS<123> SKX_EXT_B_BGA1-IC,TBD   I286 @BASEBOARD_FAB2_LIB.BASEBOARD_FAB2(SCH_1):PAGE41
  U5D1 CL22 VSS<124> SKX_EXT_B_BGA1-IC,TBD   I286 @BASEBOARD_FAB2_LIB.BASEBOARD_FAB2(SCH_1):PAGE41
  U5D1 CA20 VSS<125> SKX_EXT_B_BGA1-IC,TBD   I286 @BASEBOARD_FAB2_LIB.BASEBOARD_FAB2(SCH_1):PAGE41
  U5D1  DR6 VSS<126> SKX_EXT_B_BGA1-IC,TBD   I286 @BASEBOARD_FAB2_LIB.BASEBOARD_FAB2(SCH_1):PAGE41
  U5D1 BR26 VSS<127> SKX_EXT_B_BGA1-IC,TBD   I286 @BASEBOARD_FAB2_LIB.BASEBOARD_FAB2(SCH_1):PAGE41
  U5D1 DP83 VSS<128> SKX_EXT_B_BGA1-IC,TBD   I286 @BASEBOARD_FAB2_LIB.BASEBOARD_FAB2(SCH_1):PAGE41
  U5D1 DP81 VSS<129> SKX_EXT_B_BGA1-IC,TBD   I286 @BASEBOARD_FAB2_LIB.BASEBOARD_FAB2(SCH_1):PAGE41
  U5D1 DP71 VSS<130> SKX_EXT_B_BGA1-IC,TBD   I286 @BASEBOARD_FAB2_LIB.BASEBOARD_FAB2(SCH_1):PAGE41
  U5D1 DP69 VSS<131> SKX_EXT_B_BGA1-IC,TBD   I286 @BASEBOARD_FAB2_LIB.BASEBOARD_FAB2(SCH_1):PAGE41
  U5D1 DP67 VSS<132> SKX_EXT_B_BGA1-IC,TBD   I286 @BASEBOARD_FAB2_LIB.BASEBOARD_FAB2(SCH_1):PAGE41
  U5D1 DN78 VSS<133> SKX_EXT_B_BGA1-IC,TBD   I286 @BASEBOARD_FAB2_LIB.BASEBOARD_FAB2(SCH_1):PAGE41
 C5P18    2      B CAP_0805-47UF,4V,20%,X6S,C9533A     I2 @BASEBOARD_FAB2_LIB.BASEBOARD_FAB2(SCH_1):PAGE42
 C5P28    2      B CAP_0805-47UF,4V,20%,X6S,C9533A     I3 @BASEBOARD_FAB2_LIB.BASEBOARD_FAB2(SCH_1):PAGE42
 C5P11    2      B CAP_0805-47UF,4V,20%,X6S,C9533A     I4 @BASEBOARD_FAB2_LIB.BASEBOARD_FAB2(SCH_1):PAGE42
 C5P10    2      B CAP_0805-47UF,4V,20%,X6S,C9533A     I6 @BASEBOARD_FAB2_LIB.BASEBOARD_FAB2(SCH_1):PAGE42
  C4P3    2      B CAP_0805-47UF,4V,20%,X6S,C9533A     I8 @BASEBOARD_FAB2_LIB.BASEBOARD_FAB2(SCH_1):PAGE42
  C4P7    2      B CAP_0805-47UF,4V,20%,X6S,C9533A     I9 @BASEBOARD_FAB2_LIB.BASEBOARD_FAB2(SCH_1):PAGE42
  C4P1    2      B CAP_0805-47UF,4V,20%,X6S,C9533A    I10 @BASEBOARD_FAB2_LIB.BASEBOARD_FAB2(SCH_1):PAGE42
  C4P9    2      B CAP_0805-47UF,4V,20%,X6S,C9533A    I12 @BASEBOARD_FAB2_LIB.BASEBOARD_FAB2(SCH_1):PAGE42
 C5P19    2      B CAP_0805-47UF,4V,20%,X6S,C9533A    I13 @BASEBOARD_FAB2_LIB.BASEBOARD_FAB2(SCH_1):PAGE42
  C4P4    2      B CAP_0805-47UF,4V,20%,X6S,C9533A    I14 @BASEBOARD_FAB2_LIB.BASEBOARD_FAB2(SCH_1):PAGE42
 C4P10    2      B CAP_0805-47UF,4V,20%,X6S,C9533A    I17 @BASEBOARD_FAB2_LIB.BASEBOARD_FAB2(SCH_1):PAGE42
  C5P9    2      B CAP_0805LF-22UF,4V,20%,X6S,C95A    I18 @BASEBOARD_FAB2_LIB.BASEBOARD_FAB2(SCH_1):PAGE42
  C5P8    2      B CAP_0805LF-22UF,4V,20%,X6S,C95A    I19 @BASEBOARD_FAB2_LIB.BASEBOARD_FAB2(SCH_1):PAGE42
  C5P7    2      B CAP_0805LF-22UF,4V,20%,X6S,C95A    I25 @BASEBOARD_FAB2_LIB.BASEBOARD_FAB2(SCH_1):PAGE42
  C5P4    2      B CAP_0805-47UF,4V,20%,X6S,C9533A    I27 @BASEBOARD_FAB2_LIB.BASEBOARD_FAB2(SCH_1):PAGE42
 C5P23    2      B CAP_0805-47UF,4V,20%,X6S,C9533A    I28 @BASEBOARD_FAB2_LIB.BASEBOARD_FAB2(SCH_1):PAGE42
 C5P24    2      B CAP_0805-47UF,4V,20%,X6S,C9533A    I33 @BASEBOARD_FAB2_LIB.BASEBOARD_FAB2(SCH_1):PAGE42
 C5P25    2      B CAP_0805-47UF,4V,20%,X6S,C9533A    I37 @BASEBOARD_FAB2_LIB.BASEBOARD_FAB2(SCH_1):PAGE42
  C5P6    2      B CAP_0805-47UF,4V,20%,X6S,C9533A    I38 @BASEBOARD_FAB2_LIB.BASEBOARD_FAB2(SCH_1):PAGE42
 C5P41    2      B CAP_0805-47UF,4V,20%,X6S,C9533A    I40 @BASEBOARD_FAB2_LIB.BASEBOARD_FAB2(SCH_1):PAGE42
 C5P14    2      B CAP_0805-47UF,4V,20%,X6S,C9533A    I41 @BASEBOARD_FAB2_LIB.BASEBOARD_FAB2(SCH_1):PAGE42
  C5P5    2      B CAP_0805-47UF,4V,20%,X6S,C9533A    I42 @BASEBOARD_FAB2_LIB.BASEBOARD_FAB2(SCH_1):PAGE42
 C5P27    2      B CAP_0805-47UF,4V,20%,X6S,C9533A    I44 @BASEBOARD_FAB2_LIB.BASEBOARD_FAB2(SCH_1):PAGE42
 C5P33    2      B CAP_0805-47UF,4V,20%,X6S,C9533A    I50 @BASEBOARD_FAB2_LIB.BASEBOARD_FAB2(SCH_1):PAGE42
 C5P35    2      B CAP_0805-47UF,4V,20%,X6S,C9533A    I51 @BASEBOARD_FAB2_LIB.BASEBOARD_FAB2(SCH_1):PAGE42
 C5P32    2      B CAP_0805-47UF,4V,20%,X6S,C9533A    I53 @BASEBOARD_FAB2_LIB.BASEBOARD_FAB2(SCH_1):PAGE42
 C5P34    2      B CAP_0805-47UF,4V,20%,X6S,C9533A    I54 @BASEBOARD_FAB2_LIB.BASEBOARD_FAB2(SCH_1):PAGE42
 C5P22    2      B CAP_0805-47UF,4V,20%,X6S,C9533A    I55 @BASEBOARD_FAB2_LIB.BASEBOARD_FAB2(SCH_1):PAGE42
 C5P26    2      B CAP_0805-47UF,4V,20%,X6S,C9533A    I56 @BASEBOARD_FAB2_LIB.BASEBOARD_FAB2(SCH_1):PAGE42
 C5P40    2      B CAP_0805-47UF,4V,20%,X6S,C9533A    I57 @BASEBOARD_FAB2_LIB.BASEBOARD_FAB2(SCH_1):PAGE42
 C5P42    2      B CAP_0805-47UF,4V,20%,X6S,C9533A    I59 @BASEBOARD_FAB2_LIB.BASEBOARD_FAB2(SCH_1):PAGE42
 C5P43    2      B CAP_0805-47UF,4V,20%,X6S,C9533A    I60 @BASEBOARD_FAB2_LIB.BASEBOARD_FAB2(SCH_1):PAGE42
 C5P44    2      B CAP_0805-47UF,4V,20%,X6S,C9533A    I61 @BASEBOARD_FAB2_LIB.BASEBOARD_FAB2(SCH_1):PAGE42
 C5P37    2      B CAP_0805-47UF,4V,20%,X6S,C9533A    I63 @BASEBOARD_FAB2_LIB.BASEBOARD_FAB2(SCH_1):PAGE42
 C5P36    2      B CAP_0805-47UF,4V,20%,X6S,C9533A    I65 @BASEBOARD_FAB2_LIB.BASEBOARD_FAB2(SCH_1):PAGE42
  C6D8    2      B CAP_A_0603V-22.0UF,4V,20%,X6S,A    I68 @BASEBOARD_FAB2_LIB.BASEBOARD_FAB2(SCH_1):PAGE42
 C5D38    2      B CAP_A_0603V-22.0UF,4V,20%,X6S,A    I69 @BASEBOARD_FAB2_LIB.BASEBOARD_FAB2(SCH_1):PAGE42
 C5D37    2      B CAP_A_0603V-22.0UF,4V,20%,X6S,A    I70 @BASEBOARD_FAB2_LIB.BASEBOARD_FAB2(SCH_1):PAGE42
  C6D7    2      B CAP_A_0603V-22.0UF,4V,20%,X6S,A    I72 @BASEBOARD_FAB2_LIB.BASEBOARD_FAB2(SCH_1):PAGE42
  C6D4    2      B CAP_A_0603V-22.0UF,4V,20%,X6S,A    I74 @BASEBOARD_FAB2_LIB.BASEBOARD_FAB2(SCH_1):PAGE42
  C6D5    2      B CAP_A_0603V-22.0UF,4V,20%,X6S,A    I75 @BASEBOARD_FAB2_LIB.BASEBOARD_FAB2(SCH_1):PAGE42
  C6D2    2      B CAP_A_0603V-22.0UF,4V,20%,X6S,A    I77 @BASEBOARD_FAB2_LIB.BASEBOARD_FAB2(SCH_1):PAGE42
  C6D3    2      B CAP_A_0603V-22.0UF,4V,20%,X6S,A    I80 @BASEBOARD_FAB2_LIB.BASEBOARD_FAB2(SCH_1):PAGE42
  C6D6    2      B CAP_A_0603V-22.0UF,4V,20%,X6S,A    I81 @BASEBOARD_FAB2_LIB.BASEBOARD_FAB2(SCH_1):PAGE42
 C5D51    2      B CAP_A_0603V-22.0UF,4V,20%,X6S,A    I83 @BASEBOARD_FAB2_LIB.BASEBOARD_FAB2(SCH_1):PAGE42
 C5D21    2      B CAP_A_0603V-22.0UF,4V,20%,X6S,A    I88 @BASEBOARD_FAB2_LIB.BASEBOARD_FAB2(SCH_1):PAGE42
 C5D50    2      B CAP_A_0603V-22.0UF,4V,20%,X6S,A    I89 @BASEBOARD_FAB2_LIB.BASEBOARD_FAB2(SCH_1):PAGE42
 C5D48    2      B CAP_A_0603V-22.0UF,4V,20%,X6S,A    I90 @BASEBOARD_FAB2_LIB.BASEBOARD_FAB2(SCH_1):PAGE42
 C5D13    2      B CAP_0603LF-10UF,4V,20%,X6S,E15A    I91 @BASEBOARD_FAB2_LIB.BASEBOARD_FAB2(SCH_1):PAGE42
 C5D11    2      B CAP_0603LF-10UF,4V,20%,X6S,E15A    I93 @BASEBOARD_FAB2_LIB.BASEBOARD_FAB2(SCH_1):PAGE42
 C5D12    2      B CAP_0603LF-10UF,4V,20%,X6S,E15A    I94 @BASEBOARD_FAB2_LIB.BASEBOARD_FAB2(SCH_1):PAGE42
 C5D23    2      B CAP_A_0603V-22.0UF,4V,20%,X6S,A    I98 @BASEBOARD_FAB2_LIB.BASEBOARD_FAB2(SCH_1):PAGE42
 C5D28    2      B CAP_A_0603V-22.0UF,4V,20%,X6S,A   I100 @BASEBOARD_FAB2_LIB.BASEBOARD_FAB2(SCH_1):PAGE42
 C5D29    2      B CAP_A_0603V-22.0UF,4V,20%,X6S,A   I102 @BASEBOARD_FAB2_LIB.BASEBOARD_FAB2(SCH_1):PAGE42
 C5D32    2      B CAP_A_0603V-22.0UF,4V,20%,X6S,A   I103 @BASEBOARD_FAB2_LIB.BASEBOARD_FAB2(SCH_1):PAGE42
 C5D47    2      B CAP_A_0603V-22.0UF,4V,20%,X6S,A   I104 @BASEBOARD_FAB2_LIB.BASEBOARD_FAB2(SCH_1):PAGE42
 C5D31    2      B CAP_A_0603V-22.0UF,4V,20%,X6S,A   I106 @BASEBOARD_FAB2_LIB.BASEBOARD_FAB2(SCH_1):PAGE42
 C5D46    2      B CAP_A_0603V-22.0UF,4V,20%,X6S,A   I107 @BASEBOARD_FAB2_LIB.BASEBOARD_FAB2(SCH_1):PAGE42
 C5D10    2      B CAP_0603LF-10UF,4V,20%,X6S,E15A   I108 @BASEBOARD_FAB2_LIB.BASEBOARD_FAB2(SCH_1):PAGE42
 C5D27    2      B CAP_A_0603V-22.0UF,4V,20%,X6S,A   I109 @BASEBOARD_FAB2_LIB.BASEBOARD_FAB2(SCH_1):PAGE42
 C5D30    2      B CAP_A_0603V-22.0UF,4V,20%,X6S,A   I111 @BASEBOARD_FAB2_LIB.BASEBOARD_FAB2(SCH_1):PAGE42
 C5D60    2      B CAP_A_0603V-22.0UF,4V,20%,X6S,A   I112 @BASEBOARD_FAB2_LIB.BASEBOARD_FAB2(SCH_1):PAGE42
 C5D61    2      B CAP_A_0603V-22.0UF,4V,20%,X6S,A   I113 @BASEBOARD_FAB2_LIB.BASEBOARD_FAB2(SCH_1):PAGE42
 C5D41    2      B CAP_A_0603V-22.0UF,4V,20%,X6S,A   I114 @BASEBOARD_FAB2_LIB.BASEBOARD_FAB2(SCH_1):PAGE42
 C5D40    2      B CAP_A_0603V-22.0UF,4V,20%,X6S,A   I115 @BASEBOARD_FAB2_LIB.BASEBOARD_FAB2(SCH_1):PAGE42
 C5D14    2      B CAP_A_0603V-22.0UF,4V,20%,X6S,A   I117 @BASEBOARD_FAB2_LIB.BASEBOARD_FAB2(SCH_1):PAGE42
 C5D17    2      B CAP_A_0603V-22.0UF,4V,20%,X6S,A   I118 @BASEBOARD_FAB2_LIB.BASEBOARD_FAB2(SCH_1):PAGE42
 C5D58    2      B CAP_A_0603V-22.0UF,4V,20%,X6S,A   I120 @BASEBOARD_FAB2_LIB.BASEBOARD_FAB2(SCH_1):PAGE42
 C5D16    2      B CAP_A_0603V-22.0UF,4V,20%,X6S,A   I123 @BASEBOARD_FAB2_LIB.BASEBOARD_FAB2(SCH_1):PAGE42
  C5D5    2      B CAP_A_0603V-22.0UF,4V,20%,X6S,A   I125 @BASEBOARD_FAB2_LIB.BASEBOARD_FAB2(SCH_1):PAGE42
  C5D1    2      B CAP_A_0603V-22.0UF,4V,20%,X6S,A   I126 @BASEBOARD_FAB2_LIB.BASEBOARD_FAB2(SCH_1):PAGE42
  C5D4    2      B CAP_A_0603V-22.0UF,4V,20%,X6S,A   I127 @BASEBOARD_FAB2_LIB.BASEBOARD_FAB2(SCH_1):PAGE42
 C5D19    2      B CAP_A_0603V-22.0UF,4V,20%,X6S,A   I128 @BASEBOARD_FAB2_LIB.BASEBOARD_FAB2(SCH_1):PAGE42
 C5D59    2      B CAP_A_0603V-22.0UF,4V,20%,X6S,A   I129 @BASEBOARD_FAB2_LIB.BASEBOARD_FAB2(SCH_1):PAGE42
  C5D3    2      B CAP_A_0603V-22.0UF,4V,20%,X6S,A   I130 @BASEBOARD_FAB2_LIB.BASEBOARD_FAB2(SCH_1):PAGE42
 C5D43    2      B CAP_A_0603V-22.0UF,4V,20%,X6S,A   I131 @BASEBOARD_FAB2_LIB.BASEBOARD_FAB2(SCH_1):PAGE42
 C5D15    2      B CAP_A_0603V-22.0UF,4V,20%,X6S,A   I132 @BASEBOARD_FAB2_LIB.BASEBOARD_FAB2(SCH_1):PAGE42
 C5D18    2      B CAP_A_0603V-22.0UF,4V,20%,X6S,A   I134 @BASEBOARD_FAB2_LIB.BASEBOARD_FAB2(SCH_1):PAGE42
 C5D42    2      B CAP_A_0603V-22.0UF,4V,20%,X6S,A   I135 @BASEBOARD_FAB2_LIB.BASEBOARD_FAB2(SCH_1):PAGE42
  C5D2    2      B CAP_A_0603V-22.0UF,4V,20%,X6S,A   I136 @BASEBOARD_FAB2_LIB.BASEBOARD_FAB2(SCH_1):PAGE42
 C5D24    2      B CAP_A_0603V-22.0UF,4V,20%,X6S,A   I138 @BASEBOARD_FAB2_LIB.BASEBOARD_FAB2(SCH_1):PAGE42
 C5D39    2      B CAP_A_0603V-22.0UF,4V,20%,X6S,A   I140 @BASEBOARD_FAB2_LIB.BASEBOARD_FAB2(SCH_1):PAGE42
 C5D44    2      B CAP_A_0603V-22.0UF,4V,20%,X6S,A   I142 @BASEBOARD_FAB2_LIB.BASEBOARD_FAB2(SCH_1):PAGE42
  C6D9    2      B CAP_A_0603V-22.0UF,4V,20%,X6S,A   I145 @BASEBOARD_FAB2_LIB.BASEBOARD_FAB2(SCH_1):PAGE42
 C6D10    2      B CAP_A_0603V-22.0UF,4V,20%,X6S,A   I147 @BASEBOARD_FAB2_LIB.BASEBOARD_FAB2(SCH_1):PAGE42
 C5P30    2      B CAP_0805-47UF,4V,20%,X6S,C9533A   I148 @BASEBOARD_FAB2_LIB.BASEBOARD_FAB2(SCH_1):PAGE42
 C5P29    2      B CAP_0805-47UF,4V,20%,X6S,C9533A   I149 @BASEBOARD_FAB2_LIB.BASEBOARD_FAB2(SCH_1):PAGE42
 C5D36    2      B CAP_A_0603V-22.0UF,4V,20%,X6S,A   I151 @BASEBOARD_FAB2_LIB.BASEBOARD_FAB2(SCH_1):PAGE42
 C5D49    2      B CAP_A_0603V-22.0UF,4V,20%,X6S,A   I152 @BASEBOARD_FAB2_LIB.BASEBOARD_FAB2(SCH_1):PAGE42
 C5D22    2      B CAP_A_0603V-22.0UF,4V,20%,X6S,A   I153 @BASEBOARD_FAB2_LIB.BASEBOARD_FAB2(SCH_1):PAGE42
 C5D26    2      B CAP_A_0603V-22.0UF,4V,20%,X6S,A   I154 @BASEBOARD_FAB2_LIB.BASEBOARD_FAB2(SCH_1):PAGE42
 C5D25    2      B CAP_A_0603V-22.0UF,4V,20%,X6S,A   I155 @BASEBOARD_FAB2_LIB.BASEBOARD_FAB2(SCH_1):PAGE42
 C5D45    2      B CAP_A_0603V-22.0UF,4V,20%,X6S,A   I156 @BASEBOARD_FAB2_LIB.BASEBOARD_FAB2(SCH_1):PAGE42
 C5P31    2      B CAP_0805-47UF,4V,20%,X6S,C9533A   I162 @BASEBOARD_FAB2_LIB.BASEBOARD_FAB2(SCH_1):PAGE42
  C4P2    2      B CAP_0805-47UF,4V,20%,X6S,C9533A   I163 @BASEBOARD_FAB2_LIB.BASEBOARD_FAB2(SCH_1):PAGE42
  C4P6    2      B CAP_A_0603V-22.0UF,4V,20%,X6S,A   I164 @BASEBOARD_FAB2_LIB.BASEBOARD_FAB2(SCH_1):PAGE42
  C4P5    2      B CAP_0805-47UF,4V,20%,X6S,C9533A   I172 @BASEBOARD_FAB2_LIB.BASEBOARD_FAB2(SCH_1):PAGE42
 C5D20    2      B CAP_A_0603V-22.0UF,4V,20%,X6S,A   I173 @BASEBOARD_FAB2_LIB.BASEBOARD_FAB2(SCH_1):PAGE42
 C5D33    2      B CAP_A_0603V-22.0UF,4V,20%,X6S,A   I174 @BASEBOARD_FAB2_LIB.BASEBOARD_FAB2(SCH_1):PAGE42
 C5D34    2      B CAP_A_0603V-22.0UF,4V,20%,X6S,A   I175 @BASEBOARD_FAB2_LIB.BASEBOARD_FAB2(SCH_1):PAGE42
 C5D35    2      B CAP_A_0603V-22.0UF,4V,20%,X6S,A   I176 @BASEBOARD_FAB2_LIB.BASEBOARD_FAB2(SCH_1):PAGE42
  C4P8    2      B CAP_A_0603V-22.0UF,4V,20%,X6S,A   I178 @BASEBOARD_FAB2_LIB.BASEBOARD_FAB2(SCH_1):PAGE42
 C5D53    2      B CAP_A_0603V-22.0UF,4V,20%,X6S,A   I179 @BASEBOARD_FAB2_LIB.BASEBOARD_FAB2(SCH_1):PAGE42
 C5D52    2      B CAP_A_0603V-22.0UF,4V,20%,X6S,A   I180 @BASEBOARD_FAB2_LIB.BASEBOARD_FAB2(SCH_1):PAGE42
 C5P12    2      B CAP_0805-47UF,4V,20%,X6S,C9533A   I183 @BASEBOARD_FAB2_LIB.BASEBOARD_FAB2(SCH_1):PAGE42
 C5P21    2      B CAP_0805-47UF,4V,20%,X6S,C9533A   I184 @BASEBOARD_FAB2_LIB.BASEBOARD_FAB2(SCH_1):PAGE42
 C5P20    2      B CAP_0805-47UF,4V,20%,X6S,C9533A   I185 @BASEBOARD_FAB2_LIB.BASEBOARD_FAB2(SCH_1):PAGE42
 C5P13    2      B CAP_0805-47UF,4V,20%,X6S,C9533A   I186 @BASEBOARD_FAB2_LIB.BASEBOARD_FAB2(SCH_1):PAGE42
 C5P15    2      B CAP_0805-47UF,4V,20%,X6S,C9533A   I187 @BASEBOARD_FAB2_LIB.BASEBOARD_FAB2(SCH_1):PAGE42
 C5P16    2      B CAP_0805-47UF,4V,20%,X6S,C9533A   I188 @BASEBOARD_FAB2_LIB.BASEBOARD_FAB2(SCH_1):PAGE42
  C5P3    2      B CAP_0805-47UF,4V,20%,X6S,C9533A   I189 @BASEBOARD_FAB2_LIB.BASEBOARD_FAB2(SCH_1):PAGE42
 C5P17    2      B CAP_0805-47UF,4V,20%,X6S,C9533A   I190 @BASEBOARD_FAB2_LIB.BASEBOARD_FAB2(SCH_1):PAGE42
  J4G1  139  SA<0> SCONN288_H44441004_PIP-SCONN,HA     I1 @BASEBOARD_FAB2_LIB.BASEBOARD_FAB2(SCH_1):PAGE43
  J4G1  140  SA<1> SCONN288_H44441004_PIP-SCONN,HA     I1 @BASEBOARD_FAB2_LIB.BASEBOARD_FAB2(SCH_1):PAGE43
  J4G1  238  SA<2> SCONN288_H44441004_PIP-SCONN,HA     I1 @BASEBOARD_FAB2_LIB.BASEBOARD_FAB2(SCH_1):PAGE43
  J4G1  283 VSS<0> SCONN288_H44441004_PIP-SCONN,HA   I259 @BASEBOARD_FAB2_LIB.BASEBOARD_FAB2(SCH_1):PAGE43
  J4G1  281 VSS<1> SCONN288_H44441004_PIP-SCONN,HA   I259 @BASEBOARD_FAB2_LIB.BASEBOARD_FAB2(SCH_1):PAGE43
  J4G1  279 VSS<2> SCONN288_H44441004_PIP-SCONN,HA   I259 @BASEBOARD_FAB2_LIB.BASEBOARD_FAB2(SCH_1):PAGE43
  J4G1  276 VSS<3> SCONN288_H44441004_PIP-SCONN,HA   I259 @BASEBOARD_FAB2_LIB.BASEBOARD_FAB2(SCH_1):PAGE43
  J4G1  274 VSS<4> SCONN288_H44441004_PIP-SCONN,HA   I259 @BASEBOARD_FAB2_LIB.BASEBOARD_FAB2(SCH_1):PAGE43
  J4G1  272 VSS<5> SCONN288_H44441004_PIP-SCONN,HA   I259 @BASEBOARD_FAB2_LIB.BASEBOARD_FAB2(SCH_1):PAGE43
  J4G1  270 VSS<6> SCONN288_H44441004_PIP-SCONN,HA   I259 @BASEBOARD_FAB2_LIB.BASEBOARD_FAB2(SCH_1):PAGE43
  J4G1  268 VSS<7> SCONN288_H44441004_PIP-SCONN,HA   I259 @BASEBOARD_FAB2_LIB.BASEBOARD_FAB2(SCH_1):PAGE43
  J4G1  265 VSS<8> SCONN288_H44441004_PIP-SCONN,HA   I259 @BASEBOARD_FAB2_LIB.BASEBOARD_FAB2(SCH_1):PAGE43
  J4G1  263 VSS<9> SCONN288_H44441004_PIP-SCONN,HA   I259 @BASEBOARD_FAB2_LIB.BASEBOARD_FAB2(SCH_1):PAGE43
  J4G1  261 VSS<10> SCONN288_H44441004_PIP-SCONN,HA   I259 @BASEBOARD_FAB2_LIB.BASEBOARD_FAB2(SCH_1):PAGE43
  J4G1  259 VSS<11> SCONN288_H44441004_PIP-SCONN,HA   I259 @BASEBOARD_FAB2_LIB.BASEBOARD_FAB2(SCH_1):PAGE43
  J4G1  257 VSS<12> SCONN288_H44441004_PIP-SCONN,HA   I259 @BASEBOARD_FAB2_LIB.BASEBOARD_FAB2(SCH_1):PAGE43
  J4G1  254 VSS<13> SCONN288_H44441004_PIP-SCONN,HA   I259 @BASEBOARD_FAB2_LIB.BASEBOARD_FAB2(SCH_1):PAGE43
  J4G1  252 VSS<14> SCONN288_H44441004_PIP-SCONN,HA   I259 @BASEBOARD_FAB2_LIB.BASEBOARD_FAB2(SCH_1):PAGE43
  J4G1  250 VSS<15> SCONN288_H44441004_PIP-SCONN,HA   I259 @BASEBOARD_FAB2_LIB.BASEBOARD_FAB2(SCH_1):PAGE43
  J4G1  248 VSS<16> SCONN288_H44441004_PIP-SCONN,HA   I259 @BASEBOARD_FAB2_LIB.BASEBOARD_FAB2(SCH_1):PAGE43
  J4G1  246 VSS<17> SCONN288_H44441004_PIP-SCONN,HA   I259 @BASEBOARD_FAB2_LIB.BASEBOARD_FAB2(SCH_1):PAGE43
  J4G1  243 VSS<18> SCONN288_H44441004_PIP-SCONN,HA   I259 @BASEBOARD_FAB2_LIB.BASEBOARD_FAB2(SCH_1):PAGE43
  J4G1  241 VSS<19> SCONN288_H44441004_PIP-SCONN,HA   I259 @BASEBOARD_FAB2_LIB.BASEBOARD_FAB2(SCH_1):PAGE43
  J4G1  239 VSS<20> SCONN288_H44441004_PIP-SCONN,HA   I259 @BASEBOARD_FAB2_LIB.BASEBOARD_FAB2(SCH_1):PAGE43
  J4G1  202 VSS<21> SCONN288_H44441004_PIP-SCONN,HA   I259 @BASEBOARD_FAB2_LIB.BASEBOARD_FAB2(SCH_1):PAGE43
  J4G1  200 VSS<22> SCONN288_H44441004_PIP-SCONN,HA   I259 @BASEBOARD_FAB2_LIB.BASEBOARD_FAB2(SCH_1):PAGE43
  J4G1  198 VSS<23> SCONN288_H44441004_PIP-SCONN,HA   I259 @BASEBOARD_FAB2_LIB.BASEBOARD_FAB2(SCH_1):PAGE43
  J4G1  195 VSS<24> SCONN288_H44441004_PIP-SCONN,HA   I259 @BASEBOARD_FAB2_LIB.BASEBOARD_FAB2(SCH_1):PAGE43
  J4G1  193 VSS<25> SCONN288_H44441004_PIP-SCONN,HA   I259 @BASEBOARD_FAB2_LIB.BASEBOARD_FAB2(SCH_1):PAGE43
  J4G1  191 VSS<26> SCONN288_H44441004_PIP-SCONN,HA   I259 @BASEBOARD_FAB2_LIB.BASEBOARD_FAB2(SCH_1):PAGE43
  J4G1  189 VSS<27> SCONN288_H44441004_PIP-SCONN,HA   I259 @BASEBOARD_FAB2_LIB.BASEBOARD_FAB2(SCH_1):PAGE43
  J4G1  187 VSS<28> SCONN288_H44441004_PIP-SCONN,HA   I259 @BASEBOARD_FAB2_LIB.BASEBOARD_FAB2(SCH_1):PAGE43
  J4G1  184 VSS<29> SCONN288_H44441004_PIP-SCONN,HA   I259 @BASEBOARD_FAB2_LIB.BASEBOARD_FAB2(SCH_1):PAGE43
  J4G1  182 VSS<30> SCONN288_H44441004_PIP-SCONN,HA   I259 @BASEBOARD_FAB2_LIB.BASEBOARD_FAB2(SCH_1):PAGE43
  J4G1  180 VSS<31> SCONN288_H44441004_PIP-SCONN,HA   I259 @BASEBOARD_FAB2_LIB.BASEBOARD_FAB2(SCH_1):PAGE43
  J4G1  178 VSS<32> SCONN288_H44441004_PIP-SCONN,HA   I259 @BASEBOARD_FAB2_LIB.BASEBOARD_FAB2(SCH_1):PAGE43
  J4G1  176 VSS<33> SCONN288_H44441004_PIP-SCONN,HA   I259 @BASEBOARD_FAB2_LIB.BASEBOARD_FAB2(SCH_1):PAGE43
  J4G1  173 VSS<34> SCONN288_H44441004_PIP-SCONN,HA   I259 @BASEBOARD_FAB2_LIB.BASEBOARD_FAB2(SCH_1):PAGE43
  J4G1  171 VSS<35> SCONN288_H44441004_PIP-SCONN,HA   I259 @BASEBOARD_FAB2_LIB.BASEBOARD_FAB2(SCH_1):PAGE43
  J4G1  169 VSS<36> SCONN288_H44441004_PIP-SCONN,HA   I259 @BASEBOARD_FAB2_LIB.BASEBOARD_FAB2(SCH_1):PAGE43
  J4G1  167 VSS<37> SCONN288_H44441004_PIP-SCONN,HA   I259 @BASEBOARD_FAB2_LIB.BASEBOARD_FAB2(SCH_1):PAGE43
  J4G1  165 VSS<38> SCONN288_H44441004_PIP-SCONN,HA   I259 @BASEBOARD_FAB2_LIB.BASEBOARD_FAB2(SCH_1):PAGE43
  J4G1  162 VSS<39> SCONN288_H44441004_PIP-SCONN,HA   I259 @BASEBOARD_FAB2_LIB.BASEBOARD_FAB2(SCH_1):PAGE43
  J4G1  160 VSS<40> SCONN288_H44441004_PIP-SCONN,HA   I259 @BASEBOARD_FAB2_LIB.BASEBOARD_FAB2(SCH_1):PAGE43
  J4G1  158 VSS<41> SCONN288_H44441004_PIP-SCONN,HA   I259 @BASEBOARD_FAB2_LIB.BASEBOARD_FAB2(SCH_1):PAGE43
  J4G1  156 VSS<42> SCONN288_H44441004_PIP-SCONN,HA   I259 @BASEBOARD_FAB2_LIB.BASEBOARD_FAB2(SCH_1):PAGE43
  J4G1  154 VSS<43> SCONN288_H44441004_PIP-SCONN,HA   I259 @BASEBOARD_FAB2_LIB.BASEBOARD_FAB2(SCH_1):PAGE43
  J4G1  151 VSS<44> SCONN288_H44441004_PIP-SCONN,HA   I259 @BASEBOARD_FAB2_LIB.BASEBOARD_FAB2(SCH_1):PAGE43
  J4G1  149 VSS<45> SCONN288_H44441004_PIP-SCONN,HA   I259 @BASEBOARD_FAB2_LIB.BASEBOARD_FAB2(SCH_1):PAGE43
  J4G1  147 VSS<46> SCONN288_H44441004_PIP-SCONN,HA   I259 @BASEBOARD_FAB2_LIB.BASEBOARD_FAB2(SCH_1):PAGE43
  J4G1  138 VSS<47> SCONN288_H44441004_PIP-SCONN,HA   I259 @BASEBOARD_FAB2_LIB.BASEBOARD_FAB2(SCH_1):PAGE43
  J4G1  136 VSS<48> SCONN288_H44441004_PIP-SCONN,HA   I259 @BASEBOARD_FAB2_LIB.BASEBOARD_FAB2(SCH_1):PAGE43
  J4G1  134 VSS<49> SCONN288_H44441004_PIP-SCONN,HA   I259 @BASEBOARD_FAB2_LIB.BASEBOARD_FAB2(SCH_1):PAGE43
  J4G1  131 VSS<50> SCONN288_H44441004_PIP-SCONN,HA   I259 @BASEBOARD_FAB2_LIB.BASEBOARD_FAB2(SCH_1):PAGE43
  J4G1  129 VSS<51> SCONN288_H44441004_PIP-SCONN,HA   I259 @BASEBOARD_FAB2_LIB.BASEBOARD_FAB2(SCH_1):PAGE43
  J4G1  127 VSS<52> SCONN288_H44441004_PIP-SCONN,HA   I259 @BASEBOARD_FAB2_LIB.BASEBOARD_FAB2(SCH_1):PAGE43
  J4G1  125 VSS<53> SCONN288_H44441004_PIP-SCONN,HA   I259 @BASEBOARD_FAB2_LIB.BASEBOARD_FAB2(SCH_1):PAGE43
  J4G1  123 VSS<54> SCONN288_H44441004_PIP-SCONN,HA   I259 @BASEBOARD_FAB2_LIB.BASEBOARD_FAB2(SCH_1):PAGE43
  J4G1  120 VSS<55> SCONN288_H44441004_PIP-SCONN,HA   I259 @BASEBOARD_FAB2_LIB.BASEBOARD_FAB2(SCH_1):PAGE43
  J4G1  118 VSS<56> SCONN288_H44441004_PIP-SCONN,HA   I259 @BASEBOARD_FAB2_LIB.BASEBOARD_FAB2(SCH_1):PAGE43
  J4G1  116 VSS<57> SCONN288_H44441004_PIP-SCONN,HA   I259 @BASEBOARD_FAB2_LIB.BASEBOARD_FAB2(SCH_1):PAGE43
  J4G1  114 VSS<58> SCONN288_H44441004_PIP-SCONN,HA   I259 @BASEBOARD_FAB2_LIB.BASEBOARD_FAB2(SCH_1):PAGE43
  J4G1  112 VSS<59> SCONN288_H44441004_PIP-SCONN,HA   I259 @BASEBOARD_FAB2_LIB.BASEBOARD_FAB2(SCH_1):PAGE43
  J4G1  109 VSS<60> SCONN288_H44441004_PIP-SCONN,HA   I259 @BASEBOARD_FAB2_LIB.BASEBOARD_FAB2(SCH_1):PAGE43
  J4G1  107 VSS<61> SCONN288_H44441004_PIP-SCONN,HA   I259 @BASEBOARD_FAB2_LIB.BASEBOARD_FAB2(SCH_1):PAGE43
  J4G1  105 VSS<62> SCONN288_H44441004_PIP-SCONN,HA   I259 @BASEBOARD_FAB2_LIB.BASEBOARD_FAB2(SCH_1):PAGE43
  J4G1  103 VSS<63> SCONN288_H44441004_PIP-SCONN,HA   I259 @BASEBOARD_FAB2_LIB.BASEBOARD_FAB2(SCH_1):PAGE43
  J4G1  101 VSS<64> SCONN288_H44441004_PIP-SCONN,HA   I259 @BASEBOARD_FAB2_LIB.BASEBOARD_FAB2(SCH_1):PAGE43
  J4G1   98 VSS<65> SCONN288_H44441004_PIP-SCONN,HA   I259 @BASEBOARD_FAB2_LIB.BASEBOARD_FAB2(SCH_1):PAGE43
  J4G1   96 VSS<66> SCONN288_H44441004_PIP-SCONN,HA   I259 @BASEBOARD_FAB2_LIB.BASEBOARD_FAB2(SCH_1):PAGE43
  J4G1   94 VSS<67> SCONN288_H44441004_PIP-SCONN,HA   I259 @BASEBOARD_FAB2_LIB.BASEBOARD_FAB2(SCH_1):PAGE43
  J4G1   57 VSS<68> SCONN288_H44441004_PIP-SCONN,HA   I259 @BASEBOARD_FAB2_LIB.BASEBOARD_FAB2(SCH_1):PAGE43
  J4G1   55 VSS<69> SCONN288_H44441004_PIP-SCONN,HA   I259 @BASEBOARD_FAB2_LIB.BASEBOARD_FAB2(SCH_1):PAGE43
  J4G1   53 VSS<70> SCONN288_H44441004_PIP-SCONN,HA   I259 @BASEBOARD_FAB2_LIB.BASEBOARD_FAB2(SCH_1):PAGE43
  J4G1   50 VSS<71> SCONN288_H44441004_PIP-SCONN,HA   I259 @BASEBOARD_FAB2_LIB.BASEBOARD_FAB2(SCH_1):PAGE43
  J4G1   48 VSS<72> SCONN288_H44441004_PIP-SCONN,HA   I259 @BASEBOARD_FAB2_LIB.BASEBOARD_FAB2(SCH_1):PAGE43
  J4G1   46 VSS<73> SCONN288_H44441004_PIP-SCONN,HA   I259 @BASEBOARD_FAB2_LIB.BASEBOARD_FAB2(SCH_1):PAGE43
  J4G1   44 VSS<74> SCONN288_H44441004_PIP-SCONN,HA   I259 @BASEBOARD_FAB2_LIB.BASEBOARD_FAB2(SCH_1):PAGE43
  J4G1   42 VSS<75> SCONN288_H44441004_PIP-SCONN,HA   I259 @BASEBOARD_FAB2_LIB.BASEBOARD_FAB2(SCH_1):PAGE43
  J4G1   39 VSS<76> SCONN288_H44441004_PIP-SCONN,HA   I259 @BASEBOARD_FAB2_LIB.BASEBOARD_FAB2(SCH_1):PAGE43
  J4G1   37 VSS<77> SCONN288_H44441004_PIP-SCONN,HA   I259 @BASEBOARD_FAB2_LIB.BASEBOARD_FAB2(SCH_1):PAGE43
  J4G1   35 VSS<78> SCONN288_H44441004_PIP-SCONN,HA   I259 @BASEBOARD_FAB2_LIB.BASEBOARD_FAB2(SCH_1):PAGE43
  J4G1   33 VSS<79> SCONN288_H44441004_PIP-SCONN,HA   I259 @BASEBOARD_FAB2_LIB.BASEBOARD_FAB2(SCH_1):PAGE43
  J4G1   31 VSS<80> SCONN288_H44441004_PIP-SCONN,HA   I259 @BASEBOARD_FAB2_LIB.BASEBOARD_FAB2(SCH_1):PAGE43
  J4G1   28 VSS<81> SCONN288_H44441004_PIP-SCONN,HA   I259 @BASEBOARD_FAB2_LIB.BASEBOARD_FAB2(SCH_1):PAGE43
  J4G1   26 VSS<82> SCONN288_H44441004_PIP-SCONN,HA   I259 @BASEBOARD_FAB2_LIB.BASEBOARD_FAB2(SCH_1):PAGE43
  J4G1   24 VSS<83> SCONN288_H44441004_PIP-SCONN,HA   I259 @BASEBOARD_FAB2_LIB.BASEBOARD_FAB2(SCH_1):PAGE43
  J4G1   22 VSS<84> SCONN288_H44441004_PIP-SCONN,HA   I259 @BASEBOARD_FAB2_LIB.BASEBOARD_FAB2(SCH_1):PAGE43
  J4G1   20 VSS<85> SCONN288_H44441004_PIP-SCONN,HA   I259 @BASEBOARD_FAB2_LIB.BASEBOARD_FAB2(SCH_1):PAGE43
  J4G1   17 VSS<86> SCONN288_H44441004_PIP-SCONN,HA   I259 @BASEBOARD_FAB2_LIB.BASEBOARD_FAB2(SCH_1):PAGE43
  J4G1   15 VSS<87> SCONN288_H44441004_PIP-SCONN,HA   I259 @BASEBOARD_FAB2_LIB.BASEBOARD_FAB2(SCH_1):PAGE43
  J4G1   13 VSS<88> SCONN288_H44441004_PIP-SCONN,HA   I259 @BASEBOARD_FAB2_LIB.BASEBOARD_FAB2(SCH_1):PAGE43
  J4G1   11 VSS<89> SCONN288_H44441004_PIP-SCONN,HA   I259 @BASEBOARD_FAB2_LIB.BASEBOARD_FAB2(SCH_1):PAGE43
  J4G1    9 VSS<90> SCONN288_H44441004_PIP-SCONN,HA   I259 @BASEBOARD_FAB2_LIB.BASEBOARD_FAB2(SCH_1):PAGE43
  J4G1    6 VSS<91> SCONN288_H44441004_PIP-SCONN,HA   I259 @BASEBOARD_FAB2_LIB.BASEBOARD_FAB2(SCH_1):PAGE43
  J4G1    4 VSS<92> SCONN288_H44441004_PIP-SCONN,HA   I259 @BASEBOARD_FAB2_LIB.BASEBOARD_FAB2(SCH_1):PAGE43
  J4G1    2 VSS<93> SCONN288_H44441004_PIP-SCONN,HA   I259 @BASEBOARD_FAB2_LIB.BASEBOARD_FAB2(SCH_1):PAGE43
 C4F10    2      B CAP_A_0402V-0.01UF,25V,10%,X7RA   I272 @BASEBOARD_FAB2_LIB.BASEBOARD_FAB2(SCH_1):PAGE43
  C6T1    2      B CAP_A_0402V-0.01UF,25V,10%,X7RA     I2 @BASEBOARD_FAB2_LIB.BASEBOARD_FAB2(SCH_1):PAGE44
  J6T1  140  SA<1> SCONN288_H44441003_PIP-SCONN,HA    I13 @BASEBOARD_FAB2_LIB.BASEBOARD_FAB2(SCH_1):PAGE44
  J6T1  238  SA<2> SCONN288_H44441003_PIP-SCONN,HA    I13 @BASEBOARD_FAB2_LIB.BASEBOARD_FAB2(SCH_1):PAGE44
  J6T1  283 VSS<0> SCONN288_H44441003_PIP-SCONN,HA   I139 @BASEBOARD_FAB2_LIB.BASEBOARD_FAB2(SCH_1):PAGE44
  J6T1  281 VSS<1> SCONN288_H44441003_PIP-SCONN,HA   I139 @BASEBOARD_FAB2_LIB.BASEBOARD_FAB2(SCH_1):PAGE44
  J6T1  279 VSS<2> SCONN288_H44441003_PIP-SCONN,HA   I139 @BASEBOARD_FAB2_LIB.BASEBOARD_FAB2(SCH_1):PAGE44
  J6T1  276 VSS<3> SCONN288_H44441003_PIP-SCONN,HA   I139 @BASEBOARD_FAB2_LIB.BASEBOARD_FAB2(SCH_1):PAGE44
  J6T1  274 VSS<4> SCONN288_H44441003_PIP-SCONN,HA   I139 @BASEBOARD_FAB2_LIB.BASEBOARD_FAB2(SCH_1):PAGE44
  J6T1  272 VSS<5> SCONN288_H44441003_PIP-SCONN,HA   I139 @BASEBOARD_FAB2_LIB.BASEBOARD_FAB2(SCH_1):PAGE44
  J6T1  270 VSS<6> SCONN288_H44441003_PIP-SCONN,HA   I139 @BASEBOARD_FAB2_LIB.BASEBOARD_FAB2(SCH_1):PAGE44
  J6T1  268 VSS<7> SCONN288_H44441003_PIP-SCONN,HA   I139 @BASEBOARD_FAB2_LIB.BASEBOARD_FAB2(SCH_1):PAGE44
  J6T1  265 VSS<8> SCONN288_H44441003_PIP-SCONN,HA   I139 @BASEBOARD_FAB2_LIB.BASEBOARD_FAB2(SCH_1):PAGE44
  J6T1  263 VSS<9> SCONN288_H44441003_PIP-SCONN,HA   I139 @BASEBOARD_FAB2_LIB.BASEBOARD_FAB2(SCH_1):PAGE44
  J6T1  261 VSS<10> SCONN288_H44441003_PIP-SCONN,HA   I139 @BASEBOARD_FAB2_LIB.BASEBOARD_FAB2(SCH_1):PAGE44
  J6T1  259 VSS<11> SCONN288_H44441003_PIP-SCONN,HA   I139 @BASEBOARD_FAB2_LIB.BASEBOARD_FAB2(SCH_1):PAGE44
  J6T1  257 VSS<12> SCONN288_H44441003_PIP-SCONN,HA   I139 @BASEBOARD_FAB2_LIB.BASEBOARD_FAB2(SCH_1):PAGE44
  J6T1  254 VSS<13> SCONN288_H44441003_PIP-SCONN,HA   I139 @BASEBOARD_FAB2_LIB.BASEBOARD_FAB2(SCH_1):PAGE44
  J6T1  252 VSS<14> SCONN288_H44441003_PIP-SCONN,HA   I139 @BASEBOARD_FAB2_LIB.BASEBOARD_FAB2(SCH_1):PAGE44
  J6T1  250 VSS<15> SCONN288_H44441003_PIP-SCONN,HA   I139 @BASEBOARD_FAB2_LIB.BASEBOARD_FAB2(SCH_1):PAGE44
  J6T1  248 VSS<16> SCONN288_H44441003_PIP-SCONN,HA   I139 @BASEBOARD_FAB2_LIB.BASEBOARD_FAB2(SCH_1):PAGE44
  J6T1  246 VSS<17> SCONN288_H44441003_PIP-SCONN,HA   I139 @BASEBOARD_FAB2_LIB.BASEBOARD_FAB2(SCH_1):PAGE44
  J6T1  243 VSS<18> SCONN288_H44441003_PIP-SCONN,HA   I139 @BASEBOARD_FAB2_LIB.BASEBOARD_FAB2(SCH_1):PAGE44
  J6T1  241 VSS<19> SCONN288_H44441003_PIP-SCONN,HA   I139 @BASEBOARD_FAB2_LIB.BASEBOARD_FAB2(SCH_1):PAGE44
  J6T1  239 VSS<20> SCONN288_H44441003_PIP-SCONN,HA   I139 @BASEBOARD_FAB2_LIB.BASEBOARD_FAB2(SCH_1):PAGE44
  J6T1  202 VSS<21> SCONN288_H44441003_PIP-SCONN,HA   I139 @BASEBOARD_FAB2_LIB.BASEBOARD_FAB2(SCH_1):PAGE44
  J6T1  200 VSS<22> SCONN288_H44441003_PIP-SCONN,HA   I139 @BASEBOARD_FAB2_LIB.BASEBOARD_FAB2(SCH_1):PAGE44
  J6T1  198 VSS<23> SCONN288_H44441003_PIP-SCONN,HA   I139 @BASEBOARD_FAB2_LIB.BASEBOARD_FAB2(SCH_1):PAGE44
  J6T1  195 VSS<24> SCONN288_H44441003_PIP-SCONN,HA   I139 @BASEBOARD_FAB2_LIB.BASEBOARD_FAB2(SCH_1):PAGE44
  J6T1  193 VSS<25> SCONN288_H44441003_PIP-SCONN,HA   I139 @BASEBOARD_FAB2_LIB.BASEBOARD_FAB2(SCH_1):PAGE44
  J6T1  191 VSS<26> SCONN288_H44441003_PIP-SCONN,HA   I139 @BASEBOARD_FAB2_LIB.BASEBOARD_FAB2(SCH_1):PAGE44
  J6T1  189 VSS<27> SCONN288_H44441003_PIP-SCONN,HA   I139 @BASEBOARD_FAB2_LIB.BASEBOARD_FAB2(SCH_1):PAGE44
  J6T1  187 VSS<28> SCONN288_H44441003_PIP-SCONN,HA   I139 @BASEBOARD_FAB2_LIB.BASEBOARD_FAB2(SCH_1):PAGE44
  J6T1  184 VSS<29> SCONN288_H44441003_PIP-SCONN,HA   I139 @BASEBOARD_FAB2_LIB.BASEBOARD_FAB2(SCH_1):PAGE44
  J6T1  182 VSS<30> SCONN288_H44441003_PIP-SCONN,HA   I139 @BASEBOARD_FAB2_LIB.BASEBOARD_FAB2(SCH_1):PAGE44
  J6T1  180 VSS<31> SCONN288_H44441003_PIP-SCONN,HA   I139 @BASEBOARD_FAB2_LIB.BASEBOARD_FAB2(SCH_1):PAGE44
  J6T1  178 VSS<32> SCONN288_H44441003_PIP-SCONN,HA   I139 @BASEBOARD_FAB2_LIB.BASEBOARD_FAB2(SCH_1):PAGE44
  J6T1  176 VSS<33> SCONN288_H44441003_PIP-SCONN,HA   I139 @BASEBOARD_FAB2_LIB.BASEBOARD_FAB2(SCH_1):PAGE44
  J6T1  173 VSS<34> SCONN288_H44441003_PIP-SCONN,HA   I139 @BASEBOARD_FAB2_LIB.BASEBOARD_FAB2(SCH_1):PAGE44
  J6T1  171 VSS<35> SCONN288_H44441003_PIP-SCONN,HA   I139 @BASEBOARD_FAB2_LIB.BASEBOARD_FAB2(SCH_1):PAGE44
  J6T1  169 VSS<36> SCONN288_H44441003_PIP-SCONN,HA   I139 @BASEBOARD_FAB2_LIB.BASEBOARD_FAB2(SCH_1):PAGE44
  J6T1  167 VSS<37> SCONN288_H44441003_PIP-SCONN,HA   I139 @BASEBOARD_FAB2_LIB.BASEBOARD_FAB2(SCH_1):PAGE44
  J6T1  165 VSS<38> SCONN288_H44441003_PIP-SCONN,HA   I139 @BASEBOARD_FAB2_LIB.BASEBOARD_FAB2(SCH_1):PAGE44
  J6T1  162 VSS<39> SCONN288_H44441003_PIP-SCONN,HA   I139 @BASEBOARD_FAB2_LIB.BASEBOARD_FAB2(SCH_1):PAGE44
  J6T1  160 VSS<40> SCONN288_H44441003_PIP-SCONN,HA   I139 @BASEBOARD_FAB2_LIB.BASEBOARD_FAB2(SCH_1):PAGE44
  J6T1  158 VSS<41> SCONN288_H44441003_PIP-SCONN,HA   I139 @BASEBOARD_FAB2_LIB.BASEBOARD_FAB2(SCH_1):PAGE44
  J6T1  156 VSS<42> SCONN288_H44441003_PIP-SCONN,HA   I139 @BASEBOARD_FAB2_LIB.BASEBOARD_FAB2(SCH_1):PAGE44
  J6T1  154 VSS<43> SCONN288_H44441003_PIP-SCONN,HA   I139 @BASEBOARD_FAB2_LIB.BASEBOARD_FAB2(SCH_1):PAGE44
  J6T1  151 VSS<44> SCONN288_H44441003_PIP-SCONN,HA   I139 @BASEBOARD_FAB2_LIB.BASEBOARD_FAB2(SCH_1):PAGE44
  J6T1  149 VSS<45> SCONN288_H44441003_PIP-SCONN,HA   I139 @BASEBOARD_FAB2_LIB.BASEBOARD_FAB2(SCH_1):PAGE44
  J6T1  147 VSS<46> SCONN288_H44441003_PIP-SCONN,HA   I139 @BASEBOARD_FAB2_LIB.BASEBOARD_FAB2(SCH_1):PAGE44
  J6T1  138 VSS<47> SCONN288_H44441003_PIP-SCONN,HA   I139 @BASEBOARD_FAB2_LIB.BASEBOARD_FAB2(SCH_1):PAGE44
  J6T1  136 VSS<48> SCONN288_H44441003_PIP-SCONN,HA   I139 @BASEBOARD_FAB2_LIB.BASEBOARD_FAB2(SCH_1):PAGE44
  J6T1  134 VSS<49> SCONN288_H44441003_PIP-SCONN,HA   I139 @BASEBOARD_FAB2_LIB.BASEBOARD_FAB2(SCH_1):PAGE44
  J6T1  131 VSS<50> SCONN288_H44441003_PIP-SCONN,HA   I139 @BASEBOARD_FAB2_LIB.BASEBOARD_FAB2(SCH_1):PAGE44
  J6T1  129 VSS<51> SCONN288_H44441003_PIP-SCONN,HA   I139 @BASEBOARD_FAB2_LIB.BASEBOARD_FAB2(SCH_1):PAGE44
  J6T1  127 VSS<52> SCONN288_H44441003_PIP-SCONN,HA   I139 @BASEBOARD_FAB2_LIB.BASEBOARD_FAB2(SCH_1):PAGE44
  J6T1  125 VSS<53> SCONN288_H44441003_PIP-SCONN,HA   I139 @BASEBOARD_FAB2_LIB.BASEBOARD_FAB2(SCH_1):PAGE44
  J6T1  123 VSS<54> SCONN288_H44441003_PIP-SCONN,HA   I139 @BASEBOARD_FAB2_LIB.BASEBOARD_FAB2(SCH_1):PAGE44
  J6T1  120 VSS<55> SCONN288_H44441003_PIP-SCONN,HA   I139 @BASEBOARD_FAB2_LIB.BASEBOARD_FAB2(SCH_1):PAGE44
  J6T1  118 VSS<56> SCONN288_H44441003_PIP-SCONN,HA   I139 @BASEBOARD_FAB2_LIB.BASEBOARD_FAB2(SCH_1):PAGE44
  J6T1  116 VSS<57> SCONN288_H44441003_PIP-SCONN,HA   I139 @BASEBOARD_FAB2_LIB.BASEBOARD_FAB2(SCH_1):PAGE44
  J6T1  114 VSS<58> SCONN288_H44441003_PIP-SCONN,HA   I139 @BASEBOARD_FAB2_LIB.BASEBOARD_FAB2(SCH_1):PAGE44
  J6T1  112 VSS<59> SCONN288_H44441003_PIP-SCONN,HA   I139 @BASEBOARD_FAB2_LIB.BASEBOARD_FAB2(SCH_1):PAGE44
  J6T1  109 VSS<60> SCONN288_H44441003_PIP-SCONN,HA   I139 @BASEBOARD_FAB2_LIB.BASEBOARD_FAB2(SCH_1):PAGE44
  J6T1  107 VSS<61> SCONN288_H44441003_PIP-SCONN,HA   I139 @BASEBOARD_FAB2_LIB.BASEBOARD_FAB2(SCH_1):PAGE44
  J6T1  105 VSS<62> SCONN288_H44441003_PIP-SCONN,HA   I139 @BASEBOARD_FAB2_LIB.BASEBOARD_FAB2(SCH_1):PAGE44
  J6T1  103 VSS<63> SCONN288_H44441003_PIP-SCONN,HA   I139 @BASEBOARD_FAB2_LIB.BASEBOARD_FAB2(SCH_1):PAGE44
  J6T1  101 VSS<64> SCONN288_H44441003_PIP-SCONN,HA   I139 @BASEBOARD_FAB2_LIB.BASEBOARD_FAB2(SCH_1):PAGE44
  J6T1   98 VSS<65> SCONN288_H44441003_PIP-SCONN,HA   I139 @BASEBOARD_FAB2_LIB.BASEBOARD_FAB2(SCH_1):PAGE44
  J6T1   96 VSS<66> SCONN288_H44441003_PIP-SCONN,HA   I139 @BASEBOARD_FAB2_LIB.BASEBOARD_FAB2(SCH_1):PAGE44
  J6T1   94 VSS<67> SCONN288_H44441003_PIP-SCONN,HA   I139 @BASEBOARD_FAB2_LIB.BASEBOARD_FAB2(SCH_1):PAGE44
  J6T1   57 VSS<68> SCONN288_H44441003_PIP-SCONN,HA   I139 @BASEBOARD_FAB2_LIB.BASEBOARD_FAB2(SCH_1):PAGE44
  J6T1   55 VSS<69> SCONN288_H44441003_PIP-SCONN,HA   I139 @BASEBOARD_FAB2_LIB.BASEBOARD_FAB2(SCH_1):PAGE44
  J6T1   53 VSS<70> SCONN288_H44441003_PIP-SCONN,HA   I139 @BASEBOARD_FAB2_LIB.BASEBOARD_FAB2(SCH_1):PAGE44
  J6T1   50 VSS<71> SCONN288_H44441003_PIP-SCONN,HA   I139 @BASEBOARD_FAB2_LIB.BASEBOARD_FAB2(SCH_1):PAGE44
  J6T1   48 VSS<72> SCONN288_H44441003_PIP-SCONN,HA   I139 @BASEBOARD_FAB2_LIB.BASEBOARD_FAB2(SCH_1):PAGE44
  J6T1   46 VSS<73> SCONN288_H44441003_PIP-SCONN,HA   I139 @BASEBOARD_FAB2_LIB.BASEBOARD_FAB2(SCH_1):PAGE44
  J6T1   44 VSS<74> SCONN288_H44441003_PIP-SCONN,HA   I139 @BASEBOARD_FAB2_LIB.BASEBOARD_FAB2(SCH_1):PAGE44
  J6T1   42 VSS<75> SCONN288_H44441003_PIP-SCONN,HA   I139 @BASEBOARD_FAB2_LIB.BASEBOARD_FAB2(SCH_1):PAGE44
  J6T1   39 VSS<76> SCONN288_H44441003_PIP-SCONN,HA   I139 @BASEBOARD_FAB2_LIB.BASEBOARD_FAB2(SCH_1):PAGE44
  J6T1   37 VSS<77> SCONN288_H44441003_PIP-SCONN,HA   I139 @BASEBOARD_FAB2_LIB.BASEBOARD_FAB2(SCH_1):PAGE44
  J6T1   35 VSS<78> SCONN288_H44441003_PIP-SCONN,HA   I139 @BASEBOARD_FAB2_LIB.BASEBOARD_FAB2(SCH_1):PAGE44
  J6T1   33 VSS<79> SCONN288_H44441003_PIP-SCONN,HA   I139 @BASEBOARD_FAB2_LIB.BASEBOARD_FAB2(SCH_1):PAGE44
  J6T1   31 VSS<80> SCONN288_H44441003_PIP-SCONN,HA   I139 @BASEBOARD_FAB2_LIB.BASEBOARD_FAB2(SCH_1):PAGE44
  J6T1   28 VSS<81> SCONN288_H44441003_PIP-SCONN,HA   I139 @BASEBOARD_FAB2_LIB.BASEBOARD_FAB2(SCH_1):PAGE44
  J6T1   26 VSS<82> SCONN288_H44441003_PIP-SCONN,HA   I139 @BASEBOARD_FAB2_LIB.BASEBOARD_FAB2(SCH_1):PAGE44
  J6T1   24 VSS<83> SCONN288_H44441003_PIP-SCONN,HA   I139 @BASEBOARD_FAB2_LIB.BASEBOARD_FAB2(SCH_1):PAGE44
  J6T1   22 VSS<84> SCONN288_H44441003_PIP-SCONN,HA   I139 @BASEBOARD_FAB2_LIB.BASEBOARD_FAB2(SCH_1):PAGE44
  J6T1   20 VSS<85> SCONN288_H44441003_PIP-SCONN,HA   I139 @BASEBOARD_FAB2_LIB.BASEBOARD_FAB2(SCH_1):PAGE44
  J6T1   17 VSS<86> SCONN288_H44441003_PIP-SCONN,HA   I139 @BASEBOARD_FAB2_LIB.BASEBOARD_FAB2(SCH_1):PAGE44
  J6T1   15 VSS<87> SCONN288_H44441003_PIP-SCONN,HA   I139 @BASEBOARD_FAB2_LIB.BASEBOARD_FAB2(SCH_1):PAGE44
  J6T1   13 VSS<88> SCONN288_H44441003_PIP-SCONN,HA   I139 @BASEBOARD_FAB2_LIB.BASEBOARD_FAB2(SCH_1):PAGE44
  J6T1   11 VSS<89> SCONN288_H44441003_PIP-SCONN,HA   I139 @BASEBOARD_FAB2_LIB.BASEBOARD_FAB2(SCH_1):PAGE44
  J6T1    9 VSS<90> SCONN288_H44441003_PIP-SCONN,HA   I139 @BASEBOARD_FAB2_LIB.BASEBOARD_FAB2(SCH_1):PAGE44
  J6T1    6 VSS<91> SCONN288_H44441003_PIP-SCONN,HA   I139 @BASEBOARD_FAB2_LIB.BASEBOARD_FAB2(SCH_1):PAGE44
  J6T1    4 VSS<92> SCONN288_H44441003_PIP-SCONN,HA   I139 @BASEBOARD_FAB2_LIB.BASEBOARD_FAB2(SCH_1):PAGE44
  J6T1    2 VSS<93> SCONN288_H44441003_PIP-SCONN,HA   I139 @BASEBOARD_FAB2_LIB.BASEBOARD_FAB2(SCH_1):PAGE44
  J4G2  283 VSS<0> SCONN288_H44441004_PIP-SCONN,HA    I43 @BASEBOARD_FAB2_LIB.BASEBOARD_FAB2(SCH_1):PAGE45
  J4G2  281 VSS<1> SCONN288_H44441004_PIP-SCONN,HA    I43 @BASEBOARD_FAB2_LIB.BASEBOARD_FAB2(SCH_1):PAGE45
  J4G2  279 VSS<2> SCONN288_H44441004_PIP-SCONN,HA    I43 @BASEBOARD_FAB2_LIB.BASEBOARD_FAB2(SCH_1):PAGE45
  J4G2  276 VSS<3> SCONN288_H44441004_PIP-SCONN,HA    I43 @BASEBOARD_FAB2_LIB.BASEBOARD_FAB2(SCH_1):PAGE45
  J4G2  274 VSS<4> SCONN288_H44441004_PIP-SCONN,HA    I43 @BASEBOARD_FAB2_LIB.BASEBOARD_FAB2(SCH_1):PAGE45
  J4G2  272 VSS<5> SCONN288_H44441004_PIP-SCONN,HA    I43 @BASEBOARD_FAB2_LIB.BASEBOARD_FAB2(SCH_1):PAGE45
  J4G2  270 VSS<6> SCONN288_H44441004_PIP-SCONN,HA    I43 @BASEBOARD_FAB2_LIB.BASEBOARD_FAB2(SCH_1):PAGE45
  J4G2  268 VSS<7> SCONN288_H44441004_PIP-SCONN,HA    I43 @BASEBOARD_FAB2_LIB.BASEBOARD_FAB2(SCH_1):PAGE45
  J4G2  265 VSS<8> SCONN288_H44441004_PIP-SCONN,HA    I43 @BASEBOARD_FAB2_LIB.BASEBOARD_FAB2(SCH_1):PAGE45
  J4G2  263 VSS<9> SCONN288_H44441004_PIP-SCONN,HA    I43 @BASEBOARD_FAB2_LIB.BASEBOARD_FAB2(SCH_1):PAGE45
  J4G2  261 VSS<10> SCONN288_H44441004_PIP-SCONN,HA    I43 @BASEBOARD_FAB2_LIB.BASEBOARD_FAB2(SCH_1):PAGE45
  J4G2  259 VSS<11> SCONN288_H44441004_PIP-SCONN,HA    I43 @BASEBOARD_FAB2_LIB.BASEBOARD_FAB2(SCH_1):PAGE45
  J4G2  257 VSS<12> SCONN288_H44441004_PIP-SCONN,HA    I43 @BASEBOARD_FAB2_LIB.BASEBOARD_FAB2(SCH_1):PAGE45
  J4G2  254 VSS<13> SCONN288_H44441004_PIP-SCONN,HA    I43 @BASEBOARD_FAB2_LIB.BASEBOARD_FAB2(SCH_1):PAGE45
  J4G2  252 VSS<14> SCONN288_H44441004_PIP-SCONN,HA    I43 @BASEBOARD_FAB2_LIB.BASEBOARD_FAB2(SCH_1):PAGE45
  J4G2  250 VSS<15> SCONN288_H44441004_PIP-SCONN,HA    I43 @BASEBOARD_FAB2_LIB.BASEBOARD_FAB2(SCH_1):PAGE45
  J4G2  248 VSS<16> SCONN288_H44441004_PIP-SCONN,HA    I43 @BASEBOARD_FAB2_LIB.BASEBOARD_FAB2(SCH_1):PAGE45
  J4G2  246 VSS<17> SCONN288_H44441004_PIP-SCONN,HA    I43 @BASEBOARD_FAB2_LIB.BASEBOARD_FAB2(SCH_1):PAGE45
  J4G2  243 VSS<18> SCONN288_H44441004_PIP-SCONN,HA    I43 @BASEBOARD_FAB2_LIB.BASEBOARD_FAB2(SCH_1):PAGE45
  J4G2  241 VSS<19> SCONN288_H44441004_PIP-SCONN,HA    I43 @BASEBOARD_FAB2_LIB.BASEBOARD_FAB2(SCH_1):PAGE45
  J4G2  239 VSS<20> SCONN288_H44441004_PIP-SCONN,HA    I43 @BASEBOARD_FAB2_LIB.BASEBOARD_FAB2(SCH_1):PAGE45
  J4G2  202 VSS<21> SCONN288_H44441004_PIP-SCONN,HA    I43 @BASEBOARD_FAB2_LIB.BASEBOARD_FAB2(SCH_1):PAGE45
  J4G2  200 VSS<22> SCONN288_H44441004_PIP-SCONN,HA    I43 @BASEBOARD_FAB2_LIB.BASEBOARD_FAB2(SCH_1):PAGE45
  J4G2  198 VSS<23> SCONN288_H44441004_PIP-SCONN,HA    I43 @BASEBOARD_FAB2_LIB.BASEBOARD_FAB2(SCH_1):PAGE45
  J4G2  195 VSS<24> SCONN288_H44441004_PIP-SCONN,HA    I43 @BASEBOARD_FAB2_LIB.BASEBOARD_FAB2(SCH_1):PAGE45
  J4G2  193 VSS<25> SCONN288_H44441004_PIP-SCONN,HA    I43 @BASEBOARD_FAB2_LIB.BASEBOARD_FAB2(SCH_1):PAGE45
  J4G2  191 VSS<26> SCONN288_H44441004_PIP-SCONN,HA    I43 @BASEBOARD_FAB2_LIB.BASEBOARD_FAB2(SCH_1):PAGE45
  J4G2  189 VSS<27> SCONN288_H44441004_PIP-SCONN,HA    I43 @BASEBOARD_FAB2_LIB.BASEBOARD_FAB2(SCH_1):PAGE45
  J4G2  187 VSS<28> SCONN288_H44441004_PIP-SCONN,HA    I43 @BASEBOARD_FAB2_LIB.BASEBOARD_FAB2(SCH_1):PAGE45
  J4G2  184 VSS<29> SCONN288_H44441004_PIP-SCONN,HA    I43 @BASEBOARD_FAB2_LIB.BASEBOARD_FAB2(SCH_1):PAGE45
  J4G2  182 VSS<30> SCONN288_H44441004_PIP-SCONN,HA    I43 @BASEBOARD_FAB2_LIB.BASEBOARD_FAB2(SCH_1):PAGE45
  J4G2  180 VSS<31> SCONN288_H44441004_PIP-SCONN,HA    I43 @BASEBOARD_FAB2_LIB.BASEBOARD_FAB2(SCH_1):PAGE45
  J4G2  178 VSS<32> SCONN288_H44441004_PIP-SCONN,HA    I43 @BASEBOARD_FAB2_LIB.BASEBOARD_FAB2(SCH_1):PAGE45
  J4G2  176 VSS<33> SCONN288_H44441004_PIP-SCONN,HA    I43 @BASEBOARD_FAB2_LIB.BASEBOARD_FAB2(SCH_1):PAGE45
  J4G2  173 VSS<34> SCONN288_H44441004_PIP-SCONN,HA    I43 @BASEBOARD_FAB2_LIB.BASEBOARD_FAB2(SCH_1):PAGE45
  J4G2  171 VSS<35> SCONN288_H44441004_PIP-SCONN,HA    I43 @BASEBOARD_FAB2_LIB.BASEBOARD_FAB2(SCH_1):PAGE45
  J4G2  169 VSS<36> SCONN288_H44441004_PIP-SCONN,HA    I43 @BASEBOARD_FAB2_LIB.BASEBOARD_FAB2(SCH_1):PAGE45
  J4G2  167 VSS<37> SCONN288_H44441004_PIP-SCONN,HA    I43 @BASEBOARD_FAB2_LIB.BASEBOARD_FAB2(SCH_1):PAGE45
  J4G2  165 VSS<38> SCONN288_H44441004_PIP-SCONN,HA    I43 @BASEBOARD_FAB2_LIB.BASEBOARD_FAB2(SCH_1):PAGE45
  J4G2  162 VSS<39> SCONN288_H44441004_PIP-SCONN,HA    I43 @BASEBOARD_FAB2_LIB.BASEBOARD_FAB2(SCH_1):PAGE45
  J4G2  160 VSS<40> SCONN288_H44441004_PIP-SCONN,HA    I43 @BASEBOARD_FAB2_LIB.BASEBOARD_FAB2(SCH_1):PAGE45
  J4G2  158 VSS<41> SCONN288_H44441004_PIP-SCONN,HA    I43 @BASEBOARD_FAB2_LIB.BASEBOARD_FAB2(SCH_1):PAGE45
  J4G2  156 VSS<42> SCONN288_H44441004_PIP-SCONN,HA    I43 @BASEBOARD_FAB2_LIB.BASEBOARD_FAB2(SCH_1):PAGE45
  J4G2  154 VSS<43> SCONN288_H44441004_PIP-SCONN,HA    I43 @BASEBOARD_FAB2_LIB.BASEBOARD_FAB2(SCH_1):PAGE45
  J4G2  151 VSS<44> SCONN288_H44441004_PIP-SCONN,HA    I43 @BASEBOARD_FAB2_LIB.BASEBOARD_FAB2(SCH_1):PAGE45
  J4G2  149 VSS<45> SCONN288_H44441004_PIP-SCONN,HA    I43 @BASEBOARD_FAB2_LIB.BASEBOARD_FAB2(SCH_1):PAGE45
  J4G2  147 VSS<46> SCONN288_H44441004_PIP-SCONN,HA    I43 @BASEBOARD_FAB2_LIB.BASEBOARD_FAB2(SCH_1):PAGE45
  J4G2  138 VSS<47> SCONN288_H44441004_PIP-SCONN,HA    I43 @BASEBOARD_FAB2_LIB.BASEBOARD_FAB2(SCH_1):PAGE45
  J4G2  136 VSS<48> SCONN288_H44441004_PIP-SCONN,HA    I43 @BASEBOARD_FAB2_LIB.BASEBOARD_FAB2(SCH_1):PAGE45
  J4G2  134 VSS<49> SCONN288_H44441004_PIP-SCONN,HA    I43 @BASEBOARD_FAB2_LIB.BASEBOARD_FAB2(SCH_1):PAGE45
  J4G2  131 VSS<50> SCONN288_H44441004_PIP-SCONN,HA    I43 @BASEBOARD_FAB2_LIB.BASEBOARD_FAB2(SCH_1):PAGE45
  J4G2  129 VSS<51> SCONN288_H44441004_PIP-SCONN,HA    I43 @BASEBOARD_FAB2_LIB.BASEBOARD_FAB2(SCH_1):PAGE45
  J4G2  127 VSS<52> SCONN288_H44441004_PIP-SCONN,HA    I43 @BASEBOARD_FAB2_LIB.BASEBOARD_FAB2(SCH_1):PAGE45
  J4G2  125 VSS<53> SCONN288_H44441004_PIP-SCONN,HA    I43 @BASEBOARD_FAB2_LIB.BASEBOARD_FAB2(SCH_1):PAGE45
  J4G2  123 VSS<54> SCONN288_H44441004_PIP-SCONN,HA    I43 @BASEBOARD_FAB2_LIB.BASEBOARD_FAB2(SCH_1):PAGE45
  J4G2  120 VSS<55> SCONN288_H44441004_PIP-SCONN,HA    I43 @BASEBOARD_FAB2_LIB.BASEBOARD_FAB2(SCH_1):PAGE45
  J4G2  118 VSS<56> SCONN288_H44441004_PIP-SCONN,HA    I43 @BASEBOARD_FAB2_LIB.BASEBOARD_FAB2(SCH_1):PAGE45
  J4G2  116 VSS<57> SCONN288_H44441004_PIP-SCONN,HA    I43 @BASEBOARD_FAB2_LIB.BASEBOARD_FAB2(SCH_1):PAGE45
  J4G2  114 VSS<58> SCONN288_H44441004_PIP-SCONN,HA    I43 @BASEBOARD_FAB2_LIB.BASEBOARD_FAB2(SCH_1):PAGE45
  J4G2  112 VSS<59> SCONN288_H44441004_PIP-SCONN,HA    I43 @BASEBOARD_FAB2_LIB.BASEBOARD_FAB2(SCH_1):PAGE45
  J4G2  109 VSS<60> SCONN288_H44441004_PIP-SCONN,HA    I43 @BASEBOARD_FAB2_LIB.BASEBOARD_FAB2(SCH_1):PAGE45
  J4G2  107 VSS<61> SCONN288_H44441004_PIP-SCONN,HA    I43 @BASEBOARD_FAB2_LIB.BASEBOARD_FAB2(SCH_1):PAGE45
  J4G2  105 VSS<62> SCONN288_H44441004_PIP-SCONN,HA    I43 @BASEBOARD_FAB2_LIB.BASEBOARD_FAB2(SCH_1):PAGE45
  J4G2  103 VSS<63> SCONN288_H44441004_PIP-SCONN,HA    I43 @BASEBOARD_FAB2_LIB.BASEBOARD_FAB2(SCH_1):PAGE45
  J4G2  101 VSS<64> SCONN288_H44441004_PIP-SCONN,HA    I43 @BASEBOARD_FAB2_LIB.BASEBOARD_FAB2(SCH_1):PAGE45
  J4G2   98 VSS<65> SCONN288_H44441004_PIP-SCONN,HA    I43 @BASEBOARD_FAB2_LIB.BASEBOARD_FAB2(SCH_1):PAGE45
  J4G2   96 VSS<66> SCONN288_H44441004_PIP-SCONN,HA    I43 @BASEBOARD_FAB2_LIB.BASEBOARD_FAB2(SCH_1):PAGE45
  J4G2   94 VSS<67> SCONN288_H44441004_PIP-SCONN,HA    I43 @BASEBOARD_FAB2_LIB.BASEBOARD_FAB2(SCH_1):PAGE45
  J4G2   57 VSS<68> SCONN288_H44441004_PIP-SCONN,HA    I43 @BASEBOARD_FAB2_LIB.BASEBOARD_FAB2(SCH_1):PAGE45
  J4G2   55 VSS<69> SCONN288_H44441004_PIP-SCONN,HA    I43 @BASEBOARD_FAB2_LIB.BASEBOARD_FAB2(SCH_1):PAGE45
  J4G2   53 VSS<70> SCONN288_H44441004_PIP-SCONN,HA    I43 @BASEBOARD_FAB2_LIB.BASEBOARD_FAB2(SCH_1):PAGE45
  J4G2   50 VSS<71> SCONN288_H44441004_PIP-SCONN,HA    I43 @BASEBOARD_FAB2_LIB.BASEBOARD_FAB2(SCH_1):PAGE45
  J4G2   48 VSS<72> SCONN288_H44441004_PIP-SCONN,HA    I43 @BASEBOARD_FAB2_LIB.BASEBOARD_FAB2(SCH_1):PAGE45
  J4G2   46 VSS<73> SCONN288_H44441004_PIP-SCONN,HA    I43 @BASEBOARD_FAB2_LIB.BASEBOARD_FAB2(SCH_1):PAGE45
  J4G2   44 VSS<74> SCONN288_H44441004_PIP-SCONN,HA    I43 @BASEBOARD_FAB2_LIB.BASEBOARD_FAB2(SCH_1):PAGE45
  J4G2   42 VSS<75> SCONN288_H44441004_PIP-SCONN,HA    I43 @BASEBOARD_FAB2_LIB.BASEBOARD_FAB2(SCH_1):PAGE45
  J4G2   39 VSS<76> SCONN288_H44441004_PIP-SCONN,HA    I43 @BASEBOARD_FAB2_LIB.BASEBOARD_FAB2(SCH_1):PAGE45
  J4G2   37 VSS<77> SCONN288_H44441004_PIP-SCONN,HA    I43 @BASEBOARD_FAB2_LIB.BASEBOARD_FAB2(SCH_1):PAGE45
  J4G2   35 VSS<78> SCONN288_H44441004_PIP-SCONN,HA    I43 @BASEBOARD_FAB2_LIB.BASEBOARD_FAB2(SCH_1):PAGE45
  J4G2   33 VSS<79> SCONN288_H44441004_PIP-SCONN,HA    I43 @BASEBOARD_FAB2_LIB.BASEBOARD_FAB2(SCH_1):PAGE45
  J4G2   31 VSS<80> SCONN288_H44441004_PIP-SCONN,HA    I43 @BASEBOARD_FAB2_LIB.BASEBOARD_FAB2(SCH_1):PAGE45
  J4G2   28 VSS<81> SCONN288_H44441004_PIP-SCONN,HA    I43 @BASEBOARD_FAB2_LIB.BASEBOARD_FAB2(SCH_1):PAGE45
  J4G2   26 VSS<82> SCONN288_H44441004_PIP-SCONN,HA    I43 @BASEBOARD_FAB2_LIB.BASEBOARD_FAB2(SCH_1):PAGE45
  J4G2   24 VSS<83> SCONN288_H44441004_PIP-SCONN,HA    I43 @BASEBOARD_FAB2_LIB.BASEBOARD_FAB2(SCH_1):PAGE45
  J4G2   22 VSS<84> SCONN288_H44441004_PIP-SCONN,HA    I43 @BASEBOARD_FAB2_LIB.BASEBOARD_FAB2(SCH_1):PAGE45
  J4G2   20 VSS<85> SCONN288_H44441004_PIP-SCONN,HA    I43 @BASEBOARD_FAB2_LIB.BASEBOARD_FAB2(SCH_1):PAGE45
  J4G2   17 VSS<86> SCONN288_H44441004_PIP-SCONN,HA    I43 @BASEBOARD_FAB2_LIB.BASEBOARD_FAB2(SCH_1):PAGE45
  J4G2   15 VSS<87> SCONN288_H44441004_PIP-SCONN,HA    I43 @BASEBOARD_FAB2_LIB.BASEBOARD_FAB2(SCH_1):PAGE45
  J4G2   13 VSS<88> SCONN288_H44441004_PIP-SCONN,HA    I43 @BASEBOARD_FAB2_LIB.BASEBOARD_FAB2(SCH_1):PAGE45
  J4G2   11 VSS<89> SCONN288_H44441004_PIP-SCONN,HA    I43 @BASEBOARD_FAB2_LIB.BASEBOARD_FAB2(SCH_1):PAGE45
  J4G2    9 VSS<90> SCONN288_H44441004_PIP-SCONN,HA    I43 @BASEBOARD_FAB2_LIB.BASEBOARD_FAB2(SCH_1):PAGE45
  J4G2    6 VSS<91> SCONN288_H44441004_PIP-SCONN,HA    I43 @BASEBOARD_FAB2_LIB.BASEBOARD_FAB2(SCH_1):PAGE45
  J4G2    4 VSS<92> SCONN288_H44441004_PIP-SCONN,HA    I43 @BASEBOARD_FAB2_LIB.BASEBOARD_FAB2(SCH_1):PAGE45
  J4G2    2 VSS<93> SCONN288_H44441004_PIP-SCONN,HA    I43 @BASEBOARD_FAB2_LIB.BASEBOARD_FAB2(SCH_1):PAGE45
  J4G2  139  SA<0> SCONN288_H44441004_PIP-SCONN,HA   I111 @BASEBOARD_FAB2_LIB.BASEBOARD_FAB2(SCH_1):PAGE45
  J4G2  238  SA<2> SCONN288_H44441004_PIP-SCONN,HA   I111 @BASEBOARD_FAB2_LIB.BASEBOARD_FAB2(SCH_1):PAGE45
  C4G3    2      B CAP_A_0402V-0.01UF,25V,10%,X7RA   I179 @BASEBOARD_FAB2_LIB.BASEBOARD_FAB2(SCH_1):PAGE45
  C6U9    2      B CAP_A_0402V-0.01UF,25V,10%,X7RA     I5 @BASEBOARD_FAB2_LIB.BASEBOARD_FAB2(SCH_1):PAGE46
  J6U1  238  SA<2> SCONN288_H44441003_PIP-SCONN,HA    I14 @BASEBOARD_FAB2_LIB.BASEBOARD_FAB2(SCH_1):PAGE46
  J6U1  283 VSS<0> SCONN288_H44441003_PIP-SCONN,HA   I138 @BASEBOARD_FAB2_LIB.BASEBOARD_FAB2(SCH_1):PAGE46
  J6U1  281 VSS<1> SCONN288_H44441003_PIP-SCONN,HA   I138 @BASEBOARD_FAB2_LIB.BASEBOARD_FAB2(SCH_1):PAGE46
  J6U1  279 VSS<2> SCONN288_H44441003_PIP-SCONN,HA   I138 @BASEBOARD_FAB2_LIB.BASEBOARD_FAB2(SCH_1):PAGE46
  J6U1  276 VSS<3> SCONN288_H44441003_PIP-SCONN,HA   I138 @BASEBOARD_FAB2_LIB.BASEBOARD_FAB2(SCH_1):PAGE46
  J6U1  274 VSS<4> SCONN288_H44441003_PIP-SCONN,HA   I138 @BASEBOARD_FAB2_LIB.BASEBOARD_FAB2(SCH_1):PAGE46
  J6U1  272 VSS<5> SCONN288_H44441003_PIP-SCONN,HA   I138 @BASEBOARD_FAB2_LIB.BASEBOARD_FAB2(SCH_1):PAGE46
  J6U1  270 VSS<6> SCONN288_H44441003_PIP-SCONN,HA   I138 @BASEBOARD_FAB2_LIB.BASEBOARD_FAB2(SCH_1):PAGE46
  J6U1  268 VSS<7> SCONN288_H44441003_PIP-SCONN,HA   I138 @BASEBOARD_FAB2_LIB.BASEBOARD_FAB2(SCH_1):PAGE46
  J6U1  265 VSS<8> SCONN288_H44441003_PIP-SCONN,HA   I138 @BASEBOARD_FAB2_LIB.BASEBOARD_FAB2(SCH_1):PAGE46
  J6U1  263 VSS<9> SCONN288_H44441003_PIP-SCONN,HA   I138 @BASEBOARD_FAB2_LIB.BASEBOARD_FAB2(SCH_1):PAGE46
  J6U1  261 VSS<10> SCONN288_H44441003_PIP-SCONN,HA   I138 @BASEBOARD_FAB2_LIB.BASEBOARD_FAB2(SCH_1):PAGE46
  J6U1  259 VSS<11> SCONN288_H44441003_PIP-SCONN,HA   I138 @BASEBOARD_FAB2_LIB.BASEBOARD_FAB2(SCH_1):PAGE46
  J6U1  257 VSS<12> SCONN288_H44441003_PIP-SCONN,HA   I138 @BASEBOARD_FAB2_LIB.BASEBOARD_FAB2(SCH_1):PAGE46
  J6U1  254 VSS<13> SCONN288_H44441003_PIP-SCONN,HA   I138 @BASEBOARD_FAB2_LIB.BASEBOARD_FAB2(SCH_1):PAGE46
  J6U1  252 VSS<14> SCONN288_H44441003_PIP-SCONN,HA   I138 @BASEBOARD_FAB2_LIB.BASEBOARD_FAB2(SCH_1):PAGE46
  J6U1  250 VSS<15> SCONN288_H44441003_PIP-SCONN,HA   I138 @BASEBOARD_FAB2_LIB.BASEBOARD_FAB2(SCH_1):PAGE46
  J6U1  248 VSS<16> SCONN288_H44441003_PIP-SCONN,HA   I138 @BASEBOARD_FAB2_LIB.BASEBOARD_FAB2(SCH_1):PAGE46
  J6U1  246 VSS<17> SCONN288_H44441003_PIP-SCONN,HA   I138 @BASEBOARD_FAB2_LIB.BASEBOARD_FAB2(SCH_1):PAGE46
  J6U1  243 VSS<18> SCONN288_H44441003_PIP-SCONN,HA   I138 @BASEBOARD_FAB2_LIB.BASEBOARD_FAB2(SCH_1):PAGE46
  J6U1  241 VSS<19> SCONN288_H44441003_PIP-SCONN,HA   I138 @BASEBOARD_FAB2_LIB.BASEBOARD_FAB2(SCH_1):PAGE46
  J6U1  239 VSS<20> SCONN288_H44441003_PIP-SCONN,HA   I138 @BASEBOARD_FAB2_LIB.BASEBOARD_FAB2(SCH_1):PAGE46
  J6U1  202 VSS<21> SCONN288_H44441003_PIP-SCONN,HA   I138 @BASEBOARD_FAB2_LIB.BASEBOARD_FAB2(SCH_1):PAGE46
  J6U1  200 VSS<22> SCONN288_H44441003_PIP-SCONN,HA   I138 @BASEBOARD_FAB2_LIB.BASEBOARD_FAB2(SCH_1):PAGE46
  J6U1  198 VSS<23> SCONN288_H44441003_PIP-SCONN,HA   I138 @BASEBOARD_FAB2_LIB.BASEBOARD_FAB2(SCH_1):PAGE46
  J6U1  195 VSS<24> SCONN288_H44441003_PIP-SCONN,HA   I138 @BASEBOARD_FAB2_LIB.BASEBOARD_FAB2(SCH_1):PAGE46
  J6U1  193 VSS<25> SCONN288_H44441003_PIP-SCONN,HA   I138 @BASEBOARD_FAB2_LIB.BASEBOARD_FAB2(SCH_1):PAGE46
  J6U1  191 VSS<26> SCONN288_H44441003_PIP-SCONN,HA   I138 @BASEBOARD_FAB2_LIB.BASEBOARD_FAB2(SCH_1):PAGE46
  J6U1  189 VSS<27> SCONN288_H44441003_PIP-SCONN,HA   I138 @BASEBOARD_FAB2_LIB.BASEBOARD_FAB2(SCH_1):PAGE46
  J6U1  187 VSS<28> SCONN288_H44441003_PIP-SCONN,HA   I138 @BASEBOARD_FAB2_LIB.BASEBOARD_FAB2(SCH_1):PAGE46
  J6U1  184 VSS<29> SCONN288_H44441003_PIP-SCONN,HA   I138 @BASEBOARD_FAB2_LIB.BASEBOARD_FAB2(SCH_1):PAGE46
  J6U1  182 VSS<30> SCONN288_H44441003_PIP-SCONN,HA   I138 @BASEBOARD_FAB2_LIB.BASEBOARD_FAB2(SCH_1):PAGE46
  J6U1  180 VSS<31> SCONN288_H44441003_PIP-SCONN,HA   I138 @BASEBOARD_FAB2_LIB.BASEBOARD_FAB2(SCH_1):PAGE46
  J6U1  178 VSS<32> SCONN288_H44441003_PIP-SCONN,HA   I138 @BASEBOARD_FAB2_LIB.BASEBOARD_FAB2(SCH_1):PAGE46
  J6U1  176 VSS<33> SCONN288_H44441003_PIP-SCONN,HA   I138 @BASEBOARD_FAB2_LIB.BASEBOARD_FAB2(SCH_1):PAGE46
  J6U1  173 VSS<34> SCONN288_H44441003_PIP-SCONN,HA   I138 @BASEBOARD_FAB2_LIB.BASEBOARD_FAB2(SCH_1):PAGE46
  J6U1  171 VSS<35> SCONN288_H44441003_PIP-SCONN,HA   I138 @BASEBOARD_FAB2_LIB.BASEBOARD_FAB2(SCH_1):PAGE46
  J6U1  169 VSS<36> SCONN288_H44441003_PIP-SCONN,HA   I138 @BASEBOARD_FAB2_LIB.BASEBOARD_FAB2(SCH_1):PAGE46
  J6U1  167 VSS<37> SCONN288_H44441003_PIP-SCONN,HA   I138 @BASEBOARD_FAB2_LIB.BASEBOARD_FAB2(SCH_1):PAGE46
  J6U1  165 VSS<38> SCONN288_H44441003_PIP-SCONN,HA   I138 @BASEBOARD_FAB2_LIB.BASEBOARD_FAB2(SCH_1):PAGE46
  J6U1  162 VSS<39> SCONN288_H44441003_PIP-SCONN,HA   I138 @BASEBOARD_FAB2_LIB.BASEBOARD_FAB2(SCH_1):PAGE46
  J6U1  160 VSS<40> SCONN288_H44441003_PIP-SCONN,HA   I138 @BASEBOARD_FAB2_LIB.BASEBOARD_FAB2(SCH_1):PAGE46
  J6U1  158 VSS<41> SCONN288_H44441003_PIP-SCONN,HA   I138 @BASEBOARD_FAB2_LIB.BASEBOARD_FAB2(SCH_1):PAGE46
  J6U1  156 VSS<42> SCONN288_H44441003_PIP-SCONN,HA   I138 @BASEBOARD_FAB2_LIB.BASEBOARD_FAB2(SCH_1):PAGE46
  J6U1  154 VSS<43> SCONN288_H44441003_PIP-SCONN,HA   I138 @BASEBOARD_FAB2_LIB.BASEBOARD_FAB2(SCH_1):PAGE46
  J6U1  151 VSS<44> SCONN288_H44441003_PIP-SCONN,HA   I138 @BASEBOARD_FAB2_LIB.BASEBOARD_FAB2(SCH_1):PAGE46
  J6U1  149 VSS<45> SCONN288_H44441003_PIP-SCONN,HA   I138 @BASEBOARD_FAB2_LIB.BASEBOARD_FAB2(SCH_1):PAGE46
  J6U1  147 VSS<46> SCONN288_H44441003_PIP-SCONN,HA   I138 @BASEBOARD_FAB2_LIB.BASEBOARD_FAB2(SCH_1):PAGE46
  J6U1  138 VSS<47> SCONN288_H44441003_PIP-SCONN,HA   I138 @BASEBOARD_FAB2_LIB.BASEBOARD_FAB2(SCH_1):PAGE46
  J6U1  136 VSS<48> SCONN288_H44441003_PIP-SCONN,HA   I138 @BASEBOARD_FAB2_LIB.BASEBOARD_FAB2(SCH_1):PAGE46
  J6U1  134 VSS<49> SCONN288_H44441003_PIP-SCONN,HA   I138 @BASEBOARD_FAB2_LIB.BASEBOARD_FAB2(SCH_1):PAGE46
  J6U1  131 VSS<50> SCONN288_H44441003_PIP-SCONN,HA   I138 @BASEBOARD_FAB2_LIB.BASEBOARD_FAB2(SCH_1):PAGE46
  J6U1  129 VSS<51> SCONN288_H44441003_PIP-SCONN,HA   I138 @BASEBOARD_FAB2_LIB.BASEBOARD_FAB2(SCH_1):PAGE46
  J6U1  127 VSS<52> SCONN288_H44441003_PIP-SCONN,HA   I138 @BASEBOARD_FAB2_LIB.BASEBOARD_FAB2(SCH_1):PAGE46
  J6U1  125 VSS<53> SCONN288_H44441003_PIP-SCONN,HA   I138 @BASEBOARD_FAB2_LIB.BASEBOARD_FAB2(SCH_1):PAGE46
  J6U1  123 VSS<54> SCONN288_H44441003_PIP-SCONN,HA   I138 @BASEBOARD_FAB2_LIB.BASEBOARD_FAB2(SCH_1):PAGE46
  J6U1  120 VSS<55> SCONN288_H44441003_PIP-SCONN,HA   I138 @BASEBOARD_FAB2_LIB.BASEBOARD_FAB2(SCH_1):PAGE46
  J6U1  118 VSS<56> SCONN288_H44441003_PIP-SCONN,HA   I138 @BASEBOARD_FAB2_LIB.BASEBOARD_FAB2(SCH_1):PAGE46
  J6U1  116 VSS<57> SCONN288_H44441003_PIP-SCONN,HA   I138 @BASEBOARD_FAB2_LIB.BASEBOARD_FAB2(SCH_1):PAGE46
  J6U1  114 VSS<58> SCONN288_H44441003_PIP-SCONN,HA   I138 @BASEBOARD_FAB2_LIB.BASEBOARD_FAB2(SCH_1):PAGE46
  J6U1  112 VSS<59> SCONN288_H44441003_PIP-SCONN,HA   I138 @BASEBOARD_FAB2_LIB.BASEBOARD_FAB2(SCH_1):PAGE46
  J6U1  109 VSS<60> SCONN288_H44441003_PIP-SCONN,HA   I138 @BASEBOARD_FAB2_LIB.BASEBOARD_FAB2(SCH_1):PAGE46
  J6U1  107 VSS<61> SCONN288_H44441003_PIP-SCONN,HA   I138 @BASEBOARD_FAB2_LIB.BASEBOARD_FAB2(SCH_1):PAGE46
  J6U1  105 VSS<62> SCONN288_H44441003_PIP-SCONN,HA   I138 @BASEBOARD_FAB2_LIB.BASEBOARD_FAB2(SCH_1):PAGE46
  J6U1  103 VSS<63> SCONN288_H44441003_PIP-SCONN,HA   I138 @BASEBOARD_FAB2_LIB.BASEBOARD_FAB2(SCH_1):PAGE46
  J6U1  101 VSS<64> SCONN288_H44441003_PIP-SCONN,HA   I138 @BASEBOARD_FAB2_LIB.BASEBOARD_FAB2(SCH_1):PAGE46
  J6U1   98 VSS<65> SCONN288_H44441003_PIP-SCONN,HA   I138 @BASEBOARD_FAB2_LIB.BASEBOARD_FAB2(SCH_1):PAGE46
  J6U1   96 VSS<66> SCONN288_H44441003_PIP-SCONN,HA   I138 @BASEBOARD_FAB2_LIB.BASEBOARD_FAB2(SCH_1):PAGE46
  J6U1   94 VSS<67> SCONN288_H44441003_PIP-SCONN,HA   I138 @BASEBOARD_FAB2_LIB.BASEBOARD_FAB2(SCH_1):PAGE46
  J6U1   57 VSS<68> SCONN288_H44441003_PIP-SCONN,HA   I138 @BASEBOARD_FAB2_LIB.BASEBOARD_FAB2(SCH_1):PAGE46
  J6U1   55 VSS<69> SCONN288_H44441003_PIP-SCONN,HA   I138 @BASEBOARD_FAB2_LIB.BASEBOARD_FAB2(SCH_1):PAGE46
  J6U1   53 VSS<70> SCONN288_H44441003_PIP-SCONN,HA   I138 @BASEBOARD_FAB2_LIB.BASEBOARD_FAB2(SCH_1):PAGE46
  J6U1   50 VSS<71> SCONN288_H44441003_PIP-SCONN,HA   I138 @BASEBOARD_FAB2_LIB.BASEBOARD_FAB2(SCH_1):PAGE46
  J6U1   48 VSS<72> SCONN288_H44441003_PIP-SCONN,HA   I138 @BASEBOARD_FAB2_LIB.BASEBOARD_FAB2(SCH_1):PAGE46
  J6U1   46 VSS<73> SCONN288_H44441003_PIP-SCONN,HA   I138 @BASEBOARD_FAB2_LIB.BASEBOARD_FAB2(SCH_1):PAGE46
  J6U1   44 VSS<74> SCONN288_H44441003_PIP-SCONN,HA   I138 @BASEBOARD_FAB2_LIB.BASEBOARD_FAB2(SCH_1):PAGE46
  J6U1   42 VSS<75> SCONN288_H44441003_PIP-SCONN,HA   I138 @BASEBOARD_FAB2_LIB.BASEBOARD_FAB2(SCH_1):PAGE46
  J6U1   39 VSS<76> SCONN288_H44441003_PIP-SCONN,HA   I138 @BASEBOARD_FAB2_LIB.BASEBOARD_FAB2(SCH_1):PAGE46
  J6U1   37 VSS<77> SCONN288_H44441003_PIP-SCONN,HA   I138 @BASEBOARD_FAB2_LIB.BASEBOARD_FAB2(SCH_1):PAGE46
  J6U1   35 VSS<78> SCONN288_H44441003_PIP-SCONN,HA   I138 @BASEBOARD_FAB2_LIB.BASEBOARD_FAB2(SCH_1):PAGE46
  J6U1   33 VSS<79> SCONN288_H44441003_PIP-SCONN,HA   I138 @BASEBOARD_FAB2_LIB.BASEBOARD_FAB2(SCH_1):PAGE46
  J6U1   31 VSS<80> SCONN288_H44441003_PIP-SCONN,HA   I138 @BASEBOARD_FAB2_LIB.BASEBOARD_FAB2(SCH_1):PAGE46
  J6U1   28 VSS<81> SCONN288_H44441003_PIP-SCONN,HA   I138 @BASEBOARD_FAB2_LIB.BASEBOARD_FAB2(SCH_1):PAGE46
  J6U1   26 VSS<82> SCONN288_H44441003_PIP-SCONN,HA   I138 @BASEBOARD_FAB2_LIB.BASEBOARD_FAB2(SCH_1):PAGE46
  J6U1   24 VSS<83> SCONN288_H44441003_PIP-SCONN,HA   I138 @BASEBOARD_FAB2_LIB.BASEBOARD_FAB2(SCH_1):PAGE46
  J6U1   22 VSS<84> SCONN288_H44441003_PIP-SCONN,HA   I138 @BASEBOARD_FAB2_LIB.BASEBOARD_FAB2(SCH_1):PAGE46
  J6U1   20 VSS<85> SCONN288_H44441003_PIP-SCONN,HA   I138 @BASEBOARD_FAB2_LIB.BASEBOARD_FAB2(SCH_1):PAGE46
  J6U1   17 VSS<86> SCONN288_H44441003_PIP-SCONN,HA   I138 @BASEBOARD_FAB2_LIB.BASEBOARD_FAB2(SCH_1):PAGE46
  J6U1   15 VSS<87> SCONN288_H44441003_PIP-SCONN,HA   I138 @BASEBOARD_FAB2_LIB.BASEBOARD_FAB2(SCH_1):PAGE46
  J6U1   13 VSS<88> SCONN288_H44441003_PIP-SCONN,HA   I138 @BASEBOARD_FAB2_LIB.BASEBOARD_FAB2(SCH_1):PAGE46
  J6U1   11 VSS<89> SCONN288_H44441003_PIP-SCONN,HA   I138 @BASEBOARD_FAB2_LIB.BASEBOARD_FAB2(SCH_1):PAGE46
  J6U1    9 VSS<90> SCONN288_H44441003_PIP-SCONN,HA   I138 @BASEBOARD_FAB2_LIB.BASEBOARD_FAB2(SCH_1):PAGE46
  J6U1    6 VSS<91> SCONN288_H44441003_PIP-SCONN,HA   I138 @BASEBOARD_FAB2_LIB.BASEBOARD_FAB2(SCH_1):PAGE46
  J6U1    4 VSS<92> SCONN288_H44441003_PIP-SCONN,HA   I138 @BASEBOARD_FAB2_LIB.BASEBOARD_FAB2(SCH_1):PAGE46
  J6U1    2 VSS<93> SCONN288_H44441003_PIP-SCONN,HA   I138 @BASEBOARD_FAB2_LIB.BASEBOARD_FAB2(SCH_1):PAGE46
  J4G3  283 VSS<0> SCONN288_H44441004_PIP-SCONN,HA    I43 @BASEBOARD_FAB2_LIB.BASEBOARD_FAB2(SCH_1):PAGE47
  J4G3  281 VSS<1> SCONN288_H44441004_PIP-SCONN,HA    I43 @BASEBOARD_FAB2_LIB.BASEBOARD_FAB2(SCH_1):PAGE47
  J4G3  279 VSS<2> SCONN288_H44441004_PIP-SCONN,HA    I43 @BASEBOARD_FAB2_LIB.BASEBOARD_FAB2(SCH_1):PAGE47
  J4G3  276 VSS<3> SCONN288_H44441004_PIP-SCONN,HA    I43 @BASEBOARD_FAB2_LIB.BASEBOARD_FAB2(SCH_1):PAGE47
  J4G3  274 VSS<4> SCONN288_H44441004_PIP-SCONN,HA    I43 @BASEBOARD_FAB2_LIB.BASEBOARD_FAB2(SCH_1):PAGE47
  J4G3  272 VSS<5> SCONN288_H44441004_PIP-SCONN,HA    I43 @BASEBOARD_FAB2_LIB.BASEBOARD_FAB2(SCH_1):PAGE47
  J4G3  270 VSS<6> SCONN288_H44441004_PIP-SCONN,HA    I43 @BASEBOARD_FAB2_LIB.BASEBOARD_FAB2(SCH_1):PAGE47
  J4G3  268 VSS<7> SCONN288_H44441004_PIP-SCONN,HA    I43 @BASEBOARD_FAB2_LIB.BASEBOARD_FAB2(SCH_1):PAGE47
  J4G3  265 VSS<8> SCONN288_H44441004_PIP-SCONN,HA    I43 @BASEBOARD_FAB2_LIB.BASEBOARD_FAB2(SCH_1):PAGE47
  J4G3  263 VSS<9> SCONN288_H44441004_PIP-SCONN,HA    I43 @BASEBOARD_FAB2_LIB.BASEBOARD_FAB2(SCH_1):PAGE47
  J4G3  261 VSS<10> SCONN288_H44441004_PIP-SCONN,HA    I43 @BASEBOARD_FAB2_LIB.BASEBOARD_FAB2(SCH_1):PAGE47
  J4G3  259 VSS<11> SCONN288_H44441004_PIP-SCONN,HA    I43 @BASEBOARD_FAB2_LIB.BASEBOARD_FAB2(SCH_1):PAGE47
  J4G3  257 VSS<12> SCONN288_H44441004_PIP-SCONN,HA    I43 @BASEBOARD_FAB2_LIB.BASEBOARD_FAB2(SCH_1):PAGE47
  J4G3  254 VSS<13> SCONN288_H44441004_PIP-SCONN,HA    I43 @BASEBOARD_FAB2_LIB.BASEBOARD_FAB2(SCH_1):PAGE47
  J4G3  252 VSS<14> SCONN288_H44441004_PIP-SCONN,HA    I43 @BASEBOARD_FAB2_LIB.BASEBOARD_FAB2(SCH_1):PAGE47
  J4G3  250 VSS<15> SCONN288_H44441004_PIP-SCONN,HA    I43 @BASEBOARD_FAB2_LIB.BASEBOARD_FAB2(SCH_1):PAGE47
  J4G3  248 VSS<16> SCONN288_H44441004_PIP-SCONN,HA    I43 @BASEBOARD_FAB2_LIB.BASEBOARD_FAB2(SCH_1):PAGE47
  J4G3  246 VSS<17> SCONN288_H44441004_PIP-SCONN,HA    I43 @BASEBOARD_FAB2_LIB.BASEBOARD_FAB2(SCH_1):PAGE47
  J4G3  243 VSS<18> SCONN288_H44441004_PIP-SCONN,HA    I43 @BASEBOARD_FAB2_LIB.BASEBOARD_FAB2(SCH_1):PAGE47
  J4G3  241 VSS<19> SCONN288_H44441004_PIP-SCONN,HA    I43 @BASEBOARD_FAB2_LIB.BASEBOARD_FAB2(SCH_1):PAGE47
  J4G3  239 VSS<20> SCONN288_H44441004_PIP-SCONN,HA    I43 @BASEBOARD_FAB2_LIB.BASEBOARD_FAB2(SCH_1):PAGE47
  J4G3  202 VSS<21> SCONN288_H44441004_PIP-SCONN,HA    I43 @BASEBOARD_FAB2_LIB.BASEBOARD_FAB2(SCH_1):PAGE47
  J4G3  200 VSS<22> SCONN288_H44441004_PIP-SCONN,HA    I43 @BASEBOARD_FAB2_LIB.BASEBOARD_FAB2(SCH_1):PAGE47
  J4G3  198 VSS<23> SCONN288_H44441004_PIP-SCONN,HA    I43 @BASEBOARD_FAB2_LIB.BASEBOARD_FAB2(SCH_1):PAGE47
  J4G3  195 VSS<24> SCONN288_H44441004_PIP-SCONN,HA    I43 @BASEBOARD_FAB2_LIB.BASEBOARD_FAB2(SCH_1):PAGE47
  J4G3  193 VSS<25> SCONN288_H44441004_PIP-SCONN,HA    I43 @BASEBOARD_FAB2_LIB.BASEBOARD_FAB2(SCH_1):PAGE47
  J4G3  191 VSS<26> SCONN288_H44441004_PIP-SCONN,HA    I43 @BASEBOARD_FAB2_LIB.BASEBOARD_FAB2(SCH_1):PAGE47
  J4G3  189 VSS<27> SCONN288_H44441004_PIP-SCONN,HA    I43 @BASEBOARD_FAB2_LIB.BASEBOARD_FAB2(SCH_1):PAGE47
  J4G3  187 VSS<28> SCONN288_H44441004_PIP-SCONN,HA    I43 @BASEBOARD_FAB2_LIB.BASEBOARD_FAB2(SCH_1):PAGE47
  J4G3  184 VSS<29> SCONN288_H44441004_PIP-SCONN,HA    I43 @BASEBOARD_FAB2_LIB.BASEBOARD_FAB2(SCH_1):PAGE47
  J4G3  182 VSS<30> SCONN288_H44441004_PIP-SCONN,HA    I43 @BASEBOARD_FAB2_LIB.BASEBOARD_FAB2(SCH_1):PAGE47
  J4G3  180 VSS<31> SCONN288_H44441004_PIP-SCONN,HA    I43 @BASEBOARD_FAB2_LIB.BASEBOARD_FAB2(SCH_1):PAGE47
  J4G3  178 VSS<32> SCONN288_H44441004_PIP-SCONN,HA    I43 @BASEBOARD_FAB2_LIB.BASEBOARD_FAB2(SCH_1):PAGE47
  J4G3  176 VSS<33> SCONN288_H44441004_PIP-SCONN,HA    I43 @BASEBOARD_FAB2_LIB.BASEBOARD_FAB2(SCH_1):PAGE47
  J4G3  173 VSS<34> SCONN288_H44441004_PIP-SCONN,HA    I43 @BASEBOARD_FAB2_LIB.BASEBOARD_FAB2(SCH_1):PAGE47
  J4G3  171 VSS<35> SCONN288_H44441004_PIP-SCONN,HA    I43 @BASEBOARD_FAB2_LIB.BASEBOARD_FAB2(SCH_1):PAGE47
  J4G3  169 VSS<36> SCONN288_H44441004_PIP-SCONN,HA    I43 @BASEBOARD_FAB2_LIB.BASEBOARD_FAB2(SCH_1):PAGE47
  J4G3  167 VSS<37> SCONN288_H44441004_PIP-SCONN,HA    I43 @BASEBOARD_FAB2_LIB.BASEBOARD_FAB2(SCH_1):PAGE47
  J4G3  165 VSS<38> SCONN288_H44441004_PIP-SCONN,HA    I43 @BASEBOARD_FAB2_LIB.BASEBOARD_FAB2(SCH_1):PAGE47
  J4G3  162 VSS<39> SCONN288_H44441004_PIP-SCONN,HA    I43 @BASEBOARD_FAB2_LIB.BASEBOARD_FAB2(SCH_1):PAGE47
  J4G3  160 VSS<40> SCONN288_H44441004_PIP-SCONN,HA    I43 @BASEBOARD_FAB2_LIB.BASEBOARD_FAB2(SCH_1):PAGE47
  J4G3  158 VSS<41> SCONN288_H44441004_PIP-SCONN,HA    I43 @BASEBOARD_FAB2_LIB.BASEBOARD_FAB2(SCH_1):PAGE47
  J4G3  156 VSS<42> SCONN288_H44441004_PIP-SCONN,HA    I43 @BASEBOARD_FAB2_LIB.BASEBOARD_FAB2(SCH_1):PAGE47
  J4G3  154 VSS<43> SCONN288_H44441004_PIP-SCONN,HA    I43 @BASEBOARD_FAB2_LIB.BASEBOARD_FAB2(SCH_1):PAGE47
  J4G3  151 VSS<44> SCONN288_H44441004_PIP-SCONN,HA    I43 @BASEBOARD_FAB2_LIB.BASEBOARD_FAB2(SCH_1):PAGE47
  J4G3  149 VSS<45> SCONN288_H44441004_PIP-SCONN,HA    I43 @BASEBOARD_FAB2_LIB.BASEBOARD_FAB2(SCH_1):PAGE47
  J4G3  147 VSS<46> SCONN288_H44441004_PIP-SCONN,HA    I43 @BASEBOARD_FAB2_LIB.BASEBOARD_FAB2(SCH_1):PAGE47
  J4G3  138 VSS<47> SCONN288_H44441004_PIP-SCONN,HA    I43 @BASEBOARD_FAB2_LIB.BASEBOARD_FAB2(SCH_1):PAGE47
  J4G3  136 VSS<48> SCONN288_H44441004_PIP-SCONN,HA    I43 @BASEBOARD_FAB2_LIB.BASEBOARD_FAB2(SCH_1):PAGE47
  J4G3  134 VSS<49> SCONN288_H44441004_PIP-SCONN,HA    I43 @BASEBOARD_FAB2_LIB.BASEBOARD_FAB2(SCH_1):PAGE47
  J4G3  131 VSS<50> SCONN288_H44441004_PIP-SCONN,HA    I43 @BASEBOARD_FAB2_LIB.BASEBOARD_FAB2(SCH_1):PAGE47
  J4G3  129 VSS<51> SCONN288_H44441004_PIP-SCONN,HA    I43 @BASEBOARD_FAB2_LIB.BASEBOARD_FAB2(SCH_1):PAGE47
  J4G3  127 VSS<52> SCONN288_H44441004_PIP-SCONN,HA    I43 @BASEBOARD_FAB2_LIB.BASEBOARD_FAB2(SCH_1):PAGE47
  J4G3  125 VSS<53> SCONN288_H44441004_PIP-SCONN,HA    I43 @BASEBOARD_FAB2_LIB.BASEBOARD_FAB2(SCH_1):PAGE47
  J4G3  123 VSS<54> SCONN288_H44441004_PIP-SCONN,HA    I43 @BASEBOARD_FAB2_LIB.BASEBOARD_FAB2(SCH_1):PAGE47
  J4G3  120 VSS<55> SCONN288_H44441004_PIP-SCONN,HA    I43 @BASEBOARD_FAB2_LIB.BASEBOARD_FAB2(SCH_1):PAGE47
  J4G3  118 VSS<56> SCONN288_H44441004_PIP-SCONN,HA    I43 @BASEBOARD_FAB2_LIB.BASEBOARD_FAB2(SCH_1):PAGE47
  J4G3  116 VSS<57> SCONN288_H44441004_PIP-SCONN,HA    I43 @BASEBOARD_FAB2_LIB.BASEBOARD_FAB2(SCH_1):PAGE47
  J4G3  114 VSS<58> SCONN288_H44441004_PIP-SCONN,HA    I43 @BASEBOARD_FAB2_LIB.BASEBOARD_FAB2(SCH_1):PAGE47
  J4G3  112 VSS<59> SCONN288_H44441004_PIP-SCONN,HA    I43 @BASEBOARD_FAB2_LIB.BASEBOARD_FAB2(SCH_1):PAGE47
  J4G3  109 VSS<60> SCONN288_H44441004_PIP-SCONN,HA    I43 @BASEBOARD_FAB2_LIB.BASEBOARD_FAB2(SCH_1):PAGE47
  J4G3  107 VSS<61> SCONN288_H44441004_PIP-SCONN,HA    I43 @BASEBOARD_FAB2_LIB.BASEBOARD_FAB2(SCH_1):PAGE47
  J4G3  105 VSS<62> SCONN288_H44441004_PIP-SCONN,HA    I43 @BASEBOARD_FAB2_LIB.BASEBOARD_FAB2(SCH_1):PAGE47
  J4G3  103 VSS<63> SCONN288_H44441004_PIP-SCONN,HA    I43 @BASEBOARD_FAB2_LIB.BASEBOARD_FAB2(SCH_1):PAGE47
  J4G3  101 VSS<64> SCONN288_H44441004_PIP-SCONN,HA    I43 @BASEBOARD_FAB2_LIB.BASEBOARD_FAB2(SCH_1):PAGE47
  J4G3   98 VSS<65> SCONN288_H44441004_PIP-SCONN,HA    I43 @BASEBOARD_FAB2_LIB.BASEBOARD_FAB2(SCH_1):PAGE47
  J4G3   96 VSS<66> SCONN288_H44441004_PIP-SCONN,HA    I43 @BASEBOARD_FAB2_LIB.BASEBOARD_FAB2(SCH_1):PAGE47
  J4G3   94 VSS<67> SCONN288_H44441004_PIP-SCONN,HA    I43 @BASEBOARD_FAB2_LIB.BASEBOARD_FAB2(SCH_1):PAGE47
  J4G3   57 VSS<68> SCONN288_H44441004_PIP-SCONN,HA    I43 @BASEBOARD_FAB2_LIB.BASEBOARD_FAB2(SCH_1):PAGE47
  J4G3   55 VSS<69> SCONN288_H44441004_PIP-SCONN,HA    I43 @BASEBOARD_FAB2_LIB.BASEBOARD_FAB2(SCH_1):PAGE47
  J4G3   53 VSS<70> SCONN288_H44441004_PIP-SCONN,HA    I43 @BASEBOARD_FAB2_LIB.BASEBOARD_FAB2(SCH_1):PAGE47
  J4G3   50 VSS<71> SCONN288_H44441004_PIP-SCONN,HA    I43 @BASEBOARD_FAB2_LIB.BASEBOARD_FAB2(SCH_1):PAGE47
  J4G3   48 VSS<72> SCONN288_H44441004_PIP-SCONN,HA    I43 @BASEBOARD_FAB2_LIB.BASEBOARD_FAB2(SCH_1):PAGE47
  J4G3   46 VSS<73> SCONN288_H44441004_PIP-SCONN,HA    I43 @BASEBOARD_FAB2_LIB.BASEBOARD_FAB2(SCH_1):PAGE47
  J4G3   44 VSS<74> SCONN288_H44441004_PIP-SCONN,HA    I43 @BASEBOARD_FAB2_LIB.BASEBOARD_FAB2(SCH_1):PAGE47
  J4G3   42 VSS<75> SCONN288_H44441004_PIP-SCONN,HA    I43 @BASEBOARD_FAB2_LIB.BASEBOARD_FAB2(SCH_1):PAGE47
  J4G3   39 VSS<76> SCONN288_H44441004_PIP-SCONN,HA    I43 @BASEBOARD_FAB2_LIB.BASEBOARD_FAB2(SCH_1):PAGE47
  J4G3   37 VSS<77> SCONN288_H44441004_PIP-SCONN,HA    I43 @BASEBOARD_FAB2_LIB.BASEBOARD_FAB2(SCH_1):PAGE47
  J4G3   35 VSS<78> SCONN288_H44441004_PIP-SCONN,HA    I43 @BASEBOARD_FAB2_LIB.BASEBOARD_FAB2(SCH_1):PAGE47
  J4G3   33 VSS<79> SCONN288_H44441004_PIP-SCONN,HA    I43 @BASEBOARD_FAB2_LIB.BASEBOARD_FAB2(SCH_1):PAGE47
  J4G3   31 VSS<80> SCONN288_H44441004_PIP-SCONN,HA    I43 @BASEBOARD_FAB2_LIB.BASEBOARD_FAB2(SCH_1):PAGE47
  J4G3   28 VSS<81> SCONN288_H44441004_PIP-SCONN,HA    I43 @BASEBOARD_FAB2_LIB.BASEBOARD_FAB2(SCH_1):PAGE47
  J4G3   26 VSS<82> SCONN288_H44441004_PIP-SCONN,HA    I43 @BASEBOARD_FAB2_LIB.BASEBOARD_FAB2(SCH_1):PAGE47
  J4G3   24 VSS<83> SCONN288_H44441004_PIP-SCONN,HA    I43 @BASEBOARD_FAB2_LIB.BASEBOARD_FAB2(SCH_1):PAGE47
  J4G3   22 VSS<84> SCONN288_H44441004_PIP-SCONN,HA    I43 @BASEBOARD_FAB2_LIB.BASEBOARD_FAB2(SCH_1):PAGE47
  J4G3   20 VSS<85> SCONN288_H44441004_PIP-SCONN,HA    I43 @BASEBOARD_FAB2_LIB.BASEBOARD_FAB2(SCH_1):PAGE47
  J4G3   17 VSS<86> SCONN288_H44441004_PIP-SCONN,HA    I43 @BASEBOARD_FAB2_LIB.BASEBOARD_FAB2(SCH_1):PAGE47
  J4G3   15 VSS<87> SCONN288_H44441004_PIP-SCONN,HA    I43 @BASEBOARD_FAB2_LIB.BASEBOARD_FAB2(SCH_1):PAGE47
  J4G3   13 VSS<88> SCONN288_H44441004_PIP-SCONN,HA    I43 @BASEBOARD_FAB2_LIB.BASEBOARD_FAB2(SCH_1):PAGE47
  J4G3   11 VSS<89> SCONN288_H44441004_PIP-SCONN,HA    I43 @BASEBOARD_FAB2_LIB.BASEBOARD_FAB2(SCH_1):PAGE47
  J4G3    9 VSS<90> SCONN288_H44441004_PIP-SCONN,HA    I43 @BASEBOARD_FAB2_LIB.BASEBOARD_FAB2(SCH_1):PAGE47
  J4G3    6 VSS<91> SCONN288_H44441004_PIP-SCONN,HA    I43 @BASEBOARD_FAB2_LIB.BASEBOARD_FAB2(SCH_1):PAGE47
  J4G3    4 VSS<92> SCONN288_H44441004_PIP-SCONN,HA    I43 @BASEBOARD_FAB2_LIB.BASEBOARD_FAB2(SCH_1):PAGE47
  J4G3    2 VSS<93> SCONN288_H44441004_PIP-SCONN,HA    I43 @BASEBOARD_FAB2_LIB.BASEBOARD_FAB2(SCH_1):PAGE47
  J4G3  139  SA<0> SCONN288_H44441004_PIP-SCONN,HA   I111 @BASEBOARD_FAB2_LIB.BASEBOARD_FAB2(SCH_1):PAGE47
  J4G3  140  SA<1> SCONN288_H44441004_PIP-SCONN,HA   I111 @BASEBOARD_FAB2_LIB.BASEBOARD_FAB2(SCH_1):PAGE47
 C4G19    2      B CAP_A_0402V-0.01UF,25V,10%,X7RA   I188 @BASEBOARD_FAB2_LIB.BASEBOARD_FAB2(SCH_1):PAGE47
  J6U2  283 VSS<0> SCONN288_H44441003_PIP-SCONN,HA    I43 @BASEBOARD_FAB2_LIB.BASEBOARD_FAB2(SCH_1):PAGE48
  J6U2  281 VSS<1> SCONN288_H44441003_PIP-SCONN,HA    I43 @BASEBOARD_FAB2_LIB.BASEBOARD_FAB2(SCH_1):PAGE48
  J6U2  279 VSS<2> SCONN288_H44441003_PIP-SCONN,HA    I43 @BASEBOARD_FAB2_LIB.BASEBOARD_FAB2(SCH_1):PAGE48
  J6U2  276 VSS<3> SCONN288_H44441003_PIP-SCONN,HA    I43 @BASEBOARD_FAB2_LIB.BASEBOARD_FAB2(SCH_1):PAGE48
  J6U2  274 VSS<4> SCONN288_H44441003_PIP-SCONN,HA    I43 @BASEBOARD_FAB2_LIB.BASEBOARD_FAB2(SCH_1):PAGE48
  J6U2  272 VSS<5> SCONN288_H44441003_PIP-SCONN,HA    I43 @BASEBOARD_FAB2_LIB.BASEBOARD_FAB2(SCH_1):PAGE48
  J6U2  270 VSS<6> SCONN288_H44441003_PIP-SCONN,HA    I43 @BASEBOARD_FAB2_LIB.BASEBOARD_FAB2(SCH_1):PAGE48
  J6U2  268 VSS<7> SCONN288_H44441003_PIP-SCONN,HA    I43 @BASEBOARD_FAB2_LIB.BASEBOARD_FAB2(SCH_1):PAGE48
  J6U2  265 VSS<8> SCONN288_H44441003_PIP-SCONN,HA    I43 @BASEBOARD_FAB2_LIB.BASEBOARD_FAB2(SCH_1):PAGE48
  J6U2  263 VSS<9> SCONN288_H44441003_PIP-SCONN,HA    I43 @BASEBOARD_FAB2_LIB.BASEBOARD_FAB2(SCH_1):PAGE48
  J6U2  261 VSS<10> SCONN288_H44441003_PIP-SCONN,HA    I43 @BASEBOARD_FAB2_LIB.BASEBOARD_FAB2(SCH_1):PAGE48
  J6U2  259 VSS<11> SCONN288_H44441003_PIP-SCONN,HA    I43 @BASEBOARD_FAB2_LIB.BASEBOARD_FAB2(SCH_1):PAGE48
  J6U2  257 VSS<12> SCONN288_H44441003_PIP-SCONN,HA    I43 @BASEBOARD_FAB2_LIB.BASEBOARD_FAB2(SCH_1):PAGE48
  J6U2  254 VSS<13> SCONN288_H44441003_PIP-SCONN,HA    I43 @BASEBOARD_FAB2_LIB.BASEBOARD_FAB2(SCH_1):PAGE48
  J6U2  252 VSS<14> SCONN288_H44441003_PIP-SCONN,HA    I43 @BASEBOARD_FAB2_LIB.BASEBOARD_FAB2(SCH_1):PAGE48
  J6U2  250 VSS<15> SCONN288_H44441003_PIP-SCONN,HA    I43 @BASEBOARD_FAB2_LIB.BASEBOARD_FAB2(SCH_1):PAGE48
  J6U2  248 VSS<16> SCONN288_H44441003_PIP-SCONN,HA    I43 @BASEBOARD_FAB2_LIB.BASEBOARD_FAB2(SCH_1):PAGE48
  J6U2  246 VSS<17> SCONN288_H44441003_PIP-SCONN,HA    I43 @BASEBOARD_FAB2_LIB.BASEBOARD_FAB2(SCH_1):PAGE48
  J6U2  243 VSS<18> SCONN288_H44441003_PIP-SCONN,HA    I43 @BASEBOARD_FAB2_LIB.BASEBOARD_FAB2(SCH_1):PAGE48
  J6U2  241 VSS<19> SCONN288_H44441003_PIP-SCONN,HA    I43 @BASEBOARD_FAB2_LIB.BASEBOARD_FAB2(SCH_1):PAGE48
  J6U2  239 VSS<20> SCONN288_H44441003_PIP-SCONN,HA    I43 @BASEBOARD_FAB2_LIB.BASEBOARD_FAB2(SCH_1):PAGE48
  J6U2  202 VSS<21> SCONN288_H44441003_PIP-SCONN,HA    I43 @BASEBOARD_FAB2_LIB.BASEBOARD_FAB2(SCH_1):PAGE48
  J6U2  200 VSS<22> SCONN288_H44441003_PIP-SCONN,HA    I43 @BASEBOARD_FAB2_LIB.BASEBOARD_FAB2(SCH_1):PAGE48
  J6U2  198 VSS<23> SCONN288_H44441003_PIP-SCONN,HA    I43 @BASEBOARD_FAB2_LIB.BASEBOARD_FAB2(SCH_1):PAGE48
  J6U2  195 VSS<24> SCONN288_H44441003_PIP-SCONN,HA    I43 @BASEBOARD_FAB2_LIB.BASEBOARD_FAB2(SCH_1):PAGE48
  J6U2  193 VSS<25> SCONN288_H44441003_PIP-SCONN,HA    I43 @BASEBOARD_FAB2_LIB.BASEBOARD_FAB2(SCH_1):PAGE48
  J6U2  191 VSS<26> SCONN288_H44441003_PIP-SCONN,HA    I43 @BASEBOARD_FAB2_LIB.BASEBOARD_FAB2(SCH_1):PAGE48
  J6U2  189 VSS<27> SCONN288_H44441003_PIP-SCONN,HA    I43 @BASEBOARD_FAB2_LIB.BASEBOARD_FAB2(SCH_1):PAGE48
  J6U2  187 VSS<28> SCONN288_H44441003_PIP-SCONN,HA    I43 @BASEBOARD_FAB2_LIB.BASEBOARD_FAB2(SCH_1):PAGE48
  J6U2  184 VSS<29> SCONN288_H44441003_PIP-SCONN,HA    I43 @BASEBOARD_FAB2_LIB.BASEBOARD_FAB2(SCH_1):PAGE48
  J6U2  182 VSS<30> SCONN288_H44441003_PIP-SCONN,HA    I43 @BASEBOARD_FAB2_LIB.BASEBOARD_FAB2(SCH_1):PAGE48
  J6U2  180 VSS<31> SCONN288_H44441003_PIP-SCONN,HA    I43 @BASEBOARD_FAB2_LIB.BASEBOARD_FAB2(SCH_1):PAGE48
  J6U2  178 VSS<32> SCONN288_H44441003_PIP-SCONN,HA    I43 @BASEBOARD_FAB2_LIB.BASEBOARD_FAB2(SCH_1):PAGE48
  J6U2  176 VSS<33> SCONN288_H44441003_PIP-SCONN,HA    I43 @BASEBOARD_FAB2_LIB.BASEBOARD_FAB2(SCH_1):PAGE48
  J6U2  173 VSS<34> SCONN288_H44441003_PIP-SCONN,HA    I43 @BASEBOARD_FAB2_LIB.BASEBOARD_FAB2(SCH_1):PAGE48
  J6U2  171 VSS<35> SCONN288_H44441003_PIP-SCONN,HA    I43 @BASEBOARD_FAB2_LIB.BASEBOARD_FAB2(SCH_1):PAGE48
  J6U2  169 VSS<36> SCONN288_H44441003_PIP-SCONN,HA    I43 @BASEBOARD_FAB2_LIB.BASEBOARD_FAB2(SCH_1):PAGE48
  J6U2  167 VSS<37> SCONN288_H44441003_PIP-SCONN,HA    I43 @BASEBOARD_FAB2_LIB.BASEBOARD_FAB2(SCH_1):PAGE48
  J6U2  165 VSS<38> SCONN288_H44441003_PIP-SCONN,HA    I43 @BASEBOARD_FAB2_LIB.BASEBOARD_FAB2(SCH_1):PAGE48
  J6U2  162 VSS<39> SCONN288_H44441003_PIP-SCONN,HA    I43 @BASEBOARD_FAB2_LIB.BASEBOARD_FAB2(SCH_1):PAGE48
  J6U2  160 VSS<40> SCONN288_H44441003_PIP-SCONN,HA    I43 @BASEBOARD_FAB2_LIB.BASEBOARD_FAB2(SCH_1):PAGE48
  J6U2  158 VSS<41> SCONN288_H44441003_PIP-SCONN,HA    I43 @BASEBOARD_FAB2_LIB.BASEBOARD_FAB2(SCH_1):PAGE48
  J6U2  156 VSS<42> SCONN288_H44441003_PIP-SCONN,HA    I43 @BASEBOARD_FAB2_LIB.BASEBOARD_FAB2(SCH_1):PAGE48
  J6U2  154 VSS<43> SCONN288_H44441003_PIP-SCONN,HA    I43 @BASEBOARD_FAB2_LIB.BASEBOARD_FAB2(SCH_1):PAGE48
  J6U2  151 VSS<44> SCONN288_H44441003_PIP-SCONN,HA    I43 @BASEBOARD_FAB2_LIB.BASEBOARD_FAB2(SCH_1):PAGE48
  J6U2  149 VSS<45> SCONN288_H44441003_PIP-SCONN,HA    I43 @BASEBOARD_FAB2_LIB.BASEBOARD_FAB2(SCH_1):PAGE48
  J6U2  147 VSS<46> SCONN288_H44441003_PIP-SCONN,HA    I43 @BASEBOARD_FAB2_LIB.BASEBOARD_FAB2(SCH_1):PAGE48
  J6U2  138 VSS<47> SCONN288_H44441003_PIP-SCONN,HA    I43 @BASEBOARD_FAB2_LIB.BASEBOARD_FAB2(SCH_1):PAGE48
  J6U2  136 VSS<48> SCONN288_H44441003_PIP-SCONN,HA    I43 @BASEBOARD_FAB2_LIB.BASEBOARD_FAB2(SCH_1):PAGE48
  J6U2  134 VSS<49> SCONN288_H44441003_PIP-SCONN,HA    I43 @BASEBOARD_FAB2_LIB.BASEBOARD_FAB2(SCH_1):PAGE48
  J6U2  131 VSS<50> SCONN288_H44441003_PIP-SCONN,HA    I43 @BASEBOARD_FAB2_LIB.BASEBOARD_FAB2(SCH_1):PAGE48
  J6U2  129 VSS<51> SCONN288_H44441003_PIP-SCONN,HA    I43 @BASEBOARD_FAB2_LIB.BASEBOARD_FAB2(SCH_1):PAGE48
  J6U2  127 VSS<52> SCONN288_H44441003_PIP-SCONN,HA    I43 @BASEBOARD_FAB2_LIB.BASEBOARD_FAB2(SCH_1):PAGE48
  J6U2  125 VSS<53> SCONN288_H44441003_PIP-SCONN,HA    I43 @BASEBOARD_FAB2_LIB.BASEBOARD_FAB2(SCH_1):PAGE48
  J6U2  123 VSS<54> SCONN288_H44441003_PIP-SCONN,HA    I43 @BASEBOARD_FAB2_LIB.BASEBOARD_FAB2(SCH_1):PAGE48
  J6U2  120 VSS<55> SCONN288_H44441003_PIP-SCONN,HA    I43 @BASEBOARD_FAB2_LIB.BASEBOARD_FAB2(SCH_1):PAGE48
  J6U2  118 VSS<56> SCONN288_H44441003_PIP-SCONN,HA    I43 @BASEBOARD_FAB2_LIB.BASEBOARD_FAB2(SCH_1):PAGE48
  J6U2  116 VSS<57> SCONN288_H44441003_PIP-SCONN,HA    I43 @BASEBOARD_FAB2_LIB.BASEBOARD_FAB2(SCH_1):PAGE48
  J6U2  114 VSS<58> SCONN288_H44441003_PIP-SCONN,HA    I43 @BASEBOARD_FAB2_LIB.BASEBOARD_FAB2(SCH_1):PAGE48
  J6U2  112 VSS<59> SCONN288_H44441003_PIP-SCONN,HA    I43 @BASEBOARD_FAB2_LIB.BASEBOARD_FAB2(SCH_1):PAGE48
  J6U2  109 VSS<60> SCONN288_H44441003_PIP-SCONN,HA    I43 @BASEBOARD_FAB2_LIB.BASEBOARD_FAB2(SCH_1):PAGE48
  J6U2  107 VSS<61> SCONN288_H44441003_PIP-SCONN,HA    I43 @BASEBOARD_FAB2_LIB.BASEBOARD_FAB2(SCH_1):PAGE48
  J6U2  105 VSS<62> SCONN288_H44441003_PIP-SCONN,HA    I43 @BASEBOARD_FAB2_LIB.BASEBOARD_FAB2(SCH_1):PAGE48
  J6U2  103 VSS<63> SCONN288_H44441003_PIP-SCONN,HA    I43 @BASEBOARD_FAB2_LIB.BASEBOARD_FAB2(SCH_1):PAGE48
  J6U2  101 VSS<64> SCONN288_H44441003_PIP-SCONN,HA    I43 @BASEBOARD_FAB2_LIB.BASEBOARD_FAB2(SCH_1):PAGE48
  J6U2   98 VSS<65> SCONN288_H44441003_PIP-SCONN,HA    I43 @BASEBOARD_FAB2_LIB.BASEBOARD_FAB2(SCH_1):PAGE48
  J6U2   96 VSS<66> SCONN288_H44441003_PIP-SCONN,HA    I43 @BASEBOARD_FAB2_LIB.BASEBOARD_FAB2(SCH_1):PAGE48
  J6U2   94 VSS<67> SCONN288_H44441003_PIP-SCONN,HA    I43 @BASEBOARD_FAB2_LIB.BASEBOARD_FAB2(SCH_1):PAGE48
  J6U2   57 VSS<68> SCONN288_H44441003_PIP-SCONN,HA    I43 @BASEBOARD_FAB2_LIB.BASEBOARD_FAB2(SCH_1):PAGE48
  J6U2   55 VSS<69> SCONN288_H44441003_PIP-SCONN,HA    I43 @BASEBOARD_FAB2_LIB.BASEBOARD_FAB2(SCH_1):PAGE48
  J6U2   53 VSS<70> SCONN288_H44441003_PIP-SCONN,HA    I43 @BASEBOARD_FAB2_LIB.BASEBOARD_FAB2(SCH_1):PAGE48
  J6U2   50 VSS<71> SCONN288_H44441003_PIP-SCONN,HA    I43 @BASEBOARD_FAB2_LIB.BASEBOARD_FAB2(SCH_1):PAGE48
  J6U2   48 VSS<72> SCONN288_H44441003_PIP-SCONN,HA    I43 @BASEBOARD_FAB2_LIB.BASEBOARD_FAB2(SCH_1):PAGE48
  J6U2   46 VSS<73> SCONN288_H44441003_PIP-SCONN,HA    I43 @BASEBOARD_FAB2_LIB.BASEBOARD_FAB2(SCH_1):PAGE48
  J6U2   44 VSS<74> SCONN288_H44441003_PIP-SCONN,HA    I43 @BASEBOARD_FAB2_LIB.BASEBOARD_FAB2(SCH_1):PAGE48
  J6U2   42 VSS<75> SCONN288_H44441003_PIP-SCONN,HA    I43 @BASEBOARD_FAB2_LIB.BASEBOARD_FAB2(SCH_1):PAGE48
  J6U2   39 VSS<76> SCONN288_H44441003_PIP-SCONN,HA    I43 @BASEBOARD_FAB2_LIB.BASEBOARD_FAB2(SCH_1):PAGE48
  J6U2   37 VSS<77> SCONN288_H44441003_PIP-SCONN,HA    I43 @BASEBOARD_FAB2_LIB.BASEBOARD_FAB2(SCH_1):PAGE48
  J6U2   35 VSS<78> SCONN288_H44441003_PIP-SCONN,HA    I43 @BASEBOARD_FAB2_LIB.BASEBOARD_FAB2(SCH_1):PAGE48
  J6U2   33 VSS<79> SCONN288_H44441003_PIP-SCONN,HA    I43 @BASEBOARD_FAB2_LIB.BASEBOARD_FAB2(SCH_1):PAGE48
  J6U2   31 VSS<80> SCONN288_H44441003_PIP-SCONN,HA    I43 @BASEBOARD_FAB2_LIB.BASEBOARD_FAB2(SCH_1):PAGE48
  J6U2   28 VSS<81> SCONN288_H44441003_PIP-SCONN,HA    I43 @BASEBOARD_FAB2_LIB.BASEBOARD_FAB2(SCH_1):PAGE48
  J6U2   26 VSS<82> SCONN288_H44441003_PIP-SCONN,HA    I43 @BASEBOARD_FAB2_LIB.BASEBOARD_FAB2(SCH_1):PAGE48
  J6U2   24 VSS<83> SCONN288_H44441003_PIP-SCONN,HA    I43 @BASEBOARD_FAB2_LIB.BASEBOARD_FAB2(SCH_1):PAGE48
  J6U2   22 VSS<84> SCONN288_H44441003_PIP-SCONN,HA    I43 @BASEBOARD_FAB2_LIB.BASEBOARD_FAB2(SCH_1):PAGE48
  J6U2   20 VSS<85> SCONN288_H44441003_PIP-SCONN,HA    I43 @BASEBOARD_FAB2_LIB.BASEBOARD_FAB2(SCH_1):PAGE48
  J6U2   17 VSS<86> SCONN288_H44441003_PIP-SCONN,HA    I43 @BASEBOARD_FAB2_LIB.BASEBOARD_FAB2(SCH_1):PAGE48
  J6U2   15 VSS<87> SCONN288_H44441003_PIP-SCONN,HA    I43 @BASEBOARD_FAB2_LIB.BASEBOARD_FAB2(SCH_1):PAGE48
  J6U2   13 VSS<88> SCONN288_H44441003_PIP-SCONN,HA    I43 @BASEBOARD_FAB2_LIB.BASEBOARD_FAB2(SCH_1):PAGE48
  J6U2   11 VSS<89> SCONN288_H44441003_PIP-SCONN,HA    I43 @BASEBOARD_FAB2_LIB.BASEBOARD_FAB2(SCH_1):PAGE48
  J6U2    9 VSS<90> SCONN288_H44441003_PIP-SCONN,HA    I43 @BASEBOARD_FAB2_LIB.BASEBOARD_FAB2(SCH_1):PAGE48
  J6U2    6 VSS<91> SCONN288_H44441003_PIP-SCONN,HA    I43 @BASEBOARD_FAB2_LIB.BASEBOARD_FAB2(SCH_1):PAGE48
  J6U2    4 VSS<92> SCONN288_H44441003_PIP-SCONN,HA    I43 @BASEBOARD_FAB2_LIB.BASEBOARD_FAB2(SCH_1):PAGE48
  J6U2    2 VSS<93> SCONN288_H44441003_PIP-SCONN,HA    I43 @BASEBOARD_FAB2_LIB.BASEBOARD_FAB2(SCH_1):PAGE48
  J6U2  140  SA<1> SCONN288_H44441003_PIP-SCONN,HA   I111 @BASEBOARD_FAB2_LIB.BASEBOARD_FAB2(SCH_1):PAGE48
 C6U17    2      B CAP_A_0402V-0.01UF,25V,10%,X7RA   I176 @BASEBOARD_FAB2_LIB.BASEBOARD_FAB2(SCH_1):PAGE48
  J4B1  283 VSS<0> SCONN288_H44441004_PIP-SCONN,HA    I43 @BASEBOARD_FAB2_LIB.BASEBOARD_FAB2(SCH_1):PAGE49
  J4B1  281 VSS<1> SCONN288_H44441004_PIP-SCONN,HA    I43 @BASEBOARD_FAB2_LIB.BASEBOARD_FAB2(SCH_1):PAGE49
  J4B1  279 VSS<2> SCONN288_H44441004_PIP-SCONN,HA    I43 @BASEBOARD_FAB2_LIB.BASEBOARD_FAB2(SCH_1):PAGE49
  J4B1  276 VSS<3> SCONN288_H44441004_PIP-SCONN,HA    I43 @BASEBOARD_FAB2_LIB.BASEBOARD_FAB2(SCH_1):PAGE49
  J4B1  274 VSS<4> SCONN288_H44441004_PIP-SCONN,HA    I43 @BASEBOARD_FAB2_LIB.BASEBOARD_FAB2(SCH_1):PAGE49
  J4B1  272 VSS<5> SCONN288_H44441004_PIP-SCONN,HA    I43 @BASEBOARD_FAB2_LIB.BASEBOARD_FAB2(SCH_1):PAGE49
  J4B1  270 VSS<6> SCONN288_H44441004_PIP-SCONN,HA    I43 @BASEBOARD_FAB2_LIB.BASEBOARD_FAB2(SCH_1):PAGE49
  J4B1  268 VSS<7> SCONN288_H44441004_PIP-SCONN,HA    I43 @BASEBOARD_FAB2_LIB.BASEBOARD_FAB2(SCH_1):PAGE49
  J4B1  265 VSS<8> SCONN288_H44441004_PIP-SCONN,HA    I43 @BASEBOARD_FAB2_LIB.BASEBOARD_FAB2(SCH_1):PAGE49
  J4B1  263 VSS<9> SCONN288_H44441004_PIP-SCONN,HA    I43 @BASEBOARD_FAB2_LIB.BASEBOARD_FAB2(SCH_1):PAGE49
  J4B1  261 VSS<10> SCONN288_H44441004_PIP-SCONN,HA    I43 @BASEBOARD_FAB2_LIB.BASEBOARD_FAB2(SCH_1):PAGE49
  J4B1  259 VSS<11> SCONN288_H44441004_PIP-SCONN,HA    I43 @BASEBOARD_FAB2_LIB.BASEBOARD_FAB2(SCH_1):PAGE49
  J4B1  257 VSS<12> SCONN288_H44441004_PIP-SCONN,HA    I43 @BASEBOARD_FAB2_LIB.BASEBOARD_FAB2(SCH_1):PAGE49
  J4B1  254 VSS<13> SCONN288_H44441004_PIP-SCONN,HA    I43 @BASEBOARD_FAB2_LIB.BASEBOARD_FAB2(SCH_1):PAGE49
  J4B1  252 VSS<14> SCONN288_H44441004_PIP-SCONN,HA    I43 @BASEBOARD_FAB2_LIB.BASEBOARD_FAB2(SCH_1):PAGE49
  J4B1  250 VSS<15> SCONN288_H44441004_PIP-SCONN,HA    I43 @BASEBOARD_FAB2_LIB.BASEBOARD_FAB2(SCH_1):PAGE49
  J4B1  248 VSS<16> SCONN288_H44441004_PIP-SCONN,HA    I43 @BASEBOARD_FAB2_LIB.BASEBOARD_FAB2(SCH_1):PAGE49
  J4B1  246 VSS<17> SCONN288_H44441004_PIP-SCONN,HA    I43 @BASEBOARD_FAB2_LIB.BASEBOARD_FAB2(SCH_1):PAGE49
  J4B1  243 VSS<18> SCONN288_H44441004_PIP-SCONN,HA    I43 @BASEBOARD_FAB2_LIB.BASEBOARD_FAB2(SCH_1):PAGE49
  J4B1  241 VSS<19> SCONN288_H44441004_PIP-SCONN,HA    I43 @BASEBOARD_FAB2_LIB.BASEBOARD_FAB2(SCH_1):PAGE49
  J4B1  239 VSS<20> SCONN288_H44441004_PIP-SCONN,HA    I43 @BASEBOARD_FAB2_LIB.BASEBOARD_FAB2(SCH_1):PAGE49
  J4B1  202 VSS<21> SCONN288_H44441004_PIP-SCONN,HA    I43 @BASEBOARD_FAB2_LIB.BASEBOARD_FAB2(SCH_1):PAGE49
  J4B1  200 VSS<22> SCONN288_H44441004_PIP-SCONN,HA    I43 @BASEBOARD_FAB2_LIB.BASEBOARD_FAB2(SCH_1):PAGE49
  J4B1  198 VSS<23> SCONN288_H44441004_PIP-SCONN,HA    I43 @BASEBOARD_FAB2_LIB.BASEBOARD_FAB2(SCH_1):PAGE49
  J4B1  195 VSS<24> SCONN288_H44441004_PIP-SCONN,HA    I43 @BASEBOARD_FAB2_LIB.BASEBOARD_FAB2(SCH_1):PAGE49
  J4B1  193 VSS<25> SCONN288_H44441004_PIP-SCONN,HA    I43 @BASEBOARD_FAB2_LIB.BASEBOARD_FAB2(SCH_1):PAGE49
  J4B1  191 VSS<26> SCONN288_H44441004_PIP-SCONN,HA    I43 @BASEBOARD_FAB2_LIB.BASEBOARD_FAB2(SCH_1):PAGE49
  J4B1  189 VSS<27> SCONN288_H44441004_PIP-SCONN,HA    I43 @BASEBOARD_FAB2_LIB.BASEBOARD_FAB2(SCH_1):PAGE49
  J4B1  187 VSS<28> SCONN288_H44441004_PIP-SCONN,HA    I43 @BASEBOARD_FAB2_LIB.BASEBOARD_FAB2(SCH_1):PAGE49
  J4B1  184 VSS<29> SCONN288_H44441004_PIP-SCONN,HA    I43 @BASEBOARD_FAB2_LIB.BASEBOARD_FAB2(SCH_1):PAGE49
  J4B1  182 VSS<30> SCONN288_H44441004_PIP-SCONN,HA    I43 @BASEBOARD_FAB2_LIB.BASEBOARD_FAB2(SCH_1):PAGE49
  J4B1  180 VSS<31> SCONN288_H44441004_PIP-SCONN,HA    I43 @BASEBOARD_FAB2_LIB.BASEBOARD_FAB2(SCH_1):PAGE49
  J4B1  178 VSS<32> SCONN288_H44441004_PIP-SCONN,HA    I43 @BASEBOARD_FAB2_LIB.BASEBOARD_FAB2(SCH_1):PAGE49
  J4B1  176 VSS<33> SCONN288_H44441004_PIP-SCONN,HA    I43 @BASEBOARD_FAB2_LIB.BASEBOARD_FAB2(SCH_1):PAGE49
  J4B1  173 VSS<34> SCONN288_H44441004_PIP-SCONN,HA    I43 @BASEBOARD_FAB2_LIB.BASEBOARD_FAB2(SCH_1):PAGE49
  J4B1  171 VSS<35> SCONN288_H44441004_PIP-SCONN,HA    I43 @BASEBOARD_FAB2_LIB.BASEBOARD_FAB2(SCH_1):PAGE49
  J4B1  169 VSS<36> SCONN288_H44441004_PIP-SCONN,HA    I43 @BASEBOARD_FAB2_LIB.BASEBOARD_FAB2(SCH_1):PAGE49
  J4B1  167 VSS<37> SCONN288_H44441004_PIP-SCONN,HA    I43 @BASEBOARD_FAB2_LIB.BASEBOARD_FAB2(SCH_1):PAGE49
  J4B1  165 VSS<38> SCONN288_H44441004_PIP-SCONN,HA    I43 @BASEBOARD_FAB2_LIB.BASEBOARD_FAB2(SCH_1):PAGE49
  J4B1  162 VSS<39> SCONN288_H44441004_PIP-SCONN,HA    I43 @BASEBOARD_FAB2_LIB.BASEBOARD_FAB2(SCH_1):PAGE49
  J4B1  160 VSS<40> SCONN288_H44441004_PIP-SCONN,HA    I43 @BASEBOARD_FAB2_LIB.BASEBOARD_FAB2(SCH_1):PAGE49
  J4B1  158 VSS<41> SCONN288_H44441004_PIP-SCONN,HA    I43 @BASEBOARD_FAB2_LIB.BASEBOARD_FAB2(SCH_1):PAGE49
  J4B1  156 VSS<42> SCONN288_H44441004_PIP-SCONN,HA    I43 @BASEBOARD_FAB2_LIB.BASEBOARD_FAB2(SCH_1):PAGE49
  J4B1  154 VSS<43> SCONN288_H44441004_PIP-SCONN,HA    I43 @BASEBOARD_FAB2_LIB.BASEBOARD_FAB2(SCH_1):PAGE49
  J4B1  151 VSS<44> SCONN288_H44441004_PIP-SCONN,HA    I43 @BASEBOARD_FAB2_LIB.BASEBOARD_FAB2(SCH_1):PAGE49
  J4B1  149 VSS<45> SCONN288_H44441004_PIP-SCONN,HA    I43 @BASEBOARD_FAB2_LIB.BASEBOARD_FAB2(SCH_1):PAGE49
  J4B1  147 VSS<46> SCONN288_H44441004_PIP-SCONN,HA    I43 @BASEBOARD_FAB2_LIB.BASEBOARD_FAB2(SCH_1):PAGE49
  J4B1  138 VSS<47> SCONN288_H44441004_PIP-SCONN,HA    I43 @BASEBOARD_FAB2_LIB.BASEBOARD_FAB2(SCH_1):PAGE49
  J4B1  136 VSS<48> SCONN288_H44441004_PIP-SCONN,HA    I43 @BASEBOARD_FAB2_LIB.BASEBOARD_FAB2(SCH_1):PAGE49
  J4B1  134 VSS<49> SCONN288_H44441004_PIP-SCONN,HA    I43 @BASEBOARD_FAB2_LIB.BASEBOARD_FAB2(SCH_1):PAGE49
  J4B1  131 VSS<50> SCONN288_H44441004_PIP-SCONN,HA    I43 @BASEBOARD_FAB2_LIB.BASEBOARD_FAB2(SCH_1):PAGE49
  J4B1  129 VSS<51> SCONN288_H44441004_PIP-SCONN,HA    I43 @BASEBOARD_FAB2_LIB.BASEBOARD_FAB2(SCH_1):PAGE49
  J4B1  127 VSS<52> SCONN288_H44441004_PIP-SCONN,HA    I43 @BASEBOARD_FAB2_LIB.BASEBOARD_FAB2(SCH_1):PAGE49
  J4B1  125 VSS<53> SCONN288_H44441004_PIP-SCONN,HA    I43 @BASEBOARD_FAB2_LIB.BASEBOARD_FAB2(SCH_1):PAGE49
  J4B1  123 VSS<54> SCONN288_H44441004_PIP-SCONN,HA    I43 @BASEBOARD_FAB2_LIB.BASEBOARD_FAB2(SCH_1):PAGE49
  J4B1  120 VSS<55> SCONN288_H44441004_PIP-SCONN,HA    I43 @BASEBOARD_FAB2_LIB.BASEBOARD_FAB2(SCH_1):PAGE49
  J4B1  118 VSS<56> SCONN288_H44441004_PIP-SCONN,HA    I43 @BASEBOARD_FAB2_LIB.BASEBOARD_FAB2(SCH_1):PAGE49
  J4B1  116 VSS<57> SCONN288_H44441004_PIP-SCONN,HA    I43 @BASEBOARD_FAB2_LIB.BASEBOARD_FAB2(SCH_1):PAGE49
  J4B1  114 VSS<58> SCONN288_H44441004_PIP-SCONN,HA    I43 @BASEBOARD_FAB2_LIB.BASEBOARD_FAB2(SCH_1):PAGE49
  J4B1  112 VSS<59> SCONN288_H44441004_PIP-SCONN,HA    I43 @BASEBOARD_FAB2_LIB.BASEBOARD_FAB2(SCH_1):PAGE49
  J4B1  109 VSS<60> SCONN288_H44441004_PIP-SCONN,HA    I43 @BASEBOARD_FAB2_LIB.BASEBOARD_FAB2(SCH_1):PAGE49
  J4B1  107 VSS<61> SCONN288_H44441004_PIP-SCONN,HA    I43 @BASEBOARD_FAB2_LIB.BASEBOARD_FAB2(SCH_1):PAGE49
  J4B1  105 VSS<62> SCONN288_H44441004_PIP-SCONN,HA    I43 @BASEBOARD_FAB2_LIB.BASEBOARD_FAB2(SCH_1):PAGE49
  J4B1  103 VSS<63> SCONN288_H44441004_PIP-SCONN,HA    I43 @BASEBOARD_FAB2_LIB.BASEBOARD_FAB2(SCH_1):PAGE49
  J4B1  101 VSS<64> SCONN288_H44441004_PIP-SCONN,HA    I43 @BASEBOARD_FAB2_LIB.BASEBOARD_FAB2(SCH_1):PAGE49
  J4B1   98 VSS<65> SCONN288_H44441004_PIP-SCONN,HA    I43 @BASEBOARD_FAB2_LIB.BASEBOARD_FAB2(SCH_1):PAGE49
  J4B1   96 VSS<66> SCONN288_H44441004_PIP-SCONN,HA    I43 @BASEBOARD_FAB2_LIB.BASEBOARD_FAB2(SCH_1):PAGE49
  J4B1   94 VSS<67> SCONN288_H44441004_PIP-SCONN,HA    I43 @BASEBOARD_FAB2_LIB.BASEBOARD_FAB2(SCH_1):PAGE49
  J4B1   57 VSS<68> SCONN288_H44441004_PIP-SCONN,HA    I43 @BASEBOARD_FAB2_LIB.BASEBOARD_FAB2(SCH_1):PAGE49
  J4B1   55 VSS<69> SCONN288_H44441004_PIP-SCONN,HA    I43 @BASEBOARD_FAB2_LIB.BASEBOARD_FAB2(SCH_1):PAGE49
  J4B1   53 VSS<70> SCONN288_H44441004_PIP-SCONN,HA    I43 @BASEBOARD_FAB2_LIB.BASEBOARD_FAB2(SCH_1):PAGE49
  J4B1   50 VSS<71> SCONN288_H44441004_PIP-SCONN,HA    I43 @BASEBOARD_FAB2_LIB.BASEBOARD_FAB2(SCH_1):PAGE49
  J4B1   48 VSS<72> SCONN288_H44441004_PIP-SCONN,HA    I43 @BASEBOARD_FAB2_LIB.BASEBOARD_FAB2(SCH_1):PAGE49
  J4B1   46 VSS<73> SCONN288_H44441004_PIP-SCONN,HA    I43 @BASEBOARD_FAB2_LIB.BASEBOARD_FAB2(SCH_1):PAGE49
  J4B1   44 VSS<74> SCONN288_H44441004_PIP-SCONN,HA    I43 @BASEBOARD_FAB2_LIB.BASEBOARD_FAB2(SCH_1):PAGE49
  J4B1   42 VSS<75> SCONN288_H44441004_PIP-SCONN,HA    I43 @BASEBOARD_FAB2_LIB.BASEBOARD_FAB2(SCH_1):PAGE49
  J4B1   39 VSS<76> SCONN288_H44441004_PIP-SCONN,HA    I43 @BASEBOARD_FAB2_LIB.BASEBOARD_FAB2(SCH_1):PAGE49
  J4B1   37 VSS<77> SCONN288_H44441004_PIP-SCONN,HA    I43 @BASEBOARD_FAB2_LIB.BASEBOARD_FAB2(SCH_1):PAGE49
  J4B1   35 VSS<78> SCONN288_H44441004_PIP-SCONN,HA    I43 @BASEBOARD_FAB2_LIB.BASEBOARD_FAB2(SCH_1):PAGE49
  J4B1   33 VSS<79> SCONN288_H44441004_PIP-SCONN,HA    I43 @BASEBOARD_FAB2_LIB.BASEBOARD_FAB2(SCH_1):PAGE49
  J4B1   31 VSS<80> SCONN288_H44441004_PIP-SCONN,HA    I43 @BASEBOARD_FAB2_LIB.BASEBOARD_FAB2(SCH_1):PAGE49
  J4B1   28 VSS<81> SCONN288_H44441004_PIP-SCONN,HA    I43 @BASEBOARD_FAB2_LIB.BASEBOARD_FAB2(SCH_1):PAGE49
  J4B1   26 VSS<82> SCONN288_H44441004_PIP-SCONN,HA    I43 @BASEBOARD_FAB2_LIB.BASEBOARD_FAB2(SCH_1):PAGE49
  J4B1   24 VSS<83> SCONN288_H44441004_PIP-SCONN,HA    I43 @BASEBOARD_FAB2_LIB.BASEBOARD_FAB2(SCH_1):PAGE49
  J4B1   22 VSS<84> SCONN288_H44441004_PIP-SCONN,HA    I43 @BASEBOARD_FAB2_LIB.BASEBOARD_FAB2(SCH_1):PAGE49
  J4B1   20 VSS<85> SCONN288_H44441004_PIP-SCONN,HA    I43 @BASEBOARD_FAB2_LIB.BASEBOARD_FAB2(SCH_1):PAGE49
  J4B1   17 VSS<86> SCONN288_H44441004_PIP-SCONN,HA    I43 @BASEBOARD_FAB2_LIB.BASEBOARD_FAB2(SCH_1):PAGE49
  J4B1   15 VSS<87> SCONN288_H44441004_PIP-SCONN,HA    I43 @BASEBOARD_FAB2_LIB.BASEBOARD_FAB2(SCH_1):PAGE49
  J4B1   13 VSS<88> SCONN288_H44441004_PIP-SCONN,HA    I43 @BASEBOARD_FAB2_LIB.BASEBOARD_FAB2(SCH_1):PAGE49
  J4B1   11 VSS<89> SCONN288_H44441004_PIP-SCONN,HA    I43 @BASEBOARD_FAB2_LIB.BASEBOARD_FAB2(SCH_1):PAGE49
  J4B1    9 VSS<90> SCONN288_H44441004_PIP-SCONN,HA    I43 @BASEBOARD_FAB2_LIB.BASEBOARD_FAB2(SCH_1):PAGE49
  J4B1    6 VSS<91> SCONN288_H44441004_PIP-SCONN,HA    I43 @BASEBOARD_FAB2_LIB.BASEBOARD_FAB2(SCH_1):PAGE49
  J4B1    4 VSS<92> SCONN288_H44441004_PIP-SCONN,HA    I43 @BASEBOARD_FAB2_LIB.BASEBOARD_FAB2(SCH_1):PAGE49
  J4B1    2 VSS<93> SCONN288_H44441004_PIP-SCONN,HA    I43 @BASEBOARD_FAB2_LIB.BASEBOARD_FAB2(SCH_1):PAGE49
  J4B1  139  SA<0> SCONN288_H44441004_PIP-SCONN,HA   I111 @BASEBOARD_FAB2_LIB.BASEBOARD_FAB2(SCH_1):PAGE49
  J4B1  140  SA<1> SCONN288_H44441004_PIP-SCONN,HA   I111 @BASEBOARD_FAB2_LIB.BASEBOARD_FAB2(SCH_1):PAGE49
  J4B1  238  SA<2> SCONN288_H44441004_PIP-SCONN,HA   I111 @BASEBOARD_FAB2_LIB.BASEBOARD_FAB2(SCH_1):PAGE49
 C4B12    2      B CAP_A_0402V-0.01UF,25V,10%,X7RA   I179 @BASEBOARD_FAB2_LIB.BASEBOARD_FAB2(SCH_1):PAGE49
  J6M1  283 VSS<0> SCONN288_H44441003_PIP-SCONN,HA    I44 @BASEBOARD_FAB2_LIB.BASEBOARD_FAB2(SCH_1):PAGE50
  J6M1  281 VSS<1> SCONN288_H44441003_PIP-SCONN,HA    I44 @BASEBOARD_FAB2_LIB.BASEBOARD_FAB2(SCH_1):PAGE50
  J6M1  279 VSS<2> SCONN288_H44441003_PIP-SCONN,HA    I44 @BASEBOARD_FAB2_LIB.BASEBOARD_FAB2(SCH_1):PAGE50
  J6M1  276 VSS<3> SCONN288_H44441003_PIP-SCONN,HA    I44 @BASEBOARD_FAB2_LIB.BASEBOARD_FAB2(SCH_1):PAGE50
  J6M1  274 VSS<4> SCONN288_H44441003_PIP-SCONN,HA    I44 @BASEBOARD_FAB2_LIB.BASEBOARD_FAB2(SCH_1):PAGE50
  J6M1  272 VSS<5> SCONN288_H44441003_PIP-SCONN,HA    I44 @BASEBOARD_FAB2_LIB.BASEBOARD_FAB2(SCH_1):PAGE50
  J6M1  270 VSS<6> SCONN288_H44441003_PIP-SCONN,HA    I44 @BASEBOARD_FAB2_LIB.BASEBOARD_FAB2(SCH_1):PAGE50
  J6M1  268 VSS<7> SCONN288_H44441003_PIP-SCONN,HA    I44 @BASEBOARD_FAB2_LIB.BASEBOARD_FAB2(SCH_1):PAGE50
  J6M1  265 VSS<8> SCONN288_H44441003_PIP-SCONN,HA    I44 @BASEBOARD_FAB2_LIB.BASEBOARD_FAB2(SCH_1):PAGE50
  J6M1  263 VSS<9> SCONN288_H44441003_PIP-SCONN,HA    I44 @BASEBOARD_FAB2_LIB.BASEBOARD_FAB2(SCH_1):PAGE50
  J6M1  261 VSS<10> SCONN288_H44441003_PIP-SCONN,HA    I44 @BASEBOARD_FAB2_LIB.BASEBOARD_FAB2(SCH_1):PAGE50
  J6M1  259 VSS<11> SCONN288_H44441003_PIP-SCONN,HA    I44 @BASEBOARD_FAB2_LIB.BASEBOARD_FAB2(SCH_1):PAGE50
  J6M1  257 VSS<12> SCONN288_H44441003_PIP-SCONN,HA    I44 @BASEBOARD_FAB2_LIB.BASEBOARD_FAB2(SCH_1):PAGE50
  J6M1  254 VSS<13> SCONN288_H44441003_PIP-SCONN,HA    I44 @BASEBOARD_FAB2_LIB.BASEBOARD_FAB2(SCH_1):PAGE50
  J6M1  252 VSS<14> SCONN288_H44441003_PIP-SCONN,HA    I44 @BASEBOARD_FAB2_LIB.BASEBOARD_FAB2(SCH_1):PAGE50
  J6M1  250 VSS<15> SCONN288_H44441003_PIP-SCONN,HA    I44 @BASEBOARD_FAB2_LIB.BASEBOARD_FAB2(SCH_1):PAGE50
  J6M1  248 VSS<16> SCONN288_H44441003_PIP-SCONN,HA    I44 @BASEBOARD_FAB2_LIB.BASEBOARD_FAB2(SCH_1):PAGE50
  J6M1  246 VSS<17> SCONN288_H44441003_PIP-SCONN,HA    I44 @BASEBOARD_FAB2_LIB.BASEBOARD_FAB2(SCH_1):PAGE50
  J6M1  243 VSS<18> SCONN288_H44441003_PIP-SCONN,HA    I44 @BASEBOARD_FAB2_LIB.BASEBOARD_FAB2(SCH_1):PAGE50
  J6M1  241 VSS<19> SCONN288_H44441003_PIP-SCONN,HA    I44 @BASEBOARD_FAB2_LIB.BASEBOARD_FAB2(SCH_1):PAGE50
  J6M1  239 VSS<20> SCONN288_H44441003_PIP-SCONN,HA    I44 @BASEBOARD_FAB2_LIB.BASEBOARD_FAB2(SCH_1):PAGE50
  J6M1  202 VSS<21> SCONN288_H44441003_PIP-SCONN,HA    I44 @BASEBOARD_FAB2_LIB.BASEBOARD_FAB2(SCH_1):PAGE50
  J6M1  200 VSS<22> SCONN288_H44441003_PIP-SCONN,HA    I44 @BASEBOARD_FAB2_LIB.BASEBOARD_FAB2(SCH_1):PAGE50
  J6M1  198 VSS<23> SCONN288_H44441003_PIP-SCONN,HA    I44 @BASEBOARD_FAB2_LIB.BASEBOARD_FAB2(SCH_1):PAGE50
  J6M1  195 VSS<24> SCONN288_H44441003_PIP-SCONN,HA    I44 @BASEBOARD_FAB2_LIB.BASEBOARD_FAB2(SCH_1):PAGE50
  J6M1  193 VSS<25> SCONN288_H44441003_PIP-SCONN,HA    I44 @BASEBOARD_FAB2_LIB.BASEBOARD_FAB2(SCH_1):PAGE50
  J6M1  191 VSS<26> SCONN288_H44441003_PIP-SCONN,HA    I44 @BASEBOARD_FAB2_LIB.BASEBOARD_FAB2(SCH_1):PAGE50
  J6M1  189 VSS<27> SCONN288_H44441003_PIP-SCONN,HA    I44 @BASEBOARD_FAB2_LIB.BASEBOARD_FAB2(SCH_1):PAGE50
  J6M1  187 VSS<28> SCONN288_H44441003_PIP-SCONN,HA    I44 @BASEBOARD_FAB2_LIB.BASEBOARD_FAB2(SCH_1):PAGE50
  J6M1  184 VSS<29> SCONN288_H44441003_PIP-SCONN,HA    I44 @BASEBOARD_FAB2_LIB.BASEBOARD_FAB2(SCH_1):PAGE50
  J6M1  182 VSS<30> SCONN288_H44441003_PIP-SCONN,HA    I44 @BASEBOARD_FAB2_LIB.BASEBOARD_FAB2(SCH_1):PAGE50
  J6M1  180 VSS<31> SCONN288_H44441003_PIP-SCONN,HA    I44 @BASEBOARD_FAB2_LIB.BASEBOARD_FAB2(SCH_1):PAGE50
  J6M1  178 VSS<32> SCONN288_H44441003_PIP-SCONN,HA    I44 @BASEBOARD_FAB2_LIB.BASEBOARD_FAB2(SCH_1):PAGE50
  J6M1  176 VSS<33> SCONN288_H44441003_PIP-SCONN,HA    I44 @BASEBOARD_FAB2_LIB.BASEBOARD_FAB2(SCH_1):PAGE50
  J6M1  173 VSS<34> SCONN288_H44441003_PIP-SCONN,HA    I44 @BASEBOARD_FAB2_LIB.BASEBOARD_FAB2(SCH_1):PAGE50
  J6M1  171 VSS<35> SCONN288_H44441003_PIP-SCONN,HA    I44 @BASEBOARD_FAB2_LIB.BASEBOARD_FAB2(SCH_1):PAGE50
  J6M1  169 VSS<36> SCONN288_H44441003_PIP-SCONN,HA    I44 @BASEBOARD_FAB2_LIB.BASEBOARD_FAB2(SCH_1):PAGE50
  J6M1  167 VSS<37> SCONN288_H44441003_PIP-SCONN,HA    I44 @BASEBOARD_FAB2_LIB.BASEBOARD_FAB2(SCH_1):PAGE50
  J6M1  165 VSS<38> SCONN288_H44441003_PIP-SCONN,HA    I44 @BASEBOARD_FAB2_LIB.BASEBOARD_FAB2(SCH_1):PAGE50
  J6M1  162 VSS<39> SCONN288_H44441003_PIP-SCONN,HA    I44 @BASEBOARD_FAB2_LIB.BASEBOARD_FAB2(SCH_1):PAGE50
  J6M1  160 VSS<40> SCONN288_H44441003_PIP-SCONN,HA    I44 @BASEBOARD_FAB2_LIB.BASEBOARD_FAB2(SCH_1):PAGE50
  J6M1  158 VSS<41> SCONN288_H44441003_PIP-SCONN,HA    I44 @BASEBOARD_FAB2_LIB.BASEBOARD_FAB2(SCH_1):PAGE50
  J6M1  156 VSS<42> SCONN288_H44441003_PIP-SCONN,HA    I44 @BASEBOARD_FAB2_LIB.BASEBOARD_FAB2(SCH_1):PAGE50
  J6M1  154 VSS<43> SCONN288_H44441003_PIP-SCONN,HA    I44 @BASEBOARD_FAB2_LIB.BASEBOARD_FAB2(SCH_1):PAGE50
  J6M1  151 VSS<44> SCONN288_H44441003_PIP-SCONN,HA    I44 @BASEBOARD_FAB2_LIB.BASEBOARD_FAB2(SCH_1):PAGE50
  J6M1  149 VSS<45> SCONN288_H44441003_PIP-SCONN,HA    I44 @BASEBOARD_FAB2_LIB.BASEBOARD_FAB2(SCH_1):PAGE50
  J6M1  147 VSS<46> SCONN288_H44441003_PIP-SCONN,HA    I44 @BASEBOARD_FAB2_LIB.BASEBOARD_FAB2(SCH_1):PAGE50
  J6M1  138 VSS<47> SCONN288_H44441003_PIP-SCONN,HA    I44 @BASEBOARD_FAB2_LIB.BASEBOARD_FAB2(SCH_1):PAGE50
  J6M1  136 VSS<48> SCONN288_H44441003_PIP-SCONN,HA    I44 @BASEBOARD_FAB2_LIB.BASEBOARD_FAB2(SCH_1):PAGE50
  J6M1  134 VSS<49> SCONN288_H44441003_PIP-SCONN,HA    I44 @BASEBOARD_FAB2_LIB.BASEBOARD_FAB2(SCH_1):PAGE50
  J6M1  131 VSS<50> SCONN288_H44441003_PIP-SCONN,HA    I44 @BASEBOARD_FAB2_LIB.BASEBOARD_FAB2(SCH_1):PAGE50
  J6M1  129 VSS<51> SCONN288_H44441003_PIP-SCONN,HA    I44 @BASEBOARD_FAB2_LIB.BASEBOARD_FAB2(SCH_1):PAGE50
  J6M1  127 VSS<52> SCONN288_H44441003_PIP-SCONN,HA    I44 @BASEBOARD_FAB2_LIB.BASEBOARD_FAB2(SCH_1):PAGE50
  J6M1  125 VSS<53> SCONN288_H44441003_PIP-SCONN,HA    I44 @BASEBOARD_FAB2_LIB.BASEBOARD_FAB2(SCH_1):PAGE50
  J6M1  123 VSS<54> SCONN288_H44441003_PIP-SCONN,HA    I44 @BASEBOARD_FAB2_LIB.BASEBOARD_FAB2(SCH_1):PAGE50
  J6M1  120 VSS<55> SCONN288_H44441003_PIP-SCONN,HA    I44 @BASEBOARD_FAB2_LIB.BASEBOARD_FAB2(SCH_1):PAGE50
  J6M1  118 VSS<56> SCONN288_H44441003_PIP-SCONN,HA    I44 @BASEBOARD_FAB2_LIB.BASEBOARD_FAB2(SCH_1):PAGE50
  J6M1  116 VSS<57> SCONN288_H44441003_PIP-SCONN,HA    I44 @BASEBOARD_FAB2_LIB.BASEBOARD_FAB2(SCH_1):PAGE50
  J6M1  114 VSS<58> SCONN288_H44441003_PIP-SCONN,HA    I44 @BASEBOARD_FAB2_LIB.BASEBOARD_FAB2(SCH_1):PAGE50
  J6M1  112 VSS<59> SCONN288_H44441003_PIP-SCONN,HA    I44 @BASEBOARD_FAB2_LIB.BASEBOARD_FAB2(SCH_1):PAGE50
  J6M1  109 VSS<60> SCONN288_H44441003_PIP-SCONN,HA    I44 @BASEBOARD_FAB2_LIB.BASEBOARD_FAB2(SCH_1):PAGE50
  J6M1  107 VSS<61> SCONN288_H44441003_PIP-SCONN,HA    I44 @BASEBOARD_FAB2_LIB.BASEBOARD_FAB2(SCH_1):PAGE50
  J6M1  105 VSS<62> SCONN288_H44441003_PIP-SCONN,HA    I44 @BASEBOARD_FAB2_LIB.BASEBOARD_FAB2(SCH_1):PAGE50
  J6M1  103 VSS<63> SCONN288_H44441003_PIP-SCONN,HA    I44 @BASEBOARD_FAB2_LIB.BASEBOARD_FAB2(SCH_1):PAGE50
  J6M1  101 VSS<64> SCONN288_H44441003_PIP-SCONN,HA    I44 @BASEBOARD_FAB2_LIB.BASEBOARD_FAB2(SCH_1):PAGE50
  J6M1   98 VSS<65> SCONN288_H44441003_PIP-SCONN,HA    I44 @BASEBOARD_FAB2_LIB.BASEBOARD_FAB2(SCH_1):PAGE50
  J6M1   96 VSS<66> SCONN288_H44441003_PIP-SCONN,HA    I44 @BASEBOARD_FAB2_LIB.BASEBOARD_FAB2(SCH_1):PAGE50
  J6M1   94 VSS<67> SCONN288_H44441003_PIP-SCONN,HA    I44 @BASEBOARD_FAB2_LIB.BASEBOARD_FAB2(SCH_1):PAGE50
  J6M1   57 VSS<68> SCONN288_H44441003_PIP-SCONN,HA    I44 @BASEBOARD_FAB2_LIB.BASEBOARD_FAB2(SCH_1):PAGE50
  J6M1   55 VSS<69> SCONN288_H44441003_PIP-SCONN,HA    I44 @BASEBOARD_FAB2_LIB.BASEBOARD_FAB2(SCH_1):PAGE50
  J6M1   53 VSS<70> SCONN288_H44441003_PIP-SCONN,HA    I44 @BASEBOARD_FAB2_LIB.BASEBOARD_FAB2(SCH_1):PAGE50
  J6M1   50 VSS<71> SCONN288_H44441003_PIP-SCONN,HA    I44 @BASEBOARD_FAB2_LIB.BASEBOARD_FAB2(SCH_1):PAGE50
  J6M1   48 VSS<72> SCONN288_H44441003_PIP-SCONN,HA    I44 @BASEBOARD_FAB2_LIB.BASEBOARD_FAB2(SCH_1):PAGE50
  J6M1   46 VSS<73> SCONN288_H44441003_PIP-SCONN,HA    I44 @BASEBOARD_FAB2_LIB.BASEBOARD_FAB2(SCH_1):PAGE50
  J6M1   44 VSS<74> SCONN288_H44441003_PIP-SCONN,HA    I44 @BASEBOARD_FAB2_LIB.BASEBOARD_FAB2(SCH_1):PAGE50
  J6M1   42 VSS<75> SCONN288_H44441003_PIP-SCONN,HA    I44 @BASEBOARD_FAB2_LIB.BASEBOARD_FAB2(SCH_1):PAGE50
  J6M1   39 VSS<76> SCONN288_H44441003_PIP-SCONN,HA    I44 @BASEBOARD_FAB2_LIB.BASEBOARD_FAB2(SCH_1):PAGE50
  J6M1   37 VSS<77> SCONN288_H44441003_PIP-SCONN,HA    I44 @BASEBOARD_FAB2_LIB.BASEBOARD_FAB2(SCH_1):PAGE50
  J6M1   35 VSS<78> SCONN288_H44441003_PIP-SCONN,HA    I44 @BASEBOARD_FAB2_LIB.BASEBOARD_FAB2(SCH_1):PAGE50
  J6M1   33 VSS<79> SCONN288_H44441003_PIP-SCONN,HA    I44 @BASEBOARD_FAB2_LIB.BASEBOARD_FAB2(SCH_1):PAGE50
  J6M1   31 VSS<80> SCONN288_H44441003_PIP-SCONN,HA    I44 @BASEBOARD_FAB2_LIB.BASEBOARD_FAB2(SCH_1):PAGE50
  J6M1   28 VSS<81> SCONN288_H44441003_PIP-SCONN,HA    I44 @BASEBOARD_FAB2_LIB.BASEBOARD_FAB2(SCH_1):PAGE50
  J6M1   26 VSS<82> SCONN288_H44441003_PIP-SCONN,HA    I44 @BASEBOARD_FAB2_LIB.BASEBOARD_FAB2(SCH_1):PAGE50
  J6M1   24 VSS<83> SCONN288_H44441003_PIP-SCONN,HA    I44 @BASEBOARD_FAB2_LIB.BASEBOARD_FAB2(SCH_1):PAGE50
  J6M1   22 VSS<84> SCONN288_H44441003_PIP-SCONN,HA    I44 @BASEBOARD_FAB2_LIB.BASEBOARD_FAB2(SCH_1):PAGE50
  J6M1   20 VSS<85> SCONN288_H44441003_PIP-SCONN,HA    I44 @BASEBOARD_FAB2_LIB.BASEBOARD_FAB2(SCH_1):PAGE50
  J6M1   17 VSS<86> SCONN288_H44441003_PIP-SCONN,HA    I44 @BASEBOARD_FAB2_LIB.BASEBOARD_FAB2(SCH_1):PAGE50
  J6M1   15 VSS<87> SCONN288_H44441003_PIP-SCONN,HA    I44 @BASEBOARD_FAB2_LIB.BASEBOARD_FAB2(SCH_1):PAGE50
  J6M1   13 VSS<88> SCONN288_H44441003_PIP-SCONN,HA    I44 @BASEBOARD_FAB2_LIB.BASEBOARD_FAB2(SCH_1):PAGE50
  J6M1   11 VSS<89> SCONN288_H44441003_PIP-SCONN,HA    I44 @BASEBOARD_FAB2_LIB.BASEBOARD_FAB2(SCH_1):PAGE50
  J6M1    9 VSS<90> SCONN288_H44441003_PIP-SCONN,HA    I44 @BASEBOARD_FAB2_LIB.BASEBOARD_FAB2(SCH_1):PAGE50
  J6M1    6 VSS<91> SCONN288_H44441003_PIP-SCONN,HA    I44 @BASEBOARD_FAB2_LIB.BASEBOARD_FAB2(SCH_1):PAGE50
  J6M1    4 VSS<92> SCONN288_H44441003_PIP-SCONN,HA    I44 @BASEBOARD_FAB2_LIB.BASEBOARD_FAB2(SCH_1):PAGE50
  J6M1    2 VSS<93> SCONN288_H44441003_PIP-SCONN,HA    I44 @BASEBOARD_FAB2_LIB.BASEBOARD_FAB2(SCH_1):PAGE50
  J6M1  140  SA<1> SCONN288_H44441003_PIP-SCONN,HA   I158 @BASEBOARD_FAB2_LIB.BASEBOARD_FAB2(SCH_1):PAGE50
  J6M1  238  SA<2> SCONN288_H44441003_PIP-SCONN,HA   I158 @BASEBOARD_FAB2_LIB.BASEBOARD_FAB2(SCH_1):PAGE50
  C6M1    2      B CAP_A_0402V-0.01UF,25V,10%,X7RA   I177 @BASEBOARD_FAB2_LIB.BASEBOARD_FAB2(SCH_1):PAGE50
  J4A2  283 VSS<0> SCONN288_H44441004_PIP-SCONN,HA    I43 @BASEBOARD_FAB2_LIB.BASEBOARD_FAB2(SCH_1):PAGE51
  J4A2  281 VSS<1> SCONN288_H44441004_PIP-SCONN,HA    I43 @BASEBOARD_FAB2_LIB.BASEBOARD_FAB2(SCH_1):PAGE51
  J4A2  279 VSS<2> SCONN288_H44441004_PIP-SCONN,HA    I43 @BASEBOARD_FAB2_LIB.BASEBOARD_FAB2(SCH_1):PAGE51
  J4A2  276 VSS<3> SCONN288_H44441004_PIP-SCONN,HA    I43 @BASEBOARD_FAB2_LIB.BASEBOARD_FAB2(SCH_1):PAGE51
  J4A2  274 VSS<4> SCONN288_H44441004_PIP-SCONN,HA    I43 @BASEBOARD_FAB2_LIB.BASEBOARD_FAB2(SCH_1):PAGE51
  J4A2  272 VSS<5> SCONN288_H44441004_PIP-SCONN,HA    I43 @BASEBOARD_FAB2_LIB.BASEBOARD_FAB2(SCH_1):PAGE51
  J4A2  270 VSS<6> SCONN288_H44441004_PIP-SCONN,HA    I43 @BASEBOARD_FAB2_LIB.BASEBOARD_FAB2(SCH_1):PAGE51
  J4A2  268 VSS<7> SCONN288_H44441004_PIP-SCONN,HA    I43 @BASEBOARD_FAB2_LIB.BASEBOARD_FAB2(SCH_1):PAGE51
  J4A2  265 VSS<8> SCONN288_H44441004_PIP-SCONN,HA    I43 @BASEBOARD_FAB2_LIB.BASEBOARD_FAB2(SCH_1):PAGE51
  J4A2  263 VSS<9> SCONN288_H44441004_PIP-SCONN,HA    I43 @BASEBOARD_FAB2_LIB.BASEBOARD_FAB2(SCH_1):PAGE51
  J4A2  261 VSS<10> SCONN288_H44441004_PIP-SCONN,HA    I43 @BASEBOARD_FAB2_LIB.BASEBOARD_FAB2(SCH_1):PAGE51
  J4A2  259 VSS<11> SCONN288_H44441004_PIP-SCONN,HA    I43 @BASEBOARD_FAB2_LIB.BASEBOARD_FAB2(SCH_1):PAGE51
  J4A2  257 VSS<12> SCONN288_H44441004_PIP-SCONN,HA    I43 @BASEBOARD_FAB2_LIB.BASEBOARD_FAB2(SCH_1):PAGE51
  J4A2  254 VSS<13> SCONN288_H44441004_PIP-SCONN,HA    I43 @BASEBOARD_FAB2_LIB.BASEBOARD_FAB2(SCH_1):PAGE51
  J4A2  252 VSS<14> SCONN288_H44441004_PIP-SCONN,HA    I43 @BASEBOARD_FAB2_LIB.BASEBOARD_FAB2(SCH_1):PAGE51
  J4A2  250 VSS<15> SCONN288_H44441004_PIP-SCONN,HA    I43 @BASEBOARD_FAB2_LIB.BASEBOARD_FAB2(SCH_1):PAGE51
  J4A2  248 VSS<16> SCONN288_H44441004_PIP-SCONN,HA    I43 @BASEBOARD_FAB2_LIB.BASEBOARD_FAB2(SCH_1):PAGE51
  J4A2  246 VSS<17> SCONN288_H44441004_PIP-SCONN,HA    I43 @BASEBOARD_FAB2_LIB.BASEBOARD_FAB2(SCH_1):PAGE51
  J4A2  243 VSS<18> SCONN288_H44441004_PIP-SCONN,HA    I43 @BASEBOARD_FAB2_LIB.BASEBOARD_FAB2(SCH_1):PAGE51
  J4A2  241 VSS<19> SCONN288_H44441004_PIP-SCONN,HA    I43 @BASEBOARD_FAB2_LIB.BASEBOARD_FAB2(SCH_1):PAGE51
  J4A2  239 VSS<20> SCONN288_H44441004_PIP-SCONN,HA    I43 @BASEBOARD_FAB2_LIB.BASEBOARD_FAB2(SCH_1):PAGE51
  J4A2  202 VSS<21> SCONN288_H44441004_PIP-SCONN,HA    I43 @BASEBOARD_FAB2_LIB.BASEBOARD_FAB2(SCH_1):PAGE51
  J4A2  200 VSS<22> SCONN288_H44441004_PIP-SCONN,HA    I43 @BASEBOARD_FAB2_LIB.BASEBOARD_FAB2(SCH_1):PAGE51
  J4A2  198 VSS<23> SCONN288_H44441004_PIP-SCONN,HA    I43 @BASEBOARD_FAB2_LIB.BASEBOARD_FAB2(SCH_1):PAGE51
  J4A2  195 VSS<24> SCONN288_H44441004_PIP-SCONN,HA    I43 @BASEBOARD_FAB2_LIB.BASEBOARD_FAB2(SCH_1):PAGE51
  J4A2  193 VSS<25> SCONN288_H44441004_PIP-SCONN,HA    I43 @BASEBOARD_FAB2_LIB.BASEBOARD_FAB2(SCH_1):PAGE51
  J4A2  191 VSS<26> SCONN288_H44441004_PIP-SCONN,HA    I43 @BASEBOARD_FAB2_LIB.BASEBOARD_FAB2(SCH_1):PAGE51
  J4A2  189 VSS<27> SCONN288_H44441004_PIP-SCONN,HA    I43 @BASEBOARD_FAB2_LIB.BASEBOARD_FAB2(SCH_1):PAGE51
  J4A2  187 VSS<28> SCONN288_H44441004_PIP-SCONN,HA    I43 @BASEBOARD_FAB2_LIB.BASEBOARD_FAB2(SCH_1):PAGE51
  J4A2  184 VSS<29> SCONN288_H44441004_PIP-SCONN,HA    I43 @BASEBOARD_FAB2_LIB.BASEBOARD_FAB2(SCH_1):PAGE51
  J4A2  182 VSS<30> SCONN288_H44441004_PIP-SCONN,HA    I43 @BASEBOARD_FAB2_LIB.BASEBOARD_FAB2(SCH_1):PAGE51
  J4A2  180 VSS<31> SCONN288_H44441004_PIP-SCONN,HA    I43 @BASEBOARD_FAB2_LIB.BASEBOARD_FAB2(SCH_1):PAGE51
  J4A2  178 VSS<32> SCONN288_H44441004_PIP-SCONN,HA    I43 @BASEBOARD_FAB2_LIB.BASEBOARD_FAB2(SCH_1):PAGE51
  J4A2  176 VSS<33> SCONN288_H44441004_PIP-SCONN,HA    I43 @BASEBOARD_FAB2_LIB.BASEBOARD_FAB2(SCH_1):PAGE51
  J4A2  173 VSS<34> SCONN288_H44441004_PIP-SCONN,HA    I43 @BASEBOARD_FAB2_LIB.BASEBOARD_FAB2(SCH_1):PAGE51
  J4A2  171 VSS<35> SCONN288_H44441004_PIP-SCONN,HA    I43 @BASEBOARD_FAB2_LIB.BASEBOARD_FAB2(SCH_1):PAGE51
  J4A2  169 VSS<36> SCONN288_H44441004_PIP-SCONN,HA    I43 @BASEBOARD_FAB2_LIB.BASEBOARD_FAB2(SCH_1):PAGE51
  J4A2  167 VSS<37> SCONN288_H44441004_PIP-SCONN,HA    I43 @BASEBOARD_FAB2_LIB.BASEBOARD_FAB2(SCH_1):PAGE51
  J4A2  165 VSS<38> SCONN288_H44441004_PIP-SCONN,HA    I43 @BASEBOARD_FAB2_LIB.BASEBOARD_FAB2(SCH_1):PAGE51
  J4A2  162 VSS<39> SCONN288_H44441004_PIP-SCONN,HA    I43 @BASEBOARD_FAB2_LIB.BASEBOARD_FAB2(SCH_1):PAGE51
  J4A2  160 VSS<40> SCONN288_H44441004_PIP-SCONN,HA    I43 @BASEBOARD_FAB2_LIB.BASEBOARD_FAB2(SCH_1):PAGE51
  J4A2  158 VSS<41> SCONN288_H44441004_PIP-SCONN,HA    I43 @BASEBOARD_FAB2_LIB.BASEBOARD_FAB2(SCH_1):PAGE51
  J4A2  156 VSS<42> SCONN288_H44441004_PIP-SCONN,HA    I43 @BASEBOARD_FAB2_LIB.BASEBOARD_FAB2(SCH_1):PAGE51
  J4A2  154 VSS<43> SCONN288_H44441004_PIP-SCONN,HA    I43 @BASEBOARD_FAB2_LIB.BASEBOARD_FAB2(SCH_1):PAGE51
  J4A2  151 VSS<44> SCONN288_H44441004_PIP-SCONN,HA    I43 @BASEBOARD_FAB2_LIB.BASEBOARD_FAB2(SCH_1):PAGE51
  J4A2  149 VSS<45> SCONN288_H44441004_PIP-SCONN,HA    I43 @BASEBOARD_FAB2_LIB.BASEBOARD_FAB2(SCH_1):PAGE51
  J4A2  147 VSS<46> SCONN288_H44441004_PIP-SCONN,HA    I43 @BASEBOARD_FAB2_LIB.BASEBOARD_FAB2(SCH_1):PAGE51
  J4A2  138 VSS<47> SCONN288_H44441004_PIP-SCONN,HA    I43 @BASEBOARD_FAB2_LIB.BASEBOARD_FAB2(SCH_1):PAGE51
  J4A2  136 VSS<48> SCONN288_H44441004_PIP-SCONN,HA    I43 @BASEBOARD_FAB2_LIB.BASEBOARD_FAB2(SCH_1):PAGE51
  J4A2  134 VSS<49> SCONN288_H44441004_PIP-SCONN,HA    I43 @BASEBOARD_FAB2_LIB.BASEBOARD_FAB2(SCH_1):PAGE51
  J4A2  131 VSS<50> SCONN288_H44441004_PIP-SCONN,HA    I43 @BASEBOARD_FAB2_LIB.BASEBOARD_FAB2(SCH_1):PAGE51
  J4A2  129 VSS<51> SCONN288_H44441004_PIP-SCONN,HA    I43 @BASEBOARD_FAB2_LIB.BASEBOARD_FAB2(SCH_1):PAGE51
  J4A2  127 VSS<52> SCONN288_H44441004_PIP-SCONN,HA    I43 @BASEBOARD_FAB2_LIB.BASEBOARD_FAB2(SCH_1):PAGE51
  J4A2  125 VSS<53> SCONN288_H44441004_PIP-SCONN,HA    I43 @BASEBOARD_FAB2_LIB.BASEBOARD_FAB2(SCH_1):PAGE51
  J4A2  123 VSS<54> SCONN288_H44441004_PIP-SCONN,HA    I43 @BASEBOARD_FAB2_LIB.BASEBOARD_FAB2(SCH_1):PAGE51
  J4A2  120 VSS<55> SCONN288_H44441004_PIP-SCONN,HA    I43 @BASEBOARD_FAB2_LIB.BASEBOARD_FAB2(SCH_1):PAGE51
  J4A2  118 VSS<56> SCONN288_H44441004_PIP-SCONN,HA    I43 @BASEBOARD_FAB2_LIB.BASEBOARD_FAB2(SCH_1):PAGE51
  J4A2  116 VSS<57> SCONN288_H44441004_PIP-SCONN,HA    I43 @BASEBOARD_FAB2_LIB.BASEBOARD_FAB2(SCH_1):PAGE51
  J4A2  114 VSS<58> SCONN288_H44441004_PIP-SCONN,HA    I43 @BASEBOARD_FAB2_LIB.BASEBOARD_FAB2(SCH_1):PAGE51
  J4A2  112 VSS<59> SCONN288_H44441004_PIP-SCONN,HA    I43 @BASEBOARD_FAB2_LIB.BASEBOARD_FAB2(SCH_1):PAGE51
  J4A2  109 VSS<60> SCONN288_H44441004_PIP-SCONN,HA    I43 @BASEBOARD_FAB2_LIB.BASEBOARD_FAB2(SCH_1):PAGE51
  J4A2  107 VSS<61> SCONN288_H44441004_PIP-SCONN,HA    I43 @BASEBOARD_FAB2_LIB.BASEBOARD_FAB2(SCH_1):PAGE51
  J4A2  105 VSS<62> SCONN288_H44441004_PIP-SCONN,HA    I43 @BASEBOARD_FAB2_LIB.BASEBOARD_FAB2(SCH_1):PAGE51
  J4A2  103 VSS<63> SCONN288_H44441004_PIP-SCONN,HA    I43 @BASEBOARD_FAB2_LIB.BASEBOARD_FAB2(SCH_1):PAGE51
  J4A2  101 VSS<64> SCONN288_H44441004_PIP-SCONN,HA    I43 @BASEBOARD_FAB2_LIB.BASEBOARD_FAB2(SCH_1):PAGE51
  J4A2   98 VSS<65> SCONN288_H44441004_PIP-SCONN,HA    I43 @BASEBOARD_FAB2_LIB.BASEBOARD_FAB2(SCH_1):PAGE51
  J4A2   96 VSS<66> SCONN288_H44441004_PIP-SCONN,HA    I43 @BASEBOARD_FAB2_LIB.BASEBOARD_FAB2(SCH_1):PAGE51
  J4A2   94 VSS<67> SCONN288_H44441004_PIP-SCONN,HA    I43 @BASEBOARD_FAB2_LIB.BASEBOARD_FAB2(SCH_1):PAGE51
  J4A2   57 VSS<68> SCONN288_H44441004_PIP-SCONN,HA    I43 @BASEBOARD_FAB2_LIB.BASEBOARD_FAB2(SCH_1):PAGE51
  J4A2   55 VSS<69> SCONN288_H44441004_PIP-SCONN,HA    I43 @BASEBOARD_FAB2_LIB.BASEBOARD_FAB2(SCH_1):PAGE51
  J4A2   53 VSS<70> SCONN288_H44441004_PIP-SCONN,HA    I43 @BASEBOARD_FAB2_LIB.BASEBOARD_FAB2(SCH_1):PAGE51
  J4A2   50 VSS<71> SCONN288_H44441004_PIP-SCONN,HA    I43 @BASEBOARD_FAB2_LIB.BASEBOARD_FAB2(SCH_1):PAGE51
  J4A2   48 VSS<72> SCONN288_H44441004_PIP-SCONN,HA    I43 @BASEBOARD_FAB2_LIB.BASEBOARD_FAB2(SCH_1):PAGE51
  J4A2   46 VSS<73> SCONN288_H44441004_PIP-SCONN,HA    I43 @BASEBOARD_FAB2_LIB.BASEBOARD_FAB2(SCH_1):PAGE51
  J4A2   44 VSS<74> SCONN288_H44441004_PIP-SCONN,HA    I43 @BASEBOARD_FAB2_LIB.BASEBOARD_FAB2(SCH_1):PAGE51
  J4A2   42 VSS<75> SCONN288_H44441004_PIP-SCONN,HA    I43 @BASEBOARD_FAB2_LIB.BASEBOARD_FAB2(SCH_1):PAGE51
  J4A2   39 VSS<76> SCONN288_H44441004_PIP-SCONN,HA    I43 @BASEBOARD_FAB2_LIB.BASEBOARD_FAB2(SCH_1):PAGE51
  J4A2   37 VSS<77> SCONN288_H44441004_PIP-SCONN,HA    I43 @BASEBOARD_FAB2_LIB.BASEBOARD_FAB2(SCH_1):PAGE51
  J4A2   35 VSS<78> SCONN288_H44441004_PIP-SCONN,HA    I43 @BASEBOARD_FAB2_LIB.BASEBOARD_FAB2(SCH_1):PAGE51
  J4A2   33 VSS<79> SCONN288_H44441004_PIP-SCONN,HA    I43 @BASEBOARD_FAB2_LIB.BASEBOARD_FAB2(SCH_1):PAGE51
  J4A2   31 VSS<80> SCONN288_H44441004_PIP-SCONN,HA    I43 @BASEBOARD_FAB2_LIB.BASEBOARD_FAB2(SCH_1):PAGE51
  J4A2   28 VSS<81> SCONN288_H44441004_PIP-SCONN,HA    I43 @BASEBOARD_FAB2_LIB.BASEBOARD_FAB2(SCH_1):PAGE51
  J4A2   26 VSS<82> SCONN288_H44441004_PIP-SCONN,HA    I43 @BASEBOARD_FAB2_LIB.BASEBOARD_FAB2(SCH_1):PAGE51
  J4A2   24 VSS<83> SCONN288_H44441004_PIP-SCONN,HA    I43 @BASEBOARD_FAB2_LIB.BASEBOARD_FAB2(SCH_1):PAGE51
  J4A2   22 VSS<84> SCONN288_H44441004_PIP-SCONN,HA    I43 @BASEBOARD_FAB2_LIB.BASEBOARD_FAB2(SCH_1):PAGE51
  J4A2   20 VSS<85> SCONN288_H44441004_PIP-SCONN,HA    I43 @BASEBOARD_FAB2_LIB.BASEBOARD_FAB2(SCH_1):PAGE51
  J4A2   17 VSS<86> SCONN288_H44441004_PIP-SCONN,HA    I43 @BASEBOARD_FAB2_LIB.BASEBOARD_FAB2(SCH_1):PAGE51
  J4A2   15 VSS<87> SCONN288_H44441004_PIP-SCONN,HA    I43 @BASEBOARD_FAB2_LIB.BASEBOARD_FAB2(SCH_1):PAGE51
  J4A2   13 VSS<88> SCONN288_H44441004_PIP-SCONN,HA    I43 @BASEBOARD_FAB2_LIB.BASEBOARD_FAB2(SCH_1):PAGE51
  J4A2   11 VSS<89> SCONN288_H44441004_PIP-SCONN,HA    I43 @BASEBOARD_FAB2_LIB.BASEBOARD_FAB2(SCH_1):PAGE51
  J4A2    9 VSS<90> SCONN288_H44441004_PIP-SCONN,HA    I43 @BASEBOARD_FAB2_LIB.BASEBOARD_FAB2(SCH_1):PAGE51
  J4A2    6 VSS<91> SCONN288_H44441004_PIP-SCONN,HA    I43 @BASEBOARD_FAB2_LIB.BASEBOARD_FAB2(SCH_1):PAGE51
  J4A2    4 VSS<92> SCONN288_H44441004_PIP-SCONN,HA    I43 @BASEBOARD_FAB2_LIB.BASEBOARD_FAB2(SCH_1):PAGE51
  J4A2    2 VSS<93> SCONN288_H44441004_PIP-SCONN,HA    I43 @BASEBOARD_FAB2_LIB.BASEBOARD_FAB2(SCH_1):PAGE51
  J4A2  139  SA<0> SCONN288_H44441004_PIP-SCONN,HA   I111 @BASEBOARD_FAB2_LIB.BASEBOARD_FAB2(SCH_1):PAGE51
  J4A2  238  SA<2> SCONN288_H44441004_PIP-SCONN,HA   I111 @BASEBOARD_FAB2_LIB.BASEBOARD_FAB2(SCH_1):PAGE51
  C6L6    2      B CAP_A_0402V-0.01UF,25V,10%,X7RA   I175 @BASEBOARD_FAB2_LIB.BASEBOARD_FAB2(SCH_1):PAGE51
 C4A18    2      B CAP_A_0402V-0.01UF,25V,10%,X7RA     I3 @BASEBOARD_FAB2_LIB.BASEBOARD_FAB2(SCH_1):PAGE52
  J6L2  238  SA<2> SCONN288_H44441003_PIP-SCONN,HA    I12 @BASEBOARD_FAB2_LIB.BASEBOARD_FAB2(SCH_1):PAGE52
  J6L2  283 VSS<0> SCONN288_H44441003_PIP-SCONN,HA   I138 @BASEBOARD_FAB2_LIB.BASEBOARD_FAB2(SCH_1):PAGE52
  J6L2  281 VSS<1> SCONN288_H44441003_PIP-SCONN,HA   I138 @BASEBOARD_FAB2_LIB.BASEBOARD_FAB2(SCH_1):PAGE52
  J6L2  279 VSS<2> SCONN288_H44441003_PIP-SCONN,HA   I138 @BASEBOARD_FAB2_LIB.BASEBOARD_FAB2(SCH_1):PAGE52
  J6L2  276 VSS<3> SCONN288_H44441003_PIP-SCONN,HA   I138 @BASEBOARD_FAB2_LIB.BASEBOARD_FAB2(SCH_1):PAGE52
  J6L2  274 VSS<4> SCONN288_H44441003_PIP-SCONN,HA   I138 @BASEBOARD_FAB2_LIB.BASEBOARD_FAB2(SCH_1):PAGE52
  J6L2  272 VSS<5> SCONN288_H44441003_PIP-SCONN,HA   I138 @BASEBOARD_FAB2_LIB.BASEBOARD_FAB2(SCH_1):PAGE52
  J6L2  270 VSS<6> SCONN288_H44441003_PIP-SCONN,HA   I138 @BASEBOARD_FAB2_LIB.BASEBOARD_FAB2(SCH_1):PAGE52
  J6L2  268 VSS<7> SCONN288_H44441003_PIP-SCONN,HA   I138 @BASEBOARD_FAB2_LIB.BASEBOARD_FAB2(SCH_1):PAGE52
  J6L2  265 VSS<8> SCONN288_H44441003_PIP-SCONN,HA   I138 @BASEBOARD_FAB2_LIB.BASEBOARD_FAB2(SCH_1):PAGE52
  J6L2  263 VSS<9> SCONN288_H44441003_PIP-SCONN,HA   I138 @BASEBOARD_FAB2_LIB.BASEBOARD_FAB2(SCH_1):PAGE52
  J6L2  261 VSS<10> SCONN288_H44441003_PIP-SCONN,HA   I138 @BASEBOARD_FAB2_LIB.BASEBOARD_FAB2(SCH_1):PAGE52
  J6L2  259 VSS<11> SCONN288_H44441003_PIP-SCONN,HA   I138 @BASEBOARD_FAB2_LIB.BASEBOARD_FAB2(SCH_1):PAGE52
  J6L2  257 VSS<12> SCONN288_H44441003_PIP-SCONN,HA   I138 @BASEBOARD_FAB2_LIB.BASEBOARD_FAB2(SCH_1):PAGE52
  J6L2  254 VSS<13> SCONN288_H44441003_PIP-SCONN,HA   I138 @BASEBOARD_FAB2_LIB.BASEBOARD_FAB2(SCH_1):PAGE52
  J6L2  252 VSS<14> SCONN288_H44441003_PIP-SCONN,HA   I138 @BASEBOARD_FAB2_LIB.BASEBOARD_FAB2(SCH_1):PAGE52
  J6L2  250 VSS<15> SCONN288_H44441003_PIP-SCONN,HA   I138 @BASEBOARD_FAB2_LIB.BASEBOARD_FAB2(SCH_1):PAGE52
  J6L2  248 VSS<16> SCONN288_H44441003_PIP-SCONN,HA   I138 @BASEBOARD_FAB2_LIB.BASEBOARD_FAB2(SCH_1):PAGE52
  J6L2  246 VSS<17> SCONN288_H44441003_PIP-SCONN,HA   I138 @BASEBOARD_FAB2_LIB.BASEBOARD_FAB2(SCH_1):PAGE52
  J6L2  243 VSS<18> SCONN288_H44441003_PIP-SCONN,HA   I138 @BASEBOARD_FAB2_LIB.BASEBOARD_FAB2(SCH_1):PAGE52
  J6L2  241 VSS<19> SCONN288_H44441003_PIP-SCONN,HA   I138 @BASEBOARD_FAB2_LIB.BASEBOARD_FAB2(SCH_1):PAGE52
  J6L2  239 VSS<20> SCONN288_H44441003_PIP-SCONN,HA   I138 @BASEBOARD_FAB2_LIB.BASEBOARD_FAB2(SCH_1):PAGE52
  J6L2  202 VSS<21> SCONN288_H44441003_PIP-SCONN,HA   I138 @BASEBOARD_FAB2_LIB.BASEBOARD_FAB2(SCH_1):PAGE52
  J6L2  200 VSS<22> SCONN288_H44441003_PIP-SCONN,HA   I138 @BASEBOARD_FAB2_LIB.BASEBOARD_FAB2(SCH_1):PAGE52
  J6L2  198 VSS<23> SCONN288_H44441003_PIP-SCONN,HA   I138 @BASEBOARD_FAB2_LIB.BASEBOARD_FAB2(SCH_1):PAGE52
  J6L2  195 VSS<24> SCONN288_H44441003_PIP-SCONN,HA   I138 @BASEBOARD_FAB2_LIB.BASEBOARD_FAB2(SCH_1):PAGE52
  J6L2  193 VSS<25> SCONN288_H44441003_PIP-SCONN,HA   I138 @BASEBOARD_FAB2_LIB.BASEBOARD_FAB2(SCH_1):PAGE52
  J6L2  191 VSS<26> SCONN288_H44441003_PIP-SCONN,HA   I138 @BASEBOARD_FAB2_LIB.BASEBOARD_FAB2(SCH_1):PAGE52
  J6L2  189 VSS<27> SCONN288_H44441003_PIP-SCONN,HA   I138 @BASEBOARD_FAB2_LIB.BASEBOARD_FAB2(SCH_1):PAGE52
  J6L2  187 VSS<28> SCONN288_H44441003_PIP-SCONN,HA   I138 @BASEBOARD_FAB2_LIB.BASEBOARD_FAB2(SCH_1):PAGE52
  J6L2  184 VSS<29> SCONN288_H44441003_PIP-SCONN,HA   I138 @BASEBOARD_FAB2_LIB.BASEBOARD_FAB2(SCH_1):PAGE52
  J6L2  182 VSS<30> SCONN288_H44441003_PIP-SCONN,HA   I138 @BASEBOARD_FAB2_LIB.BASEBOARD_FAB2(SCH_1):PAGE52
  J6L2  180 VSS<31> SCONN288_H44441003_PIP-SCONN,HA   I138 @BASEBOARD_FAB2_LIB.BASEBOARD_FAB2(SCH_1):PAGE52
  J6L2  178 VSS<32> SCONN288_H44441003_PIP-SCONN,HA   I138 @BASEBOARD_FAB2_LIB.BASEBOARD_FAB2(SCH_1):PAGE52
  J6L2  176 VSS<33> SCONN288_H44441003_PIP-SCONN,HA   I138 @BASEBOARD_FAB2_LIB.BASEBOARD_FAB2(SCH_1):PAGE52
  J6L2  173 VSS<34> SCONN288_H44441003_PIP-SCONN,HA   I138 @BASEBOARD_FAB2_LIB.BASEBOARD_FAB2(SCH_1):PAGE52
  J6L2  171 VSS<35> SCONN288_H44441003_PIP-SCONN,HA   I138 @BASEBOARD_FAB2_LIB.BASEBOARD_FAB2(SCH_1):PAGE52
  J6L2  169 VSS<36> SCONN288_H44441003_PIP-SCONN,HA   I138 @BASEBOARD_FAB2_LIB.BASEBOARD_FAB2(SCH_1):PAGE52
  J6L2  167 VSS<37> SCONN288_H44441003_PIP-SCONN,HA   I138 @BASEBOARD_FAB2_LIB.BASEBOARD_FAB2(SCH_1):PAGE52
  J6L2  165 VSS<38> SCONN288_H44441003_PIP-SCONN,HA   I138 @BASEBOARD_FAB2_LIB.BASEBOARD_FAB2(SCH_1):PAGE52
  J6L2  162 VSS<39> SCONN288_H44441003_PIP-SCONN,HA   I138 @BASEBOARD_FAB2_LIB.BASEBOARD_FAB2(SCH_1):PAGE52
  J6L2  160 VSS<40> SCONN288_H44441003_PIP-SCONN,HA   I138 @BASEBOARD_FAB2_LIB.BASEBOARD_FAB2(SCH_1):PAGE52
  J6L2  158 VSS<41> SCONN288_H44441003_PIP-SCONN,HA   I138 @BASEBOARD_FAB2_LIB.BASEBOARD_FAB2(SCH_1):PAGE52
  J6L2  156 VSS<42> SCONN288_H44441003_PIP-SCONN,HA   I138 @BASEBOARD_FAB2_LIB.BASEBOARD_FAB2(SCH_1):PAGE52
  J6L2  154 VSS<43> SCONN288_H44441003_PIP-SCONN,HA   I138 @BASEBOARD_FAB2_LIB.BASEBOARD_FAB2(SCH_1):PAGE52
  J6L2  151 VSS<44> SCONN288_H44441003_PIP-SCONN,HA   I138 @BASEBOARD_FAB2_LIB.BASEBOARD_FAB2(SCH_1):PAGE52
  J6L2  149 VSS<45> SCONN288_H44441003_PIP-SCONN,HA   I138 @BASEBOARD_FAB2_LIB.BASEBOARD_FAB2(SCH_1):PAGE52
  J6L2  147 VSS<46> SCONN288_H44441003_PIP-SCONN,HA   I138 @BASEBOARD_FAB2_LIB.BASEBOARD_FAB2(SCH_1):PAGE52
  J6L2  138 VSS<47> SCONN288_H44441003_PIP-SCONN,HA   I138 @BASEBOARD_FAB2_LIB.BASEBOARD_FAB2(SCH_1):PAGE52
  J6L2  136 VSS<48> SCONN288_H44441003_PIP-SCONN,HA   I138 @BASEBOARD_FAB2_LIB.BASEBOARD_FAB2(SCH_1):PAGE52
  J6L2  134 VSS<49> SCONN288_H44441003_PIP-SCONN,HA   I138 @BASEBOARD_FAB2_LIB.BASEBOARD_FAB2(SCH_1):PAGE52
  J6L2  131 VSS<50> SCONN288_H44441003_PIP-SCONN,HA   I138 @BASEBOARD_FAB2_LIB.BASEBOARD_FAB2(SCH_1):PAGE52
  J6L2  129 VSS<51> SCONN288_H44441003_PIP-SCONN,HA   I138 @BASEBOARD_FAB2_LIB.BASEBOARD_FAB2(SCH_1):PAGE52
  J6L2  127 VSS<52> SCONN288_H44441003_PIP-SCONN,HA   I138 @BASEBOARD_FAB2_LIB.BASEBOARD_FAB2(SCH_1):PAGE52
  J6L2  125 VSS<53> SCONN288_H44441003_PIP-SCONN,HA   I138 @BASEBOARD_FAB2_LIB.BASEBOARD_FAB2(SCH_1):PAGE52
  J6L2  123 VSS<54> SCONN288_H44441003_PIP-SCONN,HA   I138 @BASEBOARD_FAB2_LIB.BASEBOARD_FAB2(SCH_1):PAGE52
  J6L2  120 VSS<55> SCONN288_H44441003_PIP-SCONN,HA   I138 @BASEBOARD_FAB2_LIB.BASEBOARD_FAB2(SCH_1):PAGE52
  J6L2  118 VSS<56> SCONN288_H44441003_PIP-SCONN,HA   I138 @BASEBOARD_FAB2_LIB.BASEBOARD_FAB2(SCH_1):PAGE52
  J6L2  116 VSS<57> SCONN288_H44441003_PIP-SCONN,HA   I138 @BASEBOARD_FAB2_LIB.BASEBOARD_FAB2(SCH_1):PAGE52
  J6L2  114 VSS<58> SCONN288_H44441003_PIP-SCONN,HA   I138 @BASEBOARD_FAB2_LIB.BASEBOARD_FAB2(SCH_1):PAGE52
  J6L2  112 VSS<59> SCONN288_H44441003_PIP-SCONN,HA   I138 @BASEBOARD_FAB2_LIB.BASEBOARD_FAB2(SCH_1):PAGE52
  J6L2  109 VSS<60> SCONN288_H44441003_PIP-SCONN,HA   I138 @BASEBOARD_FAB2_LIB.BASEBOARD_FAB2(SCH_1):PAGE52
  J6L2  107 VSS<61> SCONN288_H44441003_PIP-SCONN,HA   I138 @BASEBOARD_FAB2_LIB.BASEBOARD_FAB2(SCH_1):PAGE52
  J6L2  105 VSS<62> SCONN288_H44441003_PIP-SCONN,HA   I138 @BASEBOARD_FAB2_LIB.BASEBOARD_FAB2(SCH_1):PAGE52
  J6L2  103 VSS<63> SCONN288_H44441003_PIP-SCONN,HA   I138 @BASEBOARD_FAB2_LIB.BASEBOARD_FAB2(SCH_1):PAGE52
  J6L2  101 VSS<64> SCONN288_H44441003_PIP-SCONN,HA   I138 @BASEBOARD_FAB2_LIB.BASEBOARD_FAB2(SCH_1):PAGE52
  J6L2   98 VSS<65> SCONN288_H44441003_PIP-SCONN,HA   I138 @BASEBOARD_FAB2_LIB.BASEBOARD_FAB2(SCH_1):PAGE52
  J6L2   96 VSS<66> SCONN288_H44441003_PIP-SCONN,HA   I138 @BASEBOARD_FAB2_LIB.BASEBOARD_FAB2(SCH_1):PAGE52
  J6L2   94 VSS<67> SCONN288_H44441003_PIP-SCONN,HA   I138 @BASEBOARD_FAB2_LIB.BASEBOARD_FAB2(SCH_1):PAGE52
  J6L2   57 VSS<68> SCONN288_H44441003_PIP-SCONN,HA   I138 @BASEBOARD_FAB2_LIB.BASEBOARD_FAB2(SCH_1):PAGE52
  J6L2   55 VSS<69> SCONN288_H44441003_PIP-SCONN,HA   I138 @BASEBOARD_FAB2_LIB.BASEBOARD_FAB2(SCH_1):PAGE52
  J6L2   53 VSS<70> SCONN288_H44441003_PIP-SCONN,HA   I138 @BASEBOARD_FAB2_LIB.BASEBOARD_FAB2(SCH_1):PAGE52
  J6L2   50 VSS<71> SCONN288_H44441003_PIP-SCONN,HA   I138 @BASEBOARD_FAB2_LIB.BASEBOARD_FAB2(SCH_1):PAGE52
  J6L2   48 VSS<72> SCONN288_H44441003_PIP-SCONN,HA   I138 @BASEBOARD_FAB2_LIB.BASEBOARD_FAB2(SCH_1):PAGE52
  J6L2   46 VSS<73> SCONN288_H44441003_PIP-SCONN,HA   I138 @BASEBOARD_FAB2_LIB.BASEBOARD_FAB2(SCH_1):PAGE52
  J6L2   44 VSS<74> SCONN288_H44441003_PIP-SCONN,HA   I138 @BASEBOARD_FAB2_LIB.BASEBOARD_FAB2(SCH_1):PAGE52
  J6L2   42 VSS<75> SCONN288_H44441003_PIP-SCONN,HA   I138 @BASEBOARD_FAB2_LIB.BASEBOARD_FAB2(SCH_1):PAGE52
  J6L2   39 VSS<76> SCONN288_H44441003_PIP-SCONN,HA   I138 @BASEBOARD_FAB2_LIB.BASEBOARD_FAB2(SCH_1):PAGE52
  J6L2   37 VSS<77> SCONN288_H44441003_PIP-SCONN,HA   I138 @BASEBOARD_FAB2_LIB.BASEBOARD_FAB2(SCH_1):PAGE52
  J6L2   35 VSS<78> SCONN288_H44441003_PIP-SCONN,HA   I138 @BASEBOARD_FAB2_LIB.BASEBOARD_FAB2(SCH_1):PAGE52
  J6L2   33 VSS<79> SCONN288_H44441003_PIP-SCONN,HA   I138 @BASEBOARD_FAB2_LIB.BASEBOARD_FAB2(SCH_1):PAGE52
  J6L2   31 VSS<80> SCONN288_H44441003_PIP-SCONN,HA   I138 @BASEBOARD_FAB2_LIB.BASEBOARD_FAB2(SCH_1):PAGE52
  J6L2   28 VSS<81> SCONN288_H44441003_PIP-SCONN,HA   I138 @BASEBOARD_FAB2_LIB.BASEBOARD_FAB2(SCH_1):PAGE52
  J6L2   26 VSS<82> SCONN288_H44441003_PIP-SCONN,HA   I138 @BASEBOARD_FAB2_LIB.BASEBOARD_FAB2(SCH_1):PAGE52
  J6L2   24 VSS<83> SCONN288_H44441003_PIP-SCONN,HA   I138 @BASEBOARD_FAB2_LIB.BASEBOARD_FAB2(SCH_1):PAGE52
  J6L2   22 VSS<84> SCONN288_H44441003_PIP-SCONN,HA   I138 @BASEBOARD_FAB2_LIB.BASEBOARD_FAB2(SCH_1):PAGE52
  J6L2   20 VSS<85> SCONN288_H44441003_PIP-SCONN,HA   I138 @BASEBOARD_FAB2_LIB.BASEBOARD_FAB2(SCH_1):PAGE52
  J6L2   17 VSS<86> SCONN288_H44441003_PIP-SCONN,HA   I138 @BASEBOARD_FAB2_LIB.BASEBOARD_FAB2(SCH_1):PAGE52
  J6L2   15 VSS<87> SCONN288_H44441003_PIP-SCONN,HA   I138 @BASEBOARD_FAB2_LIB.BASEBOARD_FAB2(SCH_1):PAGE52
  J6L2   13 VSS<88> SCONN288_H44441003_PIP-SCONN,HA   I138 @BASEBOARD_FAB2_LIB.BASEBOARD_FAB2(SCH_1):PAGE52
  J6L2   11 VSS<89> SCONN288_H44441003_PIP-SCONN,HA   I138 @BASEBOARD_FAB2_LIB.BASEBOARD_FAB2(SCH_1):PAGE52
  J6L2    9 VSS<90> SCONN288_H44441003_PIP-SCONN,HA   I138 @BASEBOARD_FAB2_LIB.BASEBOARD_FAB2(SCH_1):PAGE52
  J6L2    6 VSS<91> SCONN288_H44441003_PIP-SCONN,HA   I138 @BASEBOARD_FAB2_LIB.BASEBOARD_FAB2(SCH_1):PAGE52
  J6L2    4 VSS<92> SCONN288_H44441003_PIP-SCONN,HA   I138 @BASEBOARD_FAB2_LIB.BASEBOARD_FAB2(SCH_1):PAGE52
  J6L2    2 VSS<93> SCONN288_H44441003_PIP-SCONN,HA   I138 @BASEBOARD_FAB2_LIB.BASEBOARD_FAB2(SCH_1):PAGE52
  J4A1  283 VSS<0> SCONN288_H44441004_PIP-SCONN,HA    I43 @BASEBOARD_FAB2_LIB.BASEBOARD_FAB2(SCH_1):PAGE53
  J4A1  281 VSS<1> SCONN288_H44441004_PIP-SCONN,HA    I43 @BASEBOARD_FAB2_LIB.BASEBOARD_FAB2(SCH_1):PAGE53
  J4A1  279 VSS<2> SCONN288_H44441004_PIP-SCONN,HA    I43 @BASEBOARD_FAB2_LIB.BASEBOARD_FAB2(SCH_1):PAGE53
  J4A1  276 VSS<3> SCONN288_H44441004_PIP-SCONN,HA    I43 @BASEBOARD_FAB2_LIB.BASEBOARD_FAB2(SCH_1):PAGE53
  J4A1  274 VSS<4> SCONN288_H44441004_PIP-SCONN,HA    I43 @BASEBOARD_FAB2_LIB.BASEBOARD_FAB2(SCH_1):PAGE53
  J4A1  272 VSS<5> SCONN288_H44441004_PIP-SCONN,HA    I43 @BASEBOARD_FAB2_LIB.BASEBOARD_FAB2(SCH_1):PAGE53
  J4A1  270 VSS<6> SCONN288_H44441004_PIP-SCONN,HA    I43 @BASEBOARD_FAB2_LIB.BASEBOARD_FAB2(SCH_1):PAGE53
  J4A1  268 VSS<7> SCONN288_H44441004_PIP-SCONN,HA    I43 @BASEBOARD_FAB2_LIB.BASEBOARD_FAB2(SCH_1):PAGE53
  J4A1  265 VSS<8> SCONN288_H44441004_PIP-SCONN,HA    I43 @BASEBOARD_FAB2_LIB.BASEBOARD_FAB2(SCH_1):PAGE53
  J4A1  263 VSS<9> SCONN288_H44441004_PIP-SCONN,HA    I43 @BASEBOARD_FAB2_LIB.BASEBOARD_FAB2(SCH_1):PAGE53
  J4A1  261 VSS<10> SCONN288_H44441004_PIP-SCONN,HA    I43 @BASEBOARD_FAB2_LIB.BASEBOARD_FAB2(SCH_1):PAGE53
  J4A1  259 VSS<11> SCONN288_H44441004_PIP-SCONN,HA    I43 @BASEBOARD_FAB2_LIB.BASEBOARD_FAB2(SCH_1):PAGE53
  J4A1  257 VSS<12> SCONN288_H44441004_PIP-SCONN,HA    I43 @BASEBOARD_FAB2_LIB.BASEBOARD_FAB2(SCH_1):PAGE53
  J4A1  254 VSS<13> SCONN288_H44441004_PIP-SCONN,HA    I43 @BASEBOARD_FAB2_LIB.BASEBOARD_FAB2(SCH_1):PAGE53
  J4A1  252 VSS<14> SCONN288_H44441004_PIP-SCONN,HA    I43 @BASEBOARD_FAB2_LIB.BASEBOARD_FAB2(SCH_1):PAGE53
  J4A1  250 VSS<15> SCONN288_H44441004_PIP-SCONN,HA    I43 @BASEBOARD_FAB2_LIB.BASEBOARD_FAB2(SCH_1):PAGE53
  J4A1  248 VSS<16> SCONN288_H44441004_PIP-SCONN,HA    I43 @BASEBOARD_FAB2_LIB.BASEBOARD_FAB2(SCH_1):PAGE53
  J4A1  246 VSS<17> SCONN288_H44441004_PIP-SCONN,HA    I43 @BASEBOARD_FAB2_LIB.BASEBOARD_FAB2(SCH_1):PAGE53
  J4A1  243 VSS<18> SCONN288_H44441004_PIP-SCONN,HA    I43 @BASEBOARD_FAB2_LIB.BASEBOARD_FAB2(SCH_1):PAGE53
  J4A1  241 VSS<19> SCONN288_H44441004_PIP-SCONN,HA    I43 @BASEBOARD_FAB2_LIB.BASEBOARD_FAB2(SCH_1):PAGE53
  J4A1  239 VSS<20> SCONN288_H44441004_PIP-SCONN,HA    I43 @BASEBOARD_FAB2_LIB.BASEBOARD_FAB2(SCH_1):PAGE53
  J4A1  202 VSS<21> SCONN288_H44441004_PIP-SCONN,HA    I43 @BASEBOARD_FAB2_LIB.BASEBOARD_FAB2(SCH_1):PAGE53
  J4A1  200 VSS<22> SCONN288_H44441004_PIP-SCONN,HA    I43 @BASEBOARD_FAB2_LIB.BASEBOARD_FAB2(SCH_1):PAGE53
  J4A1  198 VSS<23> SCONN288_H44441004_PIP-SCONN,HA    I43 @BASEBOARD_FAB2_LIB.BASEBOARD_FAB2(SCH_1):PAGE53
  J4A1  195 VSS<24> SCONN288_H44441004_PIP-SCONN,HA    I43 @BASEBOARD_FAB2_LIB.BASEBOARD_FAB2(SCH_1):PAGE53
  J4A1  193 VSS<25> SCONN288_H44441004_PIP-SCONN,HA    I43 @BASEBOARD_FAB2_LIB.BASEBOARD_FAB2(SCH_1):PAGE53
  J4A1  191 VSS<26> SCONN288_H44441004_PIP-SCONN,HA    I43 @BASEBOARD_FAB2_LIB.BASEBOARD_FAB2(SCH_1):PAGE53
  J4A1  189 VSS<27> SCONN288_H44441004_PIP-SCONN,HA    I43 @BASEBOARD_FAB2_LIB.BASEBOARD_FAB2(SCH_1):PAGE53
  J4A1  187 VSS<28> SCONN288_H44441004_PIP-SCONN,HA    I43 @BASEBOARD_FAB2_LIB.BASEBOARD_FAB2(SCH_1):PAGE53
  J4A1  184 VSS<29> SCONN288_H44441004_PIP-SCONN,HA    I43 @BASEBOARD_FAB2_LIB.BASEBOARD_FAB2(SCH_1):PAGE53
  J4A1  182 VSS<30> SCONN288_H44441004_PIP-SCONN,HA    I43 @BASEBOARD_FAB2_LIB.BASEBOARD_FAB2(SCH_1):PAGE53
  J4A1  180 VSS<31> SCONN288_H44441004_PIP-SCONN,HA    I43 @BASEBOARD_FAB2_LIB.BASEBOARD_FAB2(SCH_1):PAGE53
  J4A1  178 VSS<32> SCONN288_H44441004_PIP-SCONN,HA    I43 @BASEBOARD_FAB2_LIB.BASEBOARD_FAB2(SCH_1):PAGE53
  J4A1  176 VSS<33> SCONN288_H44441004_PIP-SCONN,HA    I43 @BASEBOARD_FAB2_LIB.BASEBOARD_FAB2(SCH_1):PAGE53
  J4A1  173 VSS<34> SCONN288_H44441004_PIP-SCONN,HA    I43 @BASEBOARD_FAB2_LIB.BASEBOARD_FAB2(SCH_1):PAGE53
  J4A1  171 VSS<35> SCONN288_H44441004_PIP-SCONN,HA    I43 @BASEBOARD_FAB2_LIB.BASEBOARD_FAB2(SCH_1):PAGE53
  J4A1  169 VSS<36> SCONN288_H44441004_PIP-SCONN,HA    I43 @BASEBOARD_FAB2_LIB.BASEBOARD_FAB2(SCH_1):PAGE53
  J4A1  167 VSS<37> SCONN288_H44441004_PIP-SCONN,HA    I43 @BASEBOARD_FAB2_LIB.BASEBOARD_FAB2(SCH_1):PAGE53
  J4A1  165 VSS<38> SCONN288_H44441004_PIP-SCONN,HA    I43 @BASEBOARD_FAB2_LIB.BASEBOARD_FAB2(SCH_1):PAGE53
  J4A1  162 VSS<39> SCONN288_H44441004_PIP-SCONN,HA    I43 @BASEBOARD_FAB2_LIB.BASEBOARD_FAB2(SCH_1):PAGE53
  J4A1  160 VSS<40> SCONN288_H44441004_PIP-SCONN,HA    I43 @BASEBOARD_FAB2_LIB.BASEBOARD_FAB2(SCH_1):PAGE53
  J4A1  158 VSS<41> SCONN288_H44441004_PIP-SCONN,HA    I43 @BASEBOARD_FAB2_LIB.BASEBOARD_FAB2(SCH_1):PAGE53
  J4A1  156 VSS<42> SCONN288_H44441004_PIP-SCONN,HA    I43 @BASEBOARD_FAB2_LIB.BASEBOARD_FAB2(SCH_1):PAGE53
  J4A1  154 VSS<43> SCONN288_H44441004_PIP-SCONN,HA    I43 @BASEBOARD_FAB2_LIB.BASEBOARD_FAB2(SCH_1):PAGE53
  J4A1  151 VSS<44> SCONN288_H44441004_PIP-SCONN,HA    I43 @BASEBOARD_FAB2_LIB.BASEBOARD_FAB2(SCH_1):PAGE53
  J4A1  149 VSS<45> SCONN288_H44441004_PIP-SCONN,HA    I43 @BASEBOARD_FAB2_LIB.BASEBOARD_FAB2(SCH_1):PAGE53
  J4A1  147 VSS<46> SCONN288_H44441004_PIP-SCONN,HA    I43 @BASEBOARD_FAB2_LIB.BASEBOARD_FAB2(SCH_1):PAGE53
  J4A1  138 VSS<47> SCONN288_H44441004_PIP-SCONN,HA    I43 @BASEBOARD_FAB2_LIB.BASEBOARD_FAB2(SCH_1):PAGE53
  J4A1  136 VSS<48> SCONN288_H44441004_PIP-SCONN,HA    I43 @BASEBOARD_FAB2_LIB.BASEBOARD_FAB2(SCH_1):PAGE53
  J4A1  134 VSS<49> SCONN288_H44441004_PIP-SCONN,HA    I43 @BASEBOARD_FAB2_LIB.BASEBOARD_FAB2(SCH_1):PAGE53
  J4A1  131 VSS<50> SCONN288_H44441004_PIP-SCONN,HA    I43 @BASEBOARD_FAB2_LIB.BASEBOARD_FAB2(SCH_1):PAGE53
  J4A1  129 VSS<51> SCONN288_H44441004_PIP-SCONN,HA    I43 @BASEBOARD_FAB2_LIB.BASEBOARD_FAB2(SCH_1):PAGE53
  J4A1  127 VSS<52> SCONN288_H44441004_PIP-SCONN,HA    I43 @BASEBOARD_FAB2_LIB.BASEBOARD_FAB2(SCH_1):PAGE53
  J4A1  125 VSS<53> SCONN288_H44441004_PIP-SCONN,HA    I43 @BASEBOARD_FAB2_LIB.BASEBOARD_FAB2(SCH_1):PAGE53
  J4A1  123 VSS<54> SCONN288_H44441004_PIP-SCONN,HA    I43 @BASEBOARD_FAB2_LIB.BASEBOARD_FAB2(SCH_1):PAGE53
  J4A1  120 VSS<55> SCONN288_H44441004_PIP-SCONN,HA    I43 @BASEBOARD_FAB2_LIB.BASEBOARD_FAB2(SCH_1):PAGE53
  J4A1  118 VSS<56> SCONN288_H44441004_PIP-SCONN,HA    I43 @BASEBOARD_FAB2_LIB.BASEBOARD_FAB2(SCH_1):PAGE53
  J4A1  116 VSS<57> SCONN288_H44441004_PIP-SCONN,HA    I43 @BASEBOARD_FAB2_LIB.BASEBOARD_FAB2(SCH_1):PAGE53
  J4A1  114 VSS<58> SCONN288_H44441004_PIP-SCONN,HA    I43 @BASEBOARD_FAB2_LIB.BASEBOARD_FAB2(SCH_1):PAGE53
  J4A1  112 VSS<59> SCONN288_H44441004_PIP-SCONN,HA    I43 @BASEBOARD_FAB2_LIB.BASEBOARD_FAB2(SCH_1):PAGE53
  J4A1  109 VSS<60> SCONN288_H44441004_PIP-SCONN,HA    I43 @BASEBOARD_FAB2_LIB.BASEBOARD_FAB2(SCH_1):PAGE53
  J4A1  107 VSS<61> SCONN288_H44441004_PIP-SCONN,HA    I43 @BASEBOARD_FAB2_LIB.BASEBOARD_FAB2(SCH_1):PAGE53
  J4A1  105 VSS<62> SCONN288_H44441004_PIP-SCONN,HA    I43 @BASEBOARD_FAB2_LIB.BASEBOARD_FAB2(SCH_1):PAGE53
  J4A1  103 VSS<63> SCONN288_H44441004_PIP-SCONN,HA    I43 @BASEBOARD_FAB2_LIB.BASEBOARD_FAB2(SCH_1):PAGE53
  J4A1  101 VSS<64> SCONN288_H44441004_PIP-SCONN,HA    I43 @BASEBOARD_FAB2_LIB.BASEBOARD_FAB2(SCH_1):PAGE53
  J4A1   98 VSS<65> SCONN288_H44441004_PIP-SCONN,HA    I43 @BASEBOARD_FAB2_LIB.BASEBOARD_FAB2(SCH_1):PAGE53
  J4A1   96 VSS<66> SCONN288_H44441004_PIP-SCONN,HA    I43 @BASEBOARD_FAB2_LIB.BASEBOARD_FAB2(SCH_1):PAGE53
  J4A1   94 VSS<67> SCONN288_H44441004_PIP-SCONN,HA    I43 @BASEBOARD_FAB2_LIB.BASEBOARD_FAB2(SCH_1):PAGE53
  J4A1   57 VSS<68> SCONN288_H44441004_PIP-SCONN,HA    I43 @BASEBOARD_FAB2_LIB.BASEBOARD_FAB2(SCH_1):PAGE53
  J4A1   55 VSS<69> SCONN288_H44441004_PIP-SCONN,HA    I43 @BASEBOARD_FAB2_LIB.BASEBOARD_FAB2(SCH_1):PAGE53
  J4A1   53 VSS<70> SCONN288_H44441004_PIP-SCONN,HA    I43 @BASEBOARD_FAB2_LIB.BASEBOARD_FAB2(SCH_1):PAGE53
  J4A1   50 VSS<71> SCONN288_H44441004_PIP-SCONN,HA    I43 @BASEBOARD_FAB2_LIB.BASEBOARD_FAB2(SCH_1):PAGE53
  J4A1   48 VSS<72> SCONN288_H44441004_PIP-SCONN,HA    I43 @BASEBOARD_FAB2_LIB.BASEBOARD_FAB2(SCH_1):PAGE53
  J4A1   46 VSS<73> SCONN288_H44441004_PIP-SCONN,HA    I43 @BASEBOARD_FAB2_LIB.BASEBOARD_FAB2(SCH_1):PAGE53
  J4A1   44 VSS<74> SCONN288_H44441004_PIP-SCONN,HA    I43 @BASEBOARD_FAB2_LIB.BASEBOARD_FAB2(SCH_1):PAGE53
  J4A1   42 VSS<75> SCONN288_H44441004_PIP-SCONN,HA    I43 @BASEBOARD_FAB2_LIB.BASEBOARD_FAB2(SCH_1):PAGE53
  J4A1   39 VSS<76> SCONN288_H44441004_PIP-SCONN,HA    I43 @BASEBOARD_FAB2_LIB.BASEBOARD_FAB2(SCH_1):PAGE53
  J4A1   37 VSS<77> SCONN288_H44441004_PIP-SCONN,HA    I43 @BASEBOARD_FAB2_LIB.BASEBOARD_FAB2(SCH_1):PAGE53
  J4A1   35 VSS<78> SCONN288_H44441004_PIP-SCONN,HA    I43 @BASEBOARD_FAB2_LIB.BASEBOARD_FAB2(SCH_1):PAGE53
  J4A1   33 VSS<79> SCONN288_H44441004_PIP-SCONN,HA    I43 @BASEBOARD_FAB2_LIB.BASEBOARD_FAB2(SCH_1):PAGE53
  J4A1   31 VSS<80> SCONN288_H44441004_PIP-SCONN,HA    I43 @BASEBOARD_FAB2_LIB.BASEBOARD_FAB2(SCH_1):PAGE53
  J4A1   28 VSS<81> SCONN288_H44441004_PIP-SCONN,HA    I43 @BASEBOARD_FAB2_LIB.BASEBOARD_FAB2(SCH_1):PAGE53
  J4A1   26 VSS<82> SCONN288_H44441004_PIP-SCONN,HA    I43 @BASEBOARD_FAB2_LIB.BASEBOARD_FAB2(SCH_1):PAGE53
  J4A1   24 VSS<83> SCONN288_H44441004_PIP-SCONN,HA    I43 @BASEBOARD_FAB2_LIB.BASEBOARD_FAB2(SCH_1):PAGE53
  J4A1   22 VSS<84> SCONN288_H44441004_PIP-SCONN,HA    I43 @BASEBOARD_FAB2_LIB.BASEBOARD_FAB2(SCH_1):PAGE53
  J4A1   20 VSS<85> SCONN288_H44441004_PIP-SCONN,HA    I43 @BASEBOARD_FAB2_LIB.BASEBOARD_FAB2(SCH_1):PAGE53
  J4A1   17 VSS<86> SCONN288_H44441004_PIP-SCONN,HA    I43 @BASEBOARD_FAB2_LIB.BASEBOARD_FAB2(SCH_1):PAGE53
  J4A1   15 VSS<87> SCONN288_H44441004_PIP-SCONN,HA    I43 @BASEBOARD_FAB2_LIB.BASEBOARD_FAB2(SCH_1):PAGE53
  J4A1   13 VSS<88> SCONN288_H44441004_PIP-SCONN,HA    I43 @BASEBOARD_FAB2_LIB.BASEBOARD_FAB2(SCH_1):PAGE53
  J4A1   11 VSS<89> SCONN288_H44441004_PIP-SCONN,HA    I43 @BASEBOARD_FAB2_LIB.BASEBOARD_FAB2(SCH_1):PAGE53
  J4A1    9 VSS<90> SCONN288_H44441004_PIP-SCONN,HA    I43 @BASEBOARD_FAB2_LIB.BASEBOARD_FAB2(SCH_1):PAGE53
  J4A1    6 VSS<91> SCONN288_H44441004_PIP-SCONN,HA    I43 @BASEBOARD_FAB2_LIB.BASEBOARD_FAB2(SCH_1):PAGE53
  J4A1    4 VSS<92> SCONN288_H44441004_PIP-SCONN,HA    I43 @BASEBOARD_FAB2_LIB.BASEBOARD_FAB2(SCH_1):PAGE53
  J4A1    2 VSS<93> SCONN288_H44441004_PIP-SCONN,HA    I43 @BASEBOARD_FAB2_LIB.BASEBOARD_FAB2(SCH_1):PAGE53
  J4A1  139  SA<0> SCONN288_H44441004_PIP-SCONN,HA   I111 @BASEBOARD_FAB2_LIB.BASEBOARD_FAB2(SCH_1):PAGE53
  J4A1  140  SA<1> SCONN288_H44441004_PIP-SCONN,HA   I111 @BASEBOARD_FAB2_LIB.BASEBOARD_FAB2(SCH_1):PAGE53
  C6L1    2      B CAP_A_0402V-0.01UF,25V,10%,X7RA   I178 @BASEBOARD_FAB2_LIB.BASEBOARD_FAB2(SCH_1):PAGE53
  J6L1  283 VSS<0> SCONN288_H44441003_PIP-SCONN,HA    I43 @BASEBOARD_FAB2_LIB.BASEBOARD_FAB2(SCH_1):PAGE54
  J6L1  281 VSS<1> SCONN288_H44441003_PIP-SCONN,HA    I43 @BASEBOARD_FAB2_LIB.BASEBOARD_FAB2(SCH_1):PAGE54
  J6L1  279 VSS<2> SCONN288_H44441003_PIP-SCONN,HA    I43 @BASEBOARD_FAB2_LIB.BASEBOARD_FAB2(SCH_1):PAGE54
  J6L1  276 VSS<3> SCONN288_H44441003_PIP-SCONN,HA    I43 @BASEBOARD_FAB2_LIB.BASEBOARD_FAB2(SCH_1):PAGE54
  J6L1  274 VSS<4> SCONN288_H44441003_PIP-SCONN,HA    I43 @BASEBOARD_FAB2_LIB.BASEBOARD_FAB2(SCH_1):PAGE54
  J6L1  272 VSS<5> SCONN288_H44441003_PIP-SCONN,HA    I43 @BASEBOARD_FAB2_LIB.BASEBOARD_FAB2(SCH_1):PAGE54
  J6L1  270 VSS<6> SCONN288_H44441003_PIP-SCONN,HA    I43 @BASEBOARD_FAB2_LIB.BASEBOARD_FAB2(SCH_1):PAGE54
  J6L1  268 VSS<7> SCONN288_H44441003_PIP-SCONN,HA    I43 @BASEBOARD_FAB2_LIB.BASEBOARD_FAB2(SCH_1):PAGE54
  J6L1  265 VSS<8> SCONN288_H44441003_PIP-SCONN,HA    I43 @BASEBOARD_FAB2_LIB.BASEBOARD_FAB2(SCH_1):PAGE54
  J6L1  263 VSS<9> SCONN288_H44441003_PIP-SCONN,HA    I43 @BASEBOARD_FAB2_LIB.BASEBOARD_FAB2(SCH_1):PAGE54
  J6L1  261 VSS<10> SCONN288_H44441003_PIP-SCONN,HA    I43 @BASEBOARD_FAB2_LIB.BASEBOARD_FAB2(SCH_1):PAGE54
  J6L1  259 VSS<11> SCONN288_H44441003_PIP-SCONN,HA    I43 @BASEBOARD_FAB2_LIB.BASEBOARD_FAB2(SCH_1):PAGE54
  J6L1  257 VSS<12> SCONN288_H44441003_PIP-SCONN,HA    I43 @BASEBOARD_FAB2_LIB.BASEBOARD_FAB2(SCH_1):PAGE54
  J6L1  254 VSS<13> SCONN288_H44441003_PIP-SCONN,HA    I43 @BASEBOARD_FAB2_LIB.BASEBOARD_FAB2(SCH_1):PAGE54
  J6L1  252 VSS<14> SCONN288_H44441003_PIP-SCONN,HA    I43 @BASEBOARD_FAB2_LIB.BASEBOARD_FAB2(SCH_1):PAGE54
  J6L1  250 VSS<15> SCONN288_H44441003_PIP-SCONN,HA    I43 @BASEBOARD_FAB2_LIB.BASEBOARD_FAB2(SCH_1):PAGE54
  J6L1  248 VSS<16> SCONN288_H44441003_PIP-SCONN,HA    I43 @BASEBOARD_FAB2_LIB.BASEBOARD_FAB2(SCH_1):PAGE54
  J6L1  246 VSS<17> SCONN288_H44441003_PIP-SCONN,HA    I43 @BASEBOARD_FAB2_LIB.BASEBOARD_FAB2(SCH_1):PAGE54
  J6L1  243 VSS<18> SCONN288_H44441003_PIP-SCONN,HA    I43 @BASEBOARD_FAB2_LIB.BASEBOARD_FAB2(SCH_1):PAGE54
  J6L1  241 VSS<19> SCONN288_H44441003_PIP-SCONN,HA    I43 @BASEBOARD_FAB2_LIB.BASEBOARD_FAB2(SCH_1):PAGE54
  J6L1  239 VSS<20> SCONN288_H44441003_PIP-SCONN,HA    I43 @BASEBOARD_FAB2_LIB.BASEBOARD_FAB2(SCH_1):PAGE54
  J6L1  202 VSS<21> SCONN288_H44441003_PIP-SCONN,HA    I43 @BASEBOARD_FAB2_LIB.BASEBOARD_FAB2(SCH_1):PAGE54
  J6L1  200 VSS<22> SCONN288_H44441003_PIP-SCONN,HA    I43 @BASEBOARD_FAB2_LIB.BASEBOARD_FAB2(SCH_1):PAGE54
  J6L1  198 VSS<23> SCONN288_H44441003_PIP-SCONN,HA    I43 @BASEBOARD_FAB2_LIB.BASEBOARD_FAB2(SCH_1):PAGE54
  J6L1  195 VSS<24> SCONN288_H44441003_PIP-SCONN,HA    I43 @BASEBOARD_FAB2_LIB.BASEBOARD_FAB2(SCH_1):PAGE54
  J6L1  193 VSS<25> SCONN288_H44441003_PIP-SCONN,HA    I43 @BASEBOARD_FAB2_LIB.BASEBOARD_FAB2(SCH_1):PAGE54
  J6L1  191 VSS<26> SCONN288_H44441003_PIP-SCONN,HA    I43 @BASEBOARD_FAB2_LIB.BASEBOARD_FAB2(SCH_1):PAGE54
  J6L1  189 VSS<27> SCONN288_H44441003_PIP-SCONN,HA    I43 @BASEBOARD_FAB2_LIB.BASEBOARD_FAB2(SCH_1):PAGE54
  J6L1  187 VSS<28> SCONN288_H44441003_PIP-SCONN,HA    I43 @BASEBOARD_FAB2_LIB.BASEBOARD_FAB2(SCH_1):PAGE54
  J6L1  184 VSS<29> SCONN288_H44441003_PIP-SCONN,HA    I43 @BASEBOARD_FAB2_LIB.BASEBOARD_FAB2(SCH_1):PAGE54
  J6L1  182 VSS<30> SCONN288_H44441003_PIP-SCONN,HA    I43 @BASEBOARD_FAB2_LIB.BASEBOARD_FAB2(SCH_1):PAGE54
  J6L1  180 VSS<31> SCONN288_H44441003_PIP-SCONN,HA    I43 @BASEBOARD_FAB2_LIB.BASEBOARD_FAB2(SCH_1):PAGE54
  J6L1  178 VSS<32> SCONN288_H44441003_PIP-SCONN,HA    I43 @BASEBOARD_FAB2_LIB.BASEBOARD_FAB2(SCH_1):PAGE54
  J6L1  176 VSS<33> SCONN288_H44441003_PIP-SCONN,HA    I43 @BASEBOARD_FAB2_LIB.BASEBOARD_FAB2(SCH_1):PAGE54
  J6L1  173 VSS<34> SCONN288_H44441003_PIP-SCONN,HA    I43 @BASEBOARD_FAB2_LIB.BASEBOARD_FAB2(SCH_1):PAGE54
  J6L1  171 VSS<35> SCONN288_H44441003_PIP-SCONN,HA    I43 @BASEBOARD_FAB2_LIB.BASEBOARD_FAB2(SCH_1):PAGE54
  J6L1  169 VSS<36> SCONN288_H44441003_PIP-SCONN,HA    I43 @BASEBOARD_FAB2_LIB.BASEBOARD_FAB2(SCH_1):PAGE54
  J6L1  167 VSS<37> SCONN288_H44441003_PIP-SCONN,HA    I43 @BASEBOARD_FAB2_LIB.BASEBOARD_FAB2(SCH_1):PAGE54
  J6L1  165 VSS<38> SCONN288_H44441003_PIP-SCONN,HA    I43 @BASEBOARD_FAB2_LIB.BASEBOARD_FAB2(SCH_1):PAGE54
  J6L1  162 VSS<39> SCONN288_H44441003_PIP-SCONN,HA    I43 @BASEBOARD_FAB2_LIB.BASEBOARD_FAB2(SCH_1):PAGE54
  J6L1  160 VSS<40> SCONN288_H44441003_PIP-SCONN,HA    I43 @BASEBOARD_FAB2_LIB.BASEBOARD_FAB2(SCH_1):PAGE54
  J6L1  158 VSS<41> SCONN288_H44441003_PIP-SCONN,HA    I43 @BASEBOARD_FAB2_LIB.BASEBOARD_FAB2(SCH_1):PAGE54
  J6L1  156 VSS<42> SCONN288_H44441003_PIP-SCONN,HA    I43 @BASEBOARD_FAB2_LIB.BASEBOARD_FAB2(SCH_1):PAGE54
  J6L1  154 VSS<43> SCONN288_H44441003_PIP-SCONN,HA    I43 @BASEBOARD_FAB2_LIB.BASEBOARD_FAB2(SCH_1):PAGE54
  J6L1  151 VSS<44> SCONN288_H44441003_PIP-SCONN,HA    I43 @BASEBOARD_FAB2_LIB.BASEBOARD_FAB2(SCH_1):PAGE54
  J6L1  149 VSS<45> SCONN288_H44441003_PIP-SCONN,HA    I43 @BASEBOARD_FAB2_LIB.BASEBOARD_FAB2(SCH_1):PAGE54
  J6L1  147 VSS<46> SCONN288_H44441003_PIP-SCONN,HA    I43 @BASEBOARD_FAB2_LIB.BASEBOARD_FAB2(SCH_1):PAGE54
  J6L1  138 VSS<47> SCONN288_H44441003_PIP-SCONN,HA    I43 @BASEBOARD_FAB2_LIB.BASEBOARD_FAB2(SCH_1):PAGE54
  J6L1  136 VSS<48> SCONN288_H44441003_PIP-SCONN,HA    I43 @BASEBOARD_FAB2_LIB.BASEBOARD_FAB2(SCH_1):PAGE54
  J6L1  134 VSS<49> SCONN288_H44441003_PIP-SCONN,HA    I43 @BASEBOARD_FAB2_LIB.BASEBOARD_FAB2(SCH_1):PAGE54
  J6L1  131 VSS<50> SCONN288_H44441003_PIP-SCONN,HA    I43 @BASEBOARD_FAB2_LIB.BASEBOARD_FAB2(SCH_1):PAGE54
  J6L1  129 VSS<51> SCONN288_H44441003_PIP-SCONN,HA    I43 @BASEBOARD_FAB2_LIB.BASEBOARD_FAB2(SCH_1):PAGE54
  J6L1  127 VSS<52> SCONN288_H44441003_PIP-SCONN,HA    I43 @BASEBOARD_FAB2_LIB.BASEBOARD_FAB2(SCH_1):PAGE54
  J6L1  125 VSS<53> SCONN288_H44441003_PIP-SCONN,HA    I43 @BASEBOARD_FAB2_LIB.BASEBOARD_FAB2(SCH_1):PAGE54
  J6L1  123 VSS<54> SCONN288_H44441003_PIP-SCONN,HA    I43 @BASEBOARD_FAB2_LIB.BASEBOARD_FAB2(SCH_1):PAGE54
  J6L1  120 VSS<55> SCONN288_H44441003_PIP-SCONN,HA    I43 @BASEBOARD_FAB2_LIB.BASEBOARD_FAB2(SCH_1):PAGE54
  J6L1  118 VSS<56> SCONN288_H44441003_PIP-SCONN,HA    I43 @BASEBOARD_FAB2_LIB.BASEBOARD_FAB2(SCH_1):PAGE54
  J6L1  116 VSS<57> SCONN288_H44441003_PIP-SCONN,HA    I43 @BASEBOARD_FAB2_LIB.BASEBOARD_FAB2(SCH_1):PAGE54
  J6L1  114 VSS<58> SCONN288_H44441003_PIP-SCONN,HA    I43 @BASEBOARD_FAB2_LIB.BASEBOARD_FAB2(SCH_1):PAGE54
  J6L1  112 VSS<59> SCONN288_H44441003_PIP-SCONN,HA    I43 @BASEBOARD_FAB2_LIB.BASEBOARD_FAB2(SCH_1):PAGE54
  J6L1  109 VSS<60> SCONN288_H44441003_PIP-SCONN,HA    I43 @BASEBOARD_FAB2_LIB.BASEBOARD_FAB2(SCH_1):PAGE54
  J6L1  107 VSS<61> SCONN288_H44441003_PIP-SCONN,HA    I43 @BASEBOARD_FAB2_LIB.BASEBOARD_FAB2(SCH_1):PAGE54
  J6L1  105 VSS<62> SCONN288_H44441003_PIP-SCONN,HA    I43 @BASEBOARD_FAB2_LIB.BASEBOARD_FAB2(SCH_1):PAGE54
  J6L1  103 VSS<63> SCONN288_H44441003_PIP-SCONN,HA    I43 @BASEBOARD_FAB2_LIB.BASEBOARD_FAB2(SCH_1):PAGE54
  J6L1  101 VSS<64> SCONN288_H44441003_PIP-SCONN,HA    I43 @BASEBOARD_FAB2_LIB.BASEBOARD_FAB2(SCH_1):PAGE54
  J6L1   98 VSS<65> SCONN288_H44441003_PIP-SCONN,HA    I43 @BASEBOARD_FAB2_LIB.BASEBOARD_FAB2(SCH_1):PAGE54
  J6L1   96 VSS<66> SCONN288_H44441003_PIP-SCONN,HA    I43 @BASEBOARD_FAB2_LIB.BASEBOARD_FAB2(SCH_1):PAGE54
  J6L1   94 VSS<67> SCONN288_H44441003_PIP-SCONN,HA    I43 @BASEBOARD_FAB2_LIB.BASEBOARD_FAB2(SCH_1):PAGE54
  J6L1   57 VSS<68> SCONN288_H44441003_PIP-SCONN,HA    I43 @BASEBOARD_FAB2_LIB.BASEBOARD_FAB2(SCH_1):PAGE54
  J6L1   55 VSS<69> SCONN288_H44441003_PIP-SCONN,HA    I43 @BASEBOARD_FAB2_LIB.BASEBOARD_FAB2(SCH_1):PAGE54
  J6L1   53 VSS<70> SCONN288_H44441003_PIP-SCONN,HA    I43 @BASEBOARD_FAB2_LIB.BASEBOARD_FAB2(SCH_1):PAGE54
  J6L1   50 VSS<71> SCONN288_H44441003_PIP-SCONN,HA    I43 @BASEBOARD_FAB2_LIB.BASEBOARD_FAB2(SCH_1):PAGE54
  J6L1   48 VSS<72> SCONN288_H44441003_PIP-SCONN,HA    I43 @BASEBOARD_FAB2_LIB.BASEBOARD_FAB2(SCH_1):PAGE54
  J6L1   46 VSS<73> SCONN288_H44441003_PIP-SCONN,HA    I43 @BASEBOARD_FAB2_LIB.BASEBOARD_FAB2(SCH_1):PAGE54
  J6L1   44 VSS<74> SCONN288_H44441003_PIP-SCONN,HA    I43 @BASEBOARD_FAB2_LIB.BASEBOARD_FAB2(SCH_1):PAGE54
  J6L1   42 VSS<75> SCONN288_H44441003_PIP-SCONN,HA    I43 @BASEBOARD_FAB2_LIB.BASEBOARD_FAB2(SCH_1):PAGE54
  J6L1   39 VSS<76> SCONN288_H44441003_PIP-SCONN,HA    I43 @BASEBOARD_FAB2_LIB.BASEBOARD_FAB2(SCH_1):PAGE54
  J6L1   37 VSS<77> SCONN288_H44441003_PIP-SCONN,HA    I43 @BASEBOARD_FAB2_LIB.BASEBOARD_FAB2(SCH_1):PAGE54
  J6L1   35 VSS<78> SCONN288_H44441003_PIP-SCONN,HA    I43 @BASEBOARD_FAB2_LIB.BASEBOARD_FAB2(SCH_1):PAGE54
  J6L1   33 VSS<79> SCONN288_H44441003_PIP-SCONN,HA    I43 @BASEBOARD_FAB2_LIB.BASEBOARD_FAB2(SCH_1):PAGE54
  J6L1   31 VSS<80> SCONN288_H44441003_PIP-SCONN,HA    I43 @BASEBOARD_FAB2_LIB.BASEBOARD_FAB2(SCH_1):PAGE54
  J6L1   28 VSS<81> SCONN288_H44441003_PIP-SCONN,HA    I43 @BASEBOARD_FAB2_LIB.BASEBOARD_FAB2(SCH_1):PAGE54
  J6L1   26 VSS<82> SCONN288_H44441003_PIP-SCONN,HA    I43 @BASEBOARD_FAB2_LIB.BASEBOARD_FAB2(SCH_1):PAGE54
  J6L1   24 VSS<83> SCONN288_H44441003_PIP-SCONN,HA    I43 @BASEBOARD_FAB2_LIB.BASEBOARD_FAB2(SCH_1):PAGE54
  J6L1   22 VSS<84> SCONN288_H44441003_PIP-SCONN,HA    I43 @BASEBOARD_FAB2_LIB.BASEBOARD_FAB2(SCH_1):PAGE54
  J6L1   20 VSS<85> SCONN288_H44441003_PIP-SCONN,HA    I43 @BASEBOARD_FAB2_LIB.BASEBOARD_FAB2(SCH_1):PAGE54
  J6L1   17 VSS<86> SCONN288_H44441003_PIP-SCONN,HA    I43 @BASEBOARD_FAB2_LIB.BASEBOARD_FAB2(SCH_1):PAGE54
  J6L1   15 VSS<87> SCONN288_H44441003_PIP-SCONN,HA    I43 @BASEBOARD_FAB2_LIB.BASEBOARD_FAB2(SCH_1):PAGE54
  J6L1   13 VSS<88> SCONN288_H44441003_PIP-SCONN,HA    I43 @BASEBOARD_FAB2_LIB.BASEBOARD_FAB2(SCH_1):PAGE54
  J6L1   11 VSS<89> SCONN288_H44441003_PIP-SCONN,HA    I43 @BASEBOARD_FAB2_LIB.BASEBOARD_FAB2(SCH_1):PAGE54
  J6L1    9 VSS<90> SCONN288_H44441003_PIP-SCONN,HA    I43 @BASEBOARD_FAB2_LIB.BASEBOARD_FAB2(SCH_1):PAGE54
  J6L1    6 VSS<91> SCONN288_H44441003_PIP-SCONN,HA    I43 @BASEBOARD_FAB2_LIB.BASEBOARD_FAB2(SCH_1):PAGE54
  J6L1    4 VSS<92> SCONN288_H44441003_PIP-SCONN,HA    I43 @BASEBOARD_FAB2_LIB.BASEBOARD_FAB2(SCH_1):PAGE54
  J6L1    2 VSS<93> SCONN288_H44441003_PIP-SCONN,HA    I43 @BASEBOARD_FAB2_LIB.BASEBOARD_FAB2(SCH_1):PAGE54
  J6L1  140  SA<1> SCONN288_H44441003_PIP-SCONN,HA   I111 @BASEBOARD_FAB2_LIB.BASEBOARD_FAB2(SCH_1):PAGE54
  C4A5    2      B CAP_A_0402V-0.01UF,25V,10%,X7RA   I179 @BASEBOARD_FAB2_LIB.BASEBOARD_FAB2(SCH_1):PAGE54
 R7P19    2      B RES_0402-100.0,1%,1/16W,CHIP,GA   I115 @BASEBOARD_FAB2_LIB.BASEBOARD_FAB2(SCH_1):PAGE55
  R3D1    2      B RES_0402-90.9,1%,1/16W,CHIP,G2A   I116 @BASEBOARD_FAB2_LIB.BASEBOARD_FAB2(SCH_1):PAGE55
  R3D2    2      B RES_0402-90.9,1%,1/16W,CHIP,G2A   I117 @BASEBOARD_FAB2_LIB.BASEBOARD_FAB2(SCH_1):PAGE55
  R3D3    2      B RES_0402-100.0,1%,1/16W,CHIP,GA   I118 @BASEBOARD_FAB2_LIB.BASEBOARD_FAB2(SCH_1):PAGE55
 R7P16    2      B RES_0402-90.9,1%,1/16W,CHIP,G2A   I119 @BASEBOARD_FAB2_LIB.BASEBOARD_FAB2(SCH_1):PAGE55
  R7P8    2      B RES_0402-49.9,1%,1/16W,CHIP,G2A   I123 @BASEBOARD_FAB2_LIB.BASEBOARD_FAB2(SCH_1):PAGE55
 R7P10    2      B RES_0402-49.9,1%,1/16W,CHIP,G2A   I124 @BASEBOARD_FAB2_LIB.BASEBOARD_FAB2(SCH_1):PAGE55
 R3D19    2      B RES_0402-49.9,1%,1/16W,CHIP,G2A   I125 @BASEBOARD_FAB2_LIB.BASEBOARD_FAB2(SCH_1):PAGE55
 R7P11    2      B RES_0402-49.9,1%,1/16W,CHIP,G2A   I126 @BASEBOARD_FAB2_LIB.BASEBOARD_FAB2(SCH_1):PAGE55
 R7P17    2      B RES_0402-90.9,1%,1/16W,CHIP,G2A   I140 @BASEBOARD_FAB2_LIB.BASEBOARD_FAB2(SCH_1):PAGE55
  R3D4    2      B RES_0402-49.9,1%,1/16W,CHIP,G2A   I155 @BASEBOARD_FAB2_LIB.BASEBOARD_FAB2(SCH_1):PAGE55
  R8P3    2      B RES_0402-49.9,1%,1/16W,CHIP,G2A   I173 @BASEBOARD_FAB2_LIB.BASEBOARD_FAB2(SCH_1):PAGE56
  R8R1    2      B RES_0402-49.9,1%,1/16W,CHIP,G2A   I174 @BASEBOARD_FAB2_LIB.BASEBOARD_FAB2(SCH_1):PAGE56
  U2D1 DF23 UPI2_RX_DN<0> SKX_EXT_B_BGA1-IC,TBD     I1 @BASEBOARD_FAB2_LIB.BASEBOARD_FAB2(SCH_1):PAGE69
  U2D1 DE22 UPI2_RX_DN<1> SKX_EXT_B_BGA1-IC,TBD     I1 @BASEBOARD_FAB2_LIB.BASEBOARD_FAB2(SCH_1):PAGE69
  U2D1 DC22 UPI2_RX_DN<2> SKX_EXT_B_BGA1-IC,TBD     I1 @BASEBOARD_FAB2_LIB.BASEBOARD_FAB2(SCH_1):PAGE69
  U2D1 DB21 UPI2_RX_DN<3> SKX_EXT_B_BGA1-IC,TBD     I1 @BASEBOARD_FAB2_LIB.BASEBOARD_FAB2(SCH_1):PAGE69
  U2D1 DD19 UPI2_RX_DN<4> SKX_EXT_B_BGA1-IC,TBD     I1 @BASEBOARD_FAB2_LIB.BASEBOARD_FAB2(SCH_1):PAGE69
  U2D1 DA20 UPI2_RX_DN<5> SKX_EXT_B_BGA1-IC,TBD     I1 @BASEBOARD_FAB2_LIB.BASEBOARD_FAB2(SCH_1):PAGE69
  U2D1 CW20 UPI2_RX_DN<6> SKX_EXT_B_BGA1-IC,TBD     I1 @BASEBOARD_FAB2_LIB.BASEBOARD_FAB2(SCH_1):PAGE69
  U2D1 CV19 UPI2_RX_DN<7> SKX_EXT_B_BGA1-IC,TBD     I1 @BASEBOARD_FAB2_LIB.BASEBOARD_FAB2(SCH_1):PAGE69
  U2D1 CT21 UPI2_RX_DN<8> SKX_EXT_B_BGA1-IC,TBD     I1 @BASEBOARD_FAB2_LIB.BASEBOARD_FAB2(SCH_1):PAGE69
  U2D1 CR18 UPI2_RX_DN<9> SKX_EXT_B_BGA1-IC,TBD     I1 @BASEBOARD_FAB2_LIB.BASEBOARD_FAB2(SCH_1):PAGE69
  U2D1 CN20 UPI2_RX_DN<10> SKX_EXT_B_BGA1-IC,TBD     I1 @BASEBOARD_FAB2_LIB.BASEBOARD_FAB2(SCH_1):PAGE69
  U2D1 CP21 UPI2_RX_DN<11> SKX_EXT_B_BGA1-IC,TBD     I1 @BASEBOARD_FAB2_LIB.BASEBOARD_FAB2(SCH_1):PAGE69
  U2D1 CL16 UPI2_RX_DN<12> SKX_EXT_B_BGA1-IC,TBD     I1 @BASEBOARD_FAB2_LIB.BASEBOARD_FAB2(SCH_1):PAGE69
  U2D1 CJ18 UPI2_RX_DN<13> SKX_EXT_B_BGA1-IC,TBD     I1 @BASEBOARD_FAB2_LIB.BASEBOARD_FAB2(SCH_1):PAGE69
  U2D1 CH17 UPI2_RX_DN<14> SKX_EXT_B_BGA1-IC,TBD     I1 @BASEBOARD_FAB2_LIB.BASEBOARD_FAB2(SCH_1):PAGE69
  U2D1 CE16 UPI2_RX_DN<15> SKX_EXT_B_BGA1-IC,TBD     I1 @BASEBOARD_FAB2_LIB.BASEBOARD_FAB2(SCH_1):PAGE69
  U2D1 CD15 UPI2_RX_DN<16> SKX_EXT_B_BGA1-IC,TBD     I1 @BASEBOARD_FAB2_LIB.BASEBOARD_FAB2(SCH_1):PAGE69
  U2D1 CF17 UPI2_RX_DN<17> SKX_EXT_B_BGA1-IC,TBD     I1 @BASEBOARD_FAB2_LIB.BASEBOARD_FAB2(SCH_1):PAGE69
  U2D1 CB15 UPI2_RX_DN<18> SKX_EXT_B_BGA1-IC,TBD     I1 @BASEBOARD_FAB2_LIB.BASEBOARD_FAB2(SCH_1):PAGE69
  U2D1 BY17 UPI2_RX_DN<19> SKX_EXT_B_BGA1-IC,TBD     I1 @BASEBOARD_FAB2_LIB.BASEBOARD_FAB2(SCH_1):PAGE69
  U2D1 DG22 UPI2_RX_DP<0> SKX_EXT_B_BGA1-IC,TBD     I1 @BASEBOARD_FAB2_LIB.BASEBOARD_FAB2(SCH_1):PAGE69
  U2D1 DD21 UPI2_RX_DP<1> SKX_EXT_B_BGA1-IC,TBD     I1 @BASEBOARD_FAB2_LIB.BASEBOARD_FAB2(SCH_1):PAGE69
  U2D1 DA22 UPI2_RX_DP<2> SKX_EXT_B_BGA1-IC,TBD     I1 @BASEBOARD_FAB2_LIB.BASEBOARD_FAB2(SCH_1):PAGE69
  U2D1 DC20 UPI2_RX_DP<3> SKX_EXT_B_BGA1-IC,TBD     I1 @BASEBOARD_FAB2_LIB.BASEBOARD_FAB2(SCH_1):PAGE69
  U2D1 DB19 UPI2_RX_DP<4> SKX_EXT_B_BGA1-IC,TBD     I1 @BASEBOARD_FAB2_LIB.BASEBOARD_FAB2(SCH_1):PAGE69
  U2D1 CY19 UPI2_RX_DP<5> SKX_EXT_B_BGA1-IC,TBD     I1 @BASEBOARD_FAB2_LIB.BASEBOARD_FAB2(SCH_1):PAGE69
  U2D1 CU20 UPI2_RX_DP<6> SKX_EXT_B_BGA1-IC,TBD     I1 @BASEBOARD_FAB2_LIB.BASEBOARD_FAB2(SCH_1):PAGE69
  U2D1 CW18 UPI2_RX_DP<7> SKX_EXT_B_BGA1-IC,TBD     I1 @BASEBOARD_FAB2_LIB.BASEBOARD_FAB2(SCH_1):PAGE69
  U2D1 CR20 UPI2_RX_DP<8> SKX_EXT_B_BGA1-IC,TBD     I1 @BASEBOARD_FAB2_LIB.BASEBOARD_FAB2(SCH_1):PAGE69
  U2D1 CN18 UPI2_RX_DP<9> SKX_EXT_B_BGA1-IC,TBD     I1 @BASEBOARD_FAB2_LIB.BASEBOARD_FAB2(SCH_1):PAGE69
  U2D1 CP19 UPI2_RX_DP<10> SKX_EXT_B_BGA1-IC,TBD     I1 @BASEBOARD_FAB2_LIB.BASEBOARD_FAB2(SCH_1):PAGE69
  U2D1 CM21 UPI2_RX_DP<11> SKX_EXT_B_BGA1-IC,TBD     I1 @BASEBOARD_FAB2_LIB.BASEBOARD_FAB2(SCH_1):PAGE69
  U2D1 CJ16 UPI2_RX_DP<12> SKX_EXT_B_BGA1-IC,TBD     I1 @BASEBOARD_FAB2_LIB.BASEBOARD_FAB2(SCH_1):PAGE69
  U2D1 CK17 UPI2_RX_DP<13> SKX_EXT_B_BGA1-IC,TBD     I1 @BASEBOARD_FAB2_LIB.BASEBOARD_FAB2(SCH_1):PAGE69
  U2D1 CG16 UPI2_RX_DP<14> SKX_EXT_B_BGA1-IC,TBD     I1 @BASEBOARD_FAB2_LIB.BASEBOARD_FAB2(SCH_1):PAGE69
  U2D1 CF15 UPI2_RX_DP<15> SKX_EXT_B_BGA1-IC,TBD     I1 @BASEBOARD_FAB2_LIB.BASEBOARD_FAB2(SCH_1):PAGE69
  U2D1 CC14 UPI2_RX_DP<16> SKX_EXT_B_BGA1-IC,TBD     I1 @BASEBOARD_FAB2_LIB.BASEBOARD_FAB2(SCH_1):PAGE69
  U2D1 CD17 UPI2_RX_DP<17> SKX_EXT_B_BGA1-IC,TBD     I1 @BASEBOARD_FAB2_LIB.BASEBOARD_FAB2(SCH_1):PAGE69
  U2D1 BY15 UPI2_RX_DP<18> SKX_EXT_B_BGA1-IC,TBD     I1 @BASEBOARD_FAB2_LIB.BASEBOARD_FAB2(SCH_1):PAGE69
  U2D1 CA16 UPI2_RX_DP<19> SKX_EXT_B_BGA1-IC,TBD     I1 @BASEBOARD_FAB2_LIB.BASEBOARD_FAB2(SCH_1):PAGE69
 R3D27    2      B RES_0402-249,0.1%,1/16W,CHIP,GA    I43 @BASEBOARD_FAB2_LIB.BASEBOARD_FAB2(SCH_1):PAGE71
  C3D3    2      B CAP_0603LF-10UF,4V,20%,X6S,E15A    I25 @BASEBOARD_FAB2_LIB.BASEBOARD_FAB2(SCH_1):PAGE72
  U2D1  J74 VSS<1094> SKX_EXT_B_BGA1-IC,TBD    I20 @BASEBOARD_FAB2_LIB.BASEBOARD_FAB2(SCH_1):PAGE74
  U2D1  J72 VSS<1095> SKX_EXT_B_BGA1-IC,TBD    I20 @BASEBOARD_FAB2_LIB.BASEBOARD_FAB2(SCH_1):PAGE74
  U2D1  J40 VSS<1096> SKX_EXT_B_BGA1-IC,TBD    I20 @BASEBOARD_FAB2_LIB.BASEBOARD_FAB2(SCH_1):PAGE74
  U2D1  J38 VSS<1097> SKX_EXT_B_BGA1-IC,TBD    I20 @BASEBOARD_FAB2_LIB.BASEBOARD_FAB2(SCH_1):PAGE74
  U2D1  J34 VSS<1098> SKX_EXT_B_BGA1-IC,TBD    I20 @BASEBOARD_FAB2_LIB.BASEBOARD_FAB2(SCH_1):PAGE74
  U2D1  J32 VSS<1099> SKX_EXT_B_BGA1-IC,TBD    I20 @BASEBOARD_FAB2_LIB.BASEBOARD_FAB2(SCH_1):PAGE74
  U2D1  J28 VSS<1100> SKX_EXT_B_BGA1-IC,TBD    I20 @BASEBOARD_FAB2_LIB.BASEBOARD_FAB2(SCH_1):PAGE74
  U2D1  J26 VSS<1101> SKX_EXT_B_BGA1-IC,TBD    I20 @BASEBOARD_FAB2_LIB.BASEBOARD_FAB2(SCH_1):PAGE74
  U2D1  J22 VSS<1102> SKX_EXT_B_BGA1-IC,TBD    I20 @BASEBOARD_FAB2_LIB.BASEBOARD_FAB2(SCH_1):PAGE74
  U2D1  J14 VSS<1103> SKX_EXT_B_BGA1-IC,TBD    I20 @BASEBOARD_FAB2_LIB.BASEBOARD_FAB2(SCH_1):PAGE74
  U2D1  J12 VSS<1104> SKX_EXT_B_BGA1-IC,TBD    I20 @BASEBOARD_FAB2_LIB.BASEBOARD_FAB2(SCH_1):PAGE74
  U2D1   J4 VSS<1105> SKX_EXT_B_BGA1-IC,TBD    I20 @BASEBOARD_FAB2_LIB.BASEBOARD_FAB2(SCH_1):PAGE74
  U2D1 DN44 VSS<1106> SKX_EXT_B_BGA1-IC,TBD    I20 @BASEBOARD_FAB2_LIB.BASEBOARD_FAB2(SCH_1):PAGE74
  U2D1  H75 VSS<1107> SKX_EXT_B_BGA1-IC,TBD    I20 @BASEBOARD_FAB2_LIB.BASEBOARD_FAB2(SCH_1):PAGE74
  U2D1  H71 VSS<1108> SKX_EXT_B_BGA1-IC,TBD    I20 @BASEBOARD_FAB2_LIB.BASEBOARD_FAB2(SCH_1):PAGE74
  U2D1  H65 VSS<1109> SKX_EXT_B_BGA1-IC,TBD    I20 @BASEBOARD_FAB2_LIB.BASEBOARD_FAB2(SCH_1):PAGE74
  U2D1  H41 VSS<1110> SKX_EXT_B_BGA1-IC,TBD    I20 @BASEBOARD_FAB2_LIB.BASEBOARD_FAB2(SCH_1):PAGE74
  U2D1  H39 VSS<1111> SKX_EXT_B_BGA1-IC,TBD    I20 @BASEBOARD_FAB2_LIB.BASEBOARD_FAB2(SCH_1):PAGE74
  U2D1  H37 VSS<1112> SKX_EXT_B_BGA1-IC,TBD    I20 @BASEBOARD_FAB2_LIB.BASEBOARD_FAB2(SCH_1):PAGE74
  U2D1  H35 VSS<1113> SKX_EXT_B_BGA1-IC,TBD    I20 @BASEBOARD_FAB2_LIB.BASEBOARD_FAB2(SCH_1):PAGE74
  U2D1  H33 VSS<1114> SKX_EXT_B_BGA1-IC,TBD    I20 @BASEBOARD_FAB2_LIB.BASEBOARD_FAB2(SCH_1):PAGE74
  U2D1  H31 VSS<1115> SKX_EXT_B_BGA1-IC,TBD    I20 @BASEBOARD_FAB2_LIB.BASEBOARD_FAB2(SCH_1):PAGE74
  U2D1  H29 VSS<1116> SKX_EXT_B_BGA1-IC,TBD    I20 @BASEBOARD_FAB2_LIB.BASEBOARD_FAB2(SCH_1):PAGE74
  U2D1  H27 VSS<1117> SKX_EXT_B_BGA1-IC,TBD    I20 @BASEBOARD_FAB2_LIB.BASEBOARD_FAB2(SCH_1):PAGE74
  U2D1  H25 VSS<1118> SKX_EXT_B_BGA1-IC,TBD    I20 @BASEBOARD_FAB2_LIB.BASEBOARD_FAB2(SCH_1):PAGE74
  U2D1  H11 VSS<1119> SKX_EXT_B_BGA1-IC,TBD    I20 @BASEBOARD_FAB2_LIB.BASEBOARD_FAB2(SCH_1):PAGE74
  U2D1   H3 VSS<1120> SKX_EXT_B_BGA1-IC,TBD    I20 @BASEBOARD_FAB2_LIB.BASEBOARD_FAB2(SCH_1):PAGE74
  U2D1  G82 VSS<1121> SKX_EXT_B_BGA1-IC,TBD    I20 @BASEBOARD_FAB2_LIB.BASEBOARD_FAB2(SCH_1):PAGE74
  U2D1  G80 VSS<1122> SKX_EXT_B_BGA1-IC,TBD    I20 @BASEBOARD_FAB2_LIB.BASEBOARD_FAB2(SCH_1):PAGE74
  U2D1  G78 VSS<1123> SKX_EXT_B_BGA1-IC,TBD    I20 @BASEBOARD_FAB2_LIB.BASEBOARD_FAB2(SCH_1):PAGE74
  U2D1  G76 VSS<1124> SKX_EXT_B_BGA1-IC,TBD    I20 @BASEBOARD_FAB2_LIB.BASEBOARD_FAB2(SCH_1):PAGE74
  U2D1  G70 VSS<1125> SKX_EXT_B_BGA1-IC,TBD    I20 @BASEBOARD_FAB2_LIB.BASEBOARD_FAB2(SCH_1):PAGE74
  U2D1  G66 VSS<1126> SKX_EXT_B_BGA1-IC,TBD    I20 @BASEBOARD_FAB2_LIB.BASEBOARD_FAB2(SCH_1):PAGE74
  U2D1  G42 VSS<1127> SKX_EXT_B_BGA1-IC,TBD    I20 @BASEBOARD_FAB2_LIB.BASEBOARD_FAB2(SCH_1):PAGE74
  U2D1  G38 VSS<1128> SKX_EXT_B_BGA1-IC,TBD    I20 @BASEBOARD_FAB2_LIB.BASEBOARD_FAB2(SCH_1):PAGE74
  U2D1  G36 VSS<1129> SKX_EXT_B_BGA1-IC,TBD    I20 @BASEBOARD_FAB2_LIB.BASEBOARD_FAB2(SCH_1):PAGE74
  U2D1  G32 VSS<1130> SKX_EXT_B_BGA1-IC,TBD    I20 @BASEBOARD_FAB2_LIB.BASEBOARD_FAB2(SCH_1):PAGE74
  U2D1  G30 VSS<1131> SKX_EXT_B_BGA1-IC,TBD    I20 @BASEBOARD_FAB2_LIB.BASEBOARD_FAB2(SCH_1):PAGE74
  U2D1  G26 VSS<1132> SKX_EXT_B_BGA1-IC,TBD    I20 @BASEBOARD_FAB2_LIB.BASEBOARD_FAB2(SCH_1):PAGE74
  U2D1  G24 VSS<1133> SKX_EXT_B_BGA1-IC,TBD    I20 @BASEBOARD_FAB2_LIB.BASEBOARD_FAB2(SCH_1):PAGE74
  U2D1  G22 VSS<1134> SKX_EXT_B_BGA1-IC,TBD    I20 @BASEBOARD_FAB2_LIB.BASEBOARD_FAB2(SCH_1):PAGE74
  U2D1   G8 VSS<1135> SKX_EXT_B_BGA1-IC,TBD    I20 @BASEBOARD_FAB2_LIB.BASEBOARD_FAB2(SCH_1):PAGE74
  U2D1   G4 VSS<1136> SKX_EXT_B_BGA1-IC,TBD    I20 @BASEBOARD_FAB2_LIB.BASEBOARD_FAB2(SCH_1):PAGE74
  U2D1  F69 VSS<1137> SKX_EXT_B_BGA1-IC,TBD    I20 @BASEBOARD_FAB2_LIB.BASEBOARD_FAB2(SCH_1):PAGE74
  U2D1  F67 VSS<1138> SKX_EXT_B_BGA1-IC,TBD    I20 @BASEBOARD_FAB2_LIB.BASEBOARD_FAB2(SCH_1):PAGE74
  U2D1  F43 VSS<1139> SKX_EXT_B_BGA1-IC,TBD    I20 @BASEBOARD_FAB2_LIB.BASEBOARD_FAB2(SCH_1):PAGE74
  U2D1  F37 VSS<1140> SKX_EXT_B_BGA1-IC,TBD    I20 @BASEBOARD_FAB2_LIB.BASEBOARD_FAB2(SCH_1):PAGE74
  U2D1  F31 VSS<1141> SKX_EXT_B_BGA1-IC,TBD    I20 @BASEBOARD_FAB2_LIB.BASEBOARD_FAB2(SCH_1):PAGE74
  U2D1  F25 VSS<1142> SKX_EXT_B_BGA1-IC,TBD    I20 @BASEBOARD_FAB2_LIB.BASEBOARD_FAB2(SCH_1):PAGE74
  U2D1  F19 VSS<1143> SKX_EXT_B_BGA1-IC,TBD    I20 @BASEBOARD_FAB2_LIB.BASEBOARD_FAB2(SCH_1):PAGE74
  U2D1  F17 VSS<1144> SKX_EXT_B_BGA1-IC,TBD    I20 @BASEBOARD_FAB2_LIB.BASEBOARD_FAB2(SCH_1):PAGE74
  U2D1   F5 VSS<1145> SKX_EXT_B_BGA1-IC,TBD    I20 @BASEBOARD_FAB2_LIB.BASEBOARD_FAB2(SCH_1):PAGE74
  U2D1  E76 VSS<1146> SKX_EXT_B_BGA1-IC,TBD    I20 @BASEBOARD_FAB2_LIB.BASEBOARD_FAB2(SCH_1):PAGE74
  U2D1  E74 VSS<1147> SKX_EXT_B_BGA1-IC,TBD    I20 @BASEBOARD_FAB2_LIB.BASEBOARD_FAB2(SCH_1):PAGE74
  U2D1  E72 VSS<1148> SKX_EXT_B_BGA1-IC,TBD    I20 @BASEBOARD_FAB2_LIB.BASEBOARD_FAB2(SCH_1):PAGE74
  U2D1  E22 VSS<1149> SKX_EXT_B_BGA1-IC,TBD    I20 @BASEBOARD_FAB2_LIB.BASEBOARD_FAB2(SCH_1):PAGE74
  U2D1  E20 VSS<1150> SKX_EXT_B_BGA1-IC,TBD    I20 @BASEBOARD_FAB2_LIB.BASEBOARD_FAB2(SCH_1):PAGE74
  U2D1  E18 VSS<1151> SKX_EXT_B_BGA1-IC,TBD    I20 @BASEBOARD_FAB2_LIB.BASEBOARD_FAB2(SCH_1):PAGE74
  U2D1  E16 VSS<1152> SKX_EXT_B_BGA1-IC,TBD    I20 @BASEBOARD_FAB2_LIB.BASEBOARD_FAB2(SCH_1):PAGE74
  U2D1   E8 VSS<1153> SKX_EXT_B_BGA1-IC,TBD    I20 @BASEBOARD_FAB2_LIB.BASEBOARD_FAB2(SCH_1):PAGE74
  U2D1   E6 VSS<1154> SKX_EXT_B_BGA1-IC,TBD    I20 @BASEBOARD_FAB2_LIB.BASEBOARD_FAB2(SCH_1):PAGE74
  U2D1  D77 VSS<1155> SKX_EXT_B_BGA1-IC,TBD    I20 @BASEBOARD_FAB2_LIB.BASEBOARD_FAB2(SCH_1):PAGE74
  U2D1  D43 VSS<1156> SKX_EXT_B_BGA1-IC,TBD    I20 @BASEBOARD_FAB2_LIB.BASEBOARD_FAB2(SCH_1):PAGE74
  U2D1  D41 VSS<1157> SKX_EXT_B_BGA1-IC,TBD    I20 @BASEBOARD_FAB2_LIB.BASEBOARD_FAB2(SCH_1):PAGE74
  U2D1  D39 VSS<1158> SKX_EXT_B_BGA1-IC,TBD    I20 @BASEBOARD_FAB2_LIB.BASEBOARD_FAB2(SCH_1):PAGE74
  U2D1  D37 VSS<1159> SKX_EXT_B_BGA1-IC,TBD    I20 @BASEBOARD_FAB2_LIB.BASEBOARD_FAB2(SCH_1):PAGE74
  U2D1  D35 VSS<1160> SKX_EXT_B_BGA1-IC,TBD    I20 @BASEBOARD_FAB2_LIB.BASEBOARD_FAB2(SCH_1):PAGE74
  U2D1  D33 VSS<1161> SKX_EXT_B_BGA1-IC,TBD    I20 @BASEBOARD_FAB2_LIB.BASEBOARD_FAB2(SCH_1):PAGE74
  U2D1  D31 VSS<1162> SKX_EXT_B_BGA1-IC,TBD    I20 @BASEBOARD_FAB2_LIB.BASEBOARD_FAB2(SCH_1):PAGE74
  U2D1  D29 VSS<1163> SKX_EXT_B_BGA1-IC,TBD    I20 @BASEBOARD_FAB2_LIB.BASEBOARD_FAB2(SCH_1):PAGE74
  U2D1  D27 VSS<1164> SKX_EXT_B_BGA1-IC,TBD    I20 @BASEBOARD_FAB2_LIB.BASEBOARD_FAB2(SCH_1):PAGE74
  U2D1  D25 VSS<1165> SKX_EXT_B_BGA1-IC,TBD    I20 @BASEBOARD_FAB2_LIB.BASEBOARD_FAB2(SCH_1):PAGE74
  U2D1  D13 VSS<1166> SKX_EXT_B_BGA1-IC,TBD    I20 @BASEBOARD_FAB2_LIB.BASEBOARD_FAB2(SCH_1):PAGE74
  U2D1  D11 VSS<1167> SKX_EXT_B_BGA1-IC,TBD    I20 @BASEBOARD_FAB2_LIB.BASEBOARD_FAB2(SCH_1):PAGE74
  U2D1 CM27 VSS<1168> SKX_EXT_B_BGA1-IC,TBD    I20 @BASEBOARD_FAB2_LIB.BASEBOARD_FAB2(SCH_1):PAGE74
  U2D1  C78 VSS<1169> SKX_EXT_B_BGA1-IC,TBD    I20 @BASEBOARD_FAB2_LIB.BASEBOARD_FAB2(SCH_1):PAGE74
  U2D1  C76 VSS<1170> SKX_EXT_B_BGA1-IC,TBD    I20 @BASEBOARD_FAB2_LIB.BASEBOARD_FAB2(SCH_1):PAGE74
  U2D1  C16 VSS<1171> SKX_EXT_B_BGA1-IC,TBD    I20 @BASEBOARD_FAB2_LIB.BASEBOARD_FAB2(SCH_1):PAGE74
  U2D1  C14 VSS<1172> SKX_EXT_B_BGA1-IC,TBD    I20 @BASEBOARD_FAB2_LIB.BASEBOARD_FAB2(SCH_1):PAGE74
  U2D1  C12 VSS<1173> SKX_EXT_B_BGA1-IC,TBD    I20 @BASEBOARD_FAB2_LIB.BASEBOARD_FAB2(SCH_1):PAGE74
  U2D1  C10 VSS<1174> SKX_EXT_B_BGA1-IC,TBD    I20 @BASEBOARD_FAB2_LIB.BASEBOARD_FAB2(SCH_1):PAGE74
  U2D1   C8 VSS<1175> SKX_EXT_B_BGA1-IC,TBD    I20 @BASEBOARD_FAB2_LIB.BASEBOARD_FAB2(SCH_1):PAGE74
  U2D1  B75 VSS<1176> SKX_EXT_B_BGA1-IC,TBD    I20 @BASEBOARD_FAB2_LIB.BASEBOARD_FAB2(SCH_1):PAGE74
  U2D1  B71 VSS<1177> SKX_EXT_B_BGA1-IC,TBD    I20 @BASEBOARD_FAB2_LIB.BASEBOARD_FAB2(SCH_1):PAGE74
  U2D1  B37 VSS<1178> SKX_EXT_B_BGA1-IC,TBD    I20 @BASEBOARD_FAB2_LIB.BASEBOARD_FAB2(SCH_1):PAGE74
  U2D1  B31 VSS<1179> SKX_EXT_B_BGA1-IC,TBD    I20 @BASEBOARD_FAB2_LIB.BASEBOARD_FAB2(SCH_1):PAGE74
  U2D1  B25 VSS<1180> SKX_EXT_B_BGA1-IC,TBD    I20 @BASEBOARD_FAB2_LIB.BASEBOARD_FAB2(SCH_1):PAGE74
  U2D1  A38 VSS<1181> SKX_EXT_B_BGA1-IC,TBD    I20 @BASEBOARD_FAB2_LIB.BASEBOARD_FAB2(SCH_1):PAGE74
  U2D1  A36 VSS<1182> SKX_EXT_B_BGA1-IC,TBD    I20 @BASEBOARD_FAB2_LIB.BASEBOARD_FAB2(SCH_1):PAGE74
  U2D1  A32 VSS<1183> SKX_EXT_B_BGA1-IC,TBD    I20 @BASEBOARD_FAB2_LIB.BASEBOARD_FAB2(SCH_1):PAGE74
  U2D1  A30 VSS<1184> SKX_EXT_B_BGA1-IC,TBD    I20 @BASEBOARD_FAB2_LIB.BASEBOARD_FAB2(SCH_1):PAGE74
  U2D1  A26 VSS<1185> SKX_EXT_B_BGA1-IC,TBD    I20 @BASEBOARD_FAB2_LIB.BASEBOARD_FAB2(SCH_1):PAGE74
  U2D1 AC58 VSS<1186> SKX_EXT_B_BGA1-IC,TBD    I20 @BASEBOARD_FAB2_LIB.BASEBOARD_FAB2(SCH_1):PAGE74
  U2D1 AC60 VSS<1187> SKX_EXT_B_BGA1-IC,TBD    I20 @BASEBOARD_FAB2_LIB.BASEBOARD_FAB2(SCH_1):PAGE74
  U2D1 AC62 VSS<1188> SKX_EXT_B_BGA1-IC,TBD    I20 @BASEBOARD_FAB2_LIB.BASEBOARD_FAB2(SCH_1):PAGE74
  U2D1  AJ4 VSS<1189> SKX_EXT_B_BGA1-IC,TBD    I20 @BASEBOARD_FAB2_LIB.BASEBOARD_FAB2(SCH_1):PAGE74
  U2D1  AR6 VSS<1190> SKX_EXT_B_BGA1-IC,TBD    I20 @BASEBOARD_FAB2_LIB.BASEBOARD_FAB2(SCH_1):PAGE74
  U2D1  CG6 VSS<1191> SKX_EXT_B_BGA1-IC,TBD    I20 @BASEBOARD_FAB2_LIB.BASEBOARD_FAB2(SCH_1):PAGE74
  U2D1  CW6 VSS<1192> SKX_EXT_B_BGA1-IC,TBD    I20 @BASEBOARD_FAB2_LIB.BASEBOARD_FAB2(SCH_1):PAGE74
  U2D1 DE48 VSS<1193> SKX_EXT_B_BGA1-IC,TBD    I20 @BASEBOARD_FAB2_LIB.BASEBOARD_FAB2(SCH_1):PAGE74
  U2D1 DE50 VSS<1194> SKX_EXT_B_BGA1-IC,TBD    I20 @BASEBOARD_FAB2_LIB.BASEBOARD_FAB2(SCH_1):PAGE74
  U2D1 DE52 VSS<1195> SKX_EXT_B_BGA1-IC,TBD    I20 @BASEBOARD_FAB2_LIB.BASEBOARD_FAB2(SCH_1):PAGE74
  U2D1 DE54 VSS<1196> SKX_EXT_B_BGA1-IC,TBD    I20 @BASEBOARD_FAB2_LIB.BASEBOARD_FAB2(SCH_1):PAGE74
  U2D1 DE56 VSS<1197> SKX_EXT_B_BGA1-IC,TBD    I20 @BASEBOARD_FAB2_LIB.BASEBOARD_FAB2(SCH_1):PAGE74
  U2D1 DE58 VSS<1198> SKX_EXT_B_BGA1-IC,TBD    I20 @BASEBOARD_FAB2_LIB.BASEBOARD_FAB2(SCH_1):PAGE74
  U2D1 DE60 VSS<1199> SKX_EXT_B_BGA1-IC,TBD    I20 @BASEBOARD_FAB2_LIB.BASEBOARD_FAB2(SCH_1):PAGE74
  U2D1 DE62 VSS<1200> SKX_EXT_B_BGA1-IC,TBD    I20 @BASEBOARD_FAB2_LIB.BASEBOARD_FAB2(SCH_1):PAGE74
  U2D1  DL8 VSS<1201> SKX_EXT_B_BGA1-IC,TBD    I20 @BASEBOARD_FAB2_LIB.BASEBOARD_FAB2(SCH_1):PAGE74
  U2D1 DN18 VSS<1202> SKX_EXT_B_BGA1-IC,TBD    I20 @BASEBOARD_FAB2_LIB.BASEBOARD_FAB2(SCH_1):PAGE74
  U2D1 DP45 VSS<1203> SKX_EXT_B_BGA1-IC,TBD    I20 @BASEBOARD_FAB2_LIB.BASEBOARD_FAB2(SCH_1):PAGE74
  U2D1 DP47 VSS<1204> SKX_EXT_B_BGA1-IC,TBD    I20 @BASEBOARD_FAB2_LIB.BASEBOARD_FAB2(SCH_1):PAGE74
  U2D1 DP49 VSS<1205> SKX_EXT_B_BGA1-IC,TBD    I20 @BASEBOARD_FAB2_LIB.BASEBOARD_FAB2(SCH_1):PAGE74
  U2D1 DP51 VSS<1206> SKX_EXT_B_BGA1-IC,TBD    I20 @BASEBOARD_FAB2_LIB.BASEBOARD_FAB2(SCH_1):PAGE74
  U2D1 DP53 VSS<1207> SKX_EXT_B_BGA1-IC,TBD    I20 @BASEBOARD_FAB2_LIB.BASEBOARD_FAB2(SCH_1):PAGE74
  U2D1 DP55 VSS<1208> SKX_EXT_B_BGA1-IC,TBD    I20 @BASEBOARD_FAB2_LIB.BASEBOARD_FAB2(SCH_1):PAGE74
  U2D1 DP57 VSS<1209> SKX_EXT_B_BGA1-IC,TBD    I20 @BASEBOARD_FAB2_LIB.BASEBOARD_FAB2(SCH_1):PAGE74
  U2D1 DP59 VSS<1210> SKX_EXT_B_BGA1-IC,TBD    I20 @BASEBOARD_FAB2_LIB.BASEBOARD_FAB2(SCH_1):PAGE74
  U2D1 DP61 VSS<1211> SKX_EXT_B_BGA1-IC,TBD    I20 @BASEBOARD_FAB2_LIB.BASEBOARD_FAB2(SCH_1):PAGE74
  U2D1 DP63 VSS<1212> SKX_EXT_B_BGA1-IC,TBD    I20 @BASEBOARD_FAB2_LIB.BASEBOARD_FAB2(SCH_1):PAGE74
  U2D1  DP9 VSS<1213> SKX_EXT_B_BGA1-IC,TBD    I20 @BASEBOARD_FAB2_LIB.BASEBOARD_FAB2(SCH_1):PAGE74
  U2D1 DV19 VSS<1214> SKX_EXT_B_BGA1-IC,TBD    I20 @BASEBOARD_FAB2_LIB.BASEBOARD_FAB2(SCH_1):PAGE74
  U2D1 DY45 VSS<1215> SKX_EXT_B_BGA1-IC,TBD    I20 @BASEBOARD_FAB2_LIB.BASEBOARD_FAB2(SCH_1):PAGE74
  U2D1 DY47 VSS<1216> SKX_EXT_B_BGA1-IC,TBD    I20 @BASEBOARD_FAB2_LIB.BASEBOARD_FAB2(SCH_1):PAGE74
  U2D1 DY49 VSS<1217> SKX_EXT_B_BGA1-IC,TBD    I20 @BASEBOARD_FAB2_LIB.BASEBOARD_FAB2(SCH_1):PAGE74
  U2D1 DY51 VSS<1218> SKX_EXT_B_BGA1-IC,TBD    I20 @BASEBOARD_FAB2_LIB.BASEBOARD_FAB2(SCH_1):PAGE74
  U2D1 DY53 VSS<1219> SKX_EXT_B_BGA1-IC,TBD    I20 @BASEBOARD_FAB2_LIB.BASEBOARD_FAB2(SCH_1):PAGE74
  U2D1 DY55 VSS<1220> SKX_EXT_B_BGA1-IC,TBD    I20 @BASEBOARD_FAB2_LIB.BASEBOARD_FAB2(SCH_1):PAGE74
  U2D1 DY57 VSS<1221> SKX_EXT_B_BGA1-IC,TBD    I20 @BASEBOARD_FAB2_LIB.BASEBOARD_FAB2(SCH_1):PAGE74
  U2D1 DY59 VSS<1222> SKX_EXT_B_BGA1-IC,TBD    I20 @BASEBOARD_FAB2_LIB.BASEBOARD_FAB2(SCH_1):PAGE74
  U2D1 DY61 VSS<1223> SKX_EXT_B_BGA1-IC,TBD    I20 @BASEBOARD_FAB2_LIB.BASEBOARD_FAB2(SCH_1):PAGE74
  U2D1 DY63 VSS<1224> SKX_EXT_B_BGA1-IC,TBD    I20 @BASEBOARD_FAB2_LIB.BASEBOARD_FAB2(SCH_1):PAGE74
  U2D1 EA14 VSS<1225> SKX_EXT_B_BGA1-IC,TBD    I20 @BASEBOARD_FAB2_LIB.BASEBOARD_FAB2(SCH_1):PAGE74
  U2D1   L8 VSS<1226> SKX_EXT_B_BGA1-IC,TBD    I20 @BASEBOARD_FAB2_LIB.BASEBOARD_FAB2(SCH_1):PAGE74
  U2D1  V11 VSS<1227> SKX_EXT_B_BGA1-IC,TBD    I20 @BASEBOARD_FAB2_LIB.BASEBOARD_FAB2(SCH_1):PAGE74
  U2D1  E66 VSS<1228> SKX_EXT_B_BGA1-IC,TBD    I20 @BASEBOARD_FAB2_LIB.BASEBOARD_FAB2(SCH_1):PAGE74
  U2D1 ED69 VSS<1229> SKX_EXT_B_BGA1-IC,TBD    I20 @BASEBOARD_FAB2_LIB.BASEBOARD_FAB2(SCH_1):PAGE74
  U2D1 EE80 VSS<1230> SKX_EXT_B_BGA1-IC,TBD    I20 @BASEBOARD_FAB2_LIB.BASEBOARD_FAB2(SCH_1):PAGE74
  U2D1  EE8 VSS<1231> SKX_EXT_B_BGA1-IC,TBD    I20 @BASEBOARD_FAB2_LIB.BASEBOARD_FAB2(SCH_1):PAGE74
  U2D1 EE40 VSS<1232> SKX_EXT_B_BGA1-IC,TBD    I20 @BASEBOARD_FAB2_LIB.BASEBOARD_FAB2(SCH_1):PAGE74
  U2D1 ED81 VSS<1233> SKX_EXT_B_BGA1-IC,TBD    I20 @BASEBOARD_FAB2_LIB.BASEBOARD_FAB2(SCH_1):PAGE74
  U2D1  ED7 VSS<1234> SKX_EXT_B_BGA1-IC,TBD    I20 @BASEBOARD_FAB2_LIB.BASEBOARD_FAB2(SCH_1):PAGE74
  U2D1 ED41 VSS<1235> SKX_EXT_B_BGA1-IC,TBD    I20 @BASEBOARD_FAB2_LIB.BASEBOARD_FAB2(SCH_1):PAGE74
  U2D1 EC82 VSS<1236> SKX_EXT_B_BGA1-IC,TBD    I20 @BASEBOARD_FAB2_LIB.BASEBOARD_FAB2(SCH_1):PAGE74
  U2D1  EC6 VSS<1237> SKX_EXT_B_BGA1-IC,TBD    I20 @BASEBOARD_FAB2_LIB.BASEBOARD_FAB2(SCH_1):PAGE74
  U2D1 EC42 VSS<1238> SKX_EXT_B_BGA1-IC,TBD    I20 @BASEBOARD_FAB2_LIB.BASEBOARD_FAB2(SCH_1):PAGE74
  U2D1  DW2 VSS<1239> SKX_EXT_B_BGA1-IC,TBD    I20 @BASEBOARD_FAB2_LIB.BASEBOARD_FAB2(SCH_1):PAGE74
  U2D1 EB83 VSS<1240> SKX_EXT_B_BGA1-IC,TBD    I20 @BASEBOARD_FAB2_LIB.BASEBOARD_FAB2(SCH_1):PAGE74
  U2D1 EA84 VSS<1241> SKX_EXT_B_BGA1-IC,TBD    I20 @BASEBOARD_FAB2_LIB.BASEBOARD_FAB2(SCH_1):PAGE74
  U2D1 DY85 VSS<1242> SKX_EXT_B_BGA1-IC,TBD    I20 @BASEBOARD_FAB2_LIB.BASEBOARD_FAB2(SCH_1):PAGE74
  U2D1  J86 VSS<1243> SKX_EXT_B_BGA1-IC,TBD    I20 @BASEBOARD_FAB2_LIB.BASEBOARD_FAB2(SCH_1):PAGE74
  U2D1  E82 VSS<1244> SKX_EXT_B_BGA1-IC,TBD    I20 @BASEBOARD_FAB2_LIB.BASEBOARD_FAB2(SCH_1):PAGE74
  U2D1  D81 VSS<1245> SKX_EXT_B_BGA1-IC,TBD    I20 @BASEBOARD_FAB2_LIB.BASEBOARD_FAB2(SCH_1):PAGE74
  U2D1   D3 VSS<1246> SKX_EXT_B_BGA1-IC,TBD    I20 @BASEBOARD_FAB2_LIB.BASEBOARD_FAB2(SCH_1):PAGE74
  U2D1  C80 VSS<1247> SKX_EXT_B_BGA1-IC,TBD    I20 @BASEBOARD_FAB2_LIB.BASEBOARD_FAB2(SCH_1):PAGE74
  U2D1   C4 VSS<1248> SKX_EXT_B_BGA1-IC,TBD    I20 @BASEBOARD_FAB2_LIB.BASEBOARD_FAB2(SCH_1):PAGE74
  U2D1  B79 VSS<1249> SKX_EXT_B_BGA1-IC,TBD    I20 @BASEBOARD_FAB2_LIB.BASEBOARD_FAB2(SCH_1):PAGE74
  U2D1   B5 VSS<1250> SKX_EXT_B_BGA1-IC,TBD    I20 @BASEBOARD_FAB2_LIB.BASEBOARD_FAB2(SCH_1):PAGE74
  U2D1  B43 VSS<1251> SKX_EXT_B_BGA1-IC,TBD    I20 @BASEBOARD_FAB2_LIB.BASEBOARD_FAB2(SCH_1):PAGE74
  U2D1  A42 VSS<1252> SKX_EXT_B_BGA1-IC,TBD    I20 @BASEBOARD_FAB2_LIB.BASEBOARD_FAB2(SCH_1):PAGE74
  U2D1   B9 VSS<1253> SKX_EXT_B_BGA1-IC,TBD    I20 @BASEBOARD_FAB2_LIB.BASEBOARD_FAB2(SCH_1):PAGE74
  U2D1 AA16 VSS<934> SKX_EXT_B_BGA1-IC,TBD    I21 @BASEBOARD_FAB2_LIB.BASEBOARD_FAB2(SCH_1):PAGE74
  U2D1  AA4 VSS<935> SKX_EXT_B_BGA1-IC,TBD    I21 @BASEBOARD_FAB2_LIB.BASEBOARD_FAB2(SCH_1):PAGE74
  U2D1  Y85 VSS<936> SKX_EXT_B_BGA1-IC,TBD    I21 @BASEBOARD_FAB2_LIB.BASEBOARD_FAB2(SCH_1):PAGE74
  U2D1  Y83 VSS<937> SKX_EXT_B_BGA1-IC,TBD    I21 @BASEBOARD_FAB2_LIB.BASEBOARD_FAB2(SCH_1):PAGE74
  U2D1  Y81 VSS<938> SKX_EXT_B_BGA1-IC,TBD    I21 @BASEBOARD_FAB2_LIB.BASEBOARD_FAB2(SCH_1):PAGE74
  U2D1  Y79 VSS<939> SKX_EXT_B_BGA1-IC,TBD    I21 @BASEBOARD_FAB2_LIB.BASEBOARD_FAB2(SCH_1):PAGE74
  U2D1  Y73 VSS<940> SKX_EXT_B_BGA1-IC,TBD    I21 @BASEBOARD_FAB2_LIB.BASEBOARD_FAB2(SCH_1):PAGE74
  U2D1  Y71 VSS<941> SKX_EXT_B_BGA1-IC,TBD    I21 @BASEBOARD_FAB2_LIB.BASEBOARD_FAB2(SCH_1):PAGE74
  U2D1   Y9 VSS<942> SKX_EXT_B_BGA1-IC,TBD    I21 @BASEBOARD_FAB2_LIB.BASEBOARD_FAB2(SCH_1):PAGE74
  U2D1   Y7 VSS<943> SKX_EXT_B_BGA1-IC,TBD    I21 @BASEBOARD_FAB2_LIB.BASEBOARD_FAB2(SCH_1):PAGE74
  U2D1  Y67 VSS<944> SKX_EXT_B_BGA1-IC,TBD    I21 @BASEBOARD_FAB2_LIB.BASEBOARD_FAB2(SCH_1):PAGE74
  U2D1   Y5 VSS<945> SKX_EXT_B_BGA1-IC,TBD    I21 @BASEBOARD_FAB2_LIB.BASEBOARD_FAB2(SCH_1):PAGE74
  U2D1  Y17 VSS<946> SKX_EXT_B_BGA1-IC,TBD    I21 @BASEBOARD_FAB2_LIB.BASEBOARD_FAB2(SCH_1):PAGE74
  U2D1  Y15 VSS<947> SKX_EXT_B_BGA1-IC,TBD    I21 @BASEBOARD_FAB2_LIB.BASEBOARD_FAB2(SCH_1):PAGE74
  U2D1  W82 VSS<948> SKX_EXT_B_BGA1-IC,TBD    I21 @BASEBOARD_FAB2_LIB.BASEBOARD_FAB2(SCH_1):PAGE74
  U2D1  W78 VSS<949> SKX_EXT_B_BGA1-IC,TBD    I21 @BASEBOARD_FAB2_LIB.BASEBOARD_FAB2(SCH_1):PAGE74
  U2D1  W74 VSS<950> SKX_EXT_B_BGA1-IC,TBD    I21 @BASEBOARD_FAB2_LIB.BASEBOARD_FAB2(SCH_1):PAGE74
  U2D1  W68 VSS<951> SKX_EXT_B_BGA1-IC,TBD    I21 @BASEBOARD_FAB2_LIB.BASEBOARD_FAB2(SCH_1):PAGE74
  U2D1  W42 VSS<952> SKX_EXT_B_BGA1-IC,TBD    I21 @BASEBOARD_FAB2_LIB.BASEBOARD_FAB2(SCH_1):PAGE74
  U2D1  W40 VSS<953> SKX_EXT_B_BGA1-IC,TBD    I21 @BASEBOARD_FAB2_LIB.BASEBOARD_FAB2(SCH_1):PAGE74
  U2D1  W38 VSS<954> SKX_EXT_B_BGA1-IC,TBD    I21 @BASEBOARD_FAB2_LIB.BASEBOARD_FAB2(SCH_1):PAGE74
  U2D1  W36 VSS<955> SKX_EXT_B_BGA1-IC,TBD    I21 @BASEBOARD_FAB2_LIB.BASEBOARD_FAB2(SCH_1):PAGE74
  U2D1  W34 VSS<956> SKX_EXT_B_BGA1-IC,TBD    I21 @BASEBOARD_FAB2_LIB.BASEBOARD_FAB2(SCH_1):PAGE74
  U2D1  W32 VSS<957> SKX_EXT_B_BGA1-IC,TBD    I21 @BASEBOARD_FAB2_LIB.BASEBOARD_FAB2(SCH_1):PAGE74
  U2D1  W30 VSS<958> SKX_EXT_B_BGA1-IC,TBD    I21 @BASEBOARD_FAB2_LIB.BASEBOARD_FAB2(SCH_1):PAGE74
  U2D1  W28 VSS<959> SKX_EXT_B_BGA1-IC,TBD    I21 @BASEBOARD_FAB2_LIB.BASEBOARD_FAB2(SCH_1):PAGE74
  U2D1  W26 VSS<960> SKX_EXT_B_BGA1-IC,TBD    I21 @BASEBOARD_FAB2_LIB.BASEBOARD_FAB2(SCH_1):PAGE74
  U2D1  W24 VSS<961> SKX_EXT_B_BGA1-IC,TBD    I21 @BASEBOARD_FAB2_LIB.BASEBOARD_FAB2(SCH_1):PAGE74
  U2D1  W22 VSS<962> SKX_EXT_B_BGA1-IC,TBD    I21 @BASEBOARD_FAB2_LIB.BASEBOARD_FAB2(SCH_1):PAGE74
  U2D1  W12 VSS<963> SKX_EXT_B_BGA1-IC,TBD    I21 @BASEBOARD_FAB2_LIB.BASEBOARD_FAB2(SCH_1):PAGE74
  U2D1 AC56 VSS<964> SKX_EXT_B_BGA1-IC,TBD    I21 @BASEBOARD_FAB2_LIB.BASEBOARD_FAB2(SCH_1):PAGE74
  U2D1   W8 VSS<965> SKX_EXT_B_BGA1-IC,TBD    I21 @BASEBOARD_FAB2_LIB.BASEBOARD_FAB2(SCH_1):PAGE74
  U2D1  V83 VSS<966> SKX_EXT_B_BGA1-IC,TBD    I21 @BASEBOARD_FAB2_LIB.BASEBOARD_FAB2(SCH_1):PAGE74
  U2D1  V77 VSS<967> SKX_EXT_B_BGA1-IC,TBD    I21 @BASEBOARD_FAB2_LIB.BASEBOARD_FAB2(SCH_1):PAGE74
  U2D1  V75 VSS<968> SKX_EXT_B_BGA1-IC,TBD    I21 @BASEBOARD_FAB2_LIB.BASEBOARD_FAB2(SCH_1):PAGE74
  U2D1  V73 VSS<969> SKX_EXT_B_BGA1-IC,TBD    I21 @BASEBOARD_FAB2_LIB.BASEBOARD_FAB2(SCH_1):PAGE74
  U2D1  V43 VSS<970> SKX_EXT_B_BGA1-IC,TBD    I21 @BASEBOARD_FAB2_LIB.BASEBOARD_FAB2(SCH_1):PAGE74
  U2D1  V23 VSS<971> SKX_EXT_B_BGA1-IC,TBD    I21 @BASEBOARD_FAB2_LIB.BASEBOARD_FAB2(SCH_1):PAGE74
  U2D1  V21 VSS<972> SKX_EXT_B_BGA1-IC,TBD    I21 @BASEBOARD_FAB2_LIB.BASEBOARD_FAB2(SCH_1):PAGE74
  U2D1  V15 VSS<973> SKX_EXT_B_BGA1-IC,TBD    I21 @BASEBOARD_FAB2_LIB.BASEBOARD_FAB2(SCH_1):PAGE74
  U2D1  V13 VSS<974> SKX_EXT_B_BGA1-IC,TBD    I21 @BASEBOARD_FAB2_LIB.BASEBOARD_FAB2(SCH_1):PAGE74
  U2D1   V9 VSS<975> SKX_EXT_B_BGA1-IC,TBD    I21 @BASEBOARD_FAB2_LIB.BASEBOARD_FAB2(SCH_1):PAGE74
  U2D1   V5 VSS<976> SKX_EXT_B_BGA1-IC,TBD    I21 @BASEBOARD_FAB2_LIB.BASEBOARD_FAB2(SCH_1):PAGE74
  U2D1   V1 VSS<977> SKX_EXT_B_BGA1-IC,TBD    I21 @BASEBOARD_FAB2_LIB.BASEBOARD_FAB2(SCH_1):PAGE74
  U2D1  U86 VSS<978> SKX_EXT_B_BGA1-IC,TBD    I21 @BASEBOARD_FAB2_LIB.BASEBOARD_FAB2(SCH_1):PAGE74
  U2D1  U80 VSS<979> SKX_EXT_B_BGA1-IC,TBD    I21 @BASEBOARD_FAB2_LIB.BASEBOARD_FAB2(SCH_1):PAGE74
  U2D1  U78 VSS<980> SKX_EXT_B_BGA1-IC,TBD    I21 @BASEBOARD_FAB2_LIB.BASEBOARD_FAB2(SCH_1):PAGE74
  U2D1  U76 VSS<981> SKX_EXT_B_BGA1-IC,TBD    I21 @BASEBOARD_FAB2_LIB.BASEBOARD_FAB2(SCH_1):PAGE74
  U2D1  U74 VSS<982> SKX_EXT_B_BGA1-IC,TBD    I21 @BASEBOARD_FAB2_LIB.BASEBOARD_FAB2(SCH_1):PAGE74
  U2D1  U70 VSS<983> SKX_EXT_B_BGA1-IC,TBD    I21 @BASEBOARD_FAB2_LIB.BASEBOARD_FAB2(SCH_1):PAGE74
  U2D1  U68 VSS<984> SKX_EXT_B_BGA1-IC,TBD    I21 @BASEBOARD_FAB2_LIB.BASEBOARD_FAB2(SCH_1):PAGE74
  U2D1  U42 VSS<985> SKX_EXT_B_BGA1-IC,TBD    I21 @BASEBOARD_FAB2_LIB.BASEBOARD_FAB2(SCH_1):PAGE74
  U2D1  U36 VSS<986> SKX_EXT_B_BGA1-IC,TBD    I21 @BASEBOARD_FAB2_LIB.BASEBOARD_FAB2(SCH_1):PAGE74
  U2D1  U30 VSS<987> SKX_EXT_B_BGA1-IC,TBD    I21 @BASEBOARD_FAB2_LIB.BASEBOARD_FAB2(SCH_1):PAGE74
  U2D1  U24 VSS<988> SKX_EXT_B_BGA1-IC,TBD    I21 @BASEBOARD_FAB2_LIB.BASEBOARD_FAB2(SCH_1):PAGE74
  U2D1  U22 VSS<989> SKX_EXT_B_BGA1-IC,TBD    I21 @BASEBOARD_FAB2_LIB.BASEBOARD_FAB2(SCH_1):PAGE74
  U2D1  U20 VSS<990> SKX_EXT_B_BGA1-IC,TBD    I21 @BASEBOARD_FAB2_LIB.BASEBOARD_FAB2(SCH_1):PAGE74
  U2D1   U6 VSS<991> SKX_EXT_B_BGA1-IC,TBD    I21 @BASEBOARD_FAB2_LIB.BASEBOARD_FAB2(SCH_1):PAGE74
  U2D1   U4 VSS<992> SKX_EXT_B_BGA1-IC,TBD    I21 @BASEBOARD_FAB2_LIB.BASEBOARD_FAB2(SCH_1):PAGE74
  U2D1   U2 VSS<993> SKX_EXT_B_BGA1-IC,TBD    I21 @BASEBOARD_FAB2_LIB.BASEBOARD_FAB2(SCH_1):PAGE74
  U2D1  T85 VSS<994> SKX_EXT_B_BGA1-IC,TBD    I21 @BASEBOARD_FAB2_LIB.BASEBOARD_FAB2(SCH_1):PAGE74
  U2D1  T83 VSS<995> SKX_EXT_B_BGA1-IC,TBD    I21 @BASEBOARD_FAB2_LIB.BASEBOARD_FAB2(SCH_1):PAGE74
  U2D1  T77 VSS<996> SKX_EXT_B_BGA1-IC,TBD    I21 @BASEBOARD_FAB2_LIB.BASEBOARD_FAB2(SCH_1):PAGE74
  U2D1  T73 VSS<997> SKX_EXT_B_BGA1-IC,TBD    I21 @BASEBOARD_FAB2_LIB.BASEBOARD_FAB2(SCH_1):PAGE74
  U2D1  T65 VSS<998> SKX_EXT_B_BGA1-IC,TBD    I21 @BASEBOARD_FAB2_LIB.BASEBOARD_FAB2(SCH_1):PAGE74
  U2D1  T41 VSS<999> SKX_EXT_B_BGA1-IC,TBD    I21 @BASEBOARD_FAB2_LIB.BASEBOARD_FAB2(SCH_1):PAGE74
  U2D1  T37 VSS<1000> SKX_EXT_B_BGA1-IC,TBD    I21 @BASEBOARD_FAB2_LIB.BASEBOARD_FAB2(SCH_1):PAGE74
  U2D1  T35 VSS<1001> SKX_EXT_B_BGA1-IC,TBD    I21 @BASEBOARD_FAB2_LIB.BASEBOARD_FAB2(SCH_1):PAGE74
  U2D1  T31 VSS<1002> SKX_EXT_B_BGA1-IC,TBD    I21 @BASEBOARD_FAB2_LIB.BASEBOARD_FAB2(SCH_1):PAGE74
  U2D1  T29 VSS<1003> SKX_EXT_B_BGA1-IC,TBD    I21 @BASEBOARD_FAB2_LIB.BASEBOARD_FAB2(SCH_1):PAGE74
  U2D1  T25 VSS<1004> SKX_EXT_B_BGA1-IC,TBD    I21 @BASEBOARD_FAB2_LIB.BASEBOARD_FAB2(SCH_1):PAGE74
  U2D1  T17 VSS<1005> SKX_EXT_B_BGA1-IC,TBD    I21 @BASEBOARD_FAB2_LIB.BASEBOARD_FAB2(SCH_1):PAGE74
  U2D1  T13 VSS<1006> SKX_EXT_B_BGA1-IC,TBD    I21 @BASEBOARD_FAB2_LIB.BASEBOARD_FAB2(SCH_1):PAGE74
  U2D1  R86 VSS<1007> SKX_EXT_B_BGA1-IC,TBD    I21 @BASEBOARD_FAB2_LIB.BASEBOARD_FAB2(SCH_1):PAGE74
  U2D1  R78 VSS<1008> SKX_EXT_B_BGA1-IC,TBD    I21 @BASEBOARD_FAB2_LIB.BASEBOARD_FAB2(SCH_1):PAGE74
  U2D1  R72 VSS<1009> SKX_EXT_B_BGA1-IC,TBD    I21 @BASEBOARD_FAB2_LIB.BASEBOARD_FAB2(SCH_1):PAGE74
  U2D1  R68 VSS<1010> SKX_EXT_B_BGA1-IC,TBD    I21 @BASEBOARD_FAB2_LIB.BASEBOARD_FAB2(SCH_1):PAGE74
  U2D1  R40 VSS<1011> SKX_EXT_B_BGA1-IC,TBD    I21 @BASEBOARD_FAB2_LIB.BASEBOARD_FAB2(SCH_1):PAGE74
  U2D1  R38 VSS<1012> SKX_EXT_B_BGA1-IC,TBD    I21 @BASEBOARD_FAB2_LIB.BASEBOARD_FAB2(SCH_1):PAGE74
  U2D1  R34 VSS<1013> SKX_EXT_B_BGA1-IC,TBD    I21 @BASEBOARD_FAB2_LIB.BASEBOARD_FAB2(SCH_1):PAGE74
  U2D1  R32 VSS<1014> SKX_EXT_B_BGA1-IC,TBD    I21 @BASEBOARD_FAB2_LIB.BASEBOARD_FAB2(SCH_1):PAGE74
  U2D1  R28 VSS<1015> SKX_EXT_B_BGA1-IC,TBD    I21 @BASEBOARD_FAB2_LIB.BASEBOARD_FAB2(SCH_1):PAGE74
  U2D1  R26 VSS<1016> SKX_EXT_B_BGA1-IC,TBD    I21 @BASEBOARD_FAB2_LIB.BASEBOARD_FAB2(SCH_1):PAGE74
  U2D1  R22 VSS<1017> SKX_EXT_B_BGA1-IC,TBD    I21 @BASEBOARD_FAB2_LIB.BASEBOARD_FAB2(SCH_1):PAGE74
  U2D1   R4 VSS<1018> SKX_EXT_B_BGA1-IC,TBD    I21 @BASEBOARD_FAB2_LIB.BASEBOARD_FAB2(SCH_1):PAGE74
  U2D1   R2 VSS<1019> SKX_EXT_B_BGA1-IC,TBD    I21 @BASEBOARD_FAB2_LIB.BASEBOARD_FAB2(SCH_1):PAGE74
  U2D1  R18 VSS<1020> SKX_EXT_B_BGA1-IC,TBD    I21 @BASEBOARD_FAB2_LIB.BASEBOARD_FAB2(SCH_1):PAGE74
  U2D1  R14 VSS<1021> SKX_EXT_B_BGA1-IC,TBD    I21 @BASEBOARD_FAB2_LIB.BASEBOARD_FAB2(SCH_1):PAGE74
  U2D1  P83 VSS<1022> SKX_EXT_B_BGA1-IC,TBD    I21 @BASEBOARD_FAB2_LIB.BASEBOARD_FAB2(SCH_1):PAGE74
  U2D1  P81 VSS<1023> SKX_EXT_B_BGA1-IC,TBD    I21 @BASEBOARD_FAB2_LIB.BASEBOARD_FAB2(SCH_1):PAGE74
  U2D1  P71 VSS<1024> SKX_EXT_B_BGA1-IC,TBD    I21 @BASEBOARD_FAB2_LIB.BASEBOARD_FAB2(SCH_1):PAGE74
  U2D1  P69 VSS<1025> SKX_EXT_B_BGA1-IC,TBD    I21 @BASEBOARD_FAB2_LIB.BASEBOARD_FAB2(SCH_1):PAGE74
  U2D1  P67 VSS<1026> SKX_EXT_B_BGA1-IC,TBD    I21 @BASEBOARD_FAB2_LIB.BASEBOARD_FAB2(SCH_1):PAGE74
  U2D1  P39 VSS<1027> SKX_EXT_B_BGA1-IC,TBD    I21 @BASEBOARD_FAB2_LIB.BASEBOARD_FAB2(SCH_1):PAGE74
  U2D1  P33 VSS<1028> SKX_EXT_B_BGA1-IC,TBD    I21 @BASEBOARD_FAB2_LIB.BASEBOARD_FAB2(SCH_1):PAGE74
  U2D1  P27 VSS<1029> SKX_EXT_B_BGA1-IC,TBD    I21 @BASEBOARD_FAB2_LIB.BASEBOARD_FAB2(SCH_1):PAGE74
  U2D1  P15 VSS<1030> SKX_EXT_B_BGA1-IC,TBD    I21 @BASEBOARD_FAB2_LIB.BASEBOARD_FAB2(SCH_1):PAGE74
  U2D1  P11 VSS<1031> SKX_EXT_B_BGA1-IC,TBD    I21 @BASEBOARD_FAB2_LIB.BASEBOARD_FAB2(SCH_1):PAGE74
  U2D1   N8 VSS<1032> SKX_EXT_B_BGA1-IC,TBD    I21 @BASEBOARD_FAB2_LIB.BASEBOARD_FAB2(SCH_1):PAGE74
  U2D1   N4 VSS<1033> SKX_EXT_B_BGA1-IC,TBD    I21 @BASEBOARD_FAB2_LIB.BASEBOARD_FAB2(SCH_1):PAGE74
  U2D1  N78 VSS<1034> SKX_EXT_B_BGA1-IC,TBD    I21 @BASEBOARD_FAB2_LIB.BASEBOARD_FAB2(SCH_1):PAGE74
  U2D1  N76 VSS<1035> SKX_EXT_B_BGA1-IC,TBD    I21 @BASEBOARD_FAB2_LIB.BASEBOARD_FAB2(SCH_1):PAGE74
  U2D1  N74 VSS<1036> SKX_EXT_B_BGA1-IC,TBD    I21 @BASEBOARD_FAB2_LIB.BASEBOARD_FAB2(SCH_1):PAGE74
  U2D1  N72 VSS<1037> SKX_EXT_B_BGA1-IC,TBD    I21 @BASEBOARD_FAB2_LIB.BASEBOARD_FAB2(SCH_1):PAGE74
  U2D1  N70 VSS<1038> SKX_EXT_B_BGA1-IC,TBD    I21 @BASEBOARD_FAB2_LIB.BASEBOARD_FAB2(SCH_1):PAGE74
  U2D1  N66 VSS<1039> SKX_EXT_B_BGA1-IC,TBD    I21 @BASEBOARD_FAB2_LIB.BASEBOARD_FAB2(SCH_1):PAGE74
  U2D1   N6 VSS<1040> SKX_EXT_B_BGA1-IC,TBD    I21 @BASEBOARD_FAB2_LIB.BASEBOARD_FAB2(SCH_1):PAGE74
  U2D1  N22 VSS<1041> SKX_EXT_B_BGA1-IC,TBD    I21 @BASEBOARD_FAB2_LIB.BASEBOARD_FAB2(SCH_1):PAGE74
  U2D1  N20 VSS<1042> SKX_EXT_B_BGA1-IC,TBD    I21 @BASEBOARD_FAB2_LIB.BASEBOARD_FAB2(SCH_1):PAGE74
  U2D1 DM19 VSS<1043> SKX_EXT_B_BGA1-IC,TBD    I21 @BASEBOARD_FAB2_LIB.BASEBOARD_FAB2(SCH_1):PAGE74
  U2D1  M85 VSS<1044> SKX_EXT_B_BGA1-IC,TBD    I21 @BASEBOARD_FAB2_LIB.BASEBOARD_FAB2(SCH_1):PAGE74
  U2D1  M83 VSS<1045> SKX_EXT_B_BGA1-IC,TBD    I21 @BASEBOARD_FAB2_LIB.BASEBOARD_FAB2(SCH_1):PAGE74
  U2D1  M79 VSS<1046> SKX_EXT_B_BGA1-IC,TBD    I21 @BASEBOARD_FAB2_LIB.BASEBOARD_FAB2(SCH_1):PAGE74
  U2D1  M71 VSS<1047> SKX_EXT_B_BGA1-IC,TBD    I21 @BASEBOARD_FAB2_LIB.BASEBOARD_FAB2(SCH_1):PAGE74
  U2D1  M65 VSS<1048> SKX_EXT_B_BGA1-IC,TBD    I21 @BASEBOARD_FAB2_LIB.BASEBOARD_FAB2(SCH_1):PAGE74
  U2D1  M43 VSS<1049> SKX_EXT_B_BGA1-IC,TBD    I21 @BASEBOARD_FAB2_LIB.BASEBOARD_FAB2(SCH_1):PAGE74
  U2D1  M41 VSS<1050> SKX_EXT_B_BGA1-IC,TBD    I21 @BASEBOARD_FAB2_LIB.BASEBOARD_FAB2(SCH_1):PAGE74
  U2D1  M39 VSS<1051> SKX_EXT_B_BGA1-IC,TBD    I21 @BASEBOARD_FAB2_LIB.BASEBOARD_FAB2(SCH_1):PAGE74
  U2D1  M37 VSS<1052> SKX_EXT_B_BGA1-IC,TBD    I21 @BASEBOARD_FAB2_LIB.BASEBOARD_FAB2(SCH_1):PAGE74
  U2D1  M35 VSS<1053> SKX_EXT_B_BGA1-IC,TBD    I21 @BASEBOARD_FAB2_LIB.BASEBOARD_FAB2(SCH_1):PAGE74
  U2D1  M33 VSS<1054> SKX_EXT_B_BGA1-IC,TBD    I21 @BASEBOARD_FAB2_LIB.BASEBOARD_FAB2(SCH_1):PAGE74
  U2D1  M31 VSS<1055> SKX_EXT_B_BGA1-IC,TBD    I21 @BASEBOARD_FAB2_LIB.BASEBOARD_FAB2(SCH_1):PAGE74
  U2D1  M29 VSS<1056> SKX_EXT_B_BGA1-IC,TBD    I21 @BASEBOARD_FAB2_LIB.BASEBOARD_FAB2(SCH_1):PAGE74
  U2D1  M27 VSS<1057> SKX_EXT_B_BGA1-IC,TBD    I21 @BASEBOARD_FAB2_LIB.BASEBOARD_FAB2(SCH_1):PAGE74
  U2D1  M25 VSS<1058> SKX_EXT_B_BGA1-IC,TBD    I21 @BASEBOARD_FAB2_LIB.BASEBOARD_FAB2(SCH_1):PAGE74
  U2D1  M23 VSS<1059> SKX_EXT_B_BGA1-IC,TBD    I21 @BASEBOARD_FAB2_LIB.BASEBOARD_FAB2(SCH_1):PAGE74
  U2D1  M19 VSS<1060> SKX_EXT_B_BGA1-IC,TBD    I21 @BASEBOARD_FAB2_LIB.BASEBOARD_FAB2(SCH_1):PAGE74
  U2D1  M17 VSS<1061> SKX_EXT_B_BGA1-IC,TBD    I21 @BASEBOARD_FAB2_LIB.BASEBOARD_FAB2(SCH_1):PAGE74
  U2D1  M15 VSS<1062> SKX_EXT_B_BGA1-IC,TBD    I21 @BASEBOARD_FAB2_LIB.BASEBOARD_FAB2(SCH_1):PAGE74
  U2D1  CT7 VSS<1063> SKX_EXT_B_BGA1-IC,TBD    I21 @BASEBOARD_FAB2_LIB.BASEBOARD_FAB2(SCH_1):PAGE74
  U2D1  BT9 VSS<1064> SKX_EXT_B_BGA1-IC,TBD    I21 @BASEBOARD_FAB2_LIB.BASEBOARD_FAB2(SCH_1):PAGE74
  U2D1  L82 VSS<1065> SKX_EXT_B_BGA1-IC,TBD    I21 @BASEBOARD_FAB2_LIB.BASEBOARD_FAB2(SCH_1):PAGE74
  U2D1  L80 VSS<1066> SKX_EXT_B_BGA1-IC,TBD    I21 @BASEBOARD_FAB2_LIB.BASEBOARD_FAB2(SCH_1):PAGE74
  U2D1  L78 VSS<1067> SKX_EXT_B_BGA1-IC,TBD    I21 @BASEBOARD_FAB2_LIB.BASEBOARD_FAB2(SCH_1):PAGE74
  U2D1  L72 VSS<1068> SKX_EXT_B_BGA1-IC,TBD    I21 @BASEBOARD_FAB2_LIB.BASEBOARD_FAB2(SCH_1):PAGE74
  U2D1  L22 VSS<1069> SKX_EXT_B_BGA1-IC,TBD    I21 @BASEBOARD_FAB2_LIB.BASEBOARD_FAB2(SCH_1):PAGE74
  U2D1  L20 VSS<1070> SKX_EXT_B_BGA1-IC,TBD    I21 @BASEBOARD_FAB2_LIB.BASEBOARD_FAB2(SCH_1):PAGE74
  U2D1   L6 VSS<1071> SKX_EXT_B_BGA1-IC,TBD    I21 @BASEBOARD_FAB2_LIB.BASEBOARD_FAB2(SCH_1):PAGE74
  U2D1   L2 VSS<1072> SKX_EXT_B_BGA1-IC,TBD    I21 @BASEBOARD_FAB2_LIB.BASEBOARD_FAB2(SCH_1):PAGE74
  U2D1  L10 VSS<1073> SKX_EXT_B_BGA1-IC,TBD    I21 @BASEBOARD_FAB2_LIB.BASEBOARD_FAB2(SCH_1):PAGE74
  U2D1  K85 VSS<1074> SKX_EXT_B_BGA1-IC,TBD    I21 @BASEBOARD_FAB2_LIB.BASEBOARD_FAB2(SCH_1):PAGE74
  U2D1  K83 VSS<1075> SKX_EXT_B_BGA1-IC,TBD    I21 @BASEBOARD_FAB2_LIB.BASEBOARD_FAB2(SCH_1):PAGE74
  U2D1  K81 VSS<1076> SKX_EXT_B_BGA1-IC,TBD    I21 @BASEBOARD_FAB2_LIB.BASEBOARD_FAB2(SCH_1):PAGE74
  U2D1  K77 VSS<1077> SKX_EXT_B_BGA1-IC,TBD    I21 @BASEBOARD_FAB2_LIB.BASEBOARD_FAB2(SCH_1):PAGE74
  U2D1  K73 VSS<1078> SKX_EXT_B_BGA1-IC,TBD    I21 @BASEBOARD_FAB2_LIB.BASEBOARD_FAB2(SCH_1):PAGE74
  U2D1  K71 VSS<1079> SKX_EXT_B_BGA1-IC,TBD    I21 @BASEBOARD_FAB2_LIB.BASEBOARD_FAB2(SCH_1):PAGE74
  U2D1  K69 VSS<1080> SKX_EXT_B_BGA1-IC,TBD    I21 @BASEBOARD_FAB2_LIB.BASEBOARD_FAB2(SCH_1):PAGE74
  U2D1  K67 VSS<1081> SKX_EXT_B_BGA1-IC,TBD    I21 @BASEBOARD_FAB2_LIB.BASEBOARD_FAB2(SCH_1):PAGE74
  U2D1  K65 VSS<1082> SKX_EXT_B_BGA1-IC,TBD    I21 @BASEBOARD_FAB2_LIB.BASEBOARD_FAB2(SCH_1):PAGE74
  U2D1  K39 VSS<1083> SKX_EXT_B_BGA1-IC,TBD    I21 @BASEBOARD_FAB2_LIB.BASEBOARD_FAB2(SCH_1):PAGE74
  U2D1  K33 VSS<1084> SKX_EXT_B_BGA1-IC,TBD    I21 @BASEBOARD_FAB2_LIB.BASEBOARD_FAB2(SCH_1):PAGE74
  U2D1  K27 VSS<1085> SKX_EXT_B_BGA1-IC,TBD    I21 @BASEBOARD_FAB2_LIB.BASEBOARD_FAB2(SCH_1):PAGE74
  U2D1  DB7 VSS<1086> SKX_EXT_B_BGA1-IC,TBD    I21 @BASEBOARD_FAB2_LIB.BASEBOARD_FAB2(SCH_1):PAGE74
  U2D1  K17 VSS<1087> SKX_EXT_B_BGA1-IC,TBD    I21 @BASEBOARD_FAB2_LIB.BASEBOARD_FAB2(SCH_1):PAGE74
  U2D1  K13 VSS<1088> SKX_EXT_B_BGA1-IC,TBD    I21 @BASEBOARD_FAB2_LIB.BASEBOARD_FAB2(SCH_1):PAGE74
  U2D1  K11 VSS<1089> SKX_EXT_B_BGA1-IC,TBD    I21 @BASEBOARD_FAB2_LIB.BASEBOARD_FAB2(SCH_1):PAGE74
  U2D1   K1 VSS<1090> SKX_EXT_B_BGA1-IC,TBD    I21 @BASEBOARD_FAB2_LIB.BASEBOARD_FAB2(SCH_1):PAGE74
  U2D1  J84 VSS<1091> SKX_EXT_B_BGA1-IC,TBD    I21 @BASEBOARD_FAB2_LIB.BASEBOARD_FAB2(SCH_1):PAGE74
  U2D1  J82 VSS<1092> SKX_EXT_B_BGA1-IC,TBD    I21 @BASEBOARD_FAB2_LIB.BASEBOARD_FAB2(SCH_1):PAGE74
  U2D1  J76 VSS<1093> SKX_EXT_B_BGA1-IC,TBD    I21 @BASEBOARD_FAB2_LIB.BASEBOARD_FAB2(SCH_1):PAGE74
  U2D1 AL68 VSS<774> SKX_EXT_B_BGA1-IC,TBD    I22 @BASEBOARD_FAB2_LIB.BASEBOARD_FAB2(SCH_1):PAGE74
  U2D1 AL64 VSS<775> SKX_EXT_B_BGA1-IC,TBD    I22 @BASEBOARD_FAB2_LIB.BASEBOARD_FAB2(SCH_1):PAGE74
  U2D1 AL56 VSS<776> SKX_EXT_B_BGA1-IC,TBD    I22 @BASEBOARD_FAB2_LIB.BASEBOARD_FAB2(SCH_1):PAGE74
  U2D1 AL32 VSS<777> SKX_EXT_B_BGA1-IC,TBD    I22 @BASEBOARD_FAB2_LIB.BASEBOARD_FAB2(SCH_1):PAGE74
  U2D1 AL30 VSS<778> SKX_EXT_B_BGA1-IC,TBD    I22 @BASEBOARD_FAB2_LIB.BASEBOARD_FAB2(SCH_1):PAGE74
  U2D1 AL24 VSS<779> SKX_EXT_B_BGA1-IC,TBD    I22 @BASEBOARD_FAB2_LIB.BASEBOARD_FAB2(SCH_1):PAGE74
  U2D1 AL10 VSS<780> SKX_EXT_B_BGA1-IC,TBD    I22 @BASEBOARD_FAB2_LIB.BASEBOARD_FAB2(SCH_1):PAGE74
  U2D1  AL4 VSS<781> SKX_EXT_B_BGA1-IC,TBD    I22 @BASEBOARD_FAB2_LIB.BASEBOARD_FAB2(SCH_1):PAGE74
  U2D1 AK85 VSS<782> SKX_EXT_B_BGA1-IC,TBD    I22 @BASEBOARD_FAB2_LIB.BASEBOARD_FAB2(SCH_1):PAGE74
  U2D1 AK83 VSS<783> SKX_EXT_B_BGA1-IC,TBD    I22 @BASEBOARD_FAB2_LIB.BASEBOARD_FAB2(SCH_1):PAGE74
  U2D1 AK81 VSS<784> SKX_EXT_B_BGA1-IC,TBD    I22 @BASEBOARD_FAB2_LIB.BASEBOARD_FAB2(SCH_1):PAGE74
  U2D1 AK79 VSS<785> SKX_EXT_B_BGA1-IC,TBD    I22 @BASEBOARD_FAB2_LIB.BASEBOARD_FAB2(SCH_1):PAGE74
  U2D1 AK73 VSS<786> SKX_EXT_B_BGA1-IC,TBD    I22 @BASEBOARD_FAB2_LIB.BASEBOARD_FAB2(SCH_1):PAGE74
  U2D1 AK67 VSS<787> SKX_EXT_B_BGA1-IC,TBD    I22 @BASEBOARD_FAB2_LIB.BASEBOARD_FAB2(SCH_1):PAGE74
  U2D1 AK65 VSS<788> SKX_EXT_B_BGA1-IC,TBD    I22 @BASEBOARD_FAB2_LIB.BASEBOARD_FAB2(SCH_1):PAGE74
  U2D1 AK55 VSS<789> SKX_EXT_B_BGA1-IC,TBD    I22 @BASEBOARD_FAB2_LIB.BASEBOARD_FAB2(SCH_1):PAGE74
  U2D1 AK33 VSS<790> SKX_EXT_B_BGA1-IC,TBD    I22 @BASEBOARD_FAB2_LIB.BASEBOARD_FAB2(SCH_1):PAGE74
  U2D1 AK31 VSS<791> SKX_EXT_B_BGA1-IC,TBD    I22 @BASEBOARD_FAB2_LIB.BASEBOARD_FAB2(SCH_1):PAGE74
  U2D1 AK29 VSS<792> SKX_EXT_B_BGA1-IC,TBD    I22 @BASEBOARD_FAB2_LIB.BASEBOARD_FAB2(SCH_1):PAGE74
  U2D1 AK25 VSS<793> SKX_EXT_B_BGA1-IC,TBD    I22 @BASEBOARD_FAB2_LIB.BASEBOARD_FAB2(SCH_1):PAGE74
  U2D1 AK23 VSS<794> SKX_EXT_B_BGA1-IC,TBD    I22 @BASEBOARD_FAB2_LIB.BASEBOARD_FAB2(SCH_1):PAGE74
  U2D1 AK19 VSS<795> SKX_EXT_B_BGA1-IC,TBD    I22 @BASEBOARD_FAB2_LIB.BASEBOARD_FAB2(SCH_1):PAGE74
  U2D1 AK13 VSS<796> SKX_EXT_B_BGA1-IC,TBD    I22 @BASEBOARD_FAB2_LIB.BASEBOARD_FAB2(SCH_1):PAGE74
  U2D1  AK9 VSS<797> SKX_EXT_B_BGA1-IC,TBD    I22 @BASEBOARD_FAB2_LIB.BASEBOARD_FAB2(SCH_1):PAGE74
  U2D1 AJ86 VSS<798> SKX_EXT_B_BGA1-IC,TBD    I22 @BASEBOARD_FAB2_LIB.BASEBOARD_FAB2(SCH_1):PAGE74
  U2D1 AJ82 VSS<799> SKX_EXT_B_BGA1-IC,TBD    I22 @BASEBOARD_FAB2_LIB.BASEBOARD_FAB2(SCH_1):PAGE74
  U2D1 AJ78 VSS<800> SKX_EXT_B_BGA1-IC,TBD    I22 @BASEBOARD_FAB2_LIB.BASEBOARD_FAB2(SCH_1):PAGE74
  U2D1 AJ74 VSS<801> SKX_EXT_B_BGA1-IC,TBD    I22 @BASEBOARD_FAB2_LIB.BASEBOARD_FAB2(SCH_1):PAGE74
  U2D1 AJ68 VSS<802> SKX_EXT_B_BGA1-IC,TBD    I22 @BASEBOARD_FAB2_LIB.BASEBOARD_FAB2(SCH_1):PAGE74
  U2D1 AJ66 VSS<803> SKX_EXT_B_BGA1-IC,TBD    I22 @BASEBOARD_FAB2_LIB.BASEBOARD_FAB2(SCH_1):PAGE74
  U2D1 AJ54 VSS<804> SKX_EXT_B_BGA1-IC,TBD    I22 @BASEBOARD_FAB2_LIB.BASEBOARD_FAB2(SCH_1):PAGE74
  U2D1 AJ52 VSS<805> SKX_EXT_B_BGA1-IC,TBD    I22 @BASEBOARD_FAB2_LIB.BASEBOARD_FAB2(SCH_1):PAGE74
  U2D1 AJ50 VSS<806> SKX_EXT_B_BGA1-IC,TBD    I22 @BASEBOARD_FAB2_LIB.BASEBOARD_FAB2(SCH_1):PAGE74
  U2D1 AJ48 VSS<807> SKX_EXT_B_BGA1-IC,TBD    I22 @BASEBOARD_FAB2_LIB.BASEBOARD_FAB2(SCH_1):PAGE74
  U2D1 AJ46 VSS<808> SKX_EXT_B_BGA1-IC,TBD    I22 @BASEBOARD_FAB2_LIB.BASEBOARD_FAB2(SCH_1):PAGE74
  U2D1 AJ34 VSS<809> SKX_EXT_B_BGA1-IC,TBD    I22 @BASEBOARD_FAB2_LIB.BASEBOARD_FAB2(SCH_1):PAGE74
  U2D1 AJ32 VSS<810> SKX_EXT_B_BGA1-IC,TBD    I22 @BASEBOARD_FAB2_LIB.BASEBOARD_FAB2(SCH_1):PAGE74
  U2D1 AJ28 VSS<811> SKX_EXT_B_BGA1-IC,TBD    I22 @BASEBOARD_FAB2_LIB.BASEBOARD_FAB2(SCH_1):PAGE74
  U2D1 AJ26 VSS<812> SKX_EXT_B_BGA1-IC,TBD    I22 @BASEBOARD_FAB2_LIB.BASEBOARD_FAB2(SCH_1):PAGE74
  U2D1 AJ22 VSS<813> SKX_EXT_B_BGA1-IC,TBD    I22 @BASEBOARD_FAB2_LIB.BASEBOARD_FAB2(SCH_1):PAGE74
  U2D1  AJ8 VSS<814> SKX_EXT_B_BGA1-IC,TBD    I22 @BASEBOARD_FAB2_LIB.BASEBOARD_FAB2(SCH_1):PAGE74
  U2D1 AH83 VSS<815> SKX_EXT_B_BGA1-IC,TBD    I22 @BASEBOARD_FAB2_LIB.BASEBOARD_FAB2(SCH_1):PAGE74
  U2D1 AH77 VSS<816> SKX_EXT_B_BGA1-IC,TBD    I22 @BASEBOARD_FAB2_LIB.BASEBOARD_FAB2(SCH_1):PAGE74
  U2D1 AH75 VSS<817> SKX_EXT_B_BGA1-IC,TBD    I22 @BASEBOARD_FAB2_LIB.BASEBOARD_FAB2(SCH_1):PAGE74
  U2D1 AH69 VSS<818> SKX_EXT_B_BGA1-IC,TBD    I22 @BASEBOARD_FAB2_LIB.BASEBOARD_FAB2(SCH_1):PAGE74
  U2D1 AH65 VSS<819> SKX_EXT_B_BGA1-IC,TBD    I22 @BASEBOARD_FAB2_LIB.BASEBOARD_FAB2(SCH_1):PAGE74
  U2D1 AH61 VSS<820> SKX_EXT_B_BGA1-IC,TBD    I22 @BASEBOARD_FAB2_LIB.BASEBOARD_FAB2(SCH_1):PAGE74
  U2D1 AH59 VSS<821> SKX_EXT_B_BGA1-IC,TBD    I22 @BASEBOARD_FAB2_LIB.BASEBOARD_FAB2(SCH_1):PAGE74
  U2D1 AH53 VSS<822> SKX_EXT_B_BGA1-IC,TBD    I22 @BASEBOARD_FAB2_LIB.BASEBOARD_FAB2(SCH_1):PAGE74
  U2D1 AH51 VSS<823> SKX_EXT_B_BGA1-IC,TBD    I22 @BASEBOARD_FAB2_LIB.BASEBOARD_FAB2(SCH_1):PAGE74
  U2D1 AH49 VSS<824> SKX_EXT_B_BGA1-IC,TBD    I22 @BASEBOARD_FAB2_LIB.BASEBOARD_FAB2(SCH_1):PAGE74
  U2D1 AH47 VSS<825> SKX_EXT_B_BGA1-IC,TBD    I22 @BASEBOARD_FAB2_LIB.BASEBOARD_FAB2(SCH_1):PAGE74
  U2D1 AH45 VSS<826> SKX_EXT_B_BGA1-IC,TBD    I22 @BASEBOARD_FAB2_LIB.BASEBOARD_FAB2(SCH_1):PAGE74
  U2D1 AH35 VSS<827> SKX_EXT_B_BGA1-IC,TBD    I22 @BASEBOARD_FAB2_LIB.BASEBOARD_FAB2(SCH_1):PAGE74
  U2D1 AH33 VSS<828> SKX_EXT_B_BGA1-IC,TBD    I22 @BASEBOARD_FAB2_LIB.BASEBOARD_FAB2(SCH_1):PAGE74
  U2D1 AH27 VSS<829> SKX_EXT_B_BGA1-IC,TBD    I22 @BASEBOARD_FAB2_LIB.BASEBOARD_FAB2(SCH_1):PAGE74
  U2D1 AH21 VSS<830> SKX_EXT_B_BGA1-IC,TBD    I22 @BASEBOARD_FAB2_LIB.BASEBOARD_FAB2(SCH_1):PAGE74
  U2D1  AH5 VSS<831> SKX_EXT_B_BGA1-IC,TBD    I22 @BASEBOARD_FAB2_LIB.BASEBOARD_FAB2(SCH_1):PAGE74
  U2D1  AH1 VSS<832> SKX_EXT_B_BGA1-IC,TBD    I22 @BASEBOARD_FAB2_LIB.BASEBOARD_FAB2(SCH_1):PAGE74
  U2D1 AG80 VSS<833> SKX_EXT_B_BGA1-IC,TBD    I22 @BASEBOARD_FAB2_LIB.BASEBOARD_FAB2(SCH_1):PAGE74
  U2D1 AG78 VSS<834> SKX_EXT_B_BGA1-IC,TBD    I22 @BASEBOARD_FAB2_LIB.BASEBOARD_FAB2(SCH_1):PAGE74
  U2D1 AG76 VSS<835> SKX_EXT_B_BGA1-IC,TBD    I22 @BASEBOARD_FAB2_LIB.BASEBOARD_FAB2(SCH_1):PAGE74
  U2D1 AG74 VSS<836> SKX_EXT_B_BGA1-IC,TBD    I22 @BASEBOARD_FAB2_LIB.BASEBOARD_FAB2(SCH_1):PAGE74
  U2D1 AG70 VSS<837> SKX_EXT_B_BGA1-IC,TBD    I22 @BASEBOARD_FAB2_LIB.BASEBOARD_FAB2(SCH_1):PAGE74
  U2D1 AG64 VSS<838> SKX_EXT_B_BGA1-IC,TBD    I22 @BASEBOARD_FAB2_LIB.BASEBOARD_FAB2(SCH_1):PAGE74
  U2D1 AG36 VSS<839> SKX_EXT_B_BGA1-IC,TBD    I22 @BASEBOARD_FAB2_LIB.BASEBOARD_FAB2(SCH_1):PAGE74
  U2D1 AG18 VSS<840> SKX_EXT_B_BGA1-IC,TBD    I22 @BASEBOARD_FAB2_LIB.BASEBOARD_FAB2(SCH_1):PAGE74
  U2D1 AG14 VSS<841> SKX_EXT_B_BGA1-IC,TBD    I22 @BASEBOARD_FAB2_LIB.BASEBOARD_FAB2(SCH_1):PAGE74
  U2D1 AG12 VSS<842> SKX_EXT_B_BGA1-IC,TBD    I22 @BASEBOARD_FAB2_LIB.BASEBOARD_FAB2(SCH_1):PAGE74
  U2D1 AF85 VSS<843> SKX_EXT_B_BGA1-IC,TBD    I22 @BASEBOARD_FAB2_LIB.BASEBOARD_FAB2(SCH_1):PAGE74
  U2D1 AF83 VSS<844> SKX_EXT_B_BGA1-IC,TBD    I22 @BASEBOARD_FAB2_LIB.BASEBOARD_FAB2(SCH_1):PAGE74
  U2D1 AF77 VSS<845> SKX_EXT_B_BGA1-IC,TBD    I22 @BASEBOARD_FAB2_LIB.BASEBOARD_FAB2(SCH_1):PAGE74
  U2D1 AF73 VSS<846> SKX_EXT_B_BGA1-IC,TBD    I22 @BASEBOARD_FAB2_LIB.BASEBOARD_FAB2(SCH_1):PAGE74
  U2D1 AF41 VSS<847> SKX_EXT_B_BGA1-IC,TBD    I22 @BASEBOARD_FAB2_LIB.BASEBOARD_FAB2(SCH_1):PAGE74
  U2D1 AF39 VSS<848> SKX_EXT_B_BGA1-IC,TBD    I22 @BASEBOARD_FAB2_LIB.BASEBOARD_FAB2(SCH_1):PAGE74
  U2D1 AF37 VSS<849> SKX_EXT_B_BGA1-IC,TBD    I22 @BASEBOARD_FAB2_LIB.BASEBOARD_FAB2(SCH_1):PAGE74
  U2D1 AF33 VSS<850> SKX_EXT_B_BGA1-IC,TBD    I22 @BASEBOARD_FAB2_LIB.BASEBOARD_FAB2(SCH_1):PAGE74
  U2D1 AF31 VSS<851> SKX_EXT_B_BGA1-IC,TBD    I22 @BASEBOARD_FAB2_LIB.BASEBOARD_FAB2(SCH_1):PAGE74
  U2D1 AF29 VSS<852> SKX_EXT_B_BGA1-IC,TBD    I22 @BASEBOARD_FAB2_LIB.BASEBOARD_FAB2(SCH_1):PAGE74
  U2D1 AF27 VSS<853> SKX_EXT_B_BGA1-IC,TBD    I22 @BASEBOARD_FAB2_LIB.BASEBOARD_FAB2(SCH_1):PAGE74
  U2D1 AF25 VSS<854> SKX_EXT_B_BGA1-IC,TBD    I22 @BASEBOARD_FAB2_LIB.BASEBOARD_FAB2(SCH_1):PAGE74
  U2D1 AF23 VSS<855> SKX_EXT_B_BGA1-IC,TBD    I22 @BASEBOARD_FAB2_LIB.BASEBOARD_FAB2(SCH_1):PAGE74
  U2D1 AF21 VSS<856> SKX_EXT_B_BGA1-IC,TBD    I22 @BASEBOARD_FAB2_LIB.BASEBOARD_FAB2(SCH_1):PAGE74
  U2D1  AF9 VSS<857> SKX_EXT_B_BGA1-IC,TBD    I22 @BASEBOARD_FAB2_LIB.BASEBOARD_FAB2(SCH_1):PAGE74
  U2D1 AC52 VSS<858> SKX_EXT_B_BGA1-IC,TBD    I22 @BASEBOARD_FAB2_LIB.BASEBOARD_FAB2(SCH_1):PAGE74
  U2D1  AF1 VSS<859> SKX_EXT_B_BGA1-IC,TBD    I22 @BASEBOARD_FAB2_LIB.BASEBOARD_FAB2(SCH_1):PAGE74
  U2D1 AE78 VSS<860> SKX_EXT_B_BGA1-IC,TBD    I22 @BASEBOARD_FAB2_LIB.BASEBOARD_FAB2(SCH_1):PAGE74
  U2D1 AE70 VSS<861> SKX_EXT_B_BGA1-IC,TBD    I22 @BASEBOARD_FAB2_LIB.BASEBOARD_FAB2(SCH_1):PAGE74
  U2D1 AE68 VSS<862> SKX_EXT_B_BGA1-IC,TBD    I22 @BASEBOARD_FAB2_LIB.BASEBOARD_FAB2(SCH_1):PAGE74
  U2D1 AE66 VSS<863> SKX_EXT_B_BGA1-IC,TBD    I22 @BASEBOARD_FAB2_LIB.BASEBOARD_FAB2(SCH_1):PAGE74
  U2D1 AE64 VSS<864> SKX_EXT_B_BGA1-IC,TBD    I22 @BASEBOARD_FAB2_LIB.BASEBOARD_FAB2(SCH_1):PAGE74
  U2D1 AE42 VSS<865> SKX_EXT_B_BGA1-IC,TBD    I22 @BASEBOARD_FAB2_LIB.BASEBOARD_FAB2(SCH_1):PAGE74
  U2D1 AE40 VSS<866> SKX_EXT_B_BGA1-IC,TBD    I22 @BASEBOARD_FAB2_LIB.BASEBOARD_FAB2(SCH_1):PAGE74
  U2D1 AE38 VSS<867> SKX_EXT_B_BGA1-IC,TBD    I22 @BASEBOARD_FAB2_LIB.BASEBOARD_FAB2(SCH_1):PAGE74
  U2D1 AE16 VSS<868> SKX_EXT_B_BGA1-IC,TBD    I22 @BASEBOARD_FAB2_LIB.BASEBOARD_FAB2(SCH_1):PAGE74
  U2D1 AC54 VSS<869> SKX_EXT_B_BGA1-IC,TBD    I22 @BASEBOARD_FAB2_LIB.BASEBOARD_FAB2(SCH_1):PAGE74
  U2D1  AE8 VSS<870> SKX_EXT_B_BGA1-IC,TBD    I22 @BASEBOARD_FAB2_LIB.BASEBOARD_FAB2(SCH_1):PAGE74
  U2D1  AE4 VSS<871> SKX_EXT_B_BGA1-IC,TBD    I22 @BASEBOARD_FAB2_LIB.BASEBOARD_FAB2(SCH_1):PAGE74
  U2D1 AD85 VSS<872> SKX_EXT_B_BGA1-IC,TBD    I22 @BASEBOARD_FAB2_LIB.BASEBOARD_FAB2(SCH_1):PAGE74
  U2D1 AD83 VSS<873> SKX_EXT_B_BGA1-IC,TBD    I22 @BASEBOARD_FAB2_LIB.BASEBOARD_FAB2(SCH_1):PAGE74
  U2D1 AD81 VSS<874> SKX_EXT_B_BGA1-IC,TBD    I22 @BASEBOARD_FAB2_LIB.BASEBOARD_FAB2(SCH_1):PAGE74
  U2D1 AD75 VSS<875> SKX_EXT_B_BGA1-IC,TBD    I22 @BASEBOARD_FAB2_LIB.BASEBOARD_FAB2(SCH_1):PAGE74
  U2D1 AD73 VSS<876> SKX_EXT_B_BGA1-IC,TBD    I22 @BASEBOARD_FAB2_LIB.BASEBOARD_FAB2(SCH_1):PAGE74
  U2D1 AD71 VSS<877> SKX_EXT_B_BGA1-IC,TBD    I22 @BASEBOARD_FAB2_LIB.BASEBOARD_FAB2(SCH_1):PAGE74
  U2D1 AD43 VSS<878> SKX_EXT_B_BGA1-IC,TBD    I22 @BASEBOARD_FAB2_LIB.BASEBOARD_FAB2(SCH_1):PAGE74
  U2D1 AD39 VSS<879> SKX_EXT_B_BGA1-IC,TBD    I22 @BASEBOARD_FAB2_LIB.BASEBOARD_FAB2(SCH_1):PAGE74
  U2D1 AD33 VSS<880> SKX_EXT_B_BGA1-IC,TBD    I22 @BASEBOARD_FAB2_LIB.BASEBOARD_FAB2(SCH_1):PAGE74
  U2D1 AD27 VSS<881> SKX_EXT_B_BGA1-IC,TBD    I22 @BASEBOARD_FAB2_LIB.BASEBOARD_FAB2(SCH_1):PAGE74
  U2D1 AD21 VSS<882> SKX_EXT_B_BGA1-IC,TBD    I22 @BASEBOARD_FAB2_LIB.BASEBOARD_FAB2(SCH_1):PAGE74
  U2D1 AD19 VSS<883> SKX_EXT_B_BGA1-IC,TBD    I22 @BASEBOARD_FAB2_LIB.BASEBOARD_FAB2(SCH_1):PAGE74
  U2D1 AD15 VSS<884> SKX_EXT_B_BGA1-IC,TBD    I22 @BASEBOARD_FAB2_LIB.BASEBOARD_FAB2(SCH_1):PAGE74
  U2D1 AD13 VSS<885> SKX_EXT_B_BGA1-IC,TBD    I22 @BASEBOARD_FAB2_LIB.BASEBOARD_FAB2(SCH_1):PAGE74
  U2D1 AD11 VSS<886> SKX_EXT_B_BGA1-IC,TBD    I22 @BASEBOARD_FAB2_LIB.BASEBOARD_FAB2(SCH_1):PAGE74
  U2D1  AD9 VSS<887> SKX_EXT_B_BGA1-IC,TBD    I22 @BASEBOARD_FAB2_LIB.BASEBOARD_FAB2(SCH_1):PAGE74
  U2D1  AD7 VSS<888> SKX_EXT_B_BGA1-IC,TBD    I22 @BASEBOARD_FAB2_LIB.BASEBOARD_FAB2(SCH_1):PAGE74
  U2D1  AD3 VSS<889> SKX_EXT_B_BGA1-IC,TBD    I22 @BASEBOARD_FAB2_LIB.BASEBOARD_FAB2(SCH_1):PAGE74
  U2D1 AC86 VSS<890> SKX_EXT_B_BGA1-IC,TBD    I22 @BASEBOARD_FAB2_LIB.BASEBOARD_FAB2(SCH_1):PAGE74
  U2D1 AC84 VSS<891> SKX_EXT_B_BGA1-IC,TBD    I22 @BASEBOARD_FAB2_LIB.BASEBOARD_FAB2(SCH_1):PAGE74
  U2D1 AC78 VSS<892> SKX_EXT_B_BGA1-IC,TBD    I22 @BASEBOARD_FAB2_LIB.BASEBOARD_FAB2(SCH_1):PAGE74
  U2D1 AC72 VSS<893> SKX_EXT_B_BGA1-IC,TBD    I22 @BASEBOARD_FAB2_LIB.BASEBOARD_FAB2(SCH_1):PAGE74
  U2D1 AC70 VSS<894> SKX_EXT_B_BGA1-IC,TBD    I22 @BASEBOARD_FAB2_LIB.BASEBOARD_FAB2(SCH_1):PAGE74
  U2D1 AC64 VSS<895> SKX_EXT_B_BGA1-IC,TBD    I22 @BASEBOARD_FAB2_LIB.BASEBOARD_FAB2(SCH_1):PAGE74
  U2D1 AC40 VSS<896> SKX_EXT_B_BGA1-IC,TBD    I22 @BASEBOARD_FAB2_LIB.BASEBOARD_FAB2(SCH_1):PAGE74
  U2D1 AC38 VSS<897> SKX_EXT_B_BGA1-IC,TBD    I22 @BASEBOARD_FAB2_LIB.BASEBOARD_FAB2(SCH_1):PAGE74
  U2D1 AC34 VSS<898> SKX_EXT_B_BGA1-IC,TBD    I22 @BASEBOARD_FAB2_LIB.BASEBOARD_FAB2(SCH_1):PAGE74
  U2D1 AC32 VSS<899> SKX_EXT_B_BGA1-IC,TBD    I22 @BASEBOARD_FAB2_LIB.BASEBOARD_FAB2(SCH_1):PAGE74
  U2D1 AC28 VSS<900> SKX_EXT_B_BGA1-IC,TBD    I22 @BASEBOARD_FAB2_LIB.BASEBOARD_FAB2(SCH_1):PAGE74
  U2D1 AC26 VSS<901> SKX_EXT_B_BGA1-IC,TBD    I22 @BASEBOARD_FAB2_LIB.BASEBOARD_FAB2(SCH_1):PAGE74
  U2D1 AC22 VSS<902> SKX_EXT_B_BGA1-IC,TBD    I22 @BASEBOARD_FAB2_LIB.BASEBOARD_FAB2(SCH_1):PAGE74
  U2D1 AC18 VSS<903> SKX_EXT_B_BGA1-IC,TBD    I22 @BASEBOARD_FAB2_LIB.BASEBOARD_FAB2(SCH_1):PAGE74
  U2D1 AB85 VSS<904> SKX_EXT_B_BGA1-IC,TBD    I22 @BASEBOARD_FAB2_LIB.BASEBOARD_FAB2(SCH_1):PAGE74
  U2D1 AB83 VSS<905> SKX_EXT_B_BGA1-IC,TBD    I22 @BASEBOARD_FAB2_LIB.BASEBOARD_FAB2(SCH_1):PAGE74
  U2D1 AB79 VSS<906> SKX_EXT_B_BGA1-IC,TBD    I22 @BASEBOARD_FAB2_LIB.BASEBOARD_FAB2(SCH_1):PAGE74
  U2D1 AB73 VSS<907> SKX_EXT_B_BGA1-IC,TBD    I22 @BASEBOARD_FAB2_LIB.BASEBOARD_FAB2(SCH_1):PAGE74
  U2D1 AB69 VSS<908> SKX_EXT_B_BGA1-IC,TBD    I22 @BASEBOARD_FAB2_LIB.BASEBOARD_FAB2(SCH_1):PAGE74
  U2D1 AB65 VSS<909> SKX_EXT_B_BGA1-IC,TBD    I22 @BASEBOARD_FAB2_LIB.BASEBOARD_FAB2(SCH_1):PAGE74
  U2D1 AB41 VSS<910> SKX_EXT_B_BGA1-IC,TBD    I22 @BASEBOARD_FAB2_LIB.BASEBOARD_FAB2(SCH_1):PAGE74
  U2D1 AB37 VSS<911> SKX_EXT_B_BGA1-IC,TBD    I22 @BASEBOARD_FAB2_LIB.BASEBOARD_FAB2(SCH_1):PAGE74
  U2D1 AB35 VSS<912> SKX_EXT_B_BGA1-IC,TBD    I22 @BASEBOARD_FAB2_LIB.BASEBOARD_FAB2(SCH_1):PAGE74
  U2D1 AB31 VSS<913> SKX_EXT_B_BGA1-IC,TBD    I22 @BASEBOARD_FAB2_LIB.BASEBOARD_FAB2(SCH_1):PAGE74
  U2D1 AB29 VSS<914> SKX_EXT_B_BGA1-IC,TBD    I22 @BASEBOARD_FAB2_LIB.BASEBOARD_FAB2(SCH_1):PAGE74
  U2D1 AB25 VSS<915> SKX_EXT_B_BGA1-IC,TBD    I22 @BASEBOARD_FAB2_LIB.BASEBOARD_FAB2(SCH_1):PAGE74
  U2D1 AB23 VSS<916> SKX_EXT_B_BGA1-IC,TBD    I22 @BASEBOARD_FAB2_LIB.BASEBOARD_FAB2(SCH_1):PAGE74
  U2D1 AB21 VSS<917> SKX_EXT_B_BGA1-IC,TBD    I22 @BASEBOARD_FAB2_LIB.BASEBOARD_FAB2(SCH_1):PAGE74
  U2D1 AB11 VSS<918> SKX_EXT_B_BGA1-IC,TBD    I22 @BASEBOARD_FAB2_LIB.BASEBOARD_FAB2(SCH_1):PAGE74
  U2D1  AB5 VSS<919> SKX_EXT_B_BGA1-IC,TBD    I22 @BASEBOARD_FAB2_LIB.BASEBOARD_FAB2(SCH_1):PAGE74
  U2D1  AB1 VSS<920> SKX_EXT_B_BGA1-IC,TBD    I22 @BASEBOARD_FAB2_LIB.BASEBOARD_FAB2(SCH_1):PAGE74
  U2D1 AA82 VSS<921> SKX_EXT_B_BGA1-IC,TBD    I22 @BASEBOARD_FAB2_LIB.BASEBOARD_FAB2(SCH_1):PAGE74
  U2D1 AA80 VSS<922> SKX_EXT_B_BGA1-IC,TBD    I22 @BASEBOARD_FAB2_LIB.BASEBOARD_FAB2(SCH_1):PAGE74
  U2D1 AA78 VSS<923> SKX_EXT_B_BGA1-IC,TBD    I22 @BASEBOARD_FAB2_LIB.BASEBOARD_FAB2(SCH_1):PAGE74
  U2D1 AA76 VSS<924> SKX_EXT_B_BGA1-IC,TBD    I22 @BASEBOARD_FAB2_LIB.BASEBOARD_FAB2(SCH_1):PAGE74
  U2D1 AA68 VSS<925> SKX_EXT_B_BGA1-IC,TBD    I22 @BASEBOARD_FAB2_LIB.BASEBOARD_FAB2(SCH_1):PAGE74
  U2D1 AA66 VSS<926> SKX_EXT_B_BGA1-IC,TBD    I22 @BASEBOARD_FAB2_LIB.BASEBOARD_FAB2(SCH_1):PAGE74
  U2D1 AA64 VSS<927> SKX_EXT_B_BGA1-IC,TBD    I22 @BASEBOARD_FAB2_LIB.BASEBOARD_FAB2(SCH_1):PAGE74
  U2D1 AA42 VSS<928> SKX_EXT_B_BGA1-IC,TBD    I22 @BASEBOARD_FAB2_LIB.BASEBOARD_FAB2(SCH_1):PAGE74
  U2D1 AA36 VSS<929> SKX_EXT_B_BGA1-IC,TBD    I22 @BASEBOARD_FAB2_LIB.BASEBOARD_FAB2(SCH_1):PAGE74
  U2D1 AA30 VSS<930> SKX_EXT_B_BGA1-IC,TBD    I22 @BASEBOARD_FAB2_LIB.BASEBOARD_FAB2(SCH_1):PAGE74
  U2D1 AA24 VSS<931> SKX_EXT_B_BGA1-IC,TBD    I22 @BASEBOARD_FAB2_LIB.BASEBOARD_FAB2(SCH_1):PAGE74
  U2D1 AA22 VSS<932> SKX_EXT_B_BGA1-IC,TBD    I22 @BASEBOARD_FAB2_LIB.BASEBOARD_FAB2(SCH_1):PAGE74
  U2D1 AA18 VSS<933> SKX_EXT_B_BGA1-IC,TBD    I22 @BASEBOARD_FAB2_LIB.BASEBOARD_FAB2(SCH_1):PAGE74
  U2D1 BG72 VSS<614> SKX_EXT_B_BGA1-IC,TBD    I23 @BASEBOARD_FAB2_LIB.BASEBOARD_FAB2(SCH_1):PAGE74
  U2D1 BG24 VSS<615> SKX_EXT_B_BGA1-IC,TBD    I23 @BASEBOARD_FAB2_LIB.BASEBOARD_FAB2(SCH_1):PAGE74
  U2D1 BG22 VSS<616> SKX_EXT_B_BGA1-IC,TBD    I23 @BASEBOARD_FAB2_LIB.BASEBOARD_FAB2(SCH_1):PAGE74
  U2D1 BG10 VSS<617> SKX_EXT_B_BGA1-IC,TBD    I23 @BASEBOARD_FAB2_LIB.BASEBOARD_FAB2(SCH_1):PAGE74
  U2D1  BG8 VSS<618> SKX_EXT_B_BGA1-IC,TBD    I23 @BASEBOARD_FAB2_LIB.BASEBOARD_FAB2(SCH_1):PAGE74
  U2D1  BG6 VSS<619> SKX_EXT_B_BGA1-IC,TBD    I23 @BASEBOARD_FAB2_LIB.BASEBOARD_FAB2(SCH_1):PAGE74
  U2D1 BF71 VSS<620> SKX_EXT_B_BGA1-IC,TBD    I23 @BASEBOARD_FAB2_LIB.BASEBOARD_FAB2(SCH_1):PAGE74
  U2D1 BF69 VSS<621> SKX_EXT_B_BGA1-IC,TBD    I23 @BASEBOARD_FAB2_LIB.BASEBOARD_FAB2(SCH_1):PAGE74
  U2D1 BF67 VSS<622> SKX_EXT_B_BGA1-IC,TBD    I23 @BASEBOARD_FAB2_LIB.BASEBOARD_FAB2(SCH_1):PAGE74
  U2D1 BF65 VSS<623> SKX_EXT_B_BGA1-IC,TBD    I23 @BASEBOARD_FAB2_LIB.BASEBOARD_FAB2(SCH_1):PAGE74
  U2D1 BF63 VSS<624> SKX_EXT_B_BGA1-IC,TBD    I23 @BASEBOARD_FAB2_LIB.BASEBOARD_FAB2(SCH_1):PAGE74
  U2D1 BF25 VSS<625> SKX_EXT_B_BGA1-IC,TBD    I23 @BASEBOARD_FAB2_LIB.BASEBOARD_FAB2(SCH_1):PAGE74
  U2D1 BF19 VSS<626> SKX_EXT_B_BGA1-IC,TBD    I23 @BASEBOARD_FAB2_LIB.BASEBOARD_FAB2(SCH_1):PAGE74
  U2D1 BF17 VSS<627> SKX_EXT_B_BGA1-IC,TBD    I23 @BASEBOARD_FAB2_LIB.BASEBOARD_FAB2(SCH_1):PAGE74
  U2D1 BF15 VSS<628> SKX_EXT_B_BGA1-IC,TBD    I23 @BASEBOARD_FAB2_LIB.BASEBOARD_FAB2(SCH_1):PAGE74
  U2D1  BF9 VSS<629> SKX_EXT_B_BGA1-IC,TBD    I23 @BASEBOARD_FAB2_LIB.BASEBOARD_FAB2(SCH_1):PAGE74
  U2D1 BE70 VSS<630> SKX_EXT_B_BGA1-IC,TBD    I23 @BASEBOARD_FAB2_LIB.BASEBOARD_FAB2(SCH_1):PAGE74
  U2D1 BE68 VSS<631> SKX_EXT_B_BGA1-IC,TBD    I23 @BASEBOARD_FAB2_LIB.BASEBOARD_FAB2(SCH_1):PAGE74
  U2D1 BE66 VSS<632> SKX_EXT_B_BGA1-IC,TBD    I23 @BASEBOARD_FAB2_LIB.BASEBOARD_FAB2(SCH_1):PAGE74
  U2D1 BE64 VSS<633> SKX_EXT_B_BGA1-IC,TBD    I23 @BASEBOARD_FAB2_LIB.BASEBOARD_FAB2(SCH_1):PAGE74
  U2D1 BE26 VSS<634> SKX_EXT_B_BGA1-IC,TBD    I23 @BASEBOARD_FAB2_LIB.BASEBOARD_FAB2(SCH_1):PAGE74
  U2D1 BE10 VSS<635> SKX_EXT_B_BGA1-IC,TBD    I23 @BASEBOARD_FAB2_LIB.BASEBOARD_FAB2(SCH_1):PAGE74
  U2D1  BE8 VSS<636> SKX_EXT_B_BGA1-IC,TBD    I23 @BASEBOARD_FAB2_LIB.BASEBOARD_FAB2(SCH_1):PAGE74
  U2D1  BE6 VSS<637> SKX_EXT_B_BGA1-IC,TBD    I23 @BASEBOARD_FAB2_LIB.BASEBOARD_FAB2(SCH_1):PAGE74
  U2D1  BE4 VSS<638> SKX_EXT_B_BGA1-IC,TBD    I23 @BASEBOARD_FAB2_LIB.BASEBOARD_FAB2(SCH_1):PAGE74
  U2D1 BD71 VSS<639> SKX_EXT_B_BGA1-IC,TBD    I23 @BASEBOARD_FAB2_LIB.BASEBOARD_FAB2(SCH_1):PAGE74
  U2D1 BD63 VSS<640> SKX_EXT_B_BGA1-IC,TBD    I23 @BASEBOARD_FAB2_LIB.BASEBOARD_FAB2(SCH_1):PAGE74
  U2D1 BD27 VSS<641> SKX_EXT_B_BGA1-IC,TBD    I23 @BASEBOARD_FAB2_LIB.BASEBOARD_FAB2(SCH_1):PAGE74
  U2D1 BD21 VSS<642> SKX_EXT_B_BGA1-IC,TBD    I23 @BASEBOARD_FAB2_LIB.BASEBOARD_FAB2(SCH_1):PAGE74
  U2D1 BD15 VSS<643> SKX_EXT_B_BGA1-IC,TBD    I23 @BASEBOARD_FAB2_LIB.BASEBOARD_FAB2(SCH_1):PAGE74
  U2D1 BD11 VSS<644> SKX_EXT_B_BGA1-IC,TBD    I23 @BASEBOARD_FAB2_LIB.BASEBOARD_FAB2(SCH_1):PAGE74
  U2D1  BD5 VSS<645> SKX_EXT_B_BGA1-IC,TBD    I23 @BASEBOARD_FAB2_LIB.BASEBOARD_FAB2(SCH_1):PAGE74
  U2D1 BC82 VSS<646> SKX_EXT_B_BGA1-IC,TBD    I23 @BASEBOARD_FAB2_LIB.BASEBOARD_FAB2(SCH_1):PAGE74
  U2D1 BC80 VSS<647> SKX_EXT_B_BGA1-IC,TBD    I23 @BASEBOARD_FAB2_LIB.BASEBOARD_FAB2(SCH_1):PAGE74
  U2D1 BC78 VSS<648> SKX_EXT_B_BGA1-IC,TBD    I23 @BASEBOARD_FAB2_LIB.BASEBOARD_FAB2(SCH_1):PAGE74
  U2D1 BC76 VSS<649> SKX_EXT_B_BGA1-IC,TBD    I23 @BASEBOARD_FAB2_LIB.BASEBOARD_FAB2(SCH_1):PAGE74
  U2D1 BC74 VSS<650> SKX_EXT_B_BGA1-IC,TBD    I23 @BASEBOARD_FAB2_LIB.BASEBOARD_FAB2(SCH_1):PAGE74
  U2D1 BC72 VSS<651> SKX_EXT_B_BGA1-IC,TBD    I23 @BASEBOARD_FAB2_LIB.BASEBOARD_FAB2(SCH_1):PAGE74
  U2D1 BC70 VSS<652> SKX_EXT_B_BGA1-IC,TBD    I23 @BASEBOARD_FAB2_LIB.BASEBOARD_FAB2(SCH_1):PAGE74
  U2D1 BC16 VSS<653> SKX_EXT_B_BGA1-IC,TBD    I23 @BASEBOARD_FAB2_LIB.BASEBOARD_FAB2(SCH_1):PAGE74
  U2D1 BC12 VSS<654> SKX_EXT_B_BGA1-IC,TBD    I23 @BASEBOARD_FAB2_LIB.BASEBOARD_FAB2(SCH_1):PAGE74
  U2D1  BC8 VSS<655> SKX_EXT_B_BGA1-IC,TBD    I23 @BASEBOARD_FAB2_LIB.BASEBOARD_FAB2(SCH_1):PAGE74
  U2D1  BC4 VSS<656> SKX_EXT_B_BGA1-IC,TBD    I23 @BASEBOARD_FAB2_LIB.BASEBOARD_FAB2(SCH_1):PAGE74
  U2D1 BB83 VSS<657> SKX_EXT_B_BGA1-IC,TBD    I23 @BASEBOARD_FAB2_LIB.BASEBOARD_FAB2(SCH_1):PAGE74
  U2D1 BB81 VSS<658> SKX_EXT_B_BGA1-IC,TBD    I23 @BASEBOARD_FAB2_LIB.BASEBOARD_FAB2(SCH_1):PAGE74
  U2D1 BB79 VSS<659> SKX_EXT_B_BGA1-IC,TBD    I23 @BASEBOARD_FAB2_LIB.BASEBOARD_FAB2(SCH_1):PAGE74
  U2D1 BB77 VSS<660> SKX_EXT_B_BGA1-IC,TBD    I23 @BASEBOARD_FAB2_LIB.BASEBOARD_FAB2(SCH_1):PAGE74
  U2D1 BB75 VSS<661> SKX_EXT_B_BGA1-IC,TBD    I23 @BASEBOARD_FAB2_LIB.BASEBOARD_FAB2(SCH_1):PAGE74
  U2D1 BB73 VSS<662> SKX_EXT_B_BGA1-IC,TBD    I23 @BASEBOARD_FAB2_LIB.BASEBOARD_FAB2(SCH_1):PAGE74
  U2D1 BB69 VSS<663> SKX_EXT_B_BGA1-IC,TBD    I23 @BASEBOARD_FAB2_LIB.BASEBOARD_FAB2(SCH_1):PAGE74
  U2D1 BB63 VSS<664> SKX_EXT_B_BGA1-IC,TBD    I23 @BASEBOARD_FAB2_LIB.BASEBOARD_FAB2(SCH_1):PAGE74
  U2D1 BB23 VSS<665> SKX_EXT_B_BGA1-IC,TBD    I23 @BASEBOARD_FAB2_LIB.BASEBOARD_FAB2(SCH_1):PAGE74
  U2D1 BB19 VSS<666> SKX_EXT_B_BGA1-IC,TBD    I23 @BASEBOARD_FAB2_LIB.BASEBOARD_FAB2(SCH_1):PAGE74
  U2D1 BA84 VSS<667> SKX_EXT_B_BGA1-IC,TBD    I23 @BASEBOARD_FAB2_LIB.BASEBOARD_FAB2(SCH_1):PAGE74
  U2D1 BA80 VSS<668> SKX_EXT_B_BGA1-IC,TBD    I23 @BASEBOARD_FAB2_LIB.BASEBOARD_FAB2(SCH_1):PAGE74
  U2D1 BA74 VSS<669> SKX_EXT_B_BGA1-IC,TBD    I23 @BASEBOARD_FAB2_LIB.BASEBOARD_FAB2(SCH_1):PAGE74
  U2D1 BA68 VSS<670> SKX_EXT_B_BGA1-IC,TBD    I23 @BASEBOARD_FAB2_LIB.BASEBOARD_FAB2(SCH_1):PAGE74
  U2D1 BA62 VSS<671> SKX_EXT_B_BGA1-IC,TBD    I23 @BASEBOARD_FAB2_LIB.BASEBOARD_FAB2(SCH_1):PAGE74
  U2D1 BA12 VSS<672> SKX_EXT_B_BGA1-IC,TBD    I23 @BASEBOARD_FAB2_LIB.BASEBOARD_FAB2(SCH_1):PAGE74
  U2D1  BA6 VSS<673> SKX_EXT_B_BGA1-IC,TBD    I23 @BASEBOARD_FAB2_LIB.BASEBOARD_FAB2(SCH_1):PAGE74
  U2D1  BA2 VSS<674> SKX_EXT_B_BGA1-IC,TBD    I23 @BASEBOARD_FAB2_LIB.BASEBOARD_FAB2(SCH_1):PAGE74
  U2D1 AY81 VSS<675> SKX_EXT_B_BGA1-IC,TBD    I23 @BASEBOARD_FAB2_LIB.BASEBOARD_FAB2(SCH_1):PAGE74
  U2D1 AY79 VSS<676> SKX_EXT_B_BGA1-IC,TBD    I23 @BASEBOARD_FAB2_LIB.BASEBOARD_FAB2(SCH_1):PAGE74
  U2D1 AY63 VSS<677> SKX_EXT_B_BGA1-IC,TBD    I23 @BASEBOARD_FAB2_LIB.BASEBOARD_FAB2(SCH_1):PAGE74
  U2D1 AY25 VSS<678> SKX_EXT_B_BGA1-IC,TBD    I23 @BASEBOARD_FAB2_LIB.BASEBOARD_FAB2(SCH_1):PAGE74
  U2D1 AY23 VSS<679> SKX_EXT_B_BGA1-IC,TBD    I23 @BASEBOARD_FAB2_LIB.BASEBOARD_FAB2(SCH_1):PAGE74
  U2D1 AY21 VSS<680> SKX_EXT_B_BGA1-IC,TBD    I23 @BASEBOARD_FAB2_LIB.BASEBOARD_FAB2(SCH_1):PAGE74
  U2D1 AY17 VSS<681> SKX_EXT_B_BGA1-IC,TBD    I23 @BASEBOARD_FAB2_LIB.BASEBOARD_FAB2(SCH_1):PAGE74
  U2D1 AY15 VSS<682> SKX_EXT_B_BGA1-IC,TBD    I23 @BASEBOARD_FAB2_LIB.BASEBOARD_FAB2(SCH_1):PAGE74
  U2D1  AY5 VSS<683> SKX_EXT_B_BGA1-IC,TBD    I23 @BASEBOARD_FAB2_LIB.BASEBOARD_FAB2(SCH_1):PAGE74
  U2D1 AW84 VSS<684> SKX_EXT_B_BGA1-IC,TBD    I23 @BASEBOARD_FAB2_LIB.BASEBOARD_FAB2(SCH_1):PAGE74
  U2D1 AW82 VSS<685> SKX_EXT_B_BGA1-IC,TBD    I23 @BASEBOARD_FAB2_LIB.BASEBOARD_FAB2(SCH_1):PAGE74
  U2D1 AW78 VSS<686> SKX_EXT_B_BGA1-IC,TBD    I23 @BASEBOARD_FAB2_LIB.BASEBOARD_FAB2(SCH_1):PAGE74
  U2D1 AW74 VSS<687> SKX_EXT_B_BGA1-IC,TBD    I23 @BASEBOARD_FAB2_LIB.BASEBOARD_FAB2(SCH_1):PAGE74
  U2D1 AW72 VSS<688> SKX_EXT_B_BGA1-IC,TBD    I23 @BASEBOARD_FAB2_LIB.BASEBOARD_FAB2(SCH_1):PAGE74
  U2D1 AW70 VSS<689> SKX_EXT_B_BGA1-IC,TBD    I23 @BASEBOARD_FAB2_LIB.BASEBOARD_FAB2(SCH_1):PAGE74
  U2D1 AW68 VSS<690> SKX_EXT_B_BGA1-IC,TBD    I23 @BASEBOARD_FAB2_LIB.BASEBOARD_FAB2(SCH_1):PAGE74
  U2D1 AW66 VSS<691> SKX_EXT_B_BGA1-IC,TBD    I23 @BASEBOARD_FAB2_LIB.BASEBOARD_FAB2(SCH_1):PAGE74
  U2D1 AW62 VSS<692> SKX_EXT_B_BGA1-IC,TBD    I23 @BASEBOARD_FAB2_LIB.BASEBOARD_FAB2(SCH_1):PAGE74
  U2D1 AW10 VSS<693> SKX_EXT_B_BGA1-IC,TBD    I23 @BASEBOARD_FAB2_LIB.BASEBOARD_FAB2(SCH_1):PAGE74
  U2D1  AW2 VSS<694> SKX_EXT_B_BGA1-IC,TBD    I23 @BASEBOARD_FAB2_LIB.BASEBOARD_FAB2(SCH_1):PAGE74
  U2D1 AV83 VSS<695> SKX_EXT_B_BGA1-IC,TBD    I23 @BASEBOARD_FAB2_LIB.BASEBOARD_FAB2(SCH_1):PAGE74
  U2D1 AV75 VSS<696> SKX_EXT_B_BGA1-IC,TBD    I23 @BASEBOARD_FAB2_LIB.BASEBOARD_FAB2(SCH_1):PAGE74
  U2D1 AV67 VSS<697> SKX_EXT_B_BGA1-IC,TBD    I23 @BASEBOARD_FAB2_LIB.BASEBOARD_FAB2(SCH_1):PAGE74
  U2D1 AV65 VSS<698> SKX_EXT_B_BGA1-IC,TBD    I23 @BASEBOARD_FAB2_LIB.BASEBOARD_FAB2(SCH_1):PAGE74
  U2D1 AV63 VSS<699> SKX_EXT_B_BGA1-IC,TBD    I23 @BASEBOARD_FAB2_LIB.BASEBOARD_FAB2(SCH_1):PAGE74
  U2D1 AV25 VSS<700> SKX_EXT_B_BGA1-IC,TBD    I23 @BASEBOARD_FAB2_LIB.BASEBOARD_FAB2(SCH_1):PAGE74
  U2D1 AV23 VSS<701> SKX_EXT_B_BGA1-IC,TBD    I23 @BASEBOARD_FAB2_LIB.BASEBOARD_FAB2(SCH_1):PAGE74
  U2D1 AV19 VSS<702> SKX_EXT_B_BGA1-IC,TBD    I23 @BASEBOARD_FAB2_LIB.BASEBOARD_FAB2(SCH_1):PAGE74
  U2D1 AV13 VSS<703> SKX_EXT_B_BGA1-IC,TBD    I23 @BASEBOARD_FAB2_LIB.BASEBOARD_FAB2(SCH_1):PAGE74
  U2D1 AV11 VSS<704> SKX_EXT_B_BGA1-IC,TBD    I23 @BASEBOARD_FAB2_LIB.BASEBOARD_FAB2(SCH_1):PAGE74
  U2D1  AV7 VSS<705> SKX_EXT_B_BGA1-IC,TBD    I23 @BASEBOARD_FAB2_LIB.BASEBOARD_FAB2(SCH_1):PAGE74
  U2D1  AV3 VSS<706> SKX_EXT_B_BGA1-IC,TBD    I23 @BASEBOARD_FAB2_LIB.BASEBOARD_FAB2(SCH_1):PAGE74
  U2D1  AV1 VSS<707> SKX_EXT_B_BGA1-IC,TBD    I23 @BASEBOARD_FAB2_LIB.BASEBOARD_FAB2(SCH_1):PAGE74
  U2D1 AU86 VSS<708> SKX_EXT_B_BGA1-IC,TBD    I23 @BASEBOARD_FAB2_LIB.BASEBOARD_FAB2(SCH_1):PAGE74
  U2D1 AU84 VSS<709> SKX_EXT_B_BGA1-IC,TBD    I23 @BASEBOARD_FAB2_LIB.BASEBOARD_FAB2(SCH_1):PAGE74
  U2D1 AU80 VSS<710> SKX_EXT_B_BGA1-IC,TBD    I23 @BASEBOARD_FAB2_LIB.BASEBOARD_FAB2(SCH_1):PAGE74
  U2D1 AU78 VSS<711> SKX_EXT_B_BGA1-IC,TBD    I23 @BASEBOARD_FAB2_LIB.BASEBOARD_FAB2(SCH_1):PAGE74
  U2D1 AU76 VSS<712> SKX_EXT_B_BGA1-IC,TBD    I23 @BASEBOARD_FAB2_LIB.BASEBOARD_FAB2(SCH_1):PAGE74
  U2D1 AU74 VSS<713> SKX_EXT_B_BGA1-IC,TBD    I23 @BASEBOARD_FAB2_LIB.BASEBOARD_FAB2(SCH_1):PAGE74
  U2D1 AU68 VSS<714> SKX_EXT_B_BGA1-IC,TBD    I23 @BASEBOARD_FAB2_LIB.BASEBOARD_FAB2(SCH_1):PAGE74
  U2D1 AU64 VSS<715> SKX_EXT_B_BGA1-IC,TBD    I23 @BASEBOARD_FAB2_LIB.BASEBOARD_FAB2(SCH_1):PAGE74
  U2D1 AU62 VSS<716> SKX_EXT_B_BGA1-IC,TBD    I23 @BASEBOARD_FAB2_LIB.BASEBOARD_FAB2(SCH_1):PAGE74
  U2D1 AU28 VSS<717> SKX_EXT_B_BGA1-IC,TBD    I23 @BASEBOARD_FAB2_LIB.BASEBOARD_FAB2(SCH_1):PAGE74
  U2D1 AU26 VSS<718> SKX_EXT_B_BGA1-IC,TBD    I23 @BASEBOARD_FAB2_LIB.BASEBOARD_FAB2(SCH_1):PAGE74
  U2D1  AU6 VSS<719> SKX_EXT_B_BGA1-IC,TBD    I23 @BASEBOARD_FAB2_LIB.BASEBOARD_FAB2(SCH_1):PAGE74
  U2D1  AU2 VSS<720> SKX_EXT_B_BGA1-IC,TBD    I23 @BASEBOARD_FAB2_LIB.BASEBOARD_FAB2(SCH_1):PAGE74
  U2D1 AT85 VSS<721> SKX_EXT_B_BGA1-IC,TBD    I23 @BASEBOARD_FAB2_LIB.BASEBOARD_FAB2(SCH_1):PAGE74
  U2D1 AT83 VSS<722> SKX_EXT_B_BGA1-IC,TBD    I23 @BASEBOARD_FAB2_LIB.BASEBOARD_FAB2(SCH_1):PAGE74
  U2D1 AT77 VSS<723> SKX_EXT_B_BGA1-IC,TBD    I23 @BASEBOARD_FAB2_LIB.BASEBOARD_FAB2(SCH_1):PAGE74
  U2D1 AT73 VSS<724> SKX_EXT_B_BGA1-IC,TBD    I23 @BASEBOARD_FAB2_LIB.BASEBOARD_FAB2(SCH_1):PAGE74
  U2D1 AT69 VSS<725> SKX_EXT_B_BGA1-IC,TBD    I23 @BASEBOARD_FAB2_LIB.BASEBOARD_FAB2(SCH_1):PAGE74
  U2D1 AT63 VSS<726> SKX_EXT_B_BGA1-IC,TBD    I23 @BASEBOARD_FAB2_LIB.BASEBOARD_FAB2(SCH_1):PAGE74
  U2D1 AT61 VSS<727> SKX_EXT_B_BGA1-IC,TBD    I23 @BASEBOARD_FAB2_LIB.BASEBOARD_FAB2(SCH_1):PAGE74
  U2D1 AT27 VSS<728> SKX_EXT_B_BGA1-IC,TBD    I23 @BASEBOARD_FAB2_LIB.BASEBOARD_FAB2(SCH_1):PAGE74
  U2D1 AT21 VSS<729> SKX_EXT_B_BGA1-IC,TBD    I23 @BASEBOARD_FAB2_LIB.BASEBOARD_FAB2(SCH_1):PAGE74
  U2D1 AT17 VSS<730> SKX_EXT_B_BGA1-IC,TBD    I23 @BASEBOARD_FAB2_LIB.BASEBOARD_FAB2(SCH_1):PAGE74
  U2D1 AT15 VSS<731> SKX_EXT_B_BGA1-IC,TBD    I23 @BASEBOARD_FAB2_LIB.BASEBOARD_FAB2(SCH_1):PAGE74
  U2D1  P63 VSS<732> SKX_EXT_B_BGA1-IC,TBD    I23 @BASEBOARD_FAB2_LIB.BASEBOARD_FAB2(SCH_1):PAGE74
  U2D1 AC48 VSS<733> SKX_EXT_B_BGA1-IC,TBD    I23 @BASEBOARD_FAB2_LIB.BASEBOARD_FAB2(SCH_1):PAGE74
  U2D1 AR78 VSS<734> SKX_EXT_B_BGA1-IC,TBD    I23 @BASEBOARD_FAB2_LIB.BASEBOARD_FAB2(SCH_1):PAGE74
  U2D1 AR72 VSS<735> SKX_EXT_B_BGA1-IC,TBD    I23 @BASEBOARD_FAB2_LIB.BASEBOARD_FAB2(SCH_1):PAGE74
  U2D1 AR60 VSS<736> SKX_EXT_B_BGA1-IC,TBD    I23 @BASEBOARD_FAB2_LIB.BASEBOARD_FAB2(SCH_1):PAGE74
  U2D1 AR30 VSS<737> SKX_EXT_B_BGA1-IC,TBD    I23 @BASEBOARD_FAB2_LIB.BASEBOARD_FAB2(SCH_1):PAGE74
  U2D1 AR24 VSS<738> SKX_EXT_B_BGA1-IC,TBD    I23 @BASEBOARD_FAB2_LIB.BASEBOARD_FAB2(SCH_1):PAGE74
  U2D1 AR10 VSS<739> SKX_EXT_B_BGA1-IC,TBD    I23 @BASEBOARD_FAB2_LIB.BASEBOARD_FAB2(SCH_1):PAGE74
  U2D1 AP85 VSS<740> SKX_EXT_B_BGA1-IC,TBD    I23 @BASEBOARD_FAB2_LIB.BASEBOARD_FAB2(SCH_1):PAGE74
  U2D1 AP83 VSS<741> SKX_EXT_B_BGA1-IC,TBD    I23 @BASEBOARD_FAB2_LIB.BASEBOARD_FAB2(SCH_1):PAGE74
  U2D1 AP81 VSS<742> SKX_EXT_B_BGA1-IC,TBD    I23 @BASEBOARD_FAB2_LIB.BASEBOARD_FAB2(SCH_1):PAGE74
  U2D1 AP75 VSS<743> SKX_EXT_B_BGA1-IC,TBD    I23 @BASEBOARD_FAB2_LIB.BASEBOARD_FAB2(SCH_1):PAGE74
  U2D1 AP73 VSS<744> SKX_EXT_B_BGA1-IC,TBD    I23 @BASEBOARD_FAB2_LIB.BASEBOARD_FAB2(SCH_1):PAGE74
  U2D1 AP69 VSS<745> SKX_EXT_B_BGA1-IC,TBD    I23 @BASEBOARD_FAB2_LIB.BASEBOARD_FAB2(SCH_1):PAGE74
  U2D1 AP67 VSS<746> SKX_EXT_B_BGA1-IC,TBD    I23 @BASEBOARD_FAB2_LIB.BASEBOARD_FAB2(SCH_1):PAGE74
  U2D1 AP65 VSS<747> SKX_EXT_B_BGA1-IC,TBD    I23 @BASEBOARD_FAB2_LIB.BASEBOARD_FAB2(SCH_1):PAGE74
  U2D1 AP63 VSS<748> SKX_EXT_B_BGA1-IC,TBD    I23 @BASEBOARD_FAB2_LIB.BASEBOARD_FAB2(SCH_1):PAGE74
  U2D1 AP59 VSS<749> SKX_EXT_B_BGA1-IC,TBD    I23 @BASEBOARD_FAB2_LIB.BASEBOARD_FAB2(SCH_1):PAGE74
  U2D1 AP31 VSS<750> SKX_EXT_B_BGA1-IC,TBD    I23 @BASEBOARD_FAB2_LIB.BASEBOARD_FAB2(SCH_1):PAGE74
  U2D1 AP19 VSS<751> SKX_EXT_B_BGA1-IC,TBD    I23 @BASEBOARD_FAB2_LIB.BASEBOARD_FAB2(SCH_1):PAGE74
  U2D1 AP13 VSS<752> SKX_EXT_B_BGA1-IC,TBD    I23 @BASEBOARD_FAB2_LIB.BASEBOARD_FAB2(SCH_1):PAGE74
  U2D1  AP9 VSS<753> SKX_EXT_B_BGA1-IC,TBD    I23 @BASEBOARD_FAB2_LIB.BASEBOARD_FAB2(SCH_1):PAGE74
  U2D1  AP5 VSS<754> SKX_EXT_B_BGA1-IC,TBD    I23 @BASEBOARD_FAB2_LIB.BASEBOARD_FAB2(SCH_1):PAGE74
  U2D1 AN78 VSS<755> SKX_EXT_B_BGA1-IC,TBD    I23 @BASEBOARD_FAB2_LIB.BASEBOARD_FAB2(SCH_1):PAGE74
  U2D1 AN58 VSS<756> SKX_EXT_B_BGA1-IC,TBD    I23 @BASEBOARD_FAB2_LIB.BASEBOARD_FAB2(SCH_1):PAGE74
  U2D1 AN28 VSS<757> SKX_EXT_B_BGA1-IC,TBD    I23 @BASEBOARD_FAB2_LIB.BASEBOARD_FAB2(SCH_1):PAGE74
  U2D1  AN6 VSS<758> SKX_EXT_B_BGA1-IC,TBD    I23 @BASEBOARD_FAB2_LIB.BASEBOARD_FAB2(SCH_1):PAGE74
  U2D1  AN2 VSS<759> SKX_EXT_B_BGA1-IC,TBD    I23 @BASEBOARD_FAB2_LIB.BASEBOARD_FAB2(SCH_1):PAGE74
  U2D1 AM83 VSS<760> SKX_EXT_B_BGA1-IC,TBD    I23 @BASEBOARD_FAB2_LIB.BASEBOARD_FAB2(SCH_1):PAGE74
  U2D1 AM79 VSS<761> SKX_EXT_B_BGA1-IC,TBD    I23 @BASEBOARD_FAB2_LIB.BASEBOARD_FAB2(SCH_1):PAGE74
  U2D1 AM73 VSS<762> SKX_EXT_B_BGA1-IC,TBD    I23 @BASEBOARD_FAB2_LIB.BASEBOARD_FAB2(SCH_1):PAGE74
  U2D1 AM69 VSS<763> SKX_EXT_B_BGA1-IC,TBD    I23 @BASEBOARD_FAB2_LIB.BASEBOARD_FAB2(SCH_1):PAGE74
  U2D1 AM63 VSS<764> SKX_EXT_B_BGA1-IC,TBD    I23 @BASEBOARD_FAB2_LIB.BASEBOARD_FAB2(SCH_1):PAGE74
  U2D1 AM57 VSS<765> SKX_EXT_B_BGA1-IC,TBD    I23 @BASEBOARD_FAB2_LIB.BASEBOARD_FAB2(SCH_1):PAGE74
  U2D1 AM31 VSS<766> SKX_EXT_B_BGA1-IC,TBD    I23 @BASEBOARD_FAB2_LIB.BASEBOARD_FAB2(SCH_1):PAGE74
  U2D1 AC50 VSS<767> SKX_EXT_B_BGA1-IC,TBD    I23 @BASEBOARD_FAB2_LIB.BASEBOARD_FAB2(SCH_1):PAGE74
  U2D1  AM1 VSS<768> SKX_EXT_B_BGA1-IC,TBD    I23 @BASEBOARD_FAB2_LIB.BASEBOARD_FAB2(SCH_1):PAGE74
  U2D1 AL86 VSS<769> SKX_EXT_B_BGA1-IC,TBD    I23 @BASEBOARD_FAB2_LIB.BASEBOARD_FAB2(SCH_1):PAGE74
  U2D1 AL82 VSS<770> SKX_EXT_B_BGA1-IC,TBD    I23 @BASEBOARD_FAB2_LIB.BASEBOARD_FAB2(SCH_1):PAGE74
  U2D1 AL80 VSS<771> SKX_EXT_B_BGA1-IC,TBD    I23 @BASEBOARD_FAB2_LIB.BASEBOARD_FAB2(SCH_1):PAGE74
  U2D1 AL78 VSS<772> SKX_EXT_B_BGA1-IC,TBD    I23 @BASEBOARD_FAB2_LIB.BASEBOARD_FAB2(SCH_1):PAGE74
  U2D1 AL76 VSS<773> SKX_EXT_B_BGA1-IC,TBD    I23 @BASEBOARD_FAB2_LIB.BASEBOARD_FAB2(SCH_1):PAGE74
  U2D1  P49 VSS<454> SKX_EXT_B_BGA1-IC,TBD    I17 @BASEBOARD_FAB2_LIB.BASEBOARD_FAB2(SCH_1):PAGE75
  U2D1 CJ12 VSS<455> SKX_EXT_B_BGA1-IC,TBD    I17 @BASEBOARD_FAB2_LIB.BASEBOARD_FAB2(SCH_1):PAGE75
  U2D1 CJ10 VSS<456> SKX_EXT_B_BGA1-IC,TBD    I17 @BASEBOARD_FAB2_LIB.BASEBOARD_FAB2(SCH_1):PAGE75
  U2D1  CJ8 VSS<457> SKX_EXT_B_BGA1-IC,TBD    I17 @BASEBOARD_FAB2_LIB.BASEBOARD_FAB2(SCH_1):PAGE75
  U2D1  CJ6 VSS<458> SKX_EXT_B_BGA1-IC,TBD    I17 @BASEBOARD_FAB2_LIB.BASEBOARD_FAB2(SCH_1):PAGE75
  U2D1  CJ2 VSS<459> SKX_EXT_B_BGA1-IC,TBD    I17 @BASEBOARD_FAB2_LIB.BASEBOARD_FAB2(SCH_1):PAGE75
  U2D1 CH83 VSS<460> SKX_EXT_B_BGA1-IC,TBD    I17 @BASEBOARD_FAB2_LIB.BASEBOARD_FAB2(SCH_1):PAGE75
  U2D1 CH81 VSS<461> SKX_EXT_B_BGA1-IC,TBD    I17 @BASEBOARD_FAB2_LIB.BASEBOARD_FAB2(SCH_1):PAGE75
  U2D1 CH79 VSS<462> SKX_EXT_B_BGA1-IC,TBD    I17 @BASEBOARD_FAB2_LIB.BASEBOARD_FAB2(SCH_1):PAGE75
  U2D1 CH73 VSS<463> SKX_EXT_B_BGA1-IC,TBD    I17 @BASEBOARD_FAB2_LIB.BASEBOARD_FAB2(SCH_1):PAGE75
  U2D1 CH67 VSS<464> SKX_EXT_B_BGA1-IC,TBD    I17 @BASEBOARD_FAB2_LIB.BASEBOARD_FAB2(SCH_1):PAGE75
  U2D1 CH63 VSS<465> SKX_EXT_B_BGA1-IC,TBD    I17 @BASEBOARD_FAB2_LIB.BASEBOARD_FAB2(SCH_1):PAGE75
  U2D1 CH19 VSS<466> SKX_EXT_B_BGA1-IC,TBD    I17 @BASEBOARD_FAB2_LIB.BASEBOARD_FAB2(SCH_1):PAGE75
  U2D1 CH15 VSS<467> SKX_EXT_B_BGA1-IC,TBD    I17 @BASEBOARD_FAB2_LIB.BASEBOARD_FAB2(SCH_1):PAGE75
  U2D1  CH3 VSS<468> SKX_EXT_B_BGA1-IC,TBD    I17 @BASEBOARD_FAB2_LIB.BASEBOARD_FAB2(SCH_1):PAGE75
  U2D1  CH1 VSS<469> SKX_EXT_B_BGA1-IC,TBD    I17 @BASEBOARD_FAB2_LIB.BASEBOARD_FAB2(SCH_1):PAGE75
  U2D1 CG80 VSS<470> SKX_EXT_B_BGA1-IC,TBD    I17 @BASEBOARD_FAB2_LIB.BASEBOARD_FAB2(SCH_1):PAGE75
  U2D1 CG72 VSS<471> SKX_EXT_B_BGA1-IC,TBD    I17 @BASEBOARD_FAB2_LIB.BASEBOARD_FAB2(SCH_1):PAGE75
  U2D1 CG68 VSS<472> SKX_EXT_B_BGA1-IC,TBD    I17 @BASEBOARD_FAB2_LIB.BASEBOARD_FAB2(SCH_1):PAGE75
  U2D1 CG62 VSS<473> SKX_EXT_B_BGA1-IC,TBD    I17 @BASEBOARD_FAB2_LIB.BASEBOARD_FAB2(SCH_1):PAGE75
  U2D1 CG22 VSS<474> SKX_EXT_B_BGA1-IC,TBD    I17 @BASEBOARD_FAB2_LIB.BASEBOARD_FAB2(SCH_1):PAGE75
  U2D1 CG18 VSS<475> SKX_EXT_B_BGA1-IC,TBD    I17 @BASEBOARD_FAB2_LIB.BASEBOARD_FAB2(SCH_1):PAGE75
  U2D1  P51 VSS<476> SKX_EXT_B_BGA1-IC,TBD    I17 @BASEBOARD_FAB2_LIB.BASEBOARD_FAB2(SCH_1):PAGE75
  U2D1 CF83 VSS<477> SKX_EXT_B_BGA1-IC,TBD    I17 @BASEBOARD_FAB2_LIB.BASEBOARD_FAB2(SCH_1):PAGE75
  U2D1 CF77 VSS<478> SKX_EXT_B_BGA1-IC,TBD    I17 @BASEBOARD_FAB2_LIB.BASEBOARD_FAB2(SCH_1):PAGE75
  U2D1 CF71 VSS<479> SKX_EXT_B_BGA1-IC,TBD    I17 @BASEBOARD_FAB2_LIB.BASEBOARD_FAB2(SCH_1):PAGE75
  U2D1 CF69 VSS<480> SKX_EXT_B_BGA1-IC,TBD    I17 @BASEBOARD_FAB2_LIB.BASEBOARD_FAB2(SCH_1):PAGE75
  U2D1 CF63 VSS<481> SKX_EXT_B_BGA1-IC,TBD    I17 @BASEBOARD_FAB2_LIB.BASEBOARD_FAB2(SCH_1):PAGE75
  U2D1  CF9 VSS<482> SKX_EXT_B_BGA1-IC,TBD    I17 @BASEBOARD_FAB2_LIB.BASEBOARD_FAB2(SCH_1):PAGE75
  U2D1  P53 VSS<483> SKX_EXT_B_BGA1-IC,TBD    I17 @BASEBOARD_FAB2_LIB.BASEBOARD_FAB2(SCH_1):PAGE75
  U2D1 CE82 VSS<484> SKX_EXT_B_BGA1-IC,TBD    I17 @BASEBOARD_FAB2_LIB.BASEBOARD_FAB2(SCH_1):PAGE75
  U2D1 CE70 VSS<485> SKX_EXT_B_BGA1-IC,TBD    I17 @BASEBOARD_FAB2_LIB.BASEBOARD_FAB2(SCH_1):PAGE75
  U2D1 CE62 VSS<486> SKX_EXT_B_BGA1-IC,TBD    I17 @BASEBOARD_FAB2_LIB.BASEBOARD_FAB2(SCH_1):PAGE75
  U2D1 CE26 VSS<487> SKX_EXT_B_BGA1-IC,TBD    I17 @BASEBOARD_FAB2_LIB.BASEBOARD_FAB2(SCH_1):PAGE75
  U2D1 CE20 VSS<488> SKX_EXT_B_BGA1-IC,TBD    I17 @BASEBOARD_FAB2_LIB.BASEBOARD_FAB2(SCH_1):PAGE75
  U2D1 CE14 VSS<489> SKX_EXT_B_BGA1-IC,TBD    I17 @BASEBOARD_FAB2_LIB.BASEBOARD_FAB2(SCH_1):PAGE75
  U2D1 CE10 VSS<490> SKX_EXT_B_BGA1-IC,TBD    I17 @BASEBOARD_FAB2_LIB.BASEBOARD_FAB2(SCH_1):PAGE75
  U2D1 CD81 VSS<491> SKX_EXT_B_BGA1-IC,TBD    I17 @BASEBOARD_FAB2_LIB.BASEBOARD_FAB2(SCH_1):PAGE75
  U2D1 CD79 VSS<492> SKX_EXT_B_BGA1-IC,TBD    I17 @BASEBOARD_FAB2_LIB.BASEBOARD_FAB2(SCH_1):PAGE75
  U2D1 CD77 VSS<493> SKX_EXT_B_BGA1-IC,TBD    I17 @BASEBOARD_FAB2_LIB.BASEBOARD_FAB2(SCH_1):PAGE75
  U2D1 CD75 VSS<494> SKX_EXT_B_BGA1-IC,TBD    I17 @BASEBOARD_FAB2_LIB.BASEBOARD_FAB2(SCH_1):PAGE75
  U2D1 CD73 VSS<495> SKX_EXT_B_BGA1-IC,TBD    I17 @BASEBOARD_FAB2_LIB.BASEBOARD_FAB2(SCH_1):PAGE75
  U2D1 CD63 VSS<496> SKX_EXT_B_BGA1-IC,TBD    I17 @BASEBOARD_FAB2_LIB.BASEBOARD_FAB2(SCH_1):PAGE75
  U2D1 CD13 VSS<497> SKX_EXT_B_BGA1-IC,TBD    I17 @BASEBOARD_FAB2_LIB.BASEBOARD_FAB2(SCH_1):PAGE75
  U2D1  CD5 VSS<498> SKX_EXT_B_BGA1-IC,TBD    I17 @BASEBOARD_FAB2_LIB.BASEBOARD_FAB2(SCH_1):PAGE75
  U2D1 CC82 VSS<499> SKX_EXT_B_BGA1-IC,TBD    I17 @BASEBOARD_FAB2_LIB.BASEBOARD_FAB2(SCH_1):PAGE75
  U2D1 CC80 VSS<500> SKX_EXT_B_BGA1-IC,TBD    I17 @BASEBOARD_FAB2_LIB.BASEBOARD_FAB2(SCH_1):PAGE75
  U2D1 CC78 VSS<501> SKX_EXT_B_BGA1-IC,TBD    I17 @BASEBOARD_FAB2_LIB.BASEBOARD_FAB2(SCH_1):PAGE75
  U2D1 CC76 VSS<502> SKX_EXT_B_BGA1-IC,TBD    I17 @BASEBOARD_FAB2_LIB.BASEBOARD_FAB2(SCH_1):PAGE75
  U2D1 CC74 VSS<503> SKX_EXT_B_BGA1-IC,TBD    I17 @BASEBOARD_FAB2_LIB.BASEBOARD_FAB2(SCH_1):PAGE75
  U2D1 CC72 VSS<504> SKX_EXT_B_BGA1-IC,TBD    I17 @BASEBOARD_FAB2_LIB.BASEBOARD_FAB2(SCH_1):PAGE75
  U2D1 CC64 VSS<505> SKX_EXT_B_BGA1-IC,TBD    I17 @BASEBOARD_FAB2_LIB.BASEBOARD_FAB2(SCH_1):PAGE75
  U2D1 CC24 VSS<506> SKX_EXT_B_BGA1-IC,TBD    I17 @BASEBOARD_FAB2_LIB.BASEBOARD_FAB2(SCH_1):PAGE75
  U2D1 CC18 VSS<507> SKX_EXT_B_BGA1-IC,TBD    I17 @BASEBOARD_FAB2_LIB.BASEBOARD_FAB2(SCH_1):PAGE75
  U2D1 CC16 VSS<508> SKX_EXT_B_BGA1-IC,TBD    I17 @BASEBOARD_FAB2_LIB.BASEBOARD_FAB2(SCH_1):PAGE75
  U2D1  CC4 VSS<509> SKX_EXT_B_BGA1-IC,TBD    I17 @BASEBOARD_FAB2_LIB.BASEBOARD_FAB2(SCH_1):PAGE75
  U2D1 CB71 VSS<510> SKX_EXT_B_BGA1-IC,TBD    I17 @BASEBOARD_FAB2_LIB.BASEBOARD_FAB2(SCH_1):PAGE75
  U2D1 CB63 VSS<511> SKX_EXT_B_BGA1-IC,TBD    I17 @BASEBOARD_FAB2_LIB.BASEBOARD_FAB2(SCH_1):PAGE75
  U2D1 CB27 VSS<512> SKX_EXT_B_BGA1-IC,TBD    I17 @BASEBOARD_FAB2_LIB.BASEBOARD_FAB2(SCH_1):PAGE75
  U2D1  CB9 VSS<513> SKX_EXT_B_BGA1-IC,TBD    I17 @BASEBOARD_FAB2_LIB.BASEBOARD_FAB2(SCH_1):PAGE75
  U2D1  CB7 VSS<514> SKX_EXT_B_BGA1-IC,TBD    I17 @BASEBOARD_FAB2_LIB.BASEBOARD_FAB2(SCH_1):PAGE75
  U2D1 CA70 VSS<515> SKX_EXT_B_BGA1-IC,TBD    I17 @BASEBOARD_FAB2_LIB.BASEBOARD_FAB2(SCH_1):PAGE75
  U2D1 CA68 VSS<516> SKX_EXT_B_BGA1-IC,TBD    I17 @BASEBOARD_FAB2_LIB.BASEBOARD_FAB2(SCH_1):PAGE75
  U2D1 CA66 VSS<517> SKX_EXT_B_BGA1-IC,TBD    I17 @BASEBOARD_FAB2_LIB.BASEBOARD_FAB2(SCH_1):PAGE75
  U2D1 CA64 VSS<518> SKX_EXT_B_BGA1-IC,TBD    I17 @BASEBOARD_FAB2_LIB.BASEBOARD_FAB2(SCH_1):PAGE75
  U2D1 CA26 VSS<519> SKX_EXT_B_BGA1-IC,TBD    I17 @BASEBOARD_FAB2_LIB.BASEBOARD_FAB2(SCH_1):PAGE75
  U2D1 CA18 VSS<520> SKX_EXT_B_BGA1-IC,TBD    I17 @BASEBOARD_FAB2_LIB.BASEBOARD_FAB2(SCH_1):PAGE75
  U2D1 CA14 VSS<521> SKX_EXT_B_BGA1-IC,TBD    I17 @BASEBOARD_FAB2_LIB.BASEBOARD_FAB2(SCH_1):PAGE75
  U2D1 CA10 VSS<522> SKX_EXT_B_BGA1-IC,TBD    I17 @BASEBOARD_FAB2_LIB.BASEBOARD_FAB2(SCH_1):PAGE75
  U2D1  CA8 VSS<523> SKX_EXT_B_BGA1-IC,TBD    I17 @BASEBOARD_FAB2_LIB.BASEBOARD_FAB2(SCH_1):PAGE75
  U2D1  CA6 VSS<524> SKX_EXT_B_BGA1-IC,TBD    I17 @BASEBOARD_FAB2_LIB.BASEBOARD_FAB2(SCH_1):PAGE75
  U2D1  CA2 VSS<525> SKX_EXT_B_BGA1-IC,TBD    I17 @BASEBOARD_FAB2_LIB.BASEBOARD_FAB2(SCH_1):PAGE75
  U2D1 BY71 VSS<526> SKX_EXT_B_BGA1-IC,TBD    I17 @BASEBOARD_FAB2_LIB.BASEBOARD_FAB2(SCH_1):PAGE75
  U2D1 BY69 VSS<527> SKX_EXT_B_BGA1-IC,TBD    I17 @BASEBOARD_FAB2_LIB.BASEBOARD_FAB2(SCH_1):PAGE75
  U2D1 BY67 VSS<528> SKX_EXT_B_BGA1-IC,TBD    I17 @BASEBOARD_FAB2_LIB.BASEBOARD_FAB2(SCH_1):PAGE75
  U2D1 BY65 VSS<529> SKX_EXT_B_BGA1-IC,TBD    I17 @BASEBOARD_FAB2_LIB.BASEBOARD_FAB2(SCH_1):PAGE75
  U2D1 BY63 VSS<530> SKX_EXT_B_BGA1-IC,TBD    I17 @BASEBOARD_FAB2_LIB.BASEBOARD_FAB2(SCH_1):PAGE75
  U2D1 BY23 VSS<531> SKX_EXT_B_BGA1-IC,TBD    I17 @BASEBOARD_FAB2_LIB.BASEBOARD_FAB2(SCH_1):PAGE75
  U2D1 BY13 VSS<532> SKX_EXT_B_BGA1-IC,TBD    I17 @BASEBOARD_FAB2_LIB.BASEBOARD_FAB2(SCH_1):PAGE75
  U2D1 BY11 VSS<533> SKX_EXT_B_BGA1-IC,TBD    I17 @BASEBOARD_FAB2_LIB.BASEBOARD_FAB2(SCH_1):PAGE75
  U2D1 BW82 VSS<534> SKX_EXT_B_BGA1-IC,TBD    I17 @BASEBOARD_FAB2_LIB.BASEBOARD_FAB2(SCH_1):PAGE75
  U2D1 BW80 VSS<535> SKX_EXT_B_BGA1-IC,TBD    I17 @BASEBOARD_FAB2_LIB.BASEBOARD_FAB2(SCH_1):PAGE75
  U2D1 BW78 VSS<536> SKX_EXT_B_BGA1-IC,TBD    I17 @BASEBOARD_FAB2_LIB.BASEBOARD_FAB2(SCH_1):PAGE75
  U2D1 BW76 VSS<537> SKX_EXT_B_BGA1-IC,TBD    I17 @BASEBOARD_FAB2_LIB.BASEBOARD_FAB2(SCH_1):PAGE75
  U2D1 BW74 VSS<538> SKX_EXT_B_BGA1-IC,TBD    I17 @BASEBOARD_FAB2_LIB.BASEBOARD_FAB2(SCH_1):PAGE75
  U2D1 BW72 VSS<539> SKX_EXT_B_BGA1-IC,TBD    I17 @BASEBOARD_FAB2_LIB.BASEBOARD_FAB2(SCH_1):PAGE75
  U2D1 BW26 VSS<540> SKX_EXT_B_BGA1-IC,TBD    I17 @BASEBOARD_FAB2_LIB.BASEBOARD_FAB2(SCH_1):PAGE75
  U2D1 BW18 VSS<541> SKX_EXT_B_BGA1-IC,TBD    I17 @BASEBOARD_FAB2_LIB.BASEBOARD_FAB2(SCH_1):PAGE75
  U2D1 BW16 VSS<542> SKX_EXT_B_BGA1-IC,TBD    I17 @BASEBOARD_FAB2_LIB.BASEBOARD_FAB2(SCH_1):PAGE75
  U2D1 BW14 VSS<543> SKX_EXT_B_BGA1-IC,TBD    I17 @BASEBOARD_FAB2_LIB.BASEBOARD_FAB2(SCH_1):PAGE75
  U2D1 BW12 VSS<544> SKX_EXT_B_BGA1-IC,TBD    I17 @BASEBOARD_FAB2_LIB.BASEBOARD_FAB2(SCH_1):PAGE75
  U2D1  P55 VSS<545> SKX_EXT_B_BGA1-IC,TBD    I17 @BASEBOARD_FAB2_LIB.BASEBOARD_FAB2(SCH_1):PAGE75
  U2D1  BW6 VSS<546> SKX_EXT_B_BGA1-IC,TBD    I17 @BASEBOARD_FAB2_LIB.BASEBOARD_FAB2(SCH_1):PAGE75
  U2D1 BV25 VSS<547> SKX_EXT_B_BGA1-IC,TBD    I17 @BASEBOARD_FAB2_LIB.BASEBOARD_FAB2(SCH_1):PAGE75
  U2D1 BV17 VSS<548> SKX_EXT_B_BGA1-IC,TBD    I17 @BASEBOARD_FAB2_LIB.BASEBOARD_FAB2(SCH_1):PAGE75
  U2D1 BU10 VSS<549> SKX_EXT_B_BGA1-IC,TBD    I17 @BASEBOARD_FAB2_LIB.BASEBOARD_FAB2(SCH_1):PAGE75
  U2D1  BV5 VSS<550> SKX_EXT_B_BGA1-IC,TBD    I17 @BASEBOARD_FAB2_LIB.BASEBOARD_FAB2(SCH_1):PAGE75
  U2D1  BU8 VSS<551> SKX_EXT_B_BGA1-IC,TBD    I17 @BASEBOARD_FAB2_LIB.BASEBOARD_FAB2(SCH_1):PAGE75
  U2D1 BT25 VSS<552> SKX_EXT_B_BGA1-IC,TBD    I17 @BASEBOARD_FAB2_LIB.BASEBOARD_FAB2(SCH_1):PAGE75
  U2D1 BT23 VSS<553> SKX_EXT_B_BGA1-IC,TBD    I17 @BASEBOARD_FAB2_LIB.BASEBOARD_FAB2(SCH_1):PAGE75
  U2D1 BT21 VSS<554> SKX_EXT_B_BGA1-IC,TBD    I17 @BASEBOARD_FAB2_LIB.BASEBOARD_FAB2(SCH_1):PAGE75
  U2D1  BT5 VSS<555> SKX_EXT_B_BGA1-IC,TBD    I17 @BASEBOARD_FAB2_LIB.BASEBOARD_FAB2(SCH_1):PAGE75
  U2D1  BT3 VSS<556> SKX_EXT_B_BGA1-IC,TBD    I17 @BASEBOARD_FAB2_LIB.BASEBOARD_FAB2(SCH_1):PAGE75
  U2D1 BR82 VSS<557> SKX_EXT_B_BGA1-IC,TBD    I17 @BASEBOARD_FAB2_LIB.BASEBOARD_FAB2(SCH_1):PAGE75
  U2D1 BR80 VSS<558> SKX_EXT_B_BGA1-IC,TBD    I17 @BASEBOARD_FAB2_LIB.BASEBOARD_FAB2(SCH_1):PAGE75
  U2D1 BR78 VSS<559> SKX_EXT_B_BGA1-IC,TBD    I17 @BASEBOARD_FAB2_LIB.BASEBOARD_FAB2(SCH_1):PAGE75
  U2D1 BR76 VSS<560> SKX_EXT_B_BGA1-IC,TBD    I17 @BASEBOARD_FAB2_LIB.BASEBOARD_FAB2(SCH_1):PAGE75
  U2D1 BR74 VSS<561> SKX_EXT_B_BGA1-IC,TBD    I17 @BASEBOARD_FAB2_LIB.BASEBOARD_FAB2(SCH_1):PAGE75
  U2D1 BR72 VSS<562> SKX_EXT_B_BGA1-IC,TBD    I17 @BASEBOARD_FAB2_LIB.BASEBOARD_FAB2(SCH_1):PAGE75
  U2D1 BR70 VSS<563> SKX_EXT_B_BGA1-IC,TBD    I17 @BASEBOARD_FAB2_LIB.BASEBOARD_FAB2(SCH_1):PAGE75
  U2D1 BR68 VSS<564> SKX_EXT_B_BGA1-IC,TBD    I17 @BASEBOARD_FAB2_LIB.BASEBOARD_FAB2(SCH_1):PAGE75
  U2D1 BR66 VSS<565> SKX_EXT_B_BGA1-IC,TBD    I17 @BASEBOARD_FAB2_LIB.BASEBOARD_FAB2(SCH_1):PAGE75
  U2D1 BR64 VSS<566> SKX_EXT_B_BGA1-IC,TBD    I17 @BASEBOARD_FAB2_LIB.BASEBOARD_FAB2(SCH_1):PAGE75
  U2D1  P57 VSS<567> SKX_EXT_B_BGA1-IC,TBD    I17 @BASEBOARD_FAB2_LIB.BASEBOARD_FAB2(SCH_1):PAGE75
  U2D1 BR16 VSS<568> SKX_EXT_B_BGA1-IC,TBD    I17 @BASEBOARD_FAB2_LIB.BASEBOARD_FAB2(SCH_1):PAGE75
  U2D1 BR10 VSS<569> SKX_EXT_B_BGA1-IC,TBD    I17 @BASEBOARD_FAB2_LIB.BASEBOARD_FAB2(SCH_1):PAGE75
  U2D1  BR6 VSS<570> SKX_EXT_B_BGA1-IC,TBD    I17 @BASEBOARD_FAB2_LIB.BASEBOARD_FAB2(SCH_1):PAGE75
  U2D1 BP27 VSS<571> SKX_EXT_B_BGA1-IC,TBD    I17 @BASEBOARD_FAB2_LIB.BASEBOARD_FAB2(SCH_1):PAGE75
  U2D1  BP3 VSS<572> SKX_EXT_B_BGA1-IC,TBD    I17 @BASEBOARD_FAB2_LIB.BASEBOARD_FAB2(SCH_1):PAGE75
  U2D1 BN26 VSS<573> SKX_EXT_B_BGA1-IC,TBD    I17 @BASEBOARD_FAB2_LIB.BASEBOARD_FAB2(SCH_1):PAGE75
  U2D1 BN20 VSS<574> SKX_EXT_B_BGA1-IC,TBD    I17 @BASEBOARD_FAB2_LIB.BASEBOARD_FAB2(SCH_1):PAGE75
  U2D1 BN10 VSS<575> SKX_EXT_B_BGA1-IC,TBD    I17 @BASEBOARD_FAB2_LIB.BASEBOARD_FAB2(SCH_1):PAGE75
  U2D1  BN6 VSS<576> SKX_EXT_B_BGA1-IC,TBD    I17 @BASEBOARD_FAB2_LIB.BASEBOARD_FAB2(SCH_1):PAGE75
  U2D1 BM25 VSS<577> SKX_EXT_B_BGA1-IC,TBD    I17 @BASEBOARD_FAB2_LIB.BASEBOARD_FAB2(SCH_1):PAGE75
  U2D1  P59 VSS<578> SKX_EXT_B_BGA1-IC,TBD    I17 @BASEBOARD_FAB2_LIB.BASEBOARD_FAB2(SCH_1):PAGE75
  U2D1 BM15 VSS<579> SKX_EXT_B_BGA1-IC,TBD    I17 @BASEBOARD_FAB2_LIB.BASEBOARD_FAB2(SCH_1):PAGE75
  U2D1 BM13 VSS<580> SKX_EXT_B_BGA1-IC,TBD    I17 @BASEBOARD_FAB2_LIB.BASEBOARD_FAB2(SCH_1):PAGE75
  U2D1  BM9 VSS<581> SKX_EXT_B_BGA1-IC,TBD    I17 @BASEBOARD_FAB2_LIB.BASEBOARD_FAB2(SCH_1):PAGE75
  U2D1 BL82 VSS<582> SKX_EXT_B_BGA1-IC,TBD    I17 @BASEBOARD_FAB2_LIB.BASEBOARD_FAB2(SCH_1):PAGE75
  U2D1 BL80 VSS<583> SKX_EXT_B_BGA1-IC,TBD    I17 @BASEBOARD_FAB2_LIB.BASEBOARD_FAB2(SCH_1):PAGE75
  U2D1 BL78 VSS<584> SKX_EXT_B_BGA1-IC,TBD    I17 @BASEBOARD_FAB2_LIB.BASEBOARD_FAB2(SCH_1):PAGE75
  U2D1 BL76 VSS<585> SKX_EXT_B_BGA1-IC,TBD    I17 @BASEBOARD_FAB2_LIB.BASEBOARD_FAB2(SCH_1):PAGE75
  U2D1 BL74 VSS<586> SKX_EXT_B_BGA1-IC,TBD    I17 @BASEBOARD_FAB2_LIB.BASEBOARD_FAB2(SCH_1):PAGE75
  U2D1 BL72 VSS<587> SKX_EXT_B_BGA1-IC,TBD    I17 @BASEBOARD_FAB2_LIB.BASEBOARD_FAB2(SCH_1):PAGE75
  U2D1 BL70 VSS<588> SKX_EXT_B_BGA1-IC,TBD    I17 @BASEBOARD_FAB2_LIB.BASEBOARD_FAB2(SCH_1):PAGE75
  U2D1 BL68 VSS<589> SKX_EXT_B_BGA1-IC,TBD    I17 @BASEBOARD_FAB2_LIB.BASEBOARD_FAB2(SCH_1):PAGE75
  U2D1 BL66 VSS<590> SKX_EXT_B_BGA1-IC,TBD    I17 @BASEBOARD_FAB2_LIB.BASEBOARD_FAB2(SCH_1):PAGE75
  U2D1 BL64 VSS<591> SKX_EXT_B_BGA1-IC,TBD    I17 @BASEBOARD_FAB2_LIB.BASEBOARD_FAB2(SCH_1):PAGE75
  U2D1 BL24 VSS<592> SKX_EXT_B_BGA1-IC,TBD    I17 @BASEBOARD_FAB2_LIB.BASEBOARD_FAB2(SCH_1):PAGE75
  U2D1 BL22 VSS<593> SKX_EXT_B_BGA1-IC,TBD    I17 @BASEBOARD_FAB2_LIB.BASEBOARD_FAB2(SCH_1):PAGE75
  U2D1  P61 VSS<594> SKX_EXT_B_BGA1-IC,TBD    I17 @BASEBOARD_FAB2_LIB.BASEBOARD_FAB2(SCH_1):PAGE75
  U2D1 BL12 VSS<595> SKX_EXT_B_BGA1-IC,TBD    I17 @BASEBOARD_FAB2_LIB.BASEBOARD_FAB2(SCH_1):PAGE75
  U2D1 BL10 VSS<596> SKX_EXT_B_BGA1-IC,TBD    I17 @BASEBOARD_FAB2_LIB.BASEBOARD_FAB2(SCH_1):PAGE75
  U2D1  BL6 VSS<597> SKX_EXT_B_BGA1-IC,TBD    I17 @BASEBOARD_FAB2_LIB.BASEBOARD_FAB2(SCH_1):PAGE75
  U2D1 BK19 VSS<598> SKX_EXT_B_BGA1-IC,TBD    I17 @BASEBOARD_FAB2_LIB.BASEBOARD_FAB2(SCH_1):PAGE75
  U2D1 BK11 VSS<599> SKX_EXT_B_BGA1-IC,TBD    I17 @BASEBOARD_FAB2_LIB.BASEBOARD_FAB2(SCH_1):PAGE75
  U2D1  BK7 VSS<600> SKX_EXT_B_BGA1-IC,TBD    I17 @BASEBOARD_FAB2_LIB.BASEBOARD_FAB2(SCH_1):PAGE75
  U2D1  BK3 VSS<601> SKX_EXT_B_BGA1-IC,TBD    I17 @BASEBOARD_FAB2_LIB.BASEBOARD_FAB2(SCH_1):PAGE75
  U2D1  BJ6 VSS<602> SKX_EXT_B_BGA1-IC,TBD    I17 @BASEBOARD_FAB2_LIB.BASEBOARD_FAB2(SCH_1):PAGE75
  U2D1  BJ4 VSS<603> SKX_EXT_B_BGA1-IC,TBD    I17 @BASEBOARD_FAB2_LIB.BASEBOARD_FAB2(SCH_1):PAGE75
  U2D1 BH21 VSS<604> SKX_EXT_B_BGA1-IC,TBD    I17 @BASEBOARD_FAB2_LIB.BASEBOARD_FAB2(SCH_1):PAGE75
  U2D1 BH15 VSS<605> SKX_EXT_B_BGA1-IC,TBD    I17 @BASEBOARD_FAB2_LIB.BASEBOARD_FAB2(SCH_1):PAGE75
  U2D1 BH11 VSS<606> SKX_EXT_B_BGA1-IC,TBD    I17 @BASEBOARD_FAB2_LIB.BASEBOARD_FAB2(SCH_1):PAGE75
  U2D1  BH9 VSS<607> SKX_EXT_B_BGA1-IC,TBD    I17 @BASEBOARD_FAB2_LIB.BASEBOARD_FAB2(SCH_1):PAGE75
  U2D1  BH7 VSS<608> SKX_EXT_B_BGA1-IC,TBD    I17 @BASEBOARD_FAB2_LIB.BASEBOARD_FAB2(SCH_1):PAGE75
  U2D1 BG82 VSS<609> SKX_EXT_B_BGA1-IC,TBD    I17 @BASEBOARD_FAB2_LIB.BASEBOARD_FAB2(SCH_1):PAGE75
  U2D1 BG80 VSS<610> SKX_EXT_B_BGA1-IC,TBD    I17 @BASEBOARD_FAB2_LIB.BASEBOARD_FAB2(SCH_1):PAGE75
  U2D1 BG78 VSS<611> SKX_EXT_B_BGA1-IC,TBD    I17 @BASEBOARD_FAB2_LIB.BASEBOARD_FAB2(SCH_1):PAGE75
  U2D1 BG76 VSS<612> SKX_EXT_B_BGA1-IC,TBD    I17 @BASEBOARD_FAB2_LIB.BASEBOARD_FAB2(SCH_1):PAGE75
  U2D1 BG74 VSS<613> SKX_EXT_B_BGA1-IC,TBD    I17 @BASEBOARD_FAB2_LIB.BASEBOARD_FAB2(SCH_1):PAGE75
  U2D1 DA46 VSS<294> SKX_EXT_B_BGA1-IC,TBD    I18 @BASEBOARD_FAB2_LIB.BASEBOARD_FAB2(SCH_1):PAGE75
  U2D1 DA44 VSS<295> SKX_EXT_B_BGA1-IC,TBD    I18 @BASEBOARD_FAB2_LIB.BASEBOARD_FAB2(SCH_1):PAGE75
  U2D1 DA38 VSS<296> SKX_EXT_B_BGA1-IC,TBD    I18 @BASEBOARD_FAB2_LIB.BASEBOARD_FAB2(SCH_1):PAGE75
  U2D1 DA36 VSS<297> SKX_EXT_B_BGA1-IC,TBD    I18 @BASEBOARD_FAB2_LIB.BASEBOARD_FAB2(SCH_1):PAGE75
  U2D1 DA34 VSS<298> SKX_EXT_B_BGA1-IC,TBD    I18 @BASEBOARD_FAB2_LIB.BASEBOARD_FAB2(SCH_1):PAGE75
  U2D1 DA32 VSS<299> SKX_EXT_B_BGA1-IC,TBD    I18 @BASEBOARD_FAB2_LIB.BASEBOARD_FAB2(SCH_1):PAGE75
  U2D1 DA30 VSS<300> SKX_EXT_B_BGA1-IC,TBD    I18 @BASEBOARD_FAB2_LIB.BASEBOARD_FAB2(SCH_1):PAGE75
  U2D1 DA28 VSS<301> SKX_EXT_B_BGA1-IC,TBD    I18 @BASEBOARD_FAB2_LIB.BASEBOARD_FAB2(SCH_1):PAGE75
  U2D1 DA26 VSS<302> SKX_EXT_B_BGA1-IC,TBD    I18 @BASEBOARD_FAB2_LIB.BASEBOARD_FAB2(SCH_1):PAGE75
  U2D1 DA18 VSS<303> SKX_EXT_B_BGA1-IC,TBD    I18 @BASEBOARD_FAB2_LIB.BASEBOARD_FAB2(SCH_1):PAGE75
  U2D1  H53 VSS<304> SKX_EXT_B_BGA1-IC,TBD    I18 @BASEBOARD_FAB2_LIB.BASEBOARD_FAB2(SCH_1):PAGE75
  U2D1  DA6 VSS<305> SKX_EXT_B_BGA1-IC,TBD    I18 @BASEBOARD_FAB2_LIB.BASEBOARD_FAB2(SCH_1):PAGE75
  U2D1 CY85 VSS<306> SKX_EXT_B_BGA1-IC,TBD    I18 @BASEBOARD_FAB2_LIB.BASEBOARD_FAB2(SCH_1):PAGE75
  U2D1 CY83 VSS<307> SKX_EXT_B_BGA1-IC,TBD    I18 @BASEBOARD_FAB2_LIB.BASEBOARD_FAB2(SCH_1):PAGE75
  U2D1 CY77 VSS<308> SKX_EXT_B_BGA1-IC,TBD    I18 @BASEBOARD_FAB2_LIB.BASEBOARD_FAB2(SCH_1):PAGE75
  U2D1 CY75 VSS<309> SKX_EXT_B_BGA1-IC,TBD    I18 @BASEBOARD_FAB2_LIB.BASEBOARD_FAB2(SCH_1):PAGE75
  U2D1 CY69 VSS<310> SKX_EXT_B_BGA1-IC,TBD    I18 @BASEBOARD_FAB2_LIB.BASEBOARD_FAB2(SCH_1):PAGE75
  U2D1 CY65 VSS<311> SKX_EXT_B_BGA1-IC,TBD    I18 @BASEBOARD_FAB2_LIB.BASEBOARD_FAB2(SCH_1):PAGE75
  U2D1 CY61 VSS<312> SKX_EXT_B_BGA1-IC,TBD    I18 @BASEBOARD_FAB2_LIB.BASEBOARD_FAB2(SCH_1):PAGE75
  U2D1 CY59 VSS<313> SKX_EXT_B_BGA1-IC,TBD    I18 @BASEBOARD_FAB2_LIB.BASEBOARD_FAB2(SCH_1):PAGE75
  U2D1 CY51 VSS<314> SKX_EXT_B_BGA1-IC,TBD    I18 @BASEBOARD_FAB2_LIB.BASEBOARD_FAB2(SCH_1):PAGE75
  U2D1 CY45 VSS<315> SKX_EXT_B_BGA1-IC,TBD    I18 @BASEBOARD_FAB2_LIB.BASEBOARD_FAB2(SCH_1):PAGE75
  U2D1 CY41 VSS<316> SKX_EXT_B_BGA1-IC,TBD    I18 @BASEBOARD_FAB2_LIB.BASEBOARD_FAB2(SCH_1):PAGE75
  U2D1 CY21 VSS<317> SKX_EXT_B_BGA1-IC,TBD    I18 @BASEBOARD_FAB2_LIB.BASEBOARD_FAB2(SCH_1):PAGE75
  U2D1 CY15 VSS<318> SKX_EXT_B_BGA1-IC,TBD    I18 @BASEBOARD_FAB2_LIB.BASEBOARD_FAB2(SCH_1):PAGE75
  U2D1 CY13 VSS<319> SKX_EXT_B_BGA1-IC,TBD    I18 @BASEBOARD_FAB2_LIB.BASEBOARD_FAB2(SCH_1):PAGE75
  U2D1  CY9 VSS<320> SKX_EXT_B_BGA1-IC,TBD    I18 @BASEBOARD_FAB2_LIB.BASEBOARD_FAB2(SCH_1):PAGE75
  U2D1  CY1 VSS<321> SKX_EXT_B_BGA1-IC,TBD    I18 @BASEBOARD_FAB2_LIB.BASEBOARD_FAB2(SCH_1):PAGE75
  U2D1 CW82 VSS<322> SKX_EXT_B_BGA1-IC,TBD    I18 @BASEBOARD_FAB2_LIB.BASEBOARD_FAB2(SCH_1):PAGE75
  U2D1 CW78 VSS<323> SKX_EXT_B_BGA1-IC,TBD    I18 @BASEBOARD_FAB2_LIB.BASEBOARD_FAB2(SCH_1):PAGE75
  U2D1 CW74 VSS<324> SKX_EXT_B_BGA1-IC,TBD    I18 @BASEBOARD_FAB2_LIB.BASEBOARD_FAB2(SCH_1):PAGE75
  U2D1 CW68 VSS<325> SKX_EXT_B_BGA1-IC,TBD    I18 @BASEBOARD_FAB2_LIB.BASEBOARD_FAB2(SCH_1):PAGE75
  U2D1 CW66 VSS<326> SKX_EXT_B_BGA1-IC,TBD    I18 @BASEBOARD_FAB2_LIB.BASEBOARD_FAB2(SCH_1):PAGE75
  U2D1 CW64 VSS<327> SKX_EXT_B_BGA1-IC,TBD    I18 @BASEBOARD_FAB2_LIB.BASEBOARD_FAB2(SCH_1):PAGE75
  U2D1 CW54 VSS<328> SKX_EXT_B_BGA1-IC,TBD    I18 @BASEBOARD_FAB2_LIB.BASEBOARD_FAB2(SCH_1):PAGE75
  U2D1 CW52 VSS<329> SKX_EXT_B_BGA1-IC,TBD    I18 @BASEBOARD_FAB2_LIB.BASEBOARD_FAB2(SCH_1):PAGE75
  U2D1 CW42 VSS<330> SKX_EXT_B_BGA1-IC,TBD    I18 @BASEBOARD_FAB2_LIB.BASEBOARD_FAB2(SCH_1):PAGE75
  U2D1 CW40 VSS<331> SKX_EXT_B_BGA1-IC,TBD    I18 @BASEBOARD_FAB2_LIB.BASEBOARD_FAB2(SCH_1):PAGE75
  U2D1 CW38 VSS<332> SKX_EXT_B_BGA1-IC,TBD    I18 @BASEBOARD_FAB2_LIB.BASEBOARD_FAB2(SCH_1):PAGE75
  U2D1 CW32 VSS<333> SKX_EXT_B_BGA1-IC,TBD    I18 @BASEBOARD_FAB2_LIB.BASEBOARD_FAB2(SCH_1):PAGE75
  U2D1 CW26 VSS<334> SKX_EXT_B_BGA1-IC,TBD    I18 @BASEBOARD_FAB2_LIB.BASEBOARD_FAB2(SCH_1):PAGE75
  U2D1 CW12 VSS<335> SKX_EXT_B_BGA1-IC,TBD    I18 @BASEBOARD_FAB2_LIB.BASEBOARD_FAB2(SCH_1):PAGE75
  U2D1 CV83 VSS<336> SKX_EXT_B_BGA1-IC,TBD    I18 @BASEBOARD_FAB2_LIB.BASEBOARD_FAB2(SCH_1):PAGE75
  U2D1 CV81 VSS<337> SKX_EXT_B_BGA1-IC,TBD    I18 @BASEBOARD_FAB2_LIB.BASEBOARD_FAB2(SCH_1):PAGE75
  U2D1 CV79 VSS<338> SKX_EXT_B_BGA1-IC,TBD    I18 @BASEBOARD_FAB2_LIB.BASEBOARD_FAB2(SCH_1):PAGE75
  U2D1 CV73 VSS<339> SKX_EXT_B_BGA1-IC,TBD    I18 @BASEBOARD_FAB2_LIB.BASEBOARD_FAB2(SCH_1):PAGE75
  U2D1 CV67 VSS<340> SKX_EXT_B_BGA1-IC,TBD    I18 @BASEBOARD_FAB2_LIB.BASEBOARD_FAB2(SCH_1):PAGE75
  U2D1 CV63 VSS<341> SKX_EXT_B_BGA1-IC,TBD    I18 @BASEBOARD_FAB2_LIB.BASEBOARD_FAB2(SCH_1):PAGE75
  U2D1 CV55 VSS<342> SKX_EXT_B_BGA1-IC,TBD    I18 @BASEBOARD_FAB2_LIB.BASEBOARD_FAB2(SCH_1):PAGE75
  U2D1 CV53 VSS<343> SKX_EXT_B_BGA1-IC,TBD    I18 @BASEBOARD_FAB2_LIB.BASEBOARD_FAB2(SCH_1):PAGE75
  U2D1 CV41 VSS<344> SKX_EXT_B_BGA1-IC,TBD    I18 @BASEBOARD_FAB2_LIB.BASEBOARD_FAB2(SCH_1):PAGE75
  U2D1 CV39 VSS<345> SKX_EXT_B_BGA1-IC,TBD    I18 @BASEBOARD_FAB2_LIB.BASEBOARD_FAB2(SCH_1):PAGE75
  U2D1 CV37 VSS<346> SKX_EXT_B_BGA1-IC,TBD    I18 @BASEBOARD_FAB2_LIB.BASEBOARD_FAB2(SCH_1):PAGE75
  U2D1 CV33 VSS<347> SKX_EXT_B_BGA1-IC,TBD    I18 @BASEBOARD_FAB2_LIB.BASEBOARD_FAB2(SCH_1):PAGE75
  U2D1 CV31 VSS<348> SKX_EXT_B_BGA1-IC,TBD    I18 @BASEBOARD_FAB2_LIB.BASEBOARD_FAB2(SCH_1):PAGE75
  U2D1 CV27 VSS<349> SKX_EXT_B_BGA1-IC,TBD    I18 @BASEBOARD_FAB2_LIB.BASEBOARD_FAB2(SCH_1):PAGE75
  U2D1 CV25 VSS<350> SKX_EXT_B_BGA1-IC,TBD    I18 @BASEBOARD_FAB2_LIB.BASEBOARD_FAB2(SCH_1):PAGE75
  U2D1 CV17 VSS<351> SKX_EXT_B_BGA1-IC,TBD    I18 @BASEBOARD_FAB2_LIB.BASEBOARD_FAB2(SCH_1):PAGE75
  U2D1  H55 VSS<352> SKX_EXT_B_BGA1-IC,TBD    I18 @BASEBOARD_FAB2_LIB.BASEBOARD_FAB2(SCH_1):PAGE75
  U2D1  CV1 VSS<353> SKX_EXT_B_BGA1-IC,TBD    I18 @BASEBOARD_FAB2_LIB.BASEBOARD_FAB2(SCH_1):PAGE75
  U2D1 CU86 VSS<354> SKX_EXT_B_BGA1-IC,TBD    I18 @BASEBOARD_FAB2_LIB.BASEBOARD_FAB2(SCH_1):PAGE75
  U2D1 CU82 VSS<355> SKX_EXT_B_BGA1-IC,TBD    I18 @BASEBOARD_FAB2_LIB.BASEBOARD_FAB2(SCH_1):PAGE75
  U2D1 CU80 VSS<356> SKX_EXT_B_BGA1-IC,TBD    I18 @BASEBOARD_FAB2_LIB.BASEBOARD_FAB2(SCH_1):PAGE75
  U2D1 CU78 VSS<357> SKX_EXT_B_BGA1-IC,TBD    I18 @BASEBOARD_FAB2_LIB.BASEBOARD_FAB2(SCH_1):PAGE75
  U2D1 CU76 VSS<358> SKX_EXT_B_BGA1-IC,TBD    I18 @BASEBOARD_FAB2_LIB.BASEBOARD_FAB2(SCH_1):PAGE75
  U2D1 CU68 VSS<359> SKX_EXT_B_BGA1-IC,TBD    I18 @BASEBOARD_FAB2_LIB.BASEBOARD_FAB2(SCH_1):PAGE75
  U2D1 CU62 VSS<360> SKX_EXT_B_BGA1-IC,TBD    I18 @BASEBOARD_FAB2_LIB.BASEBOARD_FAB2(SCH_1):PAGE75
  U2D1 CU56 VSS<361> SKX_EXT_B_BGA1-IC,TBD    I18 @BASEBOARD_FAB2_LIB.BASEBOARD_FAB2(SCH_1):PAGE75
  U2D1 CU36 VSS<362> SKX_EXT_B_BGA1-IC,TBD    I18 @BASEBOARD_FAB2_LIB.BASEBOARD_FAB2(SCH_1):PAGE75
  U2D1 CU34 VSS<363> SKX_EXT_B_BGA1-IC,TBD    I18 @BASEBOARD_FAB2_LIB.BASEBOARD_FAB2(SCH_1):PAGE75
  U2D1 CU30 VSS<364> SKX_EXT_B_BGA1-IC,TBD    I18 @BASEBOARD_FAB2_LIB.BASEBOARD_FAB2(SCH_1):PAGE75
  U2D1 CU28 VSS<365> SKX_EXT_B_BGA1-IC,TBD    I18 @BASEBOARD_FAB2_LIB.BASEBOARD_FAB2(SCH_1):PAGE75
  U2D1 CU22 VSS<366> SKX_EXT_B_BGA1-IC,TBD    I18 @BASEBOARD_FAB2_LIB.BASEBOARD_FAB2(SCH_1):PAGE75
  U2D1  CU4 VSS<367> SKX_EXT_B_BGA1-IC,TBD    I18 @BASEBOARD_FAB2_LIB.BASEBOARD_FAB2(SCH_1):PAGE75
  U2D1 CT85 VSS<368> SKX_EXT_B_BGA1-IC,TBD    I18 @BASEBOARD_FAB2_LIB.BASEBOARD_FAB2(SCH_1):PAGE75
  U2D1 CT83 VSS<369> SKX_EXT_B_BGA1-IC,TBD    I18 @BASEBOARD_FAB2_LIB.BASEBOARD_FAB2(SCH_1):PAGE75
  U2D1 CT79 VSS<370> SKX_EXT_B_BGA1-IC,TBD    I18 @BASEBOARD_FAB2_LIB.BASEBOARD_FAB2(SCH_1):PAGE75
  U2D1 CT73 VSS<371> SKX_EXT_B_BGA1-IC,TBD    I18 @BASEBOARD_FAB2_LIB.BASEBOARD_FAB2(SCH_1):PAGE75
  U2D1 CT57 VSS<372> SKX_EXT_B_BGA1-IC,TBD    I18 @BASEBOARD_FAB2_LIB.BASEBOARD_FAB2(SCH_1):PAGE75
  U2D1 CT35 VSS<373> SKX_EXT_B_BGA1-IC,TBD    I18 @BASEBOARD_FAB2_LIB.BASEBOARD_FAB2(SCH_1):PAGE75
  U2D1 CT33 VSS<374> SKX_EXT_B_BGA1-IC,TBD    I18 @BASEBOARD_FAB2_LIB.BASEBOARD_FAB2(SCH_1):PAGE75
  U2D1 CT29 VSS<375> SKX_EXT_B_BGA1-IC,TBD    I18 @BASEBOARD_FAB2_LIB.BASEBOARD_FAB2(SCH_1):PAGE75
  U2D1 CT27 VSS<376> SKX_EXT_B_BGA1-IC,TBD    I18 @BASEBOARD_FAB2_LIB.BASEBOARD_FAB2(SCH_1):PAGE75
  U2D1 CT19 VSS<377> SKX_EXT_B_BGA1-IC,TBD    I18 @BASEBOARD_FAB2_LIB.BASEBOARD_FAB2(SCH_1):PAGE75
  U2D1 CT13 VSS<378> SKX_EXT_B_BGA1-IC,TBD    I18 @BASEBOARD_FAB2_LIB.BASEBOARD_FAB2(SCH_1):PAGE75
  U2D1  H57 VSS<379> SKX_EXT_B_BGA1-IC,TBD    I18 @BASEBOARD_FAB2_LIB.BASEBOARD_FAB2(SCH_1):PAGE75
  U2D1 CR86 VSS<380> SKX_EXT_B_BGA1-IC,TBD    I18 @BASEBOARD_FAB2_LIB.BASEBOARD_FAB2(SCH_1):PAGE75
  U2D1 CR78 VSS<381> SKX_EXT_B_BGA1-IC,TBD    I18 @BASEBOARD_FAB2_LIB.BASEBOARD_FAB2(SCH_1):PAGE75
  U2D1 CR68 VSS<382> SKX_EXT_B_BGA1-IC,TBD    I18 @BASEBOARD_FAB2_LIB.BASEBOARD_FAB2(SCH_1):PAGE75
  U2D1 CR66 VSS<383> SKX_EXT_B_BGA1-IC,TBD    I18 @BASEBOARD_FAB2_LIB.BASEBOARD_FAB2(SCH_1):PAGE75
  U2D1 CR64 VSS<384> SKX_EXT_B_BGA1-IC,TBD    I18 @BASEBOARD_FAB2_LIB.BASEBOARD_FAB2(SCH_1):PAGE75
  U2D1 CR62 VSS<385> SKX_EXT_B_BGA1-IC,TBD    I18 @BASEBOARD_FAB2_LIB.BASEBOARD_FAB2(SCH_1):PAGE75
  U2D1 CR58 VSS<386> SKX_EXT_B_BGA1-IC,TBD    I18 @BASEBOARD_FAB2_LIB.BASEBOARD_FAB2(SCH_1):PAGE75
  U2D1 CR32 VSS<387> SKX_EXT_B_BGA1-IC,TBD    I18 @BASEBOARD_FAB2_LIB.BASEBOARD_FAB2(SCH_1):PAGE75
  U2D1 CR24 VSS<388> SKX_EXT_B_BGA1-IC,TBD    I18 @BASEBOARD_FAB2_LIB.BASEBOARD_FAB2(SCH_1):PAGE75
  U2D1 CR22 VSS<389> SKX_EXT_B_BGA1-IC,TBD    I18 @BASEBOARD_FAB2_LIB.BASEBOARD_FAB2(SCH_1):PAGE75
  U2D1 CR10 VSS<390> SKX_EXT_B_BGA1-IC,TBD    I18 @BASEBOARD_FAB2_LIB.BASEBOARD_FAB2(SCH_1):PAGE75
  U2D1  CR6 VSS<391> SKX_EXT_B_BGA1-IC,TBD    I18 @BASEBOARD_FAB2_LIB.BASEBOARD_FAB2(SCH_1):PAGE75
  U2D1 CP83 VSS<392> SKX_EXT_B_BGA1-IC,TBD    I18 @BASEBOARD_FAB2_LIB.BASEBOARD_FAB2(SCH_1):PAGE75
  U2D1 CP81 VSS<393> SKX_EXT_B_BGA1-IC,TBD    I18 @BASEBOARD_FAB2_LIB.BASEBOARD_FAB2(SCH_1):PAGE75
  U2D1 CP75 VSS<394> SKX_EXT_B_BGA1-IC,TBD    I18 @BASEBOARD_FAB2_LIB.BASEBOARD_FAB2(SCH_1):PAGE75
  U2D1 CP73 VSS<395> SKX_EXT_B_BGA1-IC,TBD    I18 @BASEBOARD_FAB2_LIB.BASEBOARD_FAB2(SCH_1):PAGE75
  U2D1 CP69 VSS<396> SKX_EXT_B_BGA1-IC,TBD    I18 @BASEBOARD_FAB2_LIB.BASEBOARD_FAB2(SCH_1):PAGE75
  U2D1 CP59 VSS<397> SKX_EXT_B_BGA1-IC,TBD    I18 @BASEBOARD_FAB2_LIB.BASEBOARD_FAB2(SCH_1):PAGE75
  U2D1 CP25 VSS<398> SKX_EXT_B_BGA1-IC,TBD    I18 @BASEBOARD_FAB2_LIB.BASEBOARD_FAB2(SCH_1):PAGE75
  U2D1  H59 VSS<399> SKX_EXT_B_BGA1-IC,TBD    I18 @BASEBOARD_FAB2_LIB.BASEBOARD_FAB2(SCH_1):PAGE75
  U2D1  CP1 VSS<400> SKX_EXT_B_BGA1-IC,TBD    I18 @BASEBOARD_FAB2_LIB.BASEBOARD_FAB2(SCH_1):PAGE75
  U2D1 CN78 VSS<401> SKX_EXT_B_BGA1-IC,TBD    I18 @BASEBOARD_FAB2_LIB.BASEBOARD_FAB2(SCH_1):PAGE75
  U2D1 CN68 VSS<402> SKX_EXT_B_BGA1-IC,TBD    I18 @BASEBOARD_FAB2_LIB.BASEBOARD_FAB2(SCH_1):PAGE75
  U2D1 CN62 VSS<403> SKX_EXT_B_BGA1-IC,TBD    I18 @BASEBOARD_FAB2_LIB.BASEBOARD_FAB2(SCH_1):PAGE75
  U2D1 CN60 VSS<404> SKX_EXT_B_BGA1-IC,TBD    I18 @BASEBOARD_FAB2_LIB.BASEBOARD_FAB2(SCH_1):PAGE75
  U2D1 CN32 VSS<405> SKX_EXT_B_BGA1-IC,TBD    I18 @BASEBOARD_FAB2_LIB.BASEBOARD_FAB2(SCH_1):PAGE75
  U2D1 CN26 VSS<406> SKX_EXT_B_BGA1-IC,TBD    I18 @BASEBOARD_FAB2_LIB.BASEBOARD_FAB2(SCH_1):PAGE75
  U2D1  H61 VSS<407> SKX_EXT_B_BGA1-IC,TBD    I18 @BASEBOARD_FAB2_LIB.BASEBOARD_FAB2(SCH_1):PAGE75
  U2D1 CN12 VSS<408> SKX_EXT_B_BGA1-IC,TBD    I18 @BASEBOARD_FAB2_LIB.BASEBOARD_FAB2(SCH_1):PAGE75
  U2D1  CN2 VSS<409> SKX_EXT_B_BGA1-IC,TBD    I18 @BASEBOARD_FAB2_LIB.BASEBOARD_FAB2(SCH_1):PAGE75
  U2D1 CM85 VSS<410> SKX_EXT_B_BGA1-IC,TBD    I18 @BASEBOARD_FAB2_LIB.BASEBOARD_FAB2(SCH_1):PAGE75
  U2D1 CM83 VSS<411> SKX_EXT_B_BGA1-IC,TBD    I18 @BASEBOARD_FAB2_LIB.BASEBOARD_FAB2(SCH_1):PAGE75
  U2D1 CM77 VSS<412> SKX_EXT_B_BGA1-IC,TBD    I18 @BASEBOARD_FAB2_LIB.BASEBOARD_FAB2(SCH_1):PAGE75
  U2D1 CM73 VSS<413> SKX_EXT_B_BGA1-IC,TBD    I18 @BASEBOARD_FAB2_LIB.BASEBOARD_FAB2(SCH_1):PAGE75
  U2D1 CM67 VSS<414> SKX_EXT_B_BGA1-IC,TBD    I18 @BASEBOARD_FAB2_LIB.BASEBOARD_FAB2(SCH_1):PAGE75
  U2D1 CM63 VSS<415> SKX_EXT_B_BGA1-IC,TBD    I18 @BASEBOARD_FAB2_LIB.BASEBOARD_FAB2(SCH_1):PAGE75
  U2D1 CM61 VSS<416> SKX_EXT_B_BGA1-IC,TBD    I18 @BASEBOARD_FAB2_LIB.BASEBOARD_FAB2(SCH_1):PAGE75
  U2D1 CM31 VSS<417> SKX_EXT_B_BGA1-IC,TBD    I18 @BASEBOARD_FAB2_LIB.BASEBOARD_FAB2(SCH_1):PAGE75
  U2D1  CM5 VSS<418> SKX_EXT_B_BGA1-IC,TBD    I18 @BASEBOARD_FAB2_LIB.BASEBOARD_FAB2(SCH_1):PAGE75
  U2D1 CM29 VSS<419> SKX_EXT_B_BGA1-IC,TBD    I18 @BASEBOARD_FAB2_LIB.BASEBOARD_FAB2(SCH_1):PAGE75
  U2D1 CM19 VSS<420> SKX_EXT_B_BGA1-IC,TBD    I18 @BASEBOARD_FAB2_LIB.BASEBOARD_FAB2(SCH_1):PAGE75
  U2D1 CL80 VSS<421> SKX_EXT_B_BGA1-IC,TBD    I18 @BASEBOARD_FAB2_LIB.BASEBOARD_FAB2(SCH_1):PAGE75
  U2D1 CL78 VSS<422> SKX_EXT_B_BGA1-IC,TBD    I18 @BASEBOARD_FAB2_LIB.BASEBOARD_FAB2(SCH_1):PAGE75
  U2D1 CL76 VSS<423> SKX_EXT_B_BGA1-IC,TBD    I18 @BASEBOARD_FAB2_LIB.BASEBOARD_FAB2(SCH_1):PAGE75
  U2D1 CL74 VSS<424> SKX_EXT_B_BGA1-IC,TBD    I18 @BASEBOARD_FAB2_LIB.BASEBOARD_FAB2(SCH_1):PAGE75
  U2D1 CL66 VSS<425> SKX_EXT_B_BGA1-IC,TBD    I18 @BASEBOARD_FAB2_LIB.BASEBOARD_FAB2(SCH_1):PAGE75
  U2D1 CL64 VSS<426> SKX_EXT_B_BGA1-IC,TBD    I18 @BASEBOARD_FAB2_LIB.BASEBOARD_FAB2(SCH_1):PAGE75
  U2D1 CL62 VSS<427> SKX_EXT_B_BGA1-IC,TBD    I18 @BASEBOARD_FAB2_LIB.BASEBOARD_FAB2(SCH_1):PAGE75
  U2D1  H63 VSS<428> SKX_EXT_B_BGA1-IC,TBD    I18 @BASEBOARD_FAB2_LIB.BASEBOARD_FAB2(SCH_1):PAGE75
  U2D1  P45 VSS<429> SKX_EXT_B_BGA1-IC,TBD    I18 @BASEBOARD_FAB2_LIB.BASEBOARD_FAB2(SCH_1):PAGE75
  U2D1 CL18 VSS<430> SKX_EXT_B_BGA1-IC,TBD    I18 @BASEBOARD_FAB2_LIB.BASEBOARD_FAB2(SCH_1):PAGE75
  U2D1 CL14 VSS<431> SKX_EXT_B_BGA1-IC,TBD    I18 @BASEBOARD_FAB2_LIB.BASEBOARD_FAB2(SCH_1):PAGE75
  U2D1  CL8 VSS<432> SKX_EXT_B_BGA1-IC,TBD    I18 @BASEBOARD_FAB2_LIB.BASEBOARD_FAB2(SCH_1):PAGE75
  U2D1 CK85 VSS<433> SKX_EXT_B_BGA1-IC,TBD    I18 @BASEBOARD_FAB2_LIB.BASEBOARD_FAB2(SCH_1):PAGE75
  U2D1 CK83 VSS<434> SKX_EXT_B_BGA1-IC,TBD    I18 @BASEBOARD_FAB2_LIB.BASEBOARD_FAB2(SCH_1):PAGE75
  U2D1 CK75 VSS<435> SKX_EXT_B_BGA1-IC,TBD    I18 @BASEBOARD_FAB2_LIB.BASEBOARD_FAB2(SCH_1):PAGE75
  U2D1 CK73 VSS<436> SKX_EXT_B_BGA1-IC,TBD    I18 @BASEBOARD_FAB2_LIB.BASEBOARD_FAB2(SCH_1):PAGE75
  U2D1 CK71 VSS<437> SKX_EXT_B_BGA1-IC,TBD    I18 @BASEBOARD_FAB2_LIB.BASEBOARD_FAB2(SCH_1):PAGE75
  U2D1 CK69 VSS<438> SKX_EXT_B_BGA1-IC,TBD    I18 @BASEBOARD_FAB2_LIB.BASEBOARD_FAB2(SCH_1):PAGE75
  U2D1 CK67 VSS<439> SKX_EXT_B_BGA1-IC,TBD    I18 @BASEBOARD_FAB2_LIB.BASEBOARD_FAB2(SCH_1):PAGE75
  U2D1 CK65 VSS<440> SKX_EXT_B_BGA1-IC,TBD    I18 @BASEBOARD_FAB2_LIB.BASEBOARD_FAB2(SCH_1):PAGE75
  U2D1 CK63 VSS<441> SKX_EXT_B_BGA1-IC,TBD    I18 @BASEBOARD_FAB2_LIB.BASEBOARD_FAB2(SCH_1):PAGE75
  U2D1 CK27 VSS<442> SKX_EXT_B_BGA1-IC,TBD    I18 @BASEBOARD_FAB2_LIB.BASEBOARD_FAB2(SCH_1):PAGE75
  U2D1 CK21 VSS<443> SKX_EXT_B_BGA1-IC,TBD    I18 @BASEBOARD_FAB2_LIB.BASEBOARD_FAB2(SCH_1):PAGE75
  U2D1 CK15 VSS<444> SKX_EXT_B_BGA1-IC,TBD    I18 @BASEBOARD_FAB2_LIB.BASEBOARD_FAB2(SCH_1):PAGE75
  U2D1 CK11 VSS<445> SKX_EXT_B_BGA1-IC,TBD    I18 @BASEBOARD_FAB2_LIB.BASEBOARD_FAB2(SCH_1):PAGE75
  U2D1 CJ86 VSS<446> SKX_EXT_B_BGA1-IC,TBD    I18 @BASEBOARD_FAB2_LIB.BASEBOARD_FAB2(SCH_1):PAGE75
  U2D1 CJ84 VSS<447> SKX_EXT_B_BGA1-IC,TBD    I18 @BASEBOARD_FAB2_LIB.BASEBOARD_FAB2(SCH_1):PAGE75
  U2D1 CJ82 VSS<448> SKX_EXT_B_BGA1-IC,TBD    I18 @BASEBOARD_FAB2_LIB.BASEBOARD_FAB2(SCH_1):PAGE75
  U2D1 CJ78 VSS<449> SKX_EXT_B_BGA1-IC,TBD    I18 @BASEBOARD_FAB2_LIB.BASEBOARD_FAB2(SCH_1):PAGE75
  U2D1 CJ76 VSS<450> SKX_EXT_B_BGA1-IC,TBD    I18 @BASEBOARD_FAB2_LIB.BASEBOARD_FAB2(SCH_1):PAGE75
  U2D1 CJ74 VSS<451> SKX_EXT_B_BGA1-IC,TBD    I18 @BASEBOARD_FAB2_LIB.BASEBOARD_FAB2(SCH_1):PAGE75
  U2D1 CJ62 VSS<452> SKX_EXT_B_BGA1-IC,TBD    I18 @BASEBOARD_FAB2_LIB.BASEBOARD_FAB2(SCH_1):PAGE75
  U2D1  P47 VSS<453> SKX_EXT_B_BGA1-IC,TBD    I18 @BASEBOARD_FAB2_LIB.BASEBOARD_FAB2(SCH_1):PAGE75
  U2D1 DN72 VSS<134> SKX_EXT_B_BGA1-IC,TBD    I19 @BASEBOARD_FAB2_LIB.BASEBOARD_FAB2(SCH_1):PAGE75
  U2D1 DN68 VSS<135> SKX_EXT_B_BGA1-IC,TBD    I19 @BASEBOARD_FAB2_LIB.BASEBOARD_FAB2(SCH_1):PAGE75
  U2D1 DN38 VSS<136> SKX_EXT_B_BGA1-IC,TBD    I19 @BASEBOARD_FAB2_LIB.BASEBOARD_FAB2(SCH_1):PAGE75
  U2D1 DN32 VSS<137> SKX_EXT_B_BGA1-IC,TBD    I19 @BASEBOARD_FAB2_LIB.BASEBOARD_FAB2(SCH_1):PAGE75
  U2D1 DN26 VSS<138> SKX_EXT_B_BGA1-IC,TBD    I19 @BASEBOARD_FAB2_LIB.BASEBOARD_FAB2(SCH_1):PAGE75
  U2D1 DN22 VSS<139> SKX_EXT_B_BGA1-IC,TBD    I19 @BASEBOARD_FAB2_LIB.BASEBOARD_FAB2(SCH_1):PAGE75
  U2D1 DN12 VSS<140> SKX_EXT_B_BGA1-IC,TBD    I19 @BASEBOARD_FAB2_LIB.BASEBOARD_FAB2(SCH_1):PAGE75
  U2D1 BH17 VSS<141> SKX_EXT_B_BGA1-IC,TBD    I19 @BASEBOARD_FAB2_LIB.BASEBOARD_FAB2(SCH_1):PAGE75
  U2D1  DN2 VSS<142> SKX_EXT_B_BGA1-IC,TBD    I19 @BASEBOARD_FAB2_LIB.BASEBOARD_FAB2(SCH_1):PAGE75
  U2D1 DM83 VSS<143> SKX_EXT_B_BGA1-IC,TBD    I19 @BASEBOARD_FAB2_LIB.BASEBOARD_FAB2(SCH_1):PAGE75
  U2D1 DM77 VSS<144> SKX_EXT_B_BGA1-IC,TBD    I19 @BASEBOARD_FAB2_LIB.BASEBOARD_FAB2(SCH_1):PAGE75
  U2D1 DM73 VSS<145> SKX_EXT_B_BGA1-IC,TBD    I19 @BASEBOARD_FAB2_LIB.BASEBOARD_FAB2(SCH_1):PAGE75
  U2D1 DM65 VSS<146> SKX_EXT_B_BGA1-IC,TBD    I19 @BASEBOARD_FAB2_LIB.BASEBOARD_FAB2(SCH_1):PAGE75
  U2D1 DM39 VSS<147> SKX_EXT_B_BGA1-IC,TBD    I19 @BASEBOARD_FAB2_LIB.BASEBOARD_FAB2(SCH_1):PAGE75
  U2D1 DM37 VSS<148> SKX_EXT_B_BGA1-IC,TBD    I19 @BASEBOARD_FAB2_LIB.BASEBOARD_FAB2(SCH_1):PAGE75
  U2D1 DM33 VSS<149> SKX_EXT_B_BGA1-IC,TBD    I19 @BASEBOARD_FAB2_LIB.BASEBOARD_FAB2(SCH_1):PAGE75
  U2D1 DM31 VSS<150> SKX_EXT_B_BGA1-IC,TBD    I19 @BASEBOARD_FAB2_LIB.BASEBOARD_FAB2(SCH_1):PAGE75
  U2D1 DM27 VSS<151> SKX_EXT_B_BGA1-IC,TBD    I19 @BASEBOARD_FAB2_LIB.BASEBOARD_FAB2(SCH_1):PAGE75
  U2D1 DM25 VSS<152> SKX_EXT_B_BGA1-IC,TBD    I19 @BASEBOARD_FAB2_LIB.BASEBOARD_FAB2(SCH_1):PAGE75
  U2D1  H45 VSS<153> SKX_EXT_B_BGA1-IC,TBD    I19 @BASEBOARD_FAB2_LIB.BASEBOARD_FAB2(SCH_1):PAGE75
  U2D1 DM15 VSS<154> SKX_EXT_B_BGA1-IC,TBD    I19 @BASEBOARD_FAB2_LIB.BASEBOARD_FAB2(SCH_1):PAGE75
  U2D1 DL80 VSS<155> SKX_EXT_B_BGA1-IC,TBD    I19 @BASEBOARD_FAB2_LIB.BASEBOARD_FAB2(SCH_1):PAGE75
  U2D1 DL78 VSS<156> SKX_EXT_B_BGA1-IC,TBD    I19 @BASEBOARD_FAB2_LIB.BASEBOARD_FAB2(SCH_1):PAGE75
  U2D1 DL76 VSS<157> SKX_EXT_B_BGA1-IC,TBD    I19 @BASEBOARD_FAB2_LIB.BASEBOARD_FAB2(SCH_1):PAGE75
  U2D1 DL74 VSS<158> SKX_EXT_B_BGA1-IC,TBD    I19 @BASEBOARD_FAB2_LIB.BASEBOARD_FAB2(SCH_1):PAGE75
  U2D1 DL70 VSS<159> SKX_EXT_B_BGA1-IC,TBD    I19 @BASEBOARD_FAB2_LIB.BASEBOARD_FAB2(SCH_1):PAGE75
  U2D1 DL68 VSS<160> SKX_EXT_B_BGA1-IC,TBD    I19 @BASEBOARD_FAB2_LIB.BASEBOARD_FAB2(SCH_1):PAGE75
  U2D1 DL40 VSS<161> SKX_EXT_B_BGA1-IC,TBD    I19 @BASEBOARD_FAB2_LIB.BASEBOARD_FAB2(SCH_1):PAGE75
  U2D1 DL36 VSS<162> SKX_EXT_B_BGA1-IC,TBD    I19 @BASEBOARD_FAB2_LIB.BASEBOARD_FAB2(SCH_1):PAGE75
  U2D1 DL34 VSS<163> SKX_EXT_B_BGA1-IC,TBD    I19 @BASEBOARD_FAB2_LIB.BASEBOARD_FAB2(SCH_1):PAGE75
  U2D1 DL30 VSS<164> SKX_EXT_B_BGA1-IC,TBD    I19 @BASEBOARD_FAB2_LIB.BASEBOARD_FAB2(SCH_1):PAGE75
  U2D1 DL28 VSS<165> SKX_EXT_B_BGA1-IC,TBD    I19 @BASEBOARD_FAB2_LIB.BASEBOARD_FAB2(SCH_1):PAGE75
  U2D1 DL24 VSS<166> SKX_EXT_B_BGA1-IC,TBD    I19 @BASEBOARD_FAB2_LIB.BASEBOARD_FAB2(SCH_1):PAGE75
  U2D1 DL22 VSS<167> SKX_EXT_B_BGA1-IC,TBD    I19 @BASEBOARD_FAB2_LIB.BASEBOARD_FAB2(SCH_1):PAGE75
  U2D1  DL4 VSS<168> SKX_EXT_B_BGA1-IC,TBD    I19 @BASEBOARD_FAB2_LIB.BASEBOARD_FAB2(SCH_1):PAGE75
  U2D1 DL18 VSS<169> SKX_EXT_B_BGA1-IC,TBD    I19 @BASEBOARD_FAB2_LIB.BASEBOARD_FAB2(SCH_1):PAGE75
  U2D1 DL16 VSS<170> SKX_EXT_B_BGA1-IC,TBD    I19 @BASEBOARD_FAB2_LIB.BASEBOARD_FAB2(SCH_1):PAGE75
  U2D1 DK85 VSS<171> SKX_EXT_B_BGA1-IC,TBD    I19 @BASEBOARD_FAB2_LIB.BASEBOARD_FAB2(SCH_1):PAGE75
  U2D1 DK83 VSS<172> SKX_EXT_B_BGA1-IC,TBD    I19 @BASEBOARD_FAB2_LIB.BASEBOARD_FAB2(SCH_1):PAGE75
  U2D1 DK77 VSS<173> SKX_EXT_B_BGA1-IC,TBD    I19 @BASEBOARD_FAB2_LIB.BASEBOARD_FAB2(SCH_1):PAGE75
  U2D1 DK75 VSS<174> SKX_EXT_B_BGA1-IC,TBD    I19 @BASEBOARD_FAB2_LIB.BASEBOARD_FAB2(SCH_1):PAGE75
  U2D1 DK73 VSS<175> SKX_EXT_B_BGA1-IC,TBD    I19 @BASEBOARD_FAB2_LIB.BASEBOARD_FAB2(SCH_1):PAGE75
  U2D1 DK41 VSS<176> SKX_EXT_B_BGA1-IC,TBD    I19 @BASEBOARD_FAB2_LIB.BASEBOARD_FAB2(SCH_1):PAGE75
  U2D1 DK39 VSS<177> SKX_EXT_B_BGA1-IC,TBD    I19 @BASEBOARD_FAB2_LIB.BASEBOARD_FAB2(SCH_1):PAGE75
  U2D1 DK35 VSS<178> SKX_EXT_B_BGA1-IC,TBD    I19 @BASEBOARD_FAB2_LIB.BASEBOARD_FAB2(SCH_1):PAGE75
  U2D1 DK29 VSS<179> SKX_EXT_B_BGA1-IC,TBD    I19 @BASEBOARD_FAB2_LIB.BASEBOARD_FAB2(SCH_1):PAGE75
  U2D1 DK23 VSS<180> SKX_EXT_B_BGA1-IC,TBD    I19 @BASEBOARD_FAB2_LIB.BASEBOARD_FAB2(SCH_1):PAGE75
  U2D1  DK7 VSS<181> SKX_EXT_B_BGA1-IC,TBD    I19 @BASEBOARD_FAB2_LIB.BASEBOARD_FAB2(SCH_1):PAGE75
  U2D1 DJ84 VSS<182> SKX_EXT_B_BGA1-IC,TBD    I19 @BASEBOARD_FAB2_LIB.BASEBOARD_FAB2(SCH_1):PAGE75
  U2D1 DJ82 VSS<183> SKX_EXT_B_BGA1-IC,TBD    I19 @BASEBOARD_FAB2_LIB.BASEBOARD_FAB2(SCH_1):PAGE75
  U2D1 DJ78 VSS<184> SKX_EXT_B_BGA1-IC,TBD    I19 @BASEBOARD_FAB2_LIB.BASEBOARD_FAB2(SCH_1):PAGE75
  U2D1 DJ74 VSS<185> SKX_EXT_B_BGA1-IC,TBD    I19 @BASEBOARD_FAB2_LIB.BASEBOARD_FAB2(SCH_1):PAGE75
  U2D1 DJ68 VSS<186> SKX_EXT_B_BGA1-IC,TBD    I19 @BASEBOARD_FAB2_LIB.BASEBOARD_FAB2(SCH_1):PAGE75
  U2D1 DJ42 VSS<187> SKX_EXT_B_BGA1-IC,TBD    I19 @BASEBOARD_FAB2_LIB.BASEBOARD_FAB2(SCH_1):PAGE75
  U2D1 DJ38 VSS<188> SKX_EXT_B_BGA1-IC,TBD    I19 @BASEBOARD_FAB2_LIB.BASEBOARD_FAB2(SCH_1):PAGE75
  U2D1 DJ22 VSS<189> SKX_EXT_B_BGA1-IC,TBD    I19 @BASEBOARD_FAB2_LIB.BASEBOARD_FAB2(SCH_1):PAGE75
  U2D1  H47 VSS<190> SKX_EXT_B_BGA1-IC,TBD    I19 @BASEBOARD_FAB2_LIB.BASEBOARD_FAB2(SCH_1):PAGE75
  U2D1 DJ10 VSS<191> SKX_EXT_B_BGA1-IC,TBD    I19 @BASEBOARD_FAB2_LIB.BASEBOARD_FAB2(SCH_1):PAGE75
  U2D1  DJ2 VSS<192> SKX_EXT_B_BGA1-IC,TBD    I19 @BASEBOARD_FAB2_LIB.BASEBOARD_FAB2(SCH_1):PAGE75
  U2D1 DH83 VSS<193> SKX_EXT_B_BGA1-IC,TBD    I19 @BASEBOARD_FAB2_LIB.BASEBOARD_FAB2(SCH_1):PAGE75
  U2D1 DH81 VSS<194> SKX_EXT_B_BGA1-IC,TBD    I19 @BASEBOARD_FAB2_LIB.BASEBOARD_FAB2(SCH_1):PAGE75
  U2D1 DH79 VSS<195> SKX_EXT_B_BGA1-IC,TBD    I19 @BASEBOARD_FAB2_LIB.BASEBOARD_FAB2(SCH_1):PAGE75
  U2D1 DH73 VSS<196> SKX_EXT_B_BGA1-IC,TBD    I19 @BASEBOARD_FAB2_LIB.BASEBOARD_FAB2(SCH_1):PAGE75
  U2D1 DH71 VSS<197> SKX_EXT_B_BGA1-IC,TBD    I19 @BASEBOARD_FAB2_LIB.BASEBOARD_FAB2(SCH_1):PAGE75
  U2D1 DH67 VSS<198> SKX_EXT_B_BGA1-IC,TBD    I19 @BASEBOARD_FAB2_LIB.BASEBOARD_FAB2(SCH_1):PAGE75
  U2D1 DH41 VSS<199> SKX_EXT_B_BGA1-IC,TBD    I19 @BASEBOARD_FAB2_LIB.BASEBOARD_FAB2(SCH_1):PAGE75
  U2D1 DH37 VSS<200> SKX_EXT_B_BGA1-IC,TBD    I19 @BASEBOARD_FAB2_LIB.BASEBOARD_FAB2(SCH_1):PAGE75
  U2D1 DH35 VSS<201> SKX_EXT_B_BGA1-IC,TBD    I19 @BASEBOARD_FAB2_LIB.BASEBOARD_FAB2(SCH_1):PAGE75
  U2D1 DH33 VSS<202> SKX_EXT_B_BGA1-IC,TBD    I19 @BASEBOARD_FAB2_LIB.BASEBOARD_FAB2(SCH_1):PAGE75
  U2D1 DH31 VSS<203> SKX_EXT_B_BGA1-IC,TBD    I19 @BASEBOARD_FAB2_LIB.BASEBOARD_FAB2(SCH_1):PAGE75
  U2D1 DH29 VSS<204> SKX_EXT_B_BGA1-IC,TBD    I19 @BASEBOARD_FAB2_LIB.BASEBOARD_FAB2(SCH_1):PAGE75
  U2D1 DH27 VSS<205> SKX_EXT_B_BGA1-IC,TBD    I19 @BASEBOARD_FAB2_LIB.BASEBOARD_FAB2(SCH_1):PAGE75
  U2D1 DH25 VSS<206> SKX_EXT_B_BGA1-IC,TBD    I19 @BASEBOARD_FAB2_LIB.BASEBOARD_FAB2(SCH_1):PAGE75
  U2D1 DH23 VSS<207> SKX_EXT_B_BGA1-IC,TBD    I19 @BASEBOARD_FAB2_LIB.BASEBOARD_FAB2(SCH_1):PAGE75
  U2D1 DH15 VSS<208> SKX_EXT_B_BGA1-IC,TBD    I19 @BASEBOARD_FAB2_LIB.BASEBOARD_FAB2(SCH_1):PAGE75
  U2D1 DH13 VSS<209> SKX_EXT_B_BGA1-IC,TBD    I19 @BASEBOARD_FAB2_LIB.BASEBOARD_FAB2(SCH_1):PAGE75
  U2D1 DG82 VSS<210> SKX_EXT_B_BGA1-IC,TBD    I19 @BASEBOARD_FAB2_LIB.BASEBOARD_FAB2(SCH_1):PAGE75
  U2D1 DG80 VSS<211> SKX_EXT_B_BGA1-IC,TBD    I19 @BASEBOARD_FAB2_LIB.BASEBOARD_FAB2(SCH_1):PAGE75
  U2D1 DG78 VSS<212> SKX_EXT_B_BGA1-IC,TBD    I19 @BASEBOARD_FAB2_LIB.BASEBOARD_FAB2(SCH_1):PAGE75
  U2D1 DG76 VSS<213> SKX_EXT_B_BGA1-IC,TBD    I19 @BASEBOARD_FAB2_LIB.BASEBOARD_FAB2(SCH_1):PAGE75
  U2D1 DG68 VSS<214> SKX_EXT_B_BGA1-IC,TBD    I19 @BASEBOARD_FAB2_LIB.BASEBOARD_FAB2(SCH_1):PAGE75
  U2D1 DG66 VSS<215> SKX_EXT_B_BGA1-IC,TBD    I19 @BASEBOARD_FAB2_LIB.BASEBOARD_FAB2(SCH_1):PAGE75
  U2D1 DG24 VSS<216> SKX_EXT_B_BGA1-IC,TBD    I19 @BASEBOARD_FAB2_LIB.BASEBOARD_FAB2(SCH_1):PAGE75
  U2D1 DG16 VSS<217> SKX_EXT_B_BGA1-IC,TBD    I19 @BASEBOARD_FAB2_LIB.BASEBOARD_FAB2(SCH_1):PAGE75
  U2D1 DG14 VSS<218> SKX_EXT_B_BGA1-IC,TBD    I19 @BASEBOARD_FAB2_LIB.BASEBOARD_FAB2(SCH_1):PAGE75
  U2D1  H49 VSS<219> SKX_EXT_B_BGA1-IC,TBD    I19 @BASEBOARD_FAB2_LIB.BASEBOARD_FAB2(SCH_1):PAGE75
  U2D1  DG2 VSS<220> SKX_EXT_B_BGA1-IC,TBD    I19 @BASEBOARD_FAB2_LIB.BASEBOARD_FAB2(SCH_1):PAGE75
  U2D1 DF85 VSS<221> SKX_EXT_B_BGA1-IC,TBD    I19 @BASEBOARD_FAB2_LIB.BASEBOARD_FAB2(SCH_1):PAGE75
  U2D1 DF83 VSS<222> SKX_EXT_B_BGA1-IC,TBD    I19 @BASEBOARD_FAB2_LIB.BASEBOARD_FAB2(SCH_1):PAGE75
  U2D1 DF79 VSS<223> SKX_EXT_B_BGA1-IC,TBD    I19 @BASEBOARD_FAB2_LIB.BASEBOARD_FAB2(SCH_1):PAGE75
  U2D1 DF73 VSS<224> SKX_EXT_B_BGA1-IC,TBD    I19 @BASEBOARD_FAB2_LIB.BASEBOARD_FAB2(SCH_1):PAGE75
  U2D1 DF69 VSS<225> SKX_EXT_B_BGA1-IC,TBD    I19 @BASEBOARD_FAB2_LIB.BASEBOARD_FAB2(SCH_1):PAGE75
  U2D1 DF65 VSS<226> SKX_EXT_B_BGA1-IC,TBD    I19 @BASEBOARD_FAB2_LIB.BASEBOARD_FAB2(SCH_1):PAGE75
  U2D1 DF41 VSS<227> SKX_EXT_B_BGA1-IC,TBD    I19 @BASEBOARD_FAB2_LIB.BASEBOARD_FAB2(SCH_1):PAGE75
  U2D1 DF39 VSS<228> SKX_EXT_B_BGA1-IC,TBD    I19 @BASEBOARD_FAB2_LIB.BASEBOARD_FAB2(SCH_1):PAGE75
  U2D1 DF37 VSS<229> SKX_EXT_B_BGA1-IC,TBD    I19 @BASEBOARD_FAB2_LIB.BASEBOARD_FAB2(SCH_1):PAGE75
  U2D1 DF35 VSS<230> SKX_EXT_B_BGA1-IC,TBD    I19 @BASEBOARD_FAB2_LIB.BASEBOARD_FAB2(SCH_1):PAGE75
  U2D1 DF29 VSS<231> SKX_EXT_B_BGA1-IC,TBD    I19 @BASEBOARD_FAB2_LIB.BASEBOARD_FAB2(SCH_1):PAGE75
  U2D1 DF19 VSS<232> SKX_EXT_B_BGA1-IC,TBD    I19 @BASEBOARD_FAB2_LIB.BASEBOARD_FAB2(SCH_1):PAGE75
  U2D1  H51 VSS<233> SKX_EXT_B_BGA1-IC,TBD    I19 @BASEBOARD_FAB2_LIB.BASEBOARD_FAB2(SCH_1):PAGE75
  U2D1  DF7 VSS<234> SKX_EXT_B_BGA1-IC,TBD    I19 @BASEBOARD_FAB2_LIB.BASEBOARD_FAB2(SCH_1):PAGE75
  U2D1  DF5 VSS<235> SKX_EXT_B_BGA1-IC,TBD    I19 @BASEBOARD_FAB2_LIB.BASEBOARD_FAB2(SCH_1):PAGE75
  U2D1 DE78 VSS<236> SKX_EXT_B_BGA1-IC,TBD    I19 @BASEBOARD_FAB2_LIB.BASEBOARD_FAB2(SCH_1):PAGE75
  U2D1 DE72 VSS<237> SKX_EXT_B_BGA1-IC,TBD    I19 @BASEBOARD_FAB2_LIB.BASEBOARD_FAB2(SCH_1):PAGE75
  U2D1 DE70 VSS<238> SKX_EXT_B_BGA1-IC,TBD    I19 @BASEBOARD_FAB2_LIB.BASEBOARD_FAB2(SCH_1):PAGE75
  U2D1 DE64 VSS<239> SKX_EXT_B_BGA1-IC,TBD    I19 @BASEBOARD_FAB2_LIB.BASEBOARD_FAB2(SCH_1):PAGE75
  U2D1 DE36 VSS<240> SKX_EXT_B_BGA1-IC,TBD    I19 @BASEBOARD_FAB2_LIB.BASEBOARD_FAB2(SCH_1):PAGE75
  U2D1 DE34 VSS<241> SKX_EXT_B_BGA1-IC,TBD    I19 @BASEBOARD_FAB2_LIB.BASEBOARD_FAB2(SCH_1):PAGE75
  U2D1 DE30 VSS<242> SKX_EXT_B_BGA1-IC,TBD    I19 @BASEBOARD_FAB2_LIB.BASEBOARD_FAB2(SCH_1):PAGE75
  U2D1 DE28 VSS<243> SKX_EXT_B_BGA1-IC,TBD    I19 @BASEBOARD_FAB2_LIB.BASEBOARD_FAB2(SCH_1):PAGE75
  U2D1 DE24 VSS<244> SKX_EXT_B_BGA1-IC,TBD    I19 @BASEBOARD_FAB2_LIB.BASEBOARD_FAB2(SCH_1):PAGE75
  U2D1 DE20 VSS<245> SKX_EXT_B_BGA1-IC,TBD    I19 @BASEBOARD_FAB2_LIB.BASEBOARD_FAB2(SCH_1):PAGE75
  U2D1 DE18 VSS<246> SKX_EXT_B_BGA1-IC,TBD    I19 @BASEBOARD_FAB2_LIB.BASEBOARD_FAB2(SCH_1):PAGE75
  U2D1  DE8 VSS<247> SKX_EXT_B_BGA1-IC,TBD    I19 @BASEBOARD_FAB2_LIB.BASEBOARD_FAB2(SCH_1):PAGE75
  U2D1  DE6 VSS<248> SKX_EXT_B_BGA1-IC,TBD    I19 @BASEBOARD_FAB2_LIB.BASEBOARD_FAB2(SCH_1):PAGE75
  U2D1 DD83 VSS<249> SKX_EXT_B_BGA1-IC,TBD    I19 @BASEBOARD_FAB2_LIB.BASEBOARD_FAB2(SCH_1):PAGE75
  U2D1 DD81 VSS<250> SKX_EXT_B_BGA1-IC,TBD    I19 @BASEBOARD_FAB2_LIB.BASEBOARD_FAB2(SCH_1):PAGE75
  U2D1 DD75 VSS<251> SKX_EXT_B_BGA1-IC,TBD    I19 @BASEBOARD_FAB2_LIB.BASEBOARD_FAB2(SCH_1):PAGE75
  U2D1 DD73 VSS<252> SKX_EXT_B_BGA1-IC,TBD    I19 @BASEBOARD_FAB2_LIB.BASEBOARD_FAB2(SCH_1):PAGE75
  U2D1 DD71 VSS<253> SKX_EXT_B_BGA1-IC,TBD    I19 @BASEBOARD_FAB2_LIB.BASEBOARD_FAB2(SCH_1):PAGE75
  U2D1 DD37 VSS<254> SKX_EXT_B_BGA1-IC,TBD    I19 @BASEBOARD_FAB2_LIB.BASEBOARD_FAB2(SCH_1):PAGE75
  U2D1 DD33 VSS<255> SKX_EXT_B_BGA1-IC,TBD    I19 @BASEBOARD_FAB2_LIB.BASEBOARD_FAB2(SCH_1):PAGE75
  U2D1 DD31 VSS<256> SKX_EXT_B_BGA1-IC,TBD    I19 @BASEBOARD_FAB2_LIB.BASEBOARD_FAB2(SCH_1):PAGE75
  U2D1 DD27 VSS<257> SKX_EXT_B_BGA1-IC,TBD    I19 @BASEBOARD_FAB2_LIB.BASEBOARD_FAB2(SCH_1):PAGE75
  U2D1 DD23 VSS<258> SKX_EXT_B_BGA1-IC,TBD    I19 @BASEBOARD_FAB2_LIB.BASEBOARD_FAB2(SCH_1):PAGE75
  U2D1 DD11 VSS<259> SKX_EXT_B_BGA1-IC,TBD    I19 @BASEBOARD_FAB2_LIB.BASEBOARD_FAB2(SCH_1):PAGE75
  U2D1 DC86 VSS<260> SKX_EXT_B_BGA1-IC,TBD    I19 @BASEBOARD_FAB2_LIB.BASEBOARD_FAB2(SCH_1):PAGE75
  U2D1 DC84 VSS<261> SKX_EXT_B_BGA1-IC,TBD    I19 @BASEBOARD_FAB2_LIB.BASEBOARD_FAB2(SCH_1):PAGE75
  U2D1 DC78 VSS<262> SKX_EXT_B_BGA1-IC,TBD    I19 @BASEBOARD_FAB2_LIB.BASEBOARD_FAB2(SCH_1):PAGE75
  U2D1 DC70 VSS<263> SKX_EXT_B_BGA1-IC,TBD    I19 @BASEBOARD_FAB2_LIB.BASEBOARD_FAB2(SCH_1):PAGE75
  U2D1 DC68 VSS<264> SKX_EXT_B_BGA1-IC,TBD    I19 @BASEBOARD_FAB2_LIB.BASEBOARD_FAB2(SCH_1):PAGE75
  U2D1 DC66 VSS<265> SKX_EXT_B_BGA1-IC,TBD    I19 @BASEBOARD_FAB2_LIB.BASEBOARD_FAB2(SCH_1):PAGE75
  U2D1 DC64 VSS<266> SKX_EXT_B_BGA1-IC,TBD    I19 @BASEBOARD_FAB2_LIB.BASEBOARD_FAB2(SCH_1):PAGE75
  U2D1 DC42 VSS<267> SKX_EXT_B_BGA1-IC,TBD    I19 @BASEBOARD_FAB2_LIB.BASEBOARD_FAB2(SCH_1):PAGE75
  U2D1 DC38 VSS<268> SKX_EXT_B_BGA1-IC,TBD    I19 @BASEBOARD_FAB2_LIB.BASEBOARD_FAB2(SCH_1):PAGE75
  U2D1 DC32 VSS<269> SKX_EXT_B_BGA1-IC,TBD    I19 @BASEBOARD_FAB2_LIB.BASEBOARD_FAB2(SCH_1):PAGE75
  U2D1 DC26 VSS<270> SKX_EXT_B_BGA1-IC,TBD    I19 @BASEBOARD_FAB2_LIB.BASEBOARD_FAB2(SCH_1):PAGE75
  U2D1 DC24 VSS<271> SKX_EXT_B_BGA1-IC,TBD    I19 @BASEBOARD_FAB2_LIB.BASEBOARD_FAB2(SCH_1):PAGE75
  U2D1 DC14 VSS<272> SKX_EXT_B_BGA1-IC,TBD    I19 @BASEBOARD_FAB2_LIB.BASEBOARD_FAB2(SCH_1):PAGE75
  U2D1 DB85 VSS<273> SKX_EXT_B_BGA1-IC,TBD    I19 @BASEBOARD_FAB2_LIB.BASEBOARD_FAB2(SCH_1):PAGE75
  U2D1 DB83 VSS<274> SKX_EXT_B_BGA1-IC,TBD    I19 @BASEBOARD_FAB2_LIB.BASEBOARD_FAB2(SCH_1):PAGE75
  U2D1 DB77 VSS<275> SKX_EXT_B_BGA1-IC,TBD    I19 @BASEBOARD_FAB2_LIB.BASEBOARD_FAB2(SCH_1):PAGE75
  U2D1 DB73 VSS<276> SKX_EXT_B_BGA1-IC,TBD    I19 @BASEBOARD_FAB2_LIB.BASEBOARD_FAB2(SCH_1):PAGE75
  U2D1 DB49 VSS<277> SKX_EXT_B_BGA1-IC,TBD    I19 @BASEBOARD_FAB2_LIB.BASEBOARD_FAB2(SCH_1):PAGE75
  U2D1 DB47 VSS<278> SKX_EXT_B_BGA1-IC,TBD    I19 @BASEBOARD_FAB2_LIB.BASEBOARD_FAB2(SCH_1):PAGE75
  U2D1 DB41 VSS<279> SKX_EXT_B_BGA1-IC,TBD    I19 @BASEBOARD_FAB2_LIB.BASEBOARD_FAB2(SCH_1):PAGE75
  U2D1 DB39 VSS<280> SKX_EXT_B_BGA1-IC,TBD    I19 @BASEBOARD_FAB2_LIB.BASEBOARD_FAB2(SCH_1):PAGE75
  U2D1 DB25 VSS<281> SKX_EXT_B_BGA1-IC,TBD    I19 @BASEBOARD_FAB2_LIB.BASEBOARD_FAB2(SCH_1):PAGE75
  U2D1 DB23 VSS<282> SKX_EXT_B_BGA1-IC,TBD    I19 @BASEBOARD_FAB2_LIB.BASEBOARD_FAB2(SCH_1):PAGE75
  U2D1 DB17 VSS<283> SKX_EXT_B_BGA1-IC,TBD    I19 @BASEBOARD_FAB2_LIB.BASEBOARD_FAB2(SCH_1):PAGE75
  U2D1 DB13 VSS<284> SKX_EXT_B_BGA1-IC,TBD    I19 @BASEBOARD_FAB2_LIB.BASEBOARD_FAB2(SCH_1):PAGE75
  U2D1  DB3 VSS<285> SKX_EXT_B_BGA1-IC,TBD    I19 @BASEBOARD_FAB2_LIB.BASEBOARD_FAB2(SCH_1):PAGE75
  U2D1 DA80 VSS<286> SKX_EXT_B_BGA1-IC,TBD    I19 @BASEBOARD_FAB2_LIB.BASEBOARD_FAB2(SCH_1):PAGE75
  U2D1 DA78 VSS<287> SKX_EXT_B_BGA1-IC,TBD    I19 @BASEBOARD_FAB2_LIB.BASEBOARD_FAB2(SCH_1):PAGE75
  U2D1 DA76 VSS<288> SKX_EXT_B_BGA1-IC,TBD    I19 @BASEBOARD_FAB2_LIB.BASEBOARD_FAB2(SCH_1):PAGE75
  U2D1 DA74 VSS<289> SKX_EXT_B_BGA1-IC,TBD    I19 @BASEBOARD_FAB2_LIB.BASEBOARD_FAB2(SCH_1):PAGE75
  U2D1 DA70 VSS<290> SKX_EXT_B_BGA1-IC,TBD    I19 @BASEBOARD_FAB2_LIB.BASEBOARD_FAB2(SCH_1):PAGE75
  U2D1 DA64 VSS<291> SKX_EXT_B_BGA1-IC,TBD    I19 @BASEBOARD_FAB2_LIB.BASEBOARD_FAB2(SCH_1):PAGE75
  U2D1 DA50 VSS<292> SKX_EXT_B_BGA1-IC,TBD    I19 @BASEBOARD_FAB2_LIB.BASEBOARD_FAB2(SCH_1):PAGE75
  U2D1 DA48 VSS<293> SKX_EXT_B_BGA1-IC,TBD    I19 @BASEBOARD_FAB2_LIB.BASEBOARD_FAB2(SCH_1):PAGE75
  U2D1 EF79 VSS<0> SKX_EXT_B_BGA1-IC,TBD    I20 @BASEBOARD_FAB2_LIB.BASEBOARD_FAB2(SCH_1):PAGE75
  U2D1 EF75 VSS<1> SKX_EXT_B_BGA1-IC,TBD    I20 @BASEBOARD_FAB2_LIB.BASEBOARD_FAB2(SCH_1):PAGE75
  U2D1 EF71 VSS<2> SKX_EXT_B_BGA1-IC,TBD    I20 @BASEBOARD_FAB2_LIB.BASEBOARD_FAB2(SCH_1):PAGE75
  U2D1 EE78 VSS<3> SKX_EXT_B_BGA1-IC,TBD    I20 @BASEBOARD_FAB2_LIB.BASEBOARD_FAB2(SCH_1):PAGE75
  U2D1 EE76 VSS<4> SKX_EXT_B_BGA1-IC,TBD    I20 @BASEBOARD_FAB2_LIB.BASEBOARD_FAB2(SCH_1):PAGE75
  U2D1 EE70 VSS<5> SKX_EXT_B_BGA1-IC,TBD    I20 @BASEBOARD_FAB2_LIB.BASEBOARD_FAB2(SCH_1):PAGE75
  U2D1 EE36 VSS<6> SKX_EXT_B_BGA1-IC,TBD    I20 @BASEBOARD_FAB2_LIB.BASEBOARD_FAB2(SCH_1):PAGE75
  U2D1 EE34 VSS<7> SKX_EXT_B_BGA1-IC,TBD    I20 @BASEBOARD_FAB2_LIB.BASEBOARD_FAB2(SCH_1):PAGE75
  U2D1 EE30 VSS<8> SKX_EXT_B_BGA1-IC,TBD    I20 @BASEBOARD_FAB2_LIB.BASEBOARD_FAB2(SCH_1):PAGE75
  U2D1 EE28 VSS<9> SKX_EXT_B_BGA1-IC,TBD    I20 @BASEBOARD_FAB2_LIB.BASEBOARD_FAB2(SCH_1):PAGE75
  U2D1 EE24 VSS<10> SKX_EXT_B_BGA1-IC,TBD    I20 @BASEBOARD_FAB2_LIB.BASEBOARD_FAB2(SCH_1):PAGE75
  U2D1 ED77 VSS<11> SKX_EXT_B_BGA1-IC,TBD    I20 @BASEBOARD_FAB2_LIB.BASEBOARD_FAB2(SCH_1):PAGE75
  U2D1 ED35 VSS<12> SKX_EXT_B_BGA1-IC,TBD    I20 @BASEBOARD_FAB2_LIB.BASEBOARD_FAB2(SCH_1):PAGE75
  U2D1 ED29 VSS<13> SKX_EXT_B_BGA1-IC,TBD    I20 @BASEBOARD_FAB2_LIB.BASEBOARD_FAB2(SCH_1):PAGE75
  U2D1 ED23 VSS<14> SKX_EXT_B_BGA1-IC,TBD    I20 @BASEBOARD_FAB2_LIB.BASEBOARD_FAB2(SCH_1):PAGE75
  U2D1 ED15 VSS<15> SKX_EXT_B_BGA1-IC,TBD    I20 @BASEBOARD_FAB2_LIB.BASEBOARD_FAB2(SCH_1):PAGE75
  U2D1 ED11 VSS<16> SKX_EXT_B_BGA1-IC,TBD    I20 @BASEBOARD_FAB2_LIB.BASEBOARD_FAB2(SCH_1):PAGE75
  U2D1 EC76 VSS<17> SKX_EXT_B_BGA1-IC,TBD    I20 @BASEBOARD_FAB2_LIB.BASEBOARD_FAB2(SCH_1):PAGE75
  U2D1 EC74 VSS<18> SKX_EXT_B_BGA1-IC,TBD    I20 @BASEBOARD_FAB2_LIB.BASEBOARD_FAB2(SCH_1):PAGE75
  U2D1 EC72 VSS<19> SKX_EXT_B_BGA1-IC,TBD    I20 @BASEBOARD_FAB2_LIB.BASEBOARD_FAB2(SCH_1):PAGE75
  U2D1 EC70 VSS<20> SKX_EXT_B_BGA1-IC,TBD    I20 @BASEBOARD_FAB2_LIB.BASEBOARD_FAB2(SCH_1):PAGE75
  U2D1 EC10 VSS<21> SKX_EXT_B_BGA1-IC,TBD    I20 @BASEBOARD_FAB2_LIB.BASEBOARD_FAB2(SCH_1):PAGE75
  U2D1 EB69 VSS<22> SKX_EXT_B_BGA1-IC,TBD    I20 @BASEBOARD_FAB2_LIB.BASEBOARD_FAB2(SCH_1):PAGE75
  U2D1 EB65 VSS<23> SKX_EXT_B_BGA1-IC,TBD    I20 @BASEBOARD_FAB2_LIB.BASEBOARD_FAB2(SCH_1):PAGE75
  U2D1 EB41 VSS<24> SKX_EXT_B_BGA1-IC,TBD    I20 @BASEBOARD_FAB2_LIB.BASEBOARD_FAB2(SCH_1):PAGE75
  U2D1 EB39 VSS<25> SKX_EXT_B_BGA1-IC,TBD    I20 @BASEBOARD_FAB2_LIB.BASEBOARD_FAB2(SCH_1):PAGE75
  U2D1 EB37 VSS<26> SKX_EXT_B_BGA1-IC,TBD    I20 @BASEBOARD_FAB2_LIB.BASEBOARD_FAB2(SCH_1):PAGE75
  U2D1 EB35 VSS<27> SKX_EXT_B_BGA1-IC,TBD    I20 @BASEBOARD_FAB2_LIB.BASEBOARD_FAB2(SCH_1):PAGE75
  U2D1 EB33 VSS<28> SKX_EXT_B_BGA1-IC,TBD    I20 @BASEBOARD_FAB2_LIB.BASEBOARD_FAB2(SCH_1):PAGE75
  U2D1 EB31 VSS<29> SKX_EXT_B_BGA1-IC,TBD    I20 @BASEBOARD_FAB2_LIB.BASEBOARD_FAB2(SCH_1):PAGE75
  U2D1 EB29 VSS<30> SKX_EXT_B_BGA1-IC,TBD    I20 @BASEBOARD_FAB2_LIB.BASEBOARD_FAB2(SCH_1):PAGE75
  U2D1 EB27 VSS<31> SKX_EXT_B_BGA1-IC,TBD    I20 @BASEBOARD_FAB2_LIB.BASEBOARD_FAB2(SCH_1):PAGE75
  U2D1 EB25 VSS<32> SKX_EXT_B_BGA1-IC,TBD    I20 @BASEBOARD_FAB2_LIB.BASEBOARD_FAB2(SCH_1):PAGE75
  U2D1 EB23 VSS<33> SKX_EXT_B_BGA1-IC,TBD    I20 @BASEBOARD_FAB2_LIB.BASEBOARD_FAB2(SCH_1):PAGE75
  U2D1 BR18 VSS<34> SKX_EXT_B_BGA1-IC,TBD    I20 @BASEBOARD_FAB2_LIB.BASEBOARD_FAB2(SCH_1):PAGE75
  U2D1 EB13 VSS<35> SKX_EXT_B_BGA1-IC,TBD    I20 @BASEBOARD_FAB2_LIB.BASEBOARD_FAB2(SCH_1):PAGE75
  U2D1 EA82 VSS<36> SKX_EXT_B_BGA1-IC,TBD    I20 @BASEBOARD_FAB2_LIB.BASEBOARD_FAB2(SCH_1):PAGE75
  U2D1 EA80 VSS<37> SKX_EXT_B_BGA1-IC,TBD    I20 @BASEBOARD_FAB2_LIB.BASEBOARD_FAB2(SCH_1):PAGE75
  U2D1 EA78 VSS<38> SKX_EXT_B_BGA1-IC,TBD    I20 @BASEBOARD_FAB2_LIB.BASEBOARD_FAB2(SCH_1):PAGE75
  U2D1 EA76 VSS<39> SKX_EXT_B_BGA1-IC,TBD    I20 @BASEBOARD_FAB2_LIB.BASEBOARD_FAB2(SCH_1):PAGE75
  U2D1 EA70 VSS<40> SKX_EXT_B_BGA1-IC,TBD    I20 @BASEBOARD_FAB2_LIB.BASEBOARD_FAB2(SCH_1):PAGE75
  U2D1 EA64 VSS<41> SKX_EXT_B_BGA1-IC,TBD    I20 @BASEBOARD_FAB2_LIB.BASEBOARD_FAB2(SCH_1):PAGE75
  U2D1 EA42 VSS<42> SKX_EXT_B_BGA1-IC,TBD    I20 @BASEBOARD_FAB2_LIB.BASEBOARD_FAB2(SCH_1):PAGE75
  U2D1 EA22 VSS<43> SKX_EXT_B_BGA1-IC,TBD    I20 @BASEBOARD_FAB2_LIB.BASEBOARD_FAB2(SCH_1):PAGE75
  U2D1 EA20 VSS<44> SKX_EXT_B_BGA1-IC,TBD    I20 @BASEBOARD_FAB2_LIB.BASEBOARD_FAB2(SCH_1):PAGE75
  U2D1 EA16 VSS<45> SKX_EXT_B_BGA1-IC,TBD    I20 @BASEBOARD_FAB2_LIB.BASEBOARD_FAB2(SCH_1):PAGE75
  U2D1  J16 VSS<46> SKX_EXT_B_BGA1-IC,TBD    I20 @BASEBOARD_FAB2_LIB.BASEBOARD_FAB2(SCH_1):PAGE75
  U2D1  EA6 VSS<47> SKX_EXT_B_BGA1-IC,TBD    I20 @BASEBOARD_FAB2_LIB.BASEBOARD_FAB2(SCH_1):PAGE75
  U2D1 DY75 VSS<48> SKX_EXT_B_BGA1-IC,TBD    I20 @BASEBOARD_FAB2_LIB.BASEBOARD_FAB2(SCH_1):PAGE75
  U2D1 DY71 VSS<49> SKX_EXT_B_BGA1-IC,TBD    I20 @BASEBOARD_FAB2_LIB.BASEBOARD_FAB2(SCH_1):PAGE75
  U2D1 DY41 VSS<50> SKX_EXT_B_BGA1-IC,TBD    I20 @BASEBOARD_FAB2_LIB.BASEBOARD_FAB2(SCH_1):PAGE75
  U2D1 DY35 VSS<51> SKX_EXT_B_BGA1-IC,TBD    I20 @BASEBOARD_FAB2_LIB.BASEBOARD_FAB2(SCH_1):PAGE75
  U2D1 DY29 VSS<52> SKX_EXT_B_BGA1-IC,TBD    I20 @BASEBOARD_FAB2_LIB.BASEBOARD_FAB2(SCH_1):PAGE75
  U2D1 DY23 VSS<53> SKX_EXT_B_BGA1-IC,TBD    I20 @BASEBOARD_FAB2_LIB.BASEBOARD_FAB2(SCH_1):PAGE75
  U2D1 DY19 VSS<54> SKX_EXT_B_BGA1-IC,TBD    I20 @BASEBOARD_FAB2_LIB.BASEBOARD_FAB2(SCH_1):PAGE75
  U2D1  DY5 VSS<55> SKX_EXT_B_BGA1-IC,TBD    I20 @BASEBOARD_FAB2_LIB.BASEBOARD_FAB2(SCH_1):PAGE75
  U2D1 DW84 VSS<56> SKX_EXT_B_BGA1-IC,TBD    I20 @BASEBOARD_FAB2_LIB.BASEBOARD_FAB2(SCH_1):PAGE75
  U2D1 DW82 VSS<57> SKX_EXT_B_BGA1-IC,TBD    I20 @BASEBOARD_FAB2_LIB.BASEBOARD_FAB2(SCH_1):PAGE75
  U2D1  DW8 VSS<58> SKX_EXT_B_BGA1-IC,TBD    I20 @BASEBOARD_FAB2_LIB.BASEBOARD_FAB2(SCH_1):PAGE75
  U2D1 DW76 VSS<59> SKX_EXT_B_BGA1-IC,TBD    I20 @BASEBOARD_FAB2_LIB.BASEBOARD_FAB2(SCH_1):PAGE75
  U2D1 DW74 VSS<60> SKX_EXT_B_BGA1-IC,TBD    I20 @BASEBOARD_FAB2_LIB.BASEBOARD_FAB2(SCH_1):PAGE75
  U2D1 DW72 VSS<61> SKX_EXT_B_BGA1-IC,TBD    I20 @BASEBOARD_FAB2_LIB.BASEBOARD_FAB2(SCH_1):PAGE75
  U2D1 DW70 VSS<62> SKX_EXT_B_BGA1-IC,TBD    I20 @BASEBOARD_FAB2_LIB.BASEBOARD_FAB2(SCH_1):PAGE75
  U2D1 DW68 VSS<63> SKX_EXT_B_BGA1-IC,TBD    I20 @BASEBOARD_FAB2_LIB.BASEBOARD_FAB2(SCH_1):PAGE75
  U2D1 DW66 VSS<64> SKX_EXT_B_BGA1-IC,TBD    I20 @BASEBOARD_FAB2_LIB.BASEBOARD_FAB2(SCH_1):PAGE75
  U2D1 DW64 VSS<65> SKX_EXT_B_BGA1-IC,TBD    I20 @BASEBOARD_FAB2_LIB.BASEBOARD_FAB2(SCH_1):PAGE75
  U2D1 DW40 VSS<66> SKX_EXT_B_BGA1-IC,TBD    I20 @BASEBOARD_FAB2_LIB.BASEBOARD_FAB2(SCH_1):PAGE75
  U2D1 DW36 VSS<67> SKX_EXT_B_BGA1-IC,TBD    I20 @BASEBOARD_FAB2_LIB.BASEBOARD_FAB2(SCH_1):PAGE75
  U2D1 DW34 VSS<68> SKX_EXT_B_BGA1-IC,TBD    I20 @BASEBOARD_FAB2_LIB.BASEBOARD_FAB2(SCH_1):PAGE75
  U2D1 DW30 VSS<69> SKX_EXT_B_BGA1-IC,TBD    I20 @BASEBOARD_FAB2_LIB.BASEBOARD_FAB2(SCH_1):PAGE75
  U2D1 DW28 VSS<70> SKX_EXT_B_BGA1-IC,TBD    I20 @BASEBOARD_FAB2_LIB.BASEBOARD_FAB2(SCH_1):PAGE75
  U2D1 DW24 VSS<71> SKX_EXT_B_BGA1-IC,TBD    I20 @BASEBOARD_FAB2_LIB.BASEBOARD_FAB2(SCH_1):PAGE75
  U2D1 DW20 VSS<72> SKX_EXT_B_BGA1-IC,TBD    I20 @BASEBOARD_FAB2_LIB.BASEBOARD_FAB2(SCH_1):PAGE75
  U2D1 DW12 VSS<73> SKX_EXT_B_BGA1-IC,TBD    I20 @BASEBOARD_FAB2_LIB.BASEBOARD_FAB2(SCH_1):PAGE75
  U2D1 DV81 VSS<74> SKX_EXT_B_BGA1-IC,TBD    I20 @BASEBOARD_FAB2_LIB.BASEBOARD_FAB2(SCH_1):PAGE75
  U2D1 DV77 VSS<75> SKX_EXT_B_BGA1-IC,TBD    I20 @BASEBOARD_FAB2_LIB.BASEBOARD_FAB2(SCH_1):PAGE75
  U2D1 DV73 VSS<76> SKX_EXT_B_BGA1-IC,TBD    I20 @BASEBOARD_FAB2_LIB.BASEBOARD_FAB2(SCH_1):PAGE75
  U2D1 DV39 VSS<77> SKX_EXT_B_BGA1-IC,TBD    I20 @BASEBOARD_FAB2_LIB.BASEBOARD_FAB2(SCH_1):PAGE75
  U2D1 DV37 VSS<78> SKX_EXT_B_BGA1-IC,TBD    I20 @BASEBOARD_FAB2_LIB.BASEBOARD_FAB2(SCH_1):PAGE75
  U2D1 DV33 VSS<79> SKX_EXT_B_BGA1-IC,TBD    I20 @BASEBOARD_FAB2_LIB.BASEBOARD_FAB2(SCH_1):PAGE75
  U2D1 DV31 VSS<80> SKX_EXT_B_BGA1-IC,TBD    I20 @BASEBOARD_FAB2_LIB.BASEBOARD_FAB2(SCH_1):PAGE75
  U2D1 DV27 VSS<81> SKX_EXT_B_BGA1-IC,TBD    I20 @BASEBOARD_FAB2_LIB.BASEBOARD_FAB2(SCH_1):PAGE75
  U2D1 DV25 VSS<82> SKX_EXT_B_BGA1-IC,TBD    I20 @BASEBOARD_FAB2_LIB.BASEBOARD_FAB2(SCH_1):PAGE75
  U2D1 DV21 VSS<83> SKX_EXT_B_BGA1-IC,TBD    I20 @BASEBOARD_FAB2_LIB.BASEBOARD_FAB2(SCH_1):PAGE75
  U2D1 DU84 VSS<84> SKX_EXT_B_BGA1-IC,TBD    I20 @BASEBOARD_FAB2_LIB.BASEBOARD_FAB2(SCH_1):PAGE75
  U2D1 DU82 VSS<85> SKX_EXT_B_BGA1-IC,TBD    I20 @BASEBOARD_FAB2_LIB.BASEBOARD_FAB2(SCH_1):PAGE75
  U2D1 DU80 VSS<86> SKX_EXT_B_BGA1-IC,TBD    I20 @BASEBOARD_FAB2_LIB.BASEBOARD_FAB2(SCH_1):PAGE75
  U2D1 DU78 VSS<87> SKX_EXT_B_BGA1-IC,TBD    I20 @BASEBOARD_FAB2_LIB.BASEBOARD_FAB2(SCH_1):PAGE75
  U2D1 DU72 VSS<88> SKX_EXT_B_BGA1-IC,TBD    I20 @BASEBOARD_FAB2_LIB.BASEBOARD_FAB2(SCH_1):PAGE75
  U2D1 DU70 VSS<89> SKX_EXT_B_BGA1-IC,TBD    I20 @BASEBOARD_FAB2_LIB.BASEBOARD_FAB2(SCH_1):PAGE75
  U2D1 DU38 VSS<90> SKX_EXT_B_BGA1-IC,TBD    I20 @BASEBOARD_FAB2_LIB.BASEBOARD_FAB2(SCH_1):PAGE75
  U2D1 DU32 VSS<91> SKX_EXT_B_BGA1-IC,TBD    I20 @BASEBOARD_FAB2_LIB.BASEBOARD_FAB2(SCH_1):PAGE75
  U2D1 DU26 VSS<92> SKX_EXT_B_BGA1-IC,TBD    I20 @BASEBOARD_FAB2_LIB.BASEBOARD_FAB2(SCH_1):PAGE75
  U2D1 DU22 VSS<93> SKX_EXT_B_BGA1-IC,TBD    I20 @BASEBOARD_FAB2_LIB.BASEBOARD_FAB2(SCH_1):PAGE75
  U2D1 CN14 VSS<94> SKX_EXT_B_BGA1-IC,TBD    I20 @BASEBOARD_FAB2_LIB.BASEBOARD_FAB2(SCH_1):PAGE75
  U2D1 DU14 VSS<95> SKX_EXT_B_BGA1-IC,TBD    I20 @BASEBOARD_FAB2_LIB.BASEBOARD_FAB2(SCH_1):PAGE75
  U2D1 DU10 VSS<96> SKX_EXT_B_BGA1-IC,TBD    I20 @BASEBOARD_FAB2_LIB.BASEBOARD_FAB2(SCH_1):PAGE75
  U2D1 DT85 VSS<97> SKX_EXT_B_BGA1-IC,TBD    I20 @BASEBOARD_FAB2_LIB.BASEBOARD_FAB2(SCH_1):PAGE75
  U2D1 DT83 VSS<98> SKX_EXT_B_BGA1-IC,TBD    I20 @BASEBOARD_FAB2_LIB.BASEBOARD_FAB2(SCH_1):PAGE75
  U2D1 DT79 VSS<99> SKX_EXT_B_BGA1-IC,TBD    I20 @BASEBOARD_FAB2_LIB.BASEBOARD_FAB2(SCH_1):PAGE75
  U2D1 DT69 VSS<100> SKX_EXT_B_BGA1-IC,TBD    I20 @BASEBOARD_FAB2_LIB.BASEBOARD_FAB2(SCH_1):PAGE75
  U2D1 DT65 VSS<101> SKX_EXT_B_BGA1-IC,TBD    I20 @BASEBOARD_FAB2_LIB.BASEBOARD_FAB2(SCH_1):PAGE75
  U2D1 DH21 VSS<102> SKX_EXT_B_BGA1-IC,TBD    I20 @BASEBOARD_FAB2_LIB.BASEBOARD_FAB2(SCH_1):PAGE75
  U2D1 DT17 VSS<103> SKX_EXT_B_BGA1-IC,TBD    I20 @BASEBOARD_FAB2_LIB.BASEBOARD_FAB2(SCH_1):PAGE75
  U2D1  DT3 VSS<104> SKX_EXT_B_BGA1-IC,TBD    I20 @BASEBOARD_FAB2_LIB.BASEBOARD_FAB2(SCH_1):PAGE75
  U2D1 DR78 VSS<105> SKX_EXT_B_BGA1-IC,TBD    I20 @BASEBOARD_FAB2_LIB.BASEBOARD_FAB2(SCH_1):PAGE75
  U2D1 DR76 VSS<106> SKX_EXT_B_BGA1-IC,TBD    I20 @BASEBOARD_FAB2_LIB.BASEBOARD_FAB2(SCH_1):PAGE75
  U2D1 DR74 VSS<107> SKX_EXT_B_BGA1-IC,TBD    I20 @BASEBOARD_FAB2_LIB.BASEBOARD_FAB2(SCH_1):PAGE75
  U2D1 DR72 VSS<108> SKX_EXT_B_BGA1-IC,TBD    I20 @BASEBOARD_FAB2_LIB.BASEBOARD_FAB2(SCH_1):PAGE75
  U2D1 DR70 VSS<109> SKX_EXT_B_BGA1-IC,TBD    I20 @BASEBOARD_FAB2_LIB.BASEBOARD_FAB2(SCH_1):PAGE75
  U2D1 DR68 VSS<110> SKX_EXT_B_BGA1-IC,TBD    I20 @BASEBOARD_FAB2_LIB.BASEBOARD_FAB2(SCH_1):PAGE75
  U2D1 DR66 VSS<111> SKX_EXT_B_BGA1-IC,TBD    I20 @BASEBOARD_FAB2_LIB.BASEBOARD_FAB2(SCH_1):PAGE75
  U2D1 DR42 VSS<112> SKX_EXT_B_BGA1-IC,TBD    I20 @BASEBOARD_FAB2_LIB.BASEBOARD_FAB2(SCH_1):PAGE75
  U2D1 DR40 VSS<113> SKX_EXT_B_BGA1-IC,TBD    I20 @BASEBOARD_FAB2_LIB.BASEBOARD_FAB2(SCH_1):PAGE75
  U2D1 DR38 VSS<114> SKX_EXT_B_BGA1-IC,TBD    I20 @BASEBOARD_FAB2_LIB.BASEBOARD_FAB2(SCH_1):PAGE75
  U2D1 DR36 VSS<115> SKX_EXT_B_BGA1-IC,TBD    I20 @BASEBOARD_FAB2_LIB.BASEBOARD_FAB2(SCH_1):PAGE75
  U2D1 DR34 VSS<116> SKX_EXT_B_BGA1-IC,TBD    I20 @BASEBOARD_FAB2_LIB.BASEBOARD_FAB2(SCH_1):PAGE75
  U2D1 DR32 VSS<117> SKX_EXT_B_BGA1-IC,TBD    I20 @BASEBOARD_FAB2_LIB.BASEBOARD_FAB2(SCH_1):PAGE75
  U2D1 DR30 VSS<118> SKX_EXT_B_BGA1-IC,TBD    I20 @BASEBOARD_FAB2_LIB.BASEBOARD_FAB2(SCH_1):PAGE75
  U2D1 DR28 VSS<119> SKX_EXT_B_BGA1-IC,TBD    I20 @BASEBOARD_FAB2_LIB.BASEBOARD_FAB2(SCH_1):PAGE75
  U2D1 DR26 VSS<120> SKX_EXT_B_BGA1-IC,TBD    I20 @BASEBOARD_FAB2_LIB.BASEBOARD_FAB2(SCH_1):PAGE75
  U2D1 DR24 VSS<121> SKX_EXT_B_BGA1-IC,TBD    I20 @BASEBOARD_FAB2_LIB.BASEBOARD_FAB2(SCH_1):PAGE75
  U2D1 DR22 VSS<122> SKX_EXT_B_BGA1-IC,TBD    I20 @BASEBOARD_FAB2_LIB.BASEBOARD_FAB2(SCH_1):PAGE75
  U2D1 DR20 VSS<123> SKX_EXT_B_BGA1-IC,TBD    I20 @BASEBOARD_FAB2_LIB.BASEBOARD_FAB2(SCH_1):PAGE75
  U2D1 CL22 VSS<124> SKX_EXT_B_BGA1-IC,TBD    I20 @BASEBOARD_FAB2_LIB.BASEBOARD_FAB2(SCH_1):PAGE75
  U2D1 CA20 VSS<125> SKX_EXT_B_BGA1-IC,TBD    I20 @BASEBOARD_FAB2_LIB.BASEBOARD_FAB2(SCH_1):PAGE75
  U2D1  DR6 VSS<126> SKX_EXT_B_BGA1-IC,TBD    I20 @BASEBOARD_FAB2_LIB.BASEBOARD_FAB2(SCH_1):PAGE75
  U2D1 BR26 VSS<127> SKX_EXT_B_BGA1-IC,TBD    I20 @BASEBOARD_FAB2_LIB.BASEBOARD_FAB2(SCH_1):PAGE75
  U2D1 DP83 VSS<128> SKX_EXT_B_BGA1-IC,TBD    I20 @BASEBOARD_FAB2_LIB.BASEBOARD_FAB2(SCH_1):PAGE75
  U2D1 DP81 VSS<129> SKX_EXT_B_BGA1-IC,TBD    I20 @BASEBOARD_FAB2_LIB.BASEBOARD_FAB2(SCH_1):PAGE75
  U2D1 DP71 VSS<130> SKX_EXT_B_BGA1-IC,TBD    I20 @BASEBOARD_FAB2_LIB.BASEBOARD_FAB2(SCH_1):PAGE75
  U2D1 DP69 VSS<131> SKX_EXT_B_BGA1-IC,TBD    I20 @BASEBOARD_FAB2_LIB.BASEBOARD_FAB2(SCH_1):PAGE75
  U2D1 DP67 VSS<132> SKX_EXT_B_BGA1-IC,TBD    I20 @BASEBOARD_FAB2_LIB.BASEBOARD_FAB2(SCH_1):PAGE75
  U2D1 DN78 VSS<133> SKX_EXT_B_BGA1-IC,TBD    I20 @BASEBOARD_FAB2_LIB.BASEBOARD_FAB2(SCH_1):PAGE75
 C3D21    2      B CAP_A_0603V-22.0UF,4V,20%,X6S,A     I1 @BASEBOARD_FAB2_LIB.BASEBOARD_FAB2(SCH_1):PAGE76
  C3D5    2      B CAP_A_0603V-22.0UF,4V,20%,X6S,A     I3 @BASEBOARD_FAB2_LIB.BASEBOARD_FAB2(SCH_1):PAGE76
 C3D12    2      B CAP_A_0603V-22.0UF,4V,20%,X6S,A     I4 @BASEBOARD_FAB2_LIB.BASEBOARD_FAB2(SCH_1):PAGE76
  C3D4    2      B CAP_A_0603V-22.0UF,4V,20%,X6S,A     I5 @BASEBOARD_FAB2_LIB.BASEBOARD_FAB2(SCH_1):PAGE76
 C3D11    2      B CAP_A_0603V-22.0UF,4V,20%,X6S,A     I7 @BASEBOARD_FAB2_LIB.BASEBOARD_FAB2(SCH_1):PAGE76
 C3D13    2      B CAP_A_0603V-22.0UF,4V,20%,X6S,A     I8 @BASEBOARD_FAB2_LIB.BASEBOARD_FAB2(SCH_1):PAGE76
 C2D40    2      B CAP_A_0603V-22.0UF,4V,20%,X6S,A    I10 @BASEBOARD_FAB2_LIB.BASEBOARD_FAB2(SCH_1):PAGE76
  C3D9    2      B CAP_A_0603V-22.0UF,4V,20%,X6S,A    I15 @BASEBOARD_FAB2_LIB.BASEBOARD_FAB2(SCH_1):PAGE76
  C3D8    2      B CAP_A_0603V-22.0UF,4V,20%,X6S,A    I18 @BASEBOARD_FAB2_LIB.BASEBOARD_FAB2(SCH_1):PAGE76
  C7P6    2      B CAP_0805-47UF,4V,20%,X6S,C9533A    I23 @BASEBOARD_FAB2_LIB.BASEBOARD_FAB2(SCH_1):PAGE76
 C7P13    2      B CAP_0805-47UF,4V,20%,X6S,C9533A    I25 @BASEBOARD_FAB2_LIB.BASEBOARD_FAB2(SCH_1):PAGE76
 C7P10    2      B CAP_0805-47UF,4V,20%,X6S,C9533A    I26 @BASEBOARD_FAB2_LIB.BASEBOARD_FAB2(SCH_1):PAGE76
  C7P7    2      B CAP_0805-47UF,4V,20%,X6S,C9533A    I27 @BASEBOARD_FAB2_LIB.BASEBOARD_FAB2(SCH_1):PAGE76
 C8P22    2      B CAP_0805-47UF,4V,20%,X6S,C9533A    I28 @BASEBOARD_FAB2_LIB.BASEBOARD_FAB2(SCH_1):PAGE76
 C7P17    2      B CAP_0805-47UF,4V,20%,X6S,C9533A    I29 @BASEBOARD_FAB2_LIB.BASEBOARD_FAB2(SCH_1):PAGE76
  C2D8    2      B CAP_0603LF-10UF,4V,20%,X6S,E15A    I33 @BASEBOARD_FAB2_LIB.BASEBOARD_FAB2(SCH_1):PAGE76
 C2D10    2      B CAP_0603LF-10UF,4V,20%,X6S,E15A    I37 @BASEBOARD_FAB2_LIB.BASEBOARD_FAB2(SCH_1):PAGE76
 C2D11    2      B CAP_0603LF-10UF,4V,20%,X6S,E15A    I42 @BASEBOARD_FAB2_LIB.BASEBOARD_FAB2(SCH_1):PAGE76
  C2D9    2      B CAP_0603LF-10UF,4V,20%,X6S,E15A    I43 @BASEBOARD_FAB2_LIB.BASEBOARD_FAB2(SCH_1):PAGE76
 C7P15    2      B CAP_0805-47UF,4V,20%,X6S,C9533A    I45 @BASEBOARD_FAB2_LIB.BASEBOARD_FAB2(SCH_1):PAGE76
 C8P23    2      B CAP_0805-47UF,4V,20%,X6S,C9533A    I48 @BASEBOARD_FAB2_LIB.BASEBOARD_FAB2(SCH_1):PAGE76
 C7P14    2      B CAP_0805-47UF,4V,20%,X6S,C9533A    I49 @BASEBOARD_FAB2_LIB.BASEBOARD_FAB2(SCH_1):PAGE76
  C8P7    2      B CAP_0805LF-22UF,4V,20%,X6S,C95A    I50 @BASEBOARD_FAB2_LIB.BASEBOARD_FAB2(SCH_1):PAGE76
 C7P18    2      B CAP_0805-47UF,4V,20%,X6S,C9533A    I51 @BASEBOARD_FAB2_LIB.BASEBOARD_FAB2(SCH_1):PAGE76
  C7P3    2      B CAP_0805-47UF,4V,20%,X6S,C9533A    I52 @BASEBOARD_FAB2_LIB.BASEBOARD_FAB2(SCH_1):PAGE76
  C8P6    2      B CAP_0805LF-22UF,4V,20%,X6S,C95A    I55 @BASEBOARD_FAB2_LIB.BASEBOARD_FAB2(SCH_1):PAGE76
  C8P5    2      B CAP_0805LF-22UF,4V,20%,X6S,C95A    I58 @BASEBOARD_FAB2_LIB.BASEBOARD_FAB2(SCH_1):PAGE76
 C2D12    2      B CAP_A_0603V-22.0UF,4V,20%,X6S,A    I59 @BASEBOARD_FAB2_LIB.BASEBOARD_FAB2(SCH_1):PAGE76
 C2D22    2      B CAP_A_0603V-22.0UF,4V,20%,X6S,A    I61 @BASEBOARD_FAB2_LIB.BASEBOARD_FAB2(SCH_1):PAGE76
 C2D31    2      B CAP_A_0603V-22.0UF,4V,20%,X6S,A    I63 @BASEBOARD_FAB2_LIB.BASEBOARD_FAB2(SCH_1):PAGE76
 C2D21    2      B CAP_A_0603V-22.0UF,4V,20%,X6S,A    I65 @BASEBOARD_FAB2_LIB.BASEBOARD_FAB2(SCH_1):PAGE76
 C2D27    2      B CAP_A_0603V-22.0UF,4V,20%,X6S,A    I66 @BASEBOARD_FAB2_LIB.BASEBOARD_FAB2(SCH_1):PAGE76
  C3D2    2      B CAP_A_0603V-22.0UF,4V,20%,X6S,A    I69 @BASEBOARD_FAB2_LIB.BASEBOARD_FAB2(SCH_1):PAGE76
 C2D36    2      B CAP_A_0603V-22.0UF,4V,20%,X6S,A    I70 @BASEBOARD_FAB2_LIB.BASEBOARD_FAB2(SCH_1):PAGE76
 C2D13    2      B CAP_A_0603V-22.0UF,4V,20%,X6S,A    I73 @BASEBOARD_FAB2_LIB.BASEBOARD_FAB2(SCH_1):PAGE76
 C2D19    2      B CAP_A_0603V-22.0UF,4V,20%,X6S,A    I75 @BASEBOARD_FAB2_LIB.BASEBOARD_FAB2(SCH_1):PAGE76
 C2D14    2      B CAP_A_0603V-22.0UF,4V,20%,X6S,A    I76 @BASEBOARD_FAB2_LIB.BASEBOARD_FAB2(SCH_1):PAGE76
 C2D20    2      B CAP_A_0603V-22.0UF,4V,20%,X6S,A    I79 @BASEBOARD_FAB2_LIB.BASEBOARD_FAB2(SCH_1):PAGE76
 C2D24    2      B CAP_A_0603V-22.0UF,4V,20%,X6S,A    I80 @BASEBOARD_FAB2_LIB.BASEBOARD_FAB2(SCH_1):PAGE76
 C2D25    2      B CAP_A_0603V-22.0UF,4V,20%,X6S,A    I82 @BASEBOARD_FAB2_LIB.BASEBOARD_FAB2(SCH_1):PAGE76
 C2D30    2      B CAP_A_0603V-22.0UF,4V,20%,X6S,A    I83 @BASEBOARD_FAB2_LIB.BASEBOARD_FAB2(SCH_1):PAGE76
 C2D33    2      B CAP_A_0603V-22.0UF,4V,20%,X6S,A    I85 @BASEBOARD_FAB2_LIB.BASEBOARD_FAB2(SCH_1):PAGE76
  C8P4    2      B CAP_0805-47UF,4V,20%,X6S,C9533A    I88 @BASEBOARD_FAB2_LIB.BASEBOARD_FAB2(SCH_1):PAGE76
 C8P20    2      B CAP_0805-47UF,4V,20%,X6S,C9533A    I89 @BASEBOARD_FAB2_LIB.BASEBOARD_FAB2(SCH_1):PAGE76
 C2D32    2      B CAP_A_0603V-22.0UF,4V,20%,X6S,A    I90 @BASEBOARD_FAB2_LIB.BASEBOARD_FAB2(SCH_1):PAGE76
 C8P18    2      B CAP_0805-47UF,4V,20%,X6S,C9533A    I92 @BASEBOARD_FAB2_LIB.BASEBOARD_FAB2(SCH_1):PAGE76
  C7P2    2      B CAP_0805-47UF,4V,20%,X6S,C9533A   I100 @BASEBOARD_FAB2_LIB.BASEBOARD_FAB2(SCH_1):PAGE76
  C8P3    2      B CAP_0805-47UF,4V,20%,X6S,C9533A   I101 @BASEBOARD_FAB2_LIB.BASEBOARD_FAB2(SCH_1):PAGE76
 C8P19    2      B CAP_0805-47UF,4V,20%,X6S,C9533A   I103 @BASEBOARD_FAB2_LIB.BASEBOARD_FAB2(SCH_1):PAGE76
  C7P1    2      B CAP_0805-47UF,4V,20%,X6S,C9533A   I105 @BASEBOARD_FAB2_LIB.BASEBOARD_FAB2(SCH_1):PAGE76
 C8P34    2      B CAP_0805-47UF,4V,20%,X6S,C9533A   I106 @BASEBOARD_FAB2_LIB.BASEBOARD_FAB2(SCH_1):PAGE76
 C8P12    2      B CAP_0805-47UF,4V,20%,X6S,C9533A   I107 @BASEBOARD_FAB2_LIB.BASEBOARD_FAB2(SCH_1):PAGE76
 C2D26    2      B CAP_A_0603V-22.0UF,4V,20%,X6S,A   I108 @BASEBOARD_FAB2_LIB.BASEBOARD_FAB2(SCH_1):PAGE76
  C3D1    2      B CAP_A_0603V-22.0UF,4V,20%,X6S,A   I111 @BASEBOARD_FAB2_LIB.BASEBOARD_FAB2(SCH_1):PAGE76
 C2D23    2      B CAP_A_0603V-22.0UF,4V,20%,X6S,A   I112 @BASEBOARD_FAB2_LIB.BASEBOARD_FAB2(SCH_1):PAGE76
 C2D17    2      B CAP_A_0603V-22.0UF,4V,20%,X6S,A   I114 @BASEBOARD_FAB2_LIB.BASEBOARD_FAB2(SCH_1):PAGE76
  C2D1    2      B CAP_A_0603V-22.0UF,4V,20%,X6S,A   I116 @BASEBOARD_FAB2_LIB.BASEBOARD_FAB2(SCH_1):PAGE76
 C8P26    2      B CAP_0805-47UF,4V,20%,X6S,C9533A   I118 @BASEBOARD_FAB2_LIB.BASEBOARD_FAB2(SCH_1):PAGE76
 C2D37    2      B CAP_A_0603V-22.0UF,4V,20%,X6S,A   I119 @BASEBOARD_FAB2_LIB.BASEBOARD_FAB2(SCH_1):PAGE76
 C2D34    2      B CAP_A_0603V-22.0UF,4V,20%,X6S,A   I122 @BASEBOARD_FAB2_LIB.BASEBOARD_FAB2(SCH_1):PAGE76
 C2D45    2      B CAP_A_0603V-22.0UF,4V,20%,X6S,A   I123 @BASEBOARD_FAB2_LIB.BASEBOARD_FAB2(SCH_1):PAGE76
 C2D16    2      B CAP_A_0603V-22.0UF,4V,20%,X6S,A   I124 @BASEBOARD_FAB2_LIB.BASEBOARD_FAB2(SCH_1):PAGE76
 C8P29    2      B CAP_0805-47UF,4V,20%,X6S,C9533A   I125 @BASEBOARD_FAB2_LIB.BASEBOARD_FAB2(SCH_1):PAGE76
 C8P10    2      B CAP_0805-47UF,4V,20%,X6S,C9533A   I127 @BASEBOARD_FAB2_LIB.BASEBOARD_FAB2(SCH_1):PAGE76
 C8P16    2      B CAP_0805-47UF,4V,20%,X6S,C9533A   I129 @BASEBOARD_FAB2_LIB.BASEBOARD_FAB2(SCH_1):PAGE76
 C8P33    2      B CAP_0805-47UF,4V,20%,X6S,C9533A   I131 @BASEBOARD_FAB2_LIB.BASEBOARD_FAB2(SCH_1):PAGE76
 C8P13    2      B CAP_0805-47UF,4V,20%,X6S,C9533A   I132 @BASEBOARD_FAB2_LIB.BASEBOARD_FAB2(SCH_1):PAGE76
 C8P17    2      B CAP_0805-47UF,4V,20%,X6S,C9533A   I133 @BASEBOARD_FAB2_LIB.BASEBOARD_FAB2(SCH_1):PAGE76
 C8P21    2      B CAP_0805-47UF,4V,20%,X6S,C9533A   I135 @BASEBOARD_FAB2_LIB.BASEBOARD_FAB2(SCH_1):PAGE76
 C8P25    2      B CAP_0805-47UF,4V,20%,X6S,C9533A   I136 @BASEBOARD_FAB2_LIB.BASEBOARD_FAB2(SCH_1):PAGE76
 C8P28    2      B CAP_0805-47UF,4V,20%,X6S,C9533A   I137 @BASEBOARD_FAB2_LIB.BASEBOARD_FAB2(SCH_1):PAGE76
 C8P11    2      B CAP_0805-47UF,4V,20%,X6S,C9533A   I139 @BASEBOARD_FAB2_LIB.BASEBOARD_FAB2(SCH_1):PAGE76
 C8P27    2      B CAP_0805-47UF,4V,20%,X6S,C9533A   I141 @BASEBOARD_FAB2_LIB.BASEBOARD_FAB2(SCH_1):PAGE76
 C2D15    2      B CAP_A_0603V-22.0UF,4V,20%,X6S,A   I159 @BASEBOARD_FAB2_LIB.BASEBOARD_FAB2(SCH_1):PAGE76
 C2D38    2      B CAP_A_0603V-22.0UF,4V,20%,X6S,A   I160 @BASEBOARD_FAB2_LIB.BASEBOARD_FAB2(SCH_1):PAGE76
 C2D35    2      B CAP_A_0603V-22.0UF,4V,20%,X6S,A   I161 @BASEBOARD_FAB2_LIB.BASEBOARD_FAB2(SCH_1):PAGE76
  C3D7    2      B CAP_A_0603V-22.0UF,4V,20%,X6S,A   I164 @BASEBOARD_FAB2_LIB.BASEBOARD_FAB2(SCH_1):PAGE76
 C2D39    2      B CAP_A_0603V-22.0UF,4V,20%,X6S,A   I165 @BASEBOARD_FAB2_LIB.BASEBOARD_FAB2(SCH_1):PAGE76
 C3D17    2      B CAP_A_0603V-22.0UF,4V,20%,X6S,A   I166 @BASEBOARD_FAB2_LIB.BASEBOARD_FAB2(SCH_1):PAGE76
 C3D18    2      B CAP_A_0603V-22.0UF,4V,20%,X6S,A   I169 @BASEBOARD_FAB2_LIB.BASEBOARD_FAB2(SCH_1):PAGE76
  C3D6    2      B CAP_A_0603V-22.0UF,4V,20%,X6S,A   I170 @BASEBOARD_FAB2_LIB.BASEBOARD_FAB2(SCH_1):PAGE76
 C3D14    2      B CAP_A_0603V-22.0UF,4V,20%,X6S,A   I171 @BASEBOARD_FAB2_LIB.BASEBOARD_FAB2(SCH_1):PAGE76
 C3D23    2      B CAP_A_0603V-22.0UF,4V,20%,X6S,A   I172 @BASEBOARD_FAB2_LIB.BASEBOARD_FAB2(SCH_1):PAGE76
 C3D15    2      B CAP_A_0603V-22.0UF,4V,20%,X6S,A   I174 @BASEBOARD_FAB2_LIB.BASEBOARD_FAB2(SCH_1):PAGE76
 C3D24    2      B CAP_A_0603V-22.0UF,4V,20%,X6S,A   I175 @BASEBOARD_FAB2_LIB.BASEBOARD_FAB2(SCH_1):PAGE76
 C3D16    2      B CAP_A_0603V-22.0UF,4V,20%,X6S,A   I176 @BASEBOARD_FAB2_LIB.BASEBOARD_FAB2(SCH_1):PAGE76
 C7P12    2      B CAP_A_0603V-22.0UF,4V,20%,X6S,A   I179 @BASEBOARD_FAB2_LIB.BASEBOARD_FAB2(SCH_1):PAGE76
  C7P9    2      B CAP_0805-47UF,4V,20%,X6S,C9533A   I181 @BASEBOARD_FAB2_LIB.BASEBOARD_FAB2(SCH_1):PAGE76
  C7P5    2      B CAP_0805-47UF,4V,20%,X6S,C9533A   I182 @BASEBOARD_FAB2_LIB.BASEBOARD_FAB2(SCH_1):PAGE76
 C7P11    2      B CAP_0805-47UF,4V,20%,X6S,C9533A   I183 @BASEBOARD_FAB2_LIB.BASEBOARD_FAB2(SCH_1):PAGE76
  C7P8    2      B CAP_0805-47UF,4V,20%,X6S,C9533A   I184 @BASEBOARD_FAB2_LIB.BASEBOARD_FAB2(SCH_1):PAGE76
  C7P4    2      B CAP_0805-47UF,4V,20%,X6S,C9533A   I195 @BASEBOARD_FAB2_LIB.BASEBOARD_FAB2(SCH_1):PAGE76
 C3D10    2      B CAP_A_0603V-22.0UF,4V,20%,X6S,A   I196 @BASEBOARD_FAB2_LIB.BASEBOARD_FAB2(SCH_1):PAGE76
 C2D18    2      B CAP_A_0603V-22.0UF,4V,20%,X6S,A   I197 @BASEBOARD_FAB2_LIB.BASEBOARD_FAB2(SCH_1):PAGE76
 C2D28    2      B CAP_A_0603V-22.0UF,4V,20%,X6S,A   I198 @BASEBOARD_FAB2_LIB.BASEBOARD_FAB2(SCH_1):PAGE76
 C2D29    2      B CAP_A_0603V-22.0UF,4V,20%,X6S,A   I199 @BASEBOARD_FAB2_LIB.BASEBOARD_FAB2(SCH_1):PAGE76
  C2D2    2      B CAP_A_0603V-22.0UF,4V,20%,X6S,A   I201 @BASEBOARD_FAB2_LIB.BASEBOARD_FAB2(SCH_1):PAGE76
  C2D3    2      B CAP_A_0603V-22.0UF,4V,20%,X6S,A   I202 @BASEBOARD_FAB2_LIB.BASEBOARD_FAB2(SCH_1):PAGE76
 C2D47    2      B CAP_A_0603V-22.0UF,4V,20%,X6S,A   I203 @BASEBOARD_FAB2_LIB.BASEBOARD_FAB2(SCH_1):PAGE76
 C2D46    2      B CAP_A_0603V-22.0UF,4V,20%,X6S,A   I204 @BASEBOARD_FAB2_LIB.BASEBOARD_FAB2(SCH_1):PAGE76
 C3D25    2      B CAP_A_0603V-22.0UF,4V,20%,X6S,A   I205 @BASEBOARD_FAB2_LIB.BASEBOARD_FAB2(SCH_1):PAGE76
 C7P16    2      B CAP_A_0603V-22.0UF,4V,20%,X6S,A   I206 @BASEBOARD_FAB2_LIB.BASEBOARD_FAB2(SCH_1):PAGE76
 C3D20    2      B CAP_A_0603V-22.0UF,4V,20%,X6S,A   I207 @BASEBOARD_FAB2_LIB.BASEBOARD_FAB2(SCH_1):PAGE76
 C3D19    2      B CAP_A_0603V-22.0UF,4V,20%,X6S,A   I208 @BASEBOARD_FAB2_LIB.BASEBOARD_FAB2(SCH_1):PAGE76
 C8P14    2      B CAP_0805-47UF,4V,20%,X6S,C9533A   I211 @BASEBOARD_FAB2_LIB.BASEBOARD_FAB2(SCH_1):PAGE76
 C8P15    2      B CAP_0805-47UF,4V,20%,X6S,C9533A   I212 @BASEBOARD_FAB2_LIB.BASEBOARD_FAB2(SCH_1):PAGE76
  C8P8    2      B CAP_0805-47UF,4V,20%,X6S,C9533A   I213 @BASEBOARD_FAB2_LIB.BASEBOARD_FAB2(SCH_1):PAGE76
  C8P9    2      B CAP_0805-47UF,4V,20%,X6S,C9533A   I214 @BASEBOARD_FAB2_LIB.BASEBOARD_FAB2(SCH_1):PAGE76
 C7P19    2      B CAP_0805-47UF,4V,20%,X6S,C9533A   I215 @BASEBOARD_FAB2_LIB.BASEBOARD_FAB2(SCH_1):PAGE76
 C8P32    2      B CAP_0805-47UF,4V,20%,X6S,C9533A   I216 @BASEBOARD_FAB2_LIB.BASEBOARD_FAB2(SCH_1):PAGE76
 C8P24    2      B CAP_0805-47UF,4V,20%,X6S,C9533A   I217 @BASEBOARD_FAB2_LIB.BASEBOARD_FAB2(SCH_1):PAGE76
 C7P20    2      B CAP_0805-47UF,4V,20%,X6S,C9533A   I218 @BASEBOARD_FAB2_LIB.BASEBOARD_FAB2(SCH_1):PAGE76
  J1G1  283 VSS<0> SCONN288_H44441004_PIP-SCONN,HA    I43 @BASEBOARD_FAB2_LIB.BASEBOARD_FAB2(SCH_1):PAGE77
  J1G1  281 VSS<1> SCONN288_H44441004_PIP-SCONN,HA    I43 @BASEBOARD_FAB2_LIB.BASEBOARD_FAB2(SCH_1):PAGE77
  J1G1  279 VSS<2> SCONN288_H44441004_PIP-SCONN,HA    I43 @BASEBOARD_FAB2_LIB.BASEBOARD_FAB2(SCH_1):PAGE77
  J1G1  276 VSS<3> SCONN288_H44441004_PIP-SCONN,HA    I43 @BASEBOARD_FAB2_LIB.BASEBOARD_FAB2(SCH_1):PAGE77
  J1G1  274 VSS<4> SCONN288_H44441004_PIP-SCONN,HA    I43 @BASEBOARD_FAB2_LIB.BASEBOARD_FAB2(SCH_1):PAGE77
  J1G1  272 VSS<5> SCONN288_H44441004_PIP-SCONN,HA    I43 @BASEBOARD_FAB2_LIB.BASEBOARD_FAB2(SCH_1):PAGE77
  J1G1  270 VSS<6> SCONN288_H44441004_PIP-SCONN,HA    I43 @BASEBOARD_FAB2_LIB.BASEBOARD_FAB2(SCH_1):PAGE77
  J1G1  268 VSS<7> SCONN288_H44441004_PIP-SCONN,HA    I43 @BASEBOARD_FAB2_LIB.BASEBOARD_FAB2(SCH_1):PAGE77
  J1G1  265 VSS<8> SCONN288_H44441004_PIP-SCONN,HA    I43 @BASEBOARD_FAB2_LIB.BASEBOARD_FAB2(SCH_1):PAGE77
  J1G1  263 VSS<9> SCONN288_H44441004_PIP-SCONN,HA    I43 @BASEBOARD_FAB2_LIB.BASEBOARD_FAB2(SCH_1):PAGE77
  J1G1  261 VSS<10> SCONN288_H44441004_PIP-SCONN,HA    I43 @BASEBOARD_FAB2_LIB.BASEBOARD_FAB2(SCH_1):PAGE77
  J1G1  259 VSS<11> SCONN288_H44441004_PIP-SCONN,HA    I43 @BASEBOARD_FAB2_LIB.BASEBOARD_FAB2(SCH_1):PAGE77
  J1G1  257 VSS<12> SCONN288_H44441004_PIP-SCONN,HA    I43 @BASEBOARD_FAB2_LIB.BASEBOARD_FAB2(SCH_1):PAGE77
  J1G1  254 VSS<13> SCONN288_H44441004_PIP-SCONN,HA    I43 @BASEBOARD_FAB2_LIB.BASEBOARD_FAB2(SCH_1):PAGE77
  J1G1  252 VSS<14> SCONN288_H44441004_PIP-SCONN,HA    I43 @BASEBOARD_FAB2_LIB.BASEBOARD_FAB2(SCH_1):PAGE77
  J1G1  250 VSS<15> SCONN288_H44441004_PIP-SCONN,HA    I43 @BASEBOARD_FAB2_LIB.BASEBOARD_FAB2(SCH_1):PAGE77
  J1G1  248 VSS<16> SCONN288_H44441004_PIP-SCONN,HA    I43 @BASEBOARD_FAB2_LIB.BASEBOARD_FAB2(SCH_1):PAGE77
  J1G1  246 VSS<17> SCONN288_H44441004_PIP-SCONN,HA    I43 @BASEBOARD_FAB2_LIB.BASEBOARD_FAB2(SCH_1):PAGE77
  J1G1  243 VSS<18> SCONN288_H44441004_PIP-SCONN,HA    I43 @BASEBOARD_FAB2_LIB.BASEBOARD_FAB2(SCH_1):PAGE77
  J1G1  241 VSS<19> SCONN288_H44441004_PIP-SCONN,HA    I43 @BASEBOARD_FAB2_LIB.BASEBOARD_FAB2(SCH_1):PAGE77
  J1G1  239 VSS<20> SCONN288_H44441004_PIP-SCONN,HA    I43 @BASEBOARD_FAB2_LIB.BASEBOARD_FAB2(SCH_1):PAGE77
  J1G1  202 VSS<21> SCONN288_H44441004_PIP-SCONN,HA    I43 @BASEBOARD_FAB2_LIB.BASEBOARD_FAB2(SCH_1):PAGE77
  J1G1  200 VSS<22> SCONN288_H44441004_PIP-SCONN,HA    I43 @BASEBOARD_FAB2_LIB.BASEBOARD_FAB2(SCH_1):PAGE77
  J1G1  198 VSS<23> SCONN288_H44441004_PIP-SCONN,HA    I43 @BASEBOARD_FAB2_LIB.BASEBOARD_FAB2(SCH_1):PAGE77
  J1G1  195 VSS<24> SCONN288_H44441004_PIP-SCONN,HA    I43 @BASEBOARD_FAB2_LIB.BASEBOARD_FAB2(SCH_1):PAGE77
  J1G1  193 VSS<25> SCONN288_H44441004_PIP-SCONN,HA    I43 @BASEBOARD_FAB2_LIB.BASEBOARD_FAB2(SCH_1):PAGE77
  J1G1  191 VSS<26> SCONN288_H44441004_PIP-SCONN,HA    I43 @BASEBOARD_FAB2_LIB.BASEBOARD_FAB2(SCH_1):PAGE77
  J1G1  189 VSS<27> SCONN288_H44441004_PIP-SCONN,HA    I43 @BASEBOARD_FAB2_LIB.BASEBOARD_FAB2(SCH_1):PAGE77
  J1G1  187 VSS<28> SCONN288_H44441004_PIP-SCONN,HA    I43 @BASEBOARD_FAB2_LIB.BASEBOARD_FAB2(SCH_1):PAGE77
  J1G1  184 VSS<29> SCONN288_H44441004_PIP-SCONN,HA    I43 @BASEBOARD_FAB2_LIB.BASEBOARD_FAB2(SCH_1):PAGE77
  J1G1  182 VSS<30> SCONN288_H44441004_PIP-SCONN,HA    I43 @BASEBOARD_FAB2_LIB.BASEBOARD_FAB2(SCH_1):PAGE77
  J1G1  180 VSS<31> SCONN288_H44441004_PIP-SCONN,HA    I43 @BASEBOARD_FAB2_LIB.BASEBOARD_FAB2(SCH_1):PAGE77
  J1G1  178 VSS<32> SCONN288_H44441004_PIP-SCONN,HA    I43 @BASEBOARD_FAB2_LIB.BASEBOARD_FAB2(SCH_1):PAGE77
  J1G1  176 VSS<33> SCONN288_H44441004_PIP-SCONN,HA    I43 @BASEBOARD_FAB2_LIB.BASEBOARD_FAB2(SCH_1):PAGE77
  J1G1  173 VSS<34> SCONN288_H44441004_PIP-SCONN,HA    I43 @BASEBOARD_FAB2_LIB.BASEBOARD_FAB2(SCH_1):PAGE77
  J1G1  171 VSS<35> SCONN288_H44441004_PIP-SCONN,HA    I43 @BASEBOARD_FAB2_LIB.BASEBOARD_FAB2(SCH_1):PAGE77
  J1G1  169 VSS<36> SCONN288_H44441004_PIP-SCONN,HA    I43 @BASEBOARD_FAB2_LIB.BASEBOARD_FAB2(SCH_1):PAGE77
  J1G1  167 VSS<37> SCONN288_H44441004_PIP-SCONN,HA    I43 @BASEBOARD_FAB2_LIB.BASEBOARD_FAB2(SCH_1):PAGE77
  J1G1  165 VSS<38> SCONN288_H44441004_PIP-SCONN,HA    I43 @BASEBOARD_FAB2_LIB.BASEBOARD_FAB2(SCH_1):PAGE77
  J1G1  162 VSS<39> SCONN288_H44441004_PIP-SCONN,HA    I43 @BASEBOARD_FAB2_LIB.BASEBOARD_FAB2(SCH_1):PAGE77
  J1G1  160 VSS<40> SCONN288_H44441004_PIP-SCONN,HA    I43 @BASEBOARD_FAB2_LIB.BASEBOARD_FAB2(SCH_1):PAGE77
  J1G1  158 VSS<41> SCONN288_H44441004_PIP-SCONN,HA    I43 @BASEBOARD_FAB2_LIB.BASEBOARD_FAB2(SCH_1):PAGE77
  J1G1  156 VSS<42> SCONN288_H44441004_PIP-SCONN,HA    I43 @BASEBOARD_FAB2_LIB.BASEBOARD_FAB2(SCH_1):PAGE77
  J1G1  154 VSS<43> SCONN288_H44441004_PIP-SCONN,HA    I43 @BASEBOARD_FAB2_LIB.BASEBOARD_FAB2(SCH_1):PAGE77
  J1G1  151 VSS<44> SCONN288_H44441004_PIP-SCONN,HA    I43 @BASEBOARD_FAB2_LIB.BASEBOARD_FAB2(SCH_1):PAGE77
  J1G1  149 VSS<45> SCONN288_H44441004_PIP-SCONN,HA    I43 @BASEBOARD_FAB2_LIB.BASEBOARD_FAB2(SCH_1):PAGE77
  J1G1  147 VSS<46> SCONN288_H44441004_PIP-SCONN,HA    I43 @BASEBOARD_FAB2_LIB.BASEBOARD_FAB2(SCH_1):PAGE77
  J1G1  138 VSS<47> SCONN288_H44441004_PIP-SCONN,HA    I43 @BASEBOARD_FAB2_LIB.BASEBOARD_FAB2(SCH_1):PAGE77
  J1G1  136 VSS<48> SCONN288_H44441004_PIP-SCONN,HA    I43 @BASEBOARD_FAB2_LIB.BASEBOARD_FAB2(SCH_1):PAGE77
  J1G1  134 VSS<49> SCONN288_H44441004_PIP-SCONN,HA    I43 @BASEBOARD_FAB2_LIB.BASEBOARD_FAB2(SCH_1):PAGE77
  J1G1  131 VSS<50> SCONN288_H44441004_PIP-SCONN,HA    I43 @BASEBOARD_FAB2_LIB.BASEBOARD_FAB2(SCH_1):PAGE77
  J1G1  129 VSS<51> SCONN288_H44441004_PIP-SCONN,HA    I43 @BASEBOARD_FAB2_LIB.BASEBOARD_FAB2(SCH_1):PAGE77
  J1G1  127 VSS<52> SCONN288_H44441004_PIP-SCONN,HA    I43 @BASEBOARD_FAB2_LIB.BASEBOARD_FAB2(SCH_1):PAGE77
  J1G1  125 VSS<53> SCONN288_H44441004_PIP-SCONN,HA    I43 @BASEBOARD_FAB2_LIB.BASEBOARD_FAB2(SCH_1):PAGE77
  J1G1  123 VSS<54> SCONN288_H44441004_PIP-SCONN,HA    I43 @BASEBOARD_FAB2_LIB.BASEBOARD_FAB2(SCH_1):PAGE77
  J1G1  120 VSS<55> SCONN288_H44441004_PIP-SCONN,HA    I43 @BASEBOARD_FAB2_LIB.BASEBOARD_FAB2(SCH_1):PAGE77
  J1G1  118 VSS<56> SCONN288_H44441004_PIP-SCONN,HA    I43 @BASEBOARD_FAB2_LIB.BASEBOARD_FAB2(SCH_1):PAGE77
  J1G1  116 VSS<57> SCONN288_H44441004_PIP-SCONN,HA    I43 @BASEBOARD_FAB2_LIB.BASEBOARD_FAB2(SCH_1):PAGE77
  J1G1  114 VSS<58> SCONN288_H44441004_PIP-SCONN,HA    I43 @BASEBOARD_FAB2_LIB.BASEBOARD_FAB2(SCH_1):PAGE77
  J1G1  112 VSS<59> SCONN288_H44441004_PIP-SCONN,HA    I43 @BASEBOARD_FAB2_LIB.BASEBOARD_FAB2(SCH_1):PAGE77
  J1G1  109 VSS<60> SCONN288_H44441004_PIP-SCONN,HA    I43 @BASEBOARD_FAB2_LIB.BASEBOARD_FAB2(SCH_1):PAGE77
  J1G1  107 VSS<61> SCONN288_H44441004_PIP-SCONN,HA    I43 @BASEBOARD_FAB2_LIB.BASEBOARD_FAB2(SCH_1):PAGE77
  J1G1  105 VSS<62> SCONN288_H44441004_PIP-SCONN,HA    I43 @BASEBOARD_FAB2_LIB.BASEBOARD_FAB2(SCH_1):PAGE77
  J1G1  103 VSS<63> SCONN288_H44441004_PIP-SCONN,HA    I43 @BASEBOARD_FAB2_LIB.BASEBOARD_FAB2(SCH_1):PAGE77
  J1G1  101 VSS<64> SCONN288_H44441004_PIP-SCONN,HA    I43 @BASEBOARD_FAB2_LIB.BASEBOARD_FAB2(SCH_1):PAGE77
  J1G1   98 VSS<65> SCONN288_H44441004_PIP-SCONN,HA    I43 @BASEBOARD_FAB2_LIB.BASEBOARD_FAB2(SCH_1):PAGE77
  J1G1   96 VSS<66> SCONN288_H44441004_PIP-SCONN,HA    I43 @BASEBOARD_FAB2_LIB.BASEBOARD_FAB2(SCH_1):PAGE77
  J1G1   94 VSS<67> SCONN288_H44441004_PIP-SCONN,HA    I43 @BASEBOARD_FAB2_LIB.BASEBOARD_FAB2(SCH_1):PAGE77
  J1G1   57 VSS<68> SCONN288_H44441004_PIP-SCONN,HA    I43 @BASEBOARD_FAB2_LIB.BASEBOARD_FAB2(SCH_1):PAGE77
  J1G1   55 VSS<69> SCONN288_H44441004_PIP-SCONN,HA    I43 @BASEBOARD_FAB2_LIB.BASEBOARD_FAB2(SCH_1):PAGE77
  J1G1   53 VSS<70> SCONN288_H44441004_PIP-SCONN,HA    I43 @BASEBOARD_FAB2_LIB.BASEBOARD_FAB2(SCH_1):PAGE77
  J1G1   50 VSS<71> SCONN288_H44441004_PIP-SCONN,HA    I43 @BASEBOARD_FAB2_LIB.BASEBOARD_FAB2(SCH_1):PAGE77
  J1G1   48 VSS<72> SCONN288_H44441004_PIP-SCONN,HA    I43 @BASEBOARD_FAB2_LIB.BASEBOARD_FAB2(SCH_1):PAGE77
  J1G1   46 VSS<73> SCONN288_H44441004_PIP-SCONN,HA    I43 @BASEBOARD_FAB2_LIB.BASEBOARD_FAB2(SCH_1):PAGE77
  J1G1   44 VSS<74> SCONN288_H44441004_PIP-SCONN,HA    I43 @BASEBOARD_FAB2_LIB.BASEBOARD_FAB2(SCH_1):PAGE77
  J1G1   42 VSS<75> SCONN288_H44441004_PIP-SCONN,HA    I43 @BASEBOARD_FAB2_LIB.BASEBOARD_FAB2(SCH_1):PAGE77
  J1G1   39 VSS<76> SCONN288_H44441004_PIP-SCONN,HA    I43 @BASEBOARD_FAB2_LIB.BASEBOARD_FAB2(SCH_1):PAGE77
  J1G1   37 VSS<77> SCONN288_H44441004_PIP-SCONN,HA    I43 @BASEBOARD_FAB2_LIB.BASEBOARD_FAB2(SCH_1):PAGE77
  J1G1   35 VSS<78> SCONN288_H44441004_PIP-SCONN,HA    I43 @BASEBOARD_FAB2_LIB.BASEBOARD_FAB2(SCH_1):PAGE77
  J1G1   33 VSS<79> SCONN288_H44441004_PIP-SCONN,HA    I43 @BASEBOARD_FAB2_LIB.BASEBOARD_FAB2(SCH_1):PAGE77
  J1G1   31 VSS<80> SCONN288_H44441004_PIP-SCONN,HA    I43 @BASEBOARD_FAB2_LIB.BASEBOARD_FAB2(SCH_1):PAGE77
  J1G1   28 VSS<81> SCONN288_H44441004_PIP-SCONN,HA    I43 @BASEBOARD_FAB2_LIB.BASEBOARD_FAB2(SCH_1):PAGE77
  J1G1   26 VSS<82> SCONN288_H44441004_PIP-SCONN,HA    I43 @BASEBOARD_FAB2_LIB.BASEBOARD_FAB2(SCH_1):PAGE77
  J1G1   24 VSS<83> SCONN288_H44441004_PIP-SCONN,HA    I43 @BASEBOARD_FAB2_LIB.BASEBOARD_FAB2(SCH_1):PAGE77
  J1G1   22 VSS<84> SCONN288_H44441004_PIP-SCONN,HA    I43 @BASEBOARD_FAB2_LIB.BASEBOARD_FAB2(SCH_1):PAGE77
  J1G1   20 VSS<85> SCONN288_H44441004_PIP-SCONN,HA    I43 @BASEBOARD_FAB2_LIB.BASEBOARD_FAB2(SCH_1):PAGE77
  J1G1   17 VSS<86> SCONN288_H44441004_PIP-SCONN,HA    I43 @BASEBOARD_FAB2_LIB.BASEBOARD_FAB2(SCH_1):PAGE77
  J1G1   15 VSS<87> SCONN288_H44441004_PIP-SCONN,HA    I43 @BASEBOARD_FAB2_LIB.BASEBOARD_FAB2(SCH_1):PAGE77
  J1G1   13 VSS<88> SCONN288_H44441004_PIP-SCONN,HA    I43 @BASEBOARD_FAB2_LIB.BASEBOARD_FAB2(SCH_1):PAGE77
  J1G1   11 VSS<89> SCONN288_H44441004_PIP-SCONN,HA    I43 @BASEBOARD_FAB2_LIB.BASEBOARD_FAB2(SCH_1):PAGE77
  J1G1    9 VSS<90> SCONN288_H44441004_PIP-SCONN,HA    I43 @BASEBOARD_FAB2_LIB.BASEBOARD_FAB2(SCH_1):PAGE77
  J1G1    6 VSS<91> SCONN288_H44441004_PIP-SCONN,HA    I43 @BASEBOARD_FAB2_LIB.BASEBOARD_FAB2(SCH_1):PAGE77
  J1G1    4 VSS<92> SCONN288_H44441004_PIP-SCONN,HA    I43 @BASEBOARD_FAB2_LIB.BASEBOARD_FAB2(SCH_1):PAGE77
  J1G1    2 VSS<93> SCONN288_H44441004_PIP-SCONN,HA    I43 @BASEBOARD_FAB2_LIB.BASEBOARD_FAB2(SCH_1):PAGE77
  J1G1  139  SA<0> SCONN288_H44441004_PIP-SCONN,HA   I111 @BASEBOARD_FAB2_LIB.BASEBOARD_FAB2(SCH_1):PAGE77
  J1G1  140  SA<1> SCONN288_H44441004_PIP-SCONN,HA   I111 @BASEBOARD_FAB2_LIB.BASEBOARD_FAB2(SCH_1):PAGE77
  J1G1  238  SA<2> SCONN288_H44441004_PIP-SCONN,HA   I111 @BASEBOARD_FAB2_LIB.BASEBOARD_FAB2(SCH_1):PAGE77
 C1F22    2      B CAP_A_0402V-0.01UF,25V,10%,X7RA   I181 @BASEBOARD_FAB2_LIB.BASEBOARD_FAB2(SCH_1):PAGE77
  C9T7    2      B CAP_A_0402V-0.01UF,25V,10%,X7RA     I2 @BASEBOARD_FAB2_LIB.BASEBOARD_FAB2(SCH_1):PAGE78
  J9T1  140  SA<1> SCONN288_H44441003_PIP-SCONN,HA    I13 @BASEBOARD_FAB2_LIB.BASEBOARD_FAB2(SCH_1):PAGE78
  J9T1  238  SA<2> SCONN288_H44441003_PIP-SCONN,HA    I13 @BASEBOARD_FAB2_LIB.BASEBOARD_FAB2(SCH_1):PAGE78
  J9T1  283 VSS<0> SCONN288_H44441003_PIP-SCONN,HA   I144 @BASEBOARD_FAB2_LIB.BASEBOARD_FAB2(SCH_1):PAGE78
  J9T1  281 VSS<1> SCONN288_H44441003_PIP-SCONN,HA   I144 @BASEBOARD_FAB2_LIB.BASEBOARD_FAB2(SCH_1):PAGE78
  J9T1  279 VSS<2> SCONN288_H44441003_PIP-SCONN,HA   I144 @BASEBOARD_FAB2_LIB.BASEBOARD_FAB2(SCH_1):PAGE78
  J9T1  276 VSS<3> SCONN288_H44441003_PIP-SCONN,HA   I144 @BASEBOARD_FAB2_LIB.BASEBOARD_FAB2(SCH_1):PAGE78
  J9T1  274 VSS<4> SCONN288_H44441003_PIP-SCONN,HA   I144 @BASEBOARD_FAB2_LIB.BASEBOARD_FAB2(SCH_1):PAGE78
  J9T1  272 VSS<5> SCONN288_H44441003_PIP-SCONN,HA   I144 @BASEBOARD_FAB2_LIB.BASEBOARD_FAB2(SCH_1):PAGE78
  J9T1  270 VSS<6> SCONN288_H44441003_PIP-SCONN,HA   I144 @BASEBOARD_FAB2_LIB.BASEBOARD_FAB2(SCH_1):PAGE78
  J9T1  268 VSS<7> SCONN288_H44441003_PIP-SCONN,HA   I144 @BASEBOARD_FAB2_LIB.BASEBOARD_FAB2(SCH_1):PAGE78
  J9T1  265 VSS<8> SCONN288_H44441003_PIP-SCONN,HA   I144 @BASEBOARD_FAB2_LIB.BASEBOARD_FAB2(SCH_1):PAGE78
  J9T1  263 VSS<9> SCONN288_H44441003_PIP-SCONN,HA   I144 @BASEBOARD_FAB2_LIB.BASEBOARD_FAB2(SCH_1):PAGE78
  J9T1  261 VSS<10> SCONN288_H44441003_PIP-SCONN,HA   I144 @BASEBOARD_FAB2_LIB.BASEBOARD_FAB2(SCH_1):PAGE78
  J9T1  259 VSS<11> SCONN288_H44441003_PIP-SCONN,HA   I144 @BASEBOARD_FAB2_LIB.BASEBOARD_FAB2(SCH_1):PAGE78
  J9T1  257 VSS<12> SCONN288_H44441003_PIP-SCONN,HA   I144 @BASEBOARD_FAB2_LIB.BASEBOARD_FAB2(SCH_1):PAGE78
  J9T1  254 VSS<13> SCONN288_H44441003_PIP-SCONN,HA   I144 @BASEBOARD_FAB2_LIB.BASEBOARD_FAB2(SCH_1):PAGE78
  J9T1  252 VSS<14> SCONN288_H44441003_PIP-SCONN,HA   I144 @BASEBOARD_FAB2_LIB.BASEBOARD_FAB2(SCH_1):PAGE78
  J9T1  250 VSS<15> SCONN288_H44441003_PIP-SCONN,HA   I144 @BASEBOARD_FAB2_LIB.BASEBOARD_FAB2(SCH_1):PAGE78
  J9T1  248 VSS<16> SCONN288_H44441003_PIP-SCONN,HA   I144 @BASEBOARD_FAB2_LIB.BASEBOARD_FAB2(SCH_1):PAGE78
  J9T1  246 VSS<17> SCONN288_H44441003_PIP-SCONN,HA   I144 @BASEBOARD_FAB2_LIB.BASEBOARD_FAB2(SCH_1):PAGE78
  J9T1  243 VSS<18> SCONN288_H44441003_PIP-SCONN,HA   I144 @BASEBOARD_FAB2_LIB.BASEBOARD_FAB2(SCH_1):PAGE78
  J9T1  241 VSS<19> SCONN288_H44441003_PIP-SCONN,HA   I144 @BASEBOARD_FAB2_LIB.BASEBOARD_FAB2(SCH_1):PAGE78
  J9T1  239 VSS<20> SCONN288_H44441003_PIP-SCONN,HA   I144 @BASEBOARD_FAB2_LIB.BASEBOARD_FAB2(SCH_1):PAGE78
  J9T1  202 VSS<21> SCONN288_H44441003_PIP-SCONN,HA   I144 @BASEBOARD_FAB2_LIB.BASEBOARD_FAB2(SCH_1):PAGE78
  J9T1  200 VSS<22> SCONN288_H44441003_PIP-SCONN,HA   I144 @BASEBOARD_FAB2_LIB.BASEBOARD_FAB2(SCH_1):PAGE78
  J9T1  198 VSS<23> SCONN288_H44441003_PIP-SCONN,HA   I144 @BASEBOARD_FAB2_LIB.BASEBOARD_FAB2(SCH_1):PAGE78
  J9T1  195 VSS<24> SCONN288_H44441003_PIP-SCONN,HA   I144 @BASEBOARD_FAB2_LIB.BASEBOARD_FAB2(SCH_1):PAGE78
  J9T1  193 VSS<25> SCONN288_H44441003_PIP-SCONN,HA   I144 @BASEBOARD_FAB2_LIB.BASEBOARD_FAB2(SCH_1):PAGE78
  J9T1  191 VSS<26> SCONN288_H44441003_PIP-SCONN,HA   I144 @BASEBOARD_FAB2_LIB.BASEBOARD_FAB2(SCH_1):PAGE78
  J9T1  189 VSS<27> SCONN288_H44441003_PIP-SCONN,HA   I144 @BASEBOARD_FAB2_LIB.BASEBOARD_FAB2(SCH_1):PAGE78
  J9T1  187 VSS<28> SCONN288_H44441003_PIP-SCONN,HA   I144 @BASEBOARD_FAB2_LIB.BASEBOARD_FAB2(SCH_1):PAGE78
  J9T1  184 VSS<29> SCONN288_H44441003_PIP-SCONN,HA   I144 @BASEBOARD_FAB2_LIB.BASEBOARD_FAB2(SCH_1):PAGE78
  J9T1  182 VSS<30> SCONN288_H44441003_PIP-SCONN,HA   I144 @BASEBOARD_FAB2_LIB.BASEBOARD_FAB2(SCH_1):PAGE78
  J9T1  180 VSS<31> SCONN288_H44441003_PIP-SCONN,HA   I144 @BASEBOARD_FAB2_LIB.BASEBOARD_FAB2(SCH_1):PAGE78
  J9T1  178 VSS<32> SCONN288_H44441003_PIP-SCONN,HA   I144 @BASEBOARD_FAB2_LIB.BASEBOARD_FAB2(SCH_1):PAGE78
  J9T1  176 VSS<33> SCONN288_H44441003_PIP-SCONN,HA   I144 @BASEBOARD_FAB2_LIB.BASEBOARD_FAB2(SCH_1):PAGE78
  J9T1  173 VSS<34> SCONN288_H44441003_PIP-SCONN,HA   I144 @BASEBOARD_FAB2_LIB.BASEBOARD_FAB2(SCH_1):PAGE78
  J9T1  171 VSS<35> SCONN288_H44441003_PIP-SCONN,HA   I144 @BASEBOARD_FAB2_LIB.BASEBOARD_FAB2(SCH_1):PAGE78
  J9T1  169 VSS<36> SCONN288_H44441003_PIP-SCONN,HA   I144 @BASEBOARD_FAB2_LIB.BASEBOARD_FAB2(SCH_1):PAGE78
  J9T1  167 VSS<37> SCONN288_H44441003_PIP-SCONN,HA   I144 @BASEBOARD_FAB2_LIB.BASEBOARD_FAB2(SCH_1):PAGE78
  J9T1  165 VSS<38> SCONN288_H44441003_PIP-SCONN,HA   I144 @BASEBOARD_FAB2_LIB.BASEBOARD_FAB2(SCH_1):PAGE78
  J9T1  162 VSS<39> SCONN288_H44441003_PIP-SCONN,HA   I144 @BASEBOARD_FAB2_LIB.BASEBOARD_FAB2(SCH_1):PAGE78
  J9T1  160 VSS<40> SCONN288_H44441003_PIP-SCONN,HA   I144 @BASEBOARD_FAB2_LIB.BASEBOARD_FAB2(SCH_1):PAGE78
  J9T1  158 VSS<41> SCONN288_H44441003_PIP-SCONN,HA   I144 @BASEBOARD_FAB2_LIB.BASEBOARD_FAB2(SCH_1):PAGE78
  J9T1  156 VSS<42> SCONN288_H44441003_PIP-SCONN,HA   I144 @BASEBOARD_FAB2_LIB.BASEBOARD_FAB2(SCH_1):PAGE78
  J9T1  154 VSS<43> SCONN288_H44441003_PIP-SCONN,HA   I144 @BASEBOARD_FAB2_LIB.BASEBOARD_FAB2(SCH_1):PAGE78
  J9T1  151 VSS<44> SCONN288_H44441003_PIP-SCONN,HA   I144 @BASEBOARD_FAB2_LIB.BASEBOARD_FAB2(SCH_1):PAGE78
  J9T1  149 VSS<45> SCONN288_H44441003_PIP-SCONN,HA   I144 @BASEBOARD_FAB2_LIB.BASEBOARD_FAB2(SCH_1):PAGE78
  J9T1  147 VSS<46> SCONN288_H44441003_PIP-SCONN,HA   I144 @BASEBOARD_FAB2_LIB.BASEBOARD_FAB2(SCH_1):PAGE78
  J9T1  138 VSS<47> SCONN288_H44441003_PIP-SCONN,HA   I144 @BASEBOARD_FAB2_LIB.BASEBOARD_FAB2(SCH_1):PAGE78
  J9T1  136 VSS<48> SCONN288_H44441003_PIP-SCONN,HA   I144 @BASEBOARD_FAB2_LIB.BASEBOARD_FAB2(SCH_1):PAGE78
  J9T1  134 VSS<49> SCONN288_H44441003_PIP-SCONN,HA   I144 @BASEBOARD_FAB2_LIB.BASEBOARD_FAB2(SCH_1):PAGE78
  J9T1  131 VSS<50> SCONN288_H44441003_PIP-SCONN,HA   I144 @BASEBOARD_FAB2_LIB.BASEBOARD_FAB2(SCH_1):PAGE78
  J9T1  129 VSS<51> SCONN288_H44441003_PIP-SCONN,HA   I144 @BASEBOARD_FAB2_LIB.BASEBOARD_FAB2(SCH_1):PAGE78
  J9T1  127 VSS<52> SCONN288_H44441003_PIP-SCONN,HA   I144 @BASEBOARD_FAB2_LIB.BASEBOARD_FAB2(SCH_1):PAGE78
  J9T1  125 VSS<53> SCONN288_H44441003_PIP-SCONN,HA   I144 @BASEBOARD_FAB2_LIB.BASEBOARD_FAB2(SCH_1):PAGE78
  J9T1  123 VSS<54> SCONN288_H44441003_PIP-SCONN,HA   I144 @BASEBOARD_FAB2_LIB.BASEBOARD_FAB2(SCH_1):PAGE78
  J9T1  120 VSS<55> SCONN288_H44441003_PIP-SCONN,HA   I144 @BASEBOARD_FAB2_LIB.BASEBOARD_FAB2(SCH_1):PAGE78
  J9T1  118 VSS<56> SCONN288_H44441003_PIP-SCONN,HA   I144 @BASEBOARD_FAB2_LIB.BASEBOARD_FAB2(SCH_1):PAGE78
  J9T1  116 VSS<57> SCONN288_H44441003_PIP-SCONN,HA   I144 @BASEBOARD_FAB2_LIB.BASEBOARD_FAB2(SCH_1):PAGE78
  J9T1  114 VSS<58> SCONN288_H44441003_PIP-SCONN,HA   I144 @BASEBOARD_FAB2_LIB.BASEBOARD_FAB2(SCH_1):PAGE78
  J9T1  112 VSS<59> SCONN288_H44441003_PIP-SCONN,HA   I144 @BASEBOARD_FAB2_LIB.BASEBOARD_FAB2(SCH_1):PAGE78
  J9T1  109 VSS<60> SCONN288_H44441003_PIP-SCONN,HA   I144 @BASEBOARD_FAB2_LIB.BASEBOARD_FAB2(SCH_1):PAGE78
  J9T1  107 VSS<61> SCONN288_H44441003_PIP-SCONN,HA   I144 @BASEBOARD_FAB2_LIB.BASEBOARD_FAB2(SCH_1):PAGE78
  J9T1  105 VSS<62> SCONN288_H44441003_PIP-SCONN,HA   I144 @BASEBOARD_FAB2_LIB.BASEBOARD_FAB2(SCH_1):PAGE78
  J9T1  103 VSS<63> SCONN288_H44441003_PIP-SCONN,HA   I144 @BASEBOARD_FAB2_LIB.BASEBOARD_FAB2(SCH_1):PAGE78
  J9T1  101 VSS<64> SCONN288_H44441003_PIP-SCONN,HA   I144 @BASEBOARD_FAB2_LIB.BASEBOARD_FAB2(SCH_1):PAGE78
  J9T1   98 VSS<65> SCONN288_H44441003_PIP-SCONN,HA   I144 @BASEBOARD_FAB2_LIB.BASEBOARD_FAB2(SCH_1):PAGE78
  J9T1   96 VSS<66> SCONN288_H44441003_PIP-SCONN,HA   I144 @BASEBOARD_FAB2_LIB.BASEBOARD_FAB2(SCH_1):PAGE78
  J9T1   94 VSS<67> SCONN288_H44441003_PIP-SCONN,HA   I144 @BASEBOARD_FAB2_LIB.BASEBOARD_FAB2(SCH_1):PAGE78
  J9T1   57 VSS<68> SCONN288_H44441003_PIP-SCONN,HA   I144 @BASEBOARD_FAB2_LIB.BASEBOARD_FAB2(SCH_1):PAGE78
  J9T1   55 VSS<69> SCONN288_H44441003_PIP-SCONN,HA   I144 @BASEBOARD_FAB2_LIB.BASEBOARD_FAB2(SCH_1):PAGE78
  J9T1   53 VSS<70> SCONN288_H44441003_PIP-SCONN,HA   I144 @BASEBOARD_FAB2_LIB.BASEBOARD_FAB2(SCH_1):PAGE78
  J9T1   50 VSS<71> SCONN288_H44441003_PIP-SCONN,HA   I144 @BASEBOARD_FAB2_LIB.BASEBOARD_FAB2(SCH_1):PAGE78
  J9T1   48 VSS<72> SCONN288_H44441003_PIP-SCONN,HA   I144 @BASEBOARD_FAB2_LIB.BASEBOARD_FAB2(SCH_1):PAGE78
  J9T1   46 VSS<73> SCONN288_H44441003_PIP-SCONN,HA   I144 @BASEBOARD_FAB2_LIB.BASEBOARD_FAB2(SCH_1):PAGE78
  J9T1   44 VSS<74> SCONN288_H44441003_PIP-SCONN,HA   I144 @BASEBOARD_FAB2_LIB.BASEBOARD_FAB2(SCH_1):PAGE78
  J9T1   42 VSS<75> SCONN288_H44441003_PIP-SCONN,HA   I144 @BASEBOARD_FAB2_LIB.BASEBOARD_FAB2(SCH_1):PAGE78
  J9T1   39 VSS<76> SCONN288_H44441003_PIP-SCONN,HA   I144 @BASEBOARD_FAB2_LIB.BASEBOARD_FAB2(SCH_1):PAGE78
  J9T1   37 VSS<77> SCONN288_H44441003_PIP-SCONN,HA   I144 @BASEBOARD_FAB2_LIB.BASEBOARD_FAB2(SCH_1):PAGE78
  J9T1   35 VSS<78> SCONN288_H44441003_PIP-SCONN,HA   I144 @BASEBOARD_FAB2_LIB.BASEBOARD_FAB2(SCH_1):PAGE78
  J9T1   33 VSS<79> SCONN288_H44441003_PIP-SCONN,HA   I144 @BASEBOARD_FAB2_LIB.BASEBOARD_FAB2(SCH_1):PAGE78
  J9T1   31 VSS<80> SCONN288_H44441003_PIP-SCONN,HA   I144 @BASEBOARD_FAB2_LIB.BASEBOARD_FAB2(SCH_1):PAGE78
  J9T1   28 VSS<81> SCONN288_H44441003_PIP-SCONN,HA   I144 @BASEBOARD_FAB2_LIB.BASEBOARD_FAB2(SCH_1):PAGE78
  J9T1   26 VSS<82> SCONN288_H44441003_PIP-SCONN,HA   I144 @BASEBOARD_FAB2_LIB.BASEBOARD_FAB2(SCH_1):PAGE78
  J9T1   24 VSS<83> SCONN288_H44441003_PIP-SCONN,HA   I144 @BASEBOARD_FAB2_LIB.BASEBOARD_FAB2(SCH_1):PAGE78
  J9T1   22 VSS<84> SCONN288_H44441003_PIP-SCONN,HA   I144 @BASEBOARD_FAB2_LIB.BASEBOARD_FAB2(SCH_1):PAGE78
  J9T1   20 VSS<85> SCONN288_H44441003_PIP-SCONN,HA   I144 @BASEBOARD_FAB2_LIB.BASEBOARD_FAB2(SCH_1):PAGE78
  J9T1   17 VSS<86> SCONN288_H44441003_PIP-SCONN,HA   I144 @BASEBOARD_FAB2_LIB.BASEBOARD_FAB2(SCH_1):PAGE78
  J9T1   15 VSS<87> SCONN288_H44441003_PIP-SCONN,HA   I144 @BASEBOARD_FAB2_LIB.BASEBOARD_FAB2(SCH_1):PAGE78
  J9T1   13 VSS<88> SCONN288_H44441003_PIP-SCONN,HA   I144 @BASEBOARD_FAB2_LIB.BASEBOARD_FAB2(SCH_1):PAGE78
  J9T1   11 VSS<89> SCONN288_H44441003_PIP-SCONN,HA   I144 @BASEBOARD_FAB2_LIB.BASEBOARD_FAB2(SCH_1):PAGE78
  J9T1    9 VSS<90> SCONN288_H44441003_PIP-SCONN,HA   I144 @BASEBOARD_FAB2_LIB.BASEBOARD_FAB2(SCH_1):PAGE78
  J9T1    6 VSS<91> SCONN288_H44441003_PIP-SCONN,HA   I144 @BASEBOARD_FAB2_LIB.BASEBOARD_FAB2(SCH_1):PAGE78
  J9T1    4 VSS<92> SCONN288_H44441003_PIP-SCONN,HA   I144 @BASEBOARD_FAB2_LIB.BASEBOARD_FAB2(SCH_1):PAGE78
  J9T1    2 VSS<93> SCONN288_H44441003_PIP-SCONN,HA   I144 @BASEBOARD_FAB2_LIB.BASEBOARD_FAB2(SCH_1):PAGE78
  J1G2  283 VSS<0> SCONN288_H44441004_PIP-SCONN,HA    I43 @BASEBOARD_FAB2_LIB.BASEBOARD_FAB2(SCH_1):PAGE79
  J1G2  281 VSS<1> SCONN288_H44441004_PIP-SCONN,HA    I43 @BASEBOARD_FAB2_LIB.BASEBOARD_FAB2(SCH_1):PAGE79
  J1G2  279 VSS<2> SCONN288_H44441004_PIP-SCONN,HA    I43 @BASEBOARD_FAB2_LIB.BASEBOARD_FAB2(SCH_1):PAGE79
  J1G2  276 VSS<3> SCONN288_H44441004_PIP-SCONN,HA    I43 @BASEBOARD_FAB2_LIB.BASEBOARD_FAB2(SCH_1):PAGE79
  J1G2  274 VSS<4> SCONN288_H44441004_PIP-SCONN,HA    I43 @BASEBOARD_FAB2_LIB.BASEBOARD_FAB2(SCH_1):PAGE79
  J1G2  272 VSS<5> SCONN288_H44441004_PIP-SCONN,HA    I43 @BASEBOARD_FAB2_LIB.BASEBOARD_FAB2(SCH_1):PAGE79
  J1G2  270 VSS<6> SCONN288_H44441004_PIP-SCONN,HA    I43 @BASEBOARD_FAB2_LIB.BASEBOARD_FAB2(SCH_1):PAGE79
  J1G2  268 VSS<7> SCONN288_H44441004_PIP-SCONN,HA    I43 @BASEBOARD_FAB2_LIB.BASEBOARD_FAB2(SCH_1):PAGE79
  J1G2  265 VSS<8> SCONN288_H44441004_PIP-SCONN,HA    I43 @BASEBOARD_FAB2_LIB.BASEBOARD_FAB2(SCH_1):PAGE79
  J1G2  263 VSS<9> SCONN288_H44441004_PIP-SCONN,HA    I43 @BASEBOARD_FAB2_LIB.BASEBOARD_FAB2(SCH_1):PAGE79
  J1G2  261 VSS<10> SCONN288_H44441004_PIP-SCONN,HA    I43 @BASEBOARD_FAB2_LIB.BASEBOARD_FAB2(SCH_1):PAGE79
  J1G2  259 VSS<11> SCONN288_H44441004_PIP-SCONN,HA    I43 @BASEBOARD_FAB2_LIB.BASEBOARD_FAB2(SCH_1):PAGE79
  J1G2  257 VSS<12> SCONN288_H44441004_PIP-SCONN,HA    I43 @BASEBOARD_FAB2_LIB.BASEBOARD_FAB2(SCH_1):PAGE79
  J1G2  254 VSS<13> SCONN288_H44441004_PIP-SCONN,HA    I43 @BASEBOARD_FAB2_LIB.BASEBOARD_FAB2(SCH_1):PAGE79
  J1G2  252 VSS<14> SCONN288_H44441004_PIP-SCONN,HA    I43 @BASEBOARD_FAB2_LIB.BASEBOARD_FAB2(SCH_1):PAGE79
  J1G2  250 VSS<15> SCONN288_H44441004_PIP-SCONN,HA    I43 @BASEBOARD_FAB2_LIB.BASEBOARD_FAB2(SCH_1):PAGE79
  J1G2  248 VSS<16> SCONN288_H44441004_PIP-SCONN,HA    I43 @BASEBOARD_FAB2_LIB.BASEBOARD_FAB2(SCH_1):PAGE79
  J1G2  246 VSS<17> SCONN288_H44441004_PIP-SCONN,HA    I43 @BASEBOARD_FAB2_LIB.BASEBOARD_FAB2(SCH_1):PAGE79
  J1G2  243 VSS<18> SCONN288_H44441004_PIP-SCONN,HA    I43 @BASEBOARD_FAB2_LIB.BASEBOARD_FAB2(SCH_1):PAGE79
  J1G2  241 VSS<19> SCONN288_H44441004_PIP-SCONN,HA    I43 @BASEBOARD_FAB2_LIB.BASEBOARD_FAB2(SCH_1):PAGE79
  J1G2  239 VSS<20> SCONN288_H44441004_PIP-SCONN,HA    I43 @BASEBOARD_FAB2_LIB.BASEBOARD_FAB2(SCH_1):PAGE79
  J1G2  202 VSS<21> SCONN288_H44441004_PIP-SCONN,HA    I43 @BASEBOARD_FAB2_LIB.BASEBOARD_FAB2(SCH_1):PAGE79
  J1G2  200 VSS<22> SCONN288_H44441004_PIP-SCONN,HA    I43 @BASEBOARD_FAB2_LIB.BASEBOARD_FAB2(SCH_1):PAGE79
  J1G2  198 VSS<23> SCONN288_H44441004_PIP-SCONN,HA    I43 @BASEBOARD_FAB2_LIB.BASEBOARD_FAB2(SCH_1):PAGE79
  J1G2  195 VSS<24> SCONN288_H44441004_PIP-SCONN,HA    I43 @BASEBOARD_FAB2_LIB.BASEBOARD_FAB2(SCH_1):PAGE79
  J1G2  193 VSS<25> SCONN288_H44441004_PIP-SCONN,HA    I43 @BASEBOARD_FAB2_LIB.BASEBOARD_FAB2(SCH_1):PAGE79
  J1G2  191 VSS<26> SCONN288_H44441004_PIP-SCONN,HA    I43 @BASEBOARD_FAB2_LIB.BASEBOARD_FAB2(SCH_1):PAGE79
  J1G2  189 VSS<27> SCONN288_H44441004_PIP-SCONN,HA    I43 @BASEBOARD_FAB2_LIB.BASEBOARD_FAB2(SCH_1):PAGE79
  J1G2  187 VSS<28> SCONN288_H44441004_PIP-SCONN,HA    I43 @BASEBOARD_FAB2_LIB.BASEBOARD_FAB2(SCH_1):PAGE79
  J1G2  184 VSS<29> SCONN288_H44441004_PIP-SCONN,HA    I43 @BASEBOARD_FAB2_LIB.BASEBOARD_FAB2(SCH_1):PAGE79
  J1G2  182 VSS<30> SCONN288_H44441004_PIP-SCONN,HA    I43 @BASEBOARD_FAB2_LIB.BASEBOARD_FAB2(SCH_1):PAGE79
  J1G2  180 VSS<31> SCONN288_H44441004_PIP-SCONN,HA    I43 @BASEBOARD_FAB2_LIB.BASEBOARD_FAB2(SCH_1):PAGE79
  J1G2  178 VSS<32> SCONN288_H44441004_PIP-SCONN,HA    I43 @BASEBOARD_FAB2_LIB.BASEBOARD_FAB2(SCH_1):PAGE79
  J1G2  176 VSS<33> SCONN288_H44441004_PIP-SCONN,HA    I43 @BASEBOARD_FAB2_LIB.BASEBOARD_FAB2(SCH_1):PAGE79
  J1G2  173 VSS<34> SCONN288_H44441004_PIP-SCONN,HA    I43 @BASEBOARD_FAB2_LIB.BASEBOARD_FAB2(SCH_1):PAGE79
  J1G2  171 VSS<35> SCONN288_H44441004_PIP-SCONN,HA    I43 @BASEBOARD_FAB2_LIB.BASEBOARD_FAB2(SCH_1):PAGE79
  J1G2  169 VSS<36> SCONN288_H44441004_PIP-SCONN,HA    I43 @BASEBOARD_FAB2_LIB.BASEBOARD_FAB2(SCH_1):PAGE79
  J1G2  167 VSS<37> SCONN288_H44441004_PIP-SCONN,HA    I43 @BASEBOARD_FAB2_LIB.BASEBOARD_FAB2(SCH_1):PAGE79
  J1G2  165 VSS<38> SCONN288_H44441004_PIP-SCONN,HA    I43 @BASEBOARD_FAB2_LIB.BASEBOARD_FAB2(SCH_1):PAGE79
  J1G2  162 VSS<39> SCONN288_H44441004_PIP-SCONN,HA    I43 @BASEBOARD_FAB2_LIB.BASEBOARD_FAB2(SCH_1):PAGE79
  J1G2  160 VSS<40> SCONN288_H44441004_PIP-SCONN,HA    I43 @BASEBOARD_FAB2_LIB.BASEBOARD_FAB2(SCH_1):PAGE79
  J1G2  158 VSS<41> SCONN288_H44441004_PIP-SCONN,HA    I43 @BASEBOARD_FAB2_LIB.BASEBOARD_FAB2(SCH_1):PAGE79
  J1G2  156 VSS<42> SCONN288_H44441004_PIP-SCONN,HA    I43 @BASEBOARD_FAB2_LIB.BASEBOARD_FAB2(SCH_1):PAGE79
  J1G2  154 VSS<43> SCONN288_H44441004_PIP-SCONN,HA    I43 @BASEBOARD_FAB2_LIB.BASEBOARD_FAB2(SCH_1):PAGE79
  J1G2  151 VSS<44> SCONN288_H44441004_PIP-SCONN,HA    I43 @BASEBOARD_FAB2_LIB.BASEBOARD_FAB2(SCH_1):PAGE79
  J1G2  149 VSS<45> SCONN288_H44441004_PIP-SCONN,HA    I43 @BASEBOARD_FAB2_LIB.BASEBOARD_FAB2(SCH_1):PAGE79
  J1G2  147 VSS<46> SCONN288_H44441004_PIP-SCONN,HA    I43 @BASEBOARD_FAB2_LIB.BASEBOARD_FAB2(SCH_1):PAGE79
  J1G2  138 VSS<47> SCONN288_H44441004_PIP-SCONN,HA    I43 @BASEBOARD_FAB2_LIB.BASEBOARD_FAB2(SCH_1):PAGE79
  J1G2  136 VSS<48> SCONN288_H44441004_PIP-SCONN,HA    I43 @BASEBOARD_FAB2_LIB.BASEBOARD_FAB2(SCH_1):PAGE79
  J1G2  134 VSS<49> SCONN288_H44441004_PIP-SCONN,HA    I43 @BASEBOARD_FAB2_LIB.BASEBOARD_FAB2(SCH_1):PAGE79
  J1G2  131 VSS<50> SCONN288_H44441004_PIP-SCONN,HA    I43 @BASEBOARD_FAB2_LIB.BASEBOARD_FAB2(SCH_1):PAGE79
  J1G2  129 VSS<51> SCONN288_H44441004_PIP-SCONN,HA    I43 @BASEBOARD_FAB2_LIB.BASEBOARD_FAB2(SCH_1):PAGE79
  J1G2  127 VSS<52> SCONN288_H44441004_PIP-SCONN,HA    I43 @BASEBOARD_FAB2_LIB.BASEBOARD_FAB2(SCH_1):PAGE79
  J1G2  125 VSS<53> SCONN288_H44441004_PIP-SCONN,HA    I43 @BASEBOARD_FAB2_LIB.BASEBOARD_FAB2(SCH_1):PAGE79
  J1G2  123 VSS<54> SCONN288_H44441004_PIP-SCONN,HA    I43 @BASEBOARD_FAB2_LIB.BASEBOARD_FAB2(SCH_1):PAGE79
  J1G2  120 VSS<55> SCONN288_H44441004_PIP-SCONN,HA    I43 @BASEBOARD_FAB2_LIB.BASEBOARD_FAB2(SCH_1):PAGE79
  J1G2  118 VSS<56> SCONN288_H44441004_PIP-SCONN,HA    I43 @BASEBOARD_FAB2_LIB.BASEBOARD_FAB2(SCH_1):PAGE79
  J1G2  116 VSS<57> SCONN288_H44441004_PIP-SCONN,HA    I43 @BASEBOARD_FAB2_LIB.BASEBOARD_FAB2(SCH_1):PAGE79
  J1G2  114 VSS<58> SCONN288_H44441004_PIP-SCONN,HA    I43 @BASEBOARD_FAB2_LIB.BASEBOARD_FAB2(SCH_1):PAGE79
  J1G2  112 VSS<59> SCONN288_H44441004_PIP-SCONN,HA    I43 @BASEBOARD_FAB2_LIB.BASEBOARD_FAB2(SCH_1):PAGE79
  J1G2  109 VSS<60> SCONN288_H44441004_PIP-SCONN,HA    I43 @BASEBOARD_FAB2_LIB.BASEBOARD_FAB2(SCH_1):PAGE79
  J1G2  107 VSS<61> SCONN288_H44441004_PIP-SCONN,HA    I43 @BASEBOARD_FAB2_LIB.BASEBOARD_FAB2(SCH_1):PAGE79
  J1G2  105 VSS<62> SCONN288_H44441004_PIP-SCONN,HA    I43 @BASEBOARD_FAB2_LIB.BASEBOARD_FAB2(SCH_1):PAGE79
  J1G2  103 VSS<63> SCONN288_H44441004_PIP-SCONN,HA    I43 @BASEBOARD_FAB2_LIB.BASEBOARD_FAB2(SCH_1):PAGE79
  J1G2  101 VSS<64> SCONN288_H44441004_PIP-SCONN,HA    I43 @BASEBOARD_FAB2_LIB.BASEBOARD_FAB2(SCH_1):PAGE79
  J1G2   98 VSS<65> SCONN288_H44441004_PIP-SCONN,HA    I43 @BASEBOARD_FAB2_LIB.BASEBOARD_FAB2(SCH_1):PAGE79
  J1G2   96 VSS<66> SCONN288_H44441004_PIP-SCONN,HA    I43 @BASEBOARD_FAB2_LIB.BASEBOARD_FAB2(SCH_1):PAGE79
  J1G2   94 VSS<67> SCONN288_H44441004_PIP-SCONN,HA    I43 @BASEBOARD_FAB2_LIB.BASEBOARD_FAB2(SCH_1):PAGE79
  J1G2   57 VSS<68> SCONN288_H44441004_PIP-SCONN,HA    I43 @BASEBOARD_FAB2_LIB.BASEBOARD_FAB2(SCH_1):PAGE79
  J1G2   55 VSS<69> SCONN288_H44441004_PIP-SCONN,HA    I43 @BASEBOARD_FAB2_LIB.BASEBOARD_FAB2(SCH_1):PAGE79
  J1G2   53 VSS<70> SCONN288_H44441004_PIP-SCONN,HA    I43 @BASEBOARD_FAB2_LIB.BASEBOARD_FAB2(SCH_1):PAGE79
  J1G2   50 VSS<71> SCONN288_H44441004_PIP-SCONN,HA    I43 @BASEBOARD_FAB2_LIB.BASEBOARD_FAB2(SCH_1):PAGE79
  J1G2   48 VSS<72> SCONN288_H44441004_PIP-SCONN,HA    I43 @BASEBOARD_FAB2_LIB.BASEBOARD_FAB2(SCH_1):PAGE79
  J1G2   46 VSS<73> SCONN288_H44441004_PIP-SCONN,HA    I43 @BASEBOARD_FAB2_LIB.BASEBOARD_FAB2(SCH_1):PAGE79
  J1G2   44 VSS<74> SCONN288_H44441004_PIP-SCONN,HA    I43 @BASEBOARD_FAB2_LIB.BASEBOARD_FAB2(SCH_1):PAGE79
  J1G2   42 VSS<75> SCONN288_H44441004_PIP-SCONN,HA    I43 @BASEBOARD_FAB2_LIB.BASEBOARD_FAB2(SCH_1):PAGE79
  J1G2   39 VSS<76> SCONN288_H44441004_PIP-SCONN,HA    I43 @BASEBOARD_FAB2_LIB.BASEBOARD_FAB2(SCH_1):PAGE79
  J1G2   37 VSS<77> SCONN288_H44441004_PIP-SCONN,HA    I43 @BASEBOARD_FAB2_LIB.BASEBOARD_FAB2(SCH_1):PAGE79
  J1G2   35 VSS<78> SCONN288_H44441004_PIP-SCONN,HA    I43 @BASEBOARD_FAB2_LIB.BASEBOARD_FAB2(SCH_1):PAGE79
  J1G2   33 VSS<79> SCONN288_H44441004_PIP-SCONN,HA    I43 @BASEBOARD_FAB2_LIB.BASEBOARD_FAB2(SCH_1):PAGE79
  J1G2   31 VSS<80> SCONN288_H44441004_PIP-SCONN,HA    I43 @BASEBOARD_FAB2_LIB.BASEBOARD_FAB2(SCH_1):PAGE79
  J1G2   28 VSS<81> SCONN288_H44441004_PIP-SCONN,HA    I43 @BASEBOARD_FAB2_LIB.BASEBOARD_FAB2(SCH_1):PAGE79
  J1G2   26 VSS<82> SCONN288_H44441004_PIP-SCONN,HA    I43 @BASEBOARD_FAB2_LIB.BASEBOARD_FAB2(SCH_1):PAGE79
  J1G2   24 VSS<83> SCONN288_H44441004_PIP-SCONN,HA    I43 @BASEBOARD_FAB2_LIB.BASEBOARD_FAB2(SCH_1):PAGE79
  J1G2   22 VSS<84> SCONN288_H44441004_PIP-SCONN,HA    I43 @BASEBOARD_FAB2_LIB.BASEBOARD_FAB2(SCH_1):PAGE79
  J1G2   20 VSS<85> SCONN288_H44441004_PIP-SCONN,HA    I43 @BASEBOARD_FAB2_LIB.BASEBOARD_FAB2(SCH_1):PAGE79
  J1G2   17 VSS<86> SCONN288_H44441004_PIP-SCONN,HA    I43 @BASEBOARD_FAB2_LIB.BASEBOARD_FAB2(SCH_1):PAGE79
  J1G2   15 VSS<87> SCONN288_H44441004_PIP-SCONN,HA    I43 @BASEBOARD_FAB2_LIB.BASEBOARD_FAB2(SCH_1):PAGE79
  J1G2   13 VSS<88> SCONN288_H44441004_PIP-SCONN,HA    I43 @BASEBOARD_FAB2_LIB.BASEBOARD_FAB2(SCH_1):PAGE79
  J1G2   11 VSS<89> SCONN288_H44441004_PIP-SCONN,HA    I43 @BASEBOARD_FAB2_LIB.BASEBOARD_FAB2(SCH_1):PAGE79
  J1G2    9 VSS<90> SCONN288_H44441004_PIP-SCONN,HA    I43 @BASEBOARD_FAB2_LIB.BASEBOARD_FAB2(SCH_1):PAGE79
  J1G2    6 VSS<91> SCONN288_H44441004_PIP-SCONN,HA    I43 @BASEBOARD_FAB2_LIB.BASEBOARD_FAB2(SCH_1):PAGE79
  J1G2    4 VSS<92> SCONN288_H44441004_PIP-SCONN,HA    I43 @BASEBOARD_FAB2_LIB.BASEBOARD_FAB2(SCH_1):PAGE79
  J1G2    2 VSS<93> SCONN288_H44441004_PIP-SCONN,HA    I43 @BASEBOARD_FAB2_LIB.BASEBOARD_FAB2(SCH_1):PAGE79
  J1G2  139  SA<0> SCONN288_H44441004_PIP-SCONN,HA   I111 @BASEBOARD_FAB2_LIB.BASEBOARD_FAB2(SCH_1):PAGE79
  J1G2  238  SA<2> SCONN288_H44441004_PIP-SCONN,HA   I111 @BASEBOARD_FAB2_LIB.BASEBOARD_FAB2(SCH_1):PAGE79
  C9U7    2      B CAP_A_0402V-0.01UF,25V,10%,X7RA   I178 @BASEBOARD_FAB2_LIB.BASEBOARD_FAB2(SCH_1):PAGE79
 C1G10    2      B CAP_A_0402V-0.01UF,25V,10%,X7RA     I3 @BASEBOARD_FAB2_LIB.BASEBOARD_FAB2(SCH_1):PAGE80
  J9U1  238  SA<2> SCONN288_H44441003_PIP-SCONN,HA    I24 @BASEBOARD_FAB2_LIB.BASEBOARD_FAB2(SCH_1):PAGE80
  J9U1  283 VSS<0> SCONN288_H44441003_PIP-SCONN,HA   I138 @BASEBOARD_FAB2_LIB.BASEBOARD_FAB2(SCH_1):PAGE80
  J9U1  281 VSS<1> SCONN288_H44441003_PIP-SCONN,HA   I138 @BASEBOARD_FAB2_LIB.BASEBOARD_FAB2(SCH_1):PAGE80
  J9U1  279 VSS<2> SCONN288_H44441003_PIP-SCONN,HA   I138 @BASEBOARD_FAB2_LIB.BASEBOARD_FAB2(SCH_1):PAGE80
  J9U1  276 VSS<3> SCONN288_H44441003_PIP-SCONN,HA   I138 @BASEBOARD_FAB2_LIB.BASEBOARD_FAB2(SCH_1):PAGE80
  J9U1  274 VSS<4> SCONN288_H44441003_PIP-SCONN,HA   I138 @BASEBOARD_FAB2_LIB.BASEBOARD_FAB2(SCH_1):PAGE80
  J9U1  272 VSS<5> SCONN288_H44441003_PIP-SCONN,HA   I138 @BASEBOARD_FAB2_LIB.BASEBOARD_FAB2(SCH_1):PAGE80
  J9U1  270 VSS<6> SCONN288_H44441003_PIP-SCONN,HA   I138 @BASEBOARD_FAB2_LIB.BASEBOARD_FAB2(SCH_1):PAGE80
  J9U1  268 VSS<7> SCONN288_H44441003_PIP-SCONN,HA   I138 @BASEBOARD_FAB2_LIB.BASEBOARD_FAB2(SCH_1):PAGE80
  J9U1  265 VSS<8> SCONN288_H44441003_PIP-SCONN,HA   I138 @BASEBOARD_FAB2_LIB.BASEBOARD_FAB2(SCH_1):PAGE80
  J9U1  263 VSS<9> SCONN288_H44441003_PIP-SCONN,HA   I138 @BASEBOARD_FAB2_LIB.BASEBOARD_FAB2(SCH_1):PAGE80
  J9U1  261 VSS<10> SCONN288_H44441003_PIP-SCONN,HA   I138 @BASEBOARD_FAB2_LIB.BASEBOARD_FAB2(SCH_1):PAGE80
  J9U1  259 VSS<11> SCONN288_H44441003_PIP-SCONN,HA   I138 @BASEBOARD_FAB2_LIB.BASEBOARD_FAB2(SCH_1):PAGE80
  J9U1  257 VSS<12> SCONN288_H44441003_PIP-SCONN,HA   I138 @BASEBOARD_FAB2_LIB.BASEBOARD_FAB2(SCH_1):PAGE80
  J9U1  254 VSS<13> SCONN288_H44441003_PIP-SCONN,HA   I138 @BASEBOARD_FAB2_LIB.BASEBOARD_FAB2(SCH_1):PAGE80
  J9U1  252 VSS<14> SCONN288_H44441003_PIP-SCONN,HA   I138 @BASEBOARD_FAB2_LIB.BASEBOARD_FAB2(SCH_1):PAGE80
  J9U1  250 VSS<15> SCONN288_H44441003_PIP-SCONN,HA   I138 @BASEBOARD_FAB2_LIB.BASEBOARD_FAB2(SCH_1):PAGE80
  J9U1  248 VSS<16> SCONN288_H44441003_PIP-SCONN,HA   I138 @BASEBOARD_FAB2_LIB.BASEBOARD_FAB2(SCH_1):PAGE80
  J9U1  246 VSS<17> SCONN288_H44441003_PIP-SCONN,HA   I138 @BASEBOARD_FAB2_LIB.BASEBOARD_FAB2(SCH_1):PAGE80
  J9U1  243 VSS<18> SCONN288_H44441003_PIP-SCONN,HA   I138 @BASEBOARD_FAB2_LIB.BASEBOARD_FAB2(SCH_1):PAGE80
  J9U1  241 VSS<19> SCONN288_H44441003_PIP-SCONN,HA   I138 @BASEBOARD_FAB2_LIB.BASEBOARD_FAB2(SCH_1):PAGE80
  J9U1  239 VSS<20> SCONN288_H44441003_PIP-SCONN,HA   I138 @BASEBOARD_FAB2_LIB.BASEBOARD_FAB2(SCH_1):PAGE80
  J9U1  202 VSS<21> SCONN288_H44441003_PIP-SCONN,HA   I138 @BASEBOARD_FAB2_LIB.BASEBOARD_FAB2(SCH_1):PAGE80
  J9U1  200 VSS<22> SCONN288_H44441003_PIP-SCONN,HA   I138 @BASEBOARD_FAB2_LIB.BASEBOARD_FAB2(SCH_1):PAGE80
  J9U1  198 VSS<23> SCONN288_H44441003_PIP-SCONN,HA   I138 @BASEBOARD_FAB2_LIB.BASEBOARD_FAB2(SCH_1):PAGE80
  J9U1  195 VSS<24> SCONN288_H44441003_PIP-SCONN,HA   I138 @BASEBOARD_FAB2_LIB.BASEBOARD_FAB2(SCH_1):PAGE80
  J9U1  193 VSS<25> SCONN288_H44441003_PIP-SCONN,HA   I138 @BASEBOARD_FAB2_LIB.BASEBOARD_FAB2(SCH_1):PAGE80
  J9U1  191 VSS<26> SCONN288_H44441003_PIP-SCONN,HA   I138 @BASEBOARD_FAB2_LIB.BASEBOARD_FAB2(SCH_1):PAGE80
  J9U1  189 VSS<27> SCONN288_H44441003_PIP-SCONN,HA   I138 @BASEBOARD_FAB2_LIB.BASEBOARD_FAB2(SCH_1):PAGE80
  J9U1  187 VSS<28> SCONN288_H44441003_PIP-SCONN,HA   I138 @BASEBOARD_FAB2_LIB.BASEBOARD_FAB2(SCH_1):PAGE80
  J9U1  184 VSS<29> SCONN288_H44441003_PIP-SCONN,HA   I138 @BASEBOARD_FAB2_LIB.BASEBOARD_FAB2(SCH_1):PAGE80
  J9U1  182 VSS<30> SCONN288_H44441003_PIP-SCONN,HA   I138 @BASEBOARD_FAB2_LIB.BASEBOARD_FAB2(SCH_1):PAGE80
  J9U1  180 VSS<31> SCONN288_H44441003_PIP-SCONN,HA   I138 @BASEBOARD_FAB2_LIB.BASEBOARD_FAB2(SCH_1):PAGE80
  J9U1  178 VSS<32> SCONN288_H44441003_PIP-SCONN,HA   I138 @BASEBOARD_FAB2_LIB.BASEBOARD_FAB2(SCH_1):PAGE80
  J9U1  176 VSS<33> SCONN288_H44441003_PIP-SCONN,HA   I138 @BASEBOARD_FAB2_LIB.BASEBOARD_FAB2(SCH_1):PAGE80
  J9U1  173 VSS<34> SCONN288_H44441003_PIP-SCONN,HA   I138 @BASEBOARD_FAB2_LIB.BASEBOARD_FAB2(SCH_1):PAGE80
  J9U1  171 VSS<35> SCONN288_H44441003_PIP-SCONN,HA   I138 @BASEBOARD_FAB2_LIB.BASEBOARD_FAB2(SCH_1):PAGE80
  J9U1  169 VSS<36> SCONN288_H44441003_PIP-SCONN,HA   I138 @BASEBOARD_FAB2_LIB.BASEBOARD_FAB2(SCH_1):PAGE80
  J9U1  167 VSS<37> SCONN288_H44441003_PIP-SCONN,HA   I138 @BASEBOARD_FAB2_LIB.BASEBOARD_FAB2(SCH_1):PAGE80
  J9U1  165 VSS<38> SCONN288_H44441003_PIP-SCONN,HA   I138 @BASEBOARD_FAB2_LIB.BASEBOARD_FAB2(SCH_1):PAGE80
  J9U1  162 VSS<39> SCONN288_H44441003_PIP-SCONN,HA   I138 @BASEBOARD_FAB2_LIB.BASEBOARD_FAB2(SCH_1):PAGE80
  J9U1  160 VSS<40> SCONN288_H44441003_PIP-SCONN,HA   I138 @BASEBOARD_FAB2_LIB.BASEBOARD_FAB2(SCH_1):PAGE80
  J9U1  158 VSS<41> SCONN288_H44441003_PIP-SCONN,HA   I138 @BASEBOARD_FAB2_LIB.BASEBOARD_FAB2(SCH_1):PAGE80
  J9U1  156 VSS<42> SCONN288_H44441003_PIP-SCONN,HA   I138 @BASEBOARD_FAB2_LIB.BASEBOARD_FAB2(SCH_1):PAGE80
  J9U1  154 VSS<43> SCONN288_H44441003_PIP-SCONN,HA   I138 @BASEBOARD_FAB2_LIB.BASEBOARD_FAB2(SCH_1):PAGE80
  J9U1  151 VSS<44> SCONN288_H44441003_PIP-SCONN,HA   I138 @BASEBOARD_FAB2_LIB.BASEBOARD_FAB2(SCH_1):PAGE80
  J9U1  149 VSS<45> SCONN288_H44441003_PIP-SCONN,HA   I138 @BASEBOARD_FAB2_LIB.BASEBOARD_FAB2(SCH_1):PAGE80
  J9U1  147 VSS<46> SCONN288_H44441003_PIP-SCONN,HA   I138 @BASEBOARD_FAB2_LIB.BASEBOARD_FAB2(SCH_1):PAGE80
  J9U1  138 VSS<47> SCONN288_H44441003_PIP-SCONN,HA   I138 @BASEBOARD_FAB2_LIB.BASEBOARD_FAB2(SCH_1):PAGE80
  J9U1  136 VSS<48> SCONN288_H44441003_PIP-SCONN,HA   I138 @BASEBOARD_FAB2_LIB.BASEBOARD_FAB2(SCH_1):PAGE80
  J9U1  134 VSS<49> SCONN288_H44441003_PIP-SCONN,HA   I138 @BASEBOARD_FAB2_LIB.BASEBOARD_FAB2(SCH_1):PAGE80
  J9U1  131 VSS<50> SCONN288_H44441003_PIP-SCONN,HA   I138 @BASEBOARD_FAB2_LIB.BASEBOARD_FAB2(SCH_1):PAGE80
  J9U1  129 VSS<51> SCONN288_H44441003_PIP-SCONN,HA   I138 @BASEBOARD_FAB2_LIB.BASEBOARD_FAB2(SCH_1):PAGE80
  J9U1  127 VSS<52> SCONN288_H44441003_PIP-SCONN,HA   I138 @BASEBOARD_FAB2_LIB.BASEBOARD_FAB2(SCH_1):PAGE80
  J9U1  125 VSS<53> SCONN288_H44441003_PIP-SCONN,HA   I138 @BASEBOARD_FAB2_LIB.BASEBOARD_FAB2(SCH_1):PAGE80
  J9U1  123 VSS<54> SCONN288_H44441003_PIP-SCONN,HA   I138 @BASEBOARD_FAB2_LIB.BASEBOARD_FAB2(SCH_1):PAGE80
  J9U1  120 VSS<55> SCONN288_H44441003_PIP-SCONN,HA   I138 @BASEBOARD_FAB2_LIB.BASEBOARD_FAB2(SCH_1):PAGE80
  J9U1  118 VSS<56> SCONN288_H44441003_PIP-SCONN,HA   I138 @BASEBOARD_FAB2_LIB.BASEBOARD_FAB2(SCH_1):PAGE80
  J9U1  116 VSS<57> SCONN288_H44441003_PIP-SCONN,HA   I138 @BASEBOARD_FAB2_LIB.BASEBOARD_FAB2(SCH_1):PAGE80
  J9U1  114 VSS<58> SCONN288_H44441003_PIP-SCONN,HA   I138 @BASEBOARD_FAB2_LIB.BASEBOARD_FAB2(SCH_1):PAGE80
  J9U1  112 VSS<59> SCONN288_H44441003_PIP-SCONN,HA   I138 @BASEBOARD_FAB2_LIB.BASEBOARD_FAB2(SCH_1):PAGE80
  J9U1  109 VSS<60> SCONN288_H44441003_PIP-SCONN,HA   I138 @BASEBOARD_FAB2_LIB.BASEBOARD_FAB2(SCH_1):PAGE80
  J9U1  107 VSS<61> SCONN288_H44441003_PIP-SCONN,HA   I138 @BASEBOARD_FAB2_LIB.BASEBOARD_FAB2(SCH_1):PAGE80
  J9U1  105 VSS<62> SCONN288_H44441003_PIP-SCONN,HA   I138 @BASEBOARD_FAB2_LIB.BASEBOARD_FAB2(SCH_1):PAGE80
  J9U1  103 VSS<63> SCONN288_H44441003_PIP-SCONN,HA   I138 @BASEBOARD_FAB2_LIB.BASEBOARD_FAB2(SCH_1):PAGE80
  J9U1  101 VSS<64> SCONN288_H44441003_PIP-SCONN,HA   I138 @BASEBOARD_FAB2_LIB.BASEBOARD_FAB2(SCH_1):PAGE80
  J9U1   98 VSS<65> SCONN288_H44441003_PIP-SCONN,HA   I138 @BASEBOARD_FAB2_LIB.BASEBOARD_FAB2(SCH_1):PAGE80
  J9U1   96 VSS<66> SCONN288_H44441003_PIP-SCONN,HA   I138 @BASEBOARD_FAB2_LIB.BASEBOARD_FAB2(SCH_1):PAGE80
  J9U1   94 VSS<67> SCONN288_H44441003_PIP-SCONN,HA   I138 @BASEBOARD_FAB2_LIB.BASEBOARD_FAB2(SCH_1):PAGE80
  J9U1   57 VSS<68> SCONN288_H44441003_PIP-SCONN,HA   I138 @BASEBOARD_FAB2_LIB.BASEBOARD_FAB2(SCH_1):PAGE80
  J9U1   55 VSS<69> SCONN288_H44441003_PIP-SCONN,HA   I138 @BASEBOARD_FAB2_LIB.BASEBOARD_FAB2(SCH_1):PAGE80
  J9U1   53 VSS<70> SCONN288_H44441003_PIP-SCONN,HA   I138 @BASEBOARD_FAB2_LIB.BASEBOARD_FAB2(SCH_1):PAGE80
  J9U1   50 VSS<71> SCONN288_H44441003_PIP-SCONN,HA   I138 @BASEBOARD_FAB2_LIB.BASEBOARD_FAB2(SCH_1):PAGE80
  J9U1   48 VSS<72> SCONN288_H44441003_PIP-SCONN,HA   I138 @BASEBOARD_FAB2_LIB.BASEBOARD_FAB2(SCH_1):PAGE80
  J9U1   46 VSS<73> SCONN288_H44441003_PIP-SCONN,HA   I138 @BASEBOARD_FAB2_LIB.BASEBOARD_FAB2(SCH_1):PAGE80
  J9U1   44 VSS<74> SCONN288_H44441003_PIP-SCONN,HA   I138 @BASEBOARD_FAB2_LIB.BASEBOARD_FAB2(SCH_1):PAGE80
  J9U1   42 VSS<75> SCONN288_H44441003_PIP-SCONN,HA   I138 @BASEBOARD_FAB2_LIB.BASEBOARD_FAB2(SCH_1):PAGE80
  J9U1   39 VSS<76> SCONN288_H44441003_PIP-SCONN,HA   I138 @BASEBOARD_FAB2_LIB.BASEBOARD_FAB2(SCH_1):PAGE80
  J9U1   37 VSS<77> SCONN288_H44441003_PIP-SCONN,HA   I138 @BASEBOARD_FAB2_LIB.BASEBOARD_FAB2(SCH_1):PAGE80
  J9U1   35 VSS<78> SCONN288_H44441003_PIP-SCONN,HA   I138 @BASEBOARD_FAB2_LIB.BASEBOARD_FAB2(SCH_1):PAGE80
  J9U1   33 VSS<79> SCONN288_H44441003_PIP-SCONN,HA   I138 @BASEBOARD_FAB2_LIB.BASEBOARD_FAB2(SCH_1):PAGE80
  J9U1   31 VSS<80> SCONN288_H44441003_PIP-SCONN,HA   I138 @BASEBOARD_FAB2_LIB.BASEBOARD_FAB2(SCH_1):PAGE80
  J9U1   28 VSS<81> SCONN288_H44441003_PIP-SCONN,HA   I138 @BASEBOARD_FAB2_LIB.BASEBOARD_FAB2(SCH_1):PAGE80
  J9U1   26 VSS<82> SCONN288_H44441003_PIP-SCONN,HA   I138 @BASEBOARD_FAB2_LIB.BASEBOARD_FAB2(SCH_1):PAGE80
  J9U1   24 VSS<83> SCONN288_H44441003_PIP-SCONN,HA   I138 @BASEBOARD_FAB2_LIB.BASEBOARD_FAB2(SCH_1):PAGE80
  J9U1   22 VSS<84> SCONN288_H44441003_PIP-SCONN,HA   I138 @BASEBOARD_FAB2_LIB.BASEBOARD_FAB2(SCH_1):PAGE80
  J9U1   20 VSS<85> SCONN288_H44441003_PIP-SCONN,HA   I138 @BASEBOARD_FAB2_LIB.BASEBOARD_FAB2(SCH_1):PAGE80
  J9U1   17 VSS<86> SCONN288_H44441003_PIP-SCONN,HA   I138 @BASEBOARD_FAB2_LIB.BASEBOARD_FAB2(SCH_1):PAGE80
  J9U1   15 VSS<87> SCONN288_H44441003_PIP-SCONN,HA   I138 @BASEBOARD_FAB2_LIB.BASEBOARD_FAB2(SCH_1):PAGE80
  J9U1   13 VSS<88> SCONN288_H44441003_PIP-SCONN,HA   I138 @BASEBOARD_FAB2_LIB.BASEBOARD_FAB2(SCH_1):PAGE80
  J9U1   11 VSS<89> SCONN288_H44441003_PIP-SCONN,HA   I138 @BASEBOARD_FAB2_LIB.BASEBOARD_FAB2(SCH_1):PAGE80
  J9U1    9 VSS<90> SCONN288_H44441003_PIP-SCONN,HA   I138 @BASEBOARD_FAB2_LIB.BASEBOARD_FAB2(SCH_1):PAGE80
  J9U1    6 VSS<91> SCONN288_H44441003_PIP-SCONN,HA   I138 @BASEBOARD_FAB2_LIB.BASEBOARD_FAB2(SCH_1):PAGE80
  J9U1    4 VSS<92> SCONN288_H44441003_PIP-SCONN,HA   I138 @BASEBOARD_FAB2_LIB.BASEBOARD_FAB2(SCH_1):PAGE80
  J9U1    2 VSS<93> SCONN288_H44441003_PIP-SCONN,HA   I138 @BASEBOARD_FAB2_LIB.BASEBOARD_FAB2(SCH_1):PAGE80
 C9U10    2      B CAP_A_0402V-0.01UF,25V,10%,X7RA   I178 @BASEBOARD_FAB2_LIB.BASEBOARD_FAB2(SCH_1):PAGE81
  J1G3  283 VSS<0> SCONN288_H44441004_PIP-SCONN,HA   I185 @BASEBOARD_FAB2_LIB.BASEBOARD_FAB2(SCH_1):PAGE81
  J1G3  281 VSS<1> SCONN288_H44441004_PIP-SCONN,HA   I185 @BASEBOARD_FAB2_LIB.BASEBOARD_FAB2(SCH_1):PAGE81
  J1G3  279 VSS<2> SCONN288_H44441004_PIP-SCONN,HA   I185 @BASEBOARD_FAB2_LIB.BASEBOARD_FAB2(SCH_1):PAGE81
  J1G3  276 VSS<3> SCONN288_H44441004_PIP-SCONN,HA   I185 @BASEBOARD_FAB2_LIB.BASEBOARD_FAB2(SCH_1):PAGE81
  J1G3  274 VSS<4> SCONN288_H44441004_PIP-SCONN,HA   I185 @BASEBOARD_FAB2_LIB.BASEBOARD_FAB2(SCH_1):PAGE81
  J1G3  272 VSS<5> SCONN288_H44441004_PIP-SCONN,HA   I185 @BASEBOARD_FAB2_LIB.BASEBOARD_FAB2(SCH_1):PAGE81
  J1G3  270 VSS<6> SCONN288_H44441004_PIP-SCONN,HA   I185 @BASEBOARD_FAB2_LIB.BASEBOARD_FAB2(SCH_1):PAGE81
  J1G3  268 VSS<7> SCONN288_H44441004_PIP-SCONN,HA   I185 @BASEBOARD_FAB2_LIB.BASEBOARD_FAB2(SCH_1):PAGE81
  J1G3  265 VSS<8> SCONN288_H44441004_PIP-SCONN,HA   I185 @BASEBOARD_FAB2_LIB.BASEBOARD_FAB2(SCH_1):PAGE81
  J1G3  263 VSS<9> SCONN288_H44441004_PIP-SCONN,HA   I185 @BASEBOARD_FAB2_LIB.BASEBOARD_FAB2(SCH_1):PAGE81
  J1G3  261 VSS<10> SCONN288_H44441004_PIP-SCONN,HA   I185 @BASEBOARD_FAB2_LIB.BASEBOARD_FAB2(SCH_1):PAGE81
  J1G3  259 VSS<11> SCONN288_H44441004_PIP-SCONN,HA   I185 @BASEBOARD_FAB2_LIB.BASEBOARD_FAB2(SCH_1):PAGE81
  J1G3  257 VSS<12> SCONN288_H44441004_PIP-SCONN,HA   I185 @BASEBOARD_FAB2_LIB.BASEBOARD_FAB2(SCH_1):PAGE81
  J1G3  254 VSS<13> SCONN288_H44441004_PIP-SCONN,HA   I185 @BASEBOARD_FAB2_LIB.BASEBOARD_FAB2(SCH_1):PAGE81
  J1G3  252 VSS<14> SCONN288_H44441004_PIP-SCONN,HA   I185 @BASEBOARD_FAB2_LIB.BASEBOARD_FAB2(SCH_1):PAGE81
  J1G3  250 VSS<15> SCONN288_H44441004_PIP-SCONN,HA   I185 @BASEBOARD_FAB2_LIB.BASEBOARD_FAB2(SCH_1):PAGE81
  J1G3  248 VSS<16> SCONN288_H44441004_PIP-SCONN,HA   I185 @BASEBOARD_FAB2_LIB.BASEBOARD_FAB2(SCH_1):PAGE81
  J1G3  246 VSS<17> SCONN288_H44441004_PIP-SCONN,HA   I185 @BASEBOARD_FAB2_LIB.BASEBOARD_FAB2(SCH_1):PAGE81
  J1G3  243 VSS<18> SCONN288_H44441004_PIP-SCONN,HA   I185 @BASEBOARD_FAB2_LIB.BASEBOARD_FAB2(SCH_1):PAGE81
  J1G3  241 VSS<19> SCONN288_H44441004_PIP-SCONN,HA   I185 @BASEBOARD_FAB2_LIB.BASEBOARD_FAB2(SCH_1):PAGE81
  J1G3  239 VSS<20> SCONN288_H44441004_PIP-SCONN,HA   I185 @BASEBOARD_FAB2_LIB.BASEBOARD_FAB2(SCH_1):PAGE81
  J1G3  202 VSS<21> SCONN288_H44441004_PIP-SCONN,HA   I185 @BASEBOARD_FAB2_LIB.BASEBOARD_FAB2(SCH_1):PAGE81
  J1G3  200 VSS<22> SCONN288_H44441004_PIP-SCONN,HA   I185 @BASEBOARD_FAB2_LIB.BASEBOARD_FAB2(SCH_1):PAGE81
  J1G3  198 VSS<23> SCONN288_H44441004_PIP-SCONN,HA   I185 @BASEBOARD_FAB2_LIB.BASEBOARD_FAB2(SCH_1):PAGE81
  J1G3  195 VSS<24> SCONN288_H44441004_PIP-SCONN,HA   I185 @BASEBOARD_FAB2_LIB.BASEBOARD_FAB2(SCH_1):PAGE81
  J1G3  193 VSS<25> SCONN288_H44441004_PIP-SCONN,HA   I185 @BASEBOARD_FAB2_LIB.BASEBOARD_FAB2(SCH_1):PAGE81
  J1G3  191 VSS<26> SCONN288_H44441004_PIP-SCONN,HA   I185 @BASEBOARD_FAB2_LIB.BASEBOARD_FAB2(SCH_1):PAGE81
  J1G3  189 VSS<27> SCONN288_H44441004_PIP-SCONN,HA   I185 @BASEBOARD_FAB2_LIB.BASEBOARD_FAB2(SCH_1):PAGE81
  J1G3  187 VSS<28> SCONN288_H44441004_PIP-SCONN,HA   I185 @BASEBOARD_FAB2_LIB.BASEBOARD_FAB2(SCH_1):PAGE81
  J1G3  184 VSS<29> SCONN288_H44441004_PIP-SCONN,HA   I185 @BASEBOARD_FAB2_LIB.BASEBOARD_FAB2(SCH_1):PAGE81
  J1G3  182 VSS<30> SCONN288_H44441004_PIP-SCONN,HA   I185 @BASEBOARD_FAB2_LIB.BASEBOARD_FAB2(SCH_1):PAGE81
  J1G3  180 VSS<31> SCONN288_H44441004_PIP-SCONN,HA   I185 @BASEBOARD_FAB2_LIB.BASEBOARD_FAB2(SCH_1):PAGE81
  J1G3  178 VSS<32> SCONN288_H44441004_PIP-SCONN,HA   I185 @BASEBOARD_FAB2_LIB.BASEBOARD_FAB2(SCH_1):PAGE81
  J1G3  176 VSS<33> SCONN288_H44441004_PIP-SCONN,HA   I185 @BASEBOARD_FAB2_LIB.BASEBOARD_FAB2(SCH_1):PAGE81
  J1G3  173 VSS<34> SCONN288_H44441004_PIP-SCONN,HA   I185 @BASEBOARD_FAB2_LIB.BASEBOARD_FAB2(SCH_1):PAGE81
  J1G3  171 VSS<35> SCONN288_H44441004_PIP-SCONN,HA   I185 @BASEBOARD_FAB2_LIB.BASEBOARD_FAB2(SCH_1):PAGE81
  J1G3  169 VSS<36> SCONN288_H44441004_PIP-SCONN,HA   I185 @BASEBOARD_FAB2_LIB.BASEBOARD_FAB2(SCH_1):PAGE81
  J1G3  167 VSS<37> SCONN288_H44441004_PIP-SCONN,HA   I185 @BASEBOARD_FAB2_LIB.BASEBOARD_FAB2(SCH_1):PAGE81
  J1G3  165 VSS<38> SCONN288_H44441004_PIP-SCONN,HA   I185 @BASEBOARD_FAB2_LIB.BASEBOARD_FAB2(SCH_1):PAGE81
  J1G3  162 VSS<39> SCONN288_H44441004_PIP-SCONN,HA   I185 @BASEBOARD_FAB2_LIB.BASEBOARD_FAB2(SCH_1):PAGE81
  J1G3  160 VSS<40> SCONN288_H44441004_PIP-SCONN,HA   I185 @BASEBOARD_FAB2_LIB.BASEBOARD_FAB2(SCH_1):PAGE81
  J1G3  158 VSS<41> SCONN288_H44441004_PIP-SCONN,HA   I185 @BASEBOARD_FAB2_LIB.BASEBOARD_FAB2(SCH_1):PAGE81
  J1G3  156 VSS<42> SCONN288_H44441004_PIP-SCONN,HA   I185 @BASEBOARD_FAB2_LIB.BASEBOARD_FAB2(SCH_1):PAGE81
  J1G3  154 VSS<43> SCONN288_H44441004_PIP-SCONN,HA   I185 @BASEBOARD_FAB2_LIB.BASEBOARD_FAB2(SCH_1):PAGE81
  J1G3  151 VSS<44> SCONN288_H44441004_PIP-SCONN,HA   I185 @BASEBOARD_FAB2_LIB.BASEBOARD_FAB2(SCH_1):PAGE81
  J1G3  149 VSS<45> SCONN288_H44441004_PIP-SCONN,HA   I185 @BASEBOARD_FAB2_LIB.BASEBOARD_FAB2(SCH_1):PAGE81
  J1G3  147 VSS<46> SCONN288_H44441004_PIP-SCONN,HA   I185 @BASEBOARD_FAB2_LIB.BASEBOARD_FAB2(SCH_1):PAGE81
  J1G3  138 VSS<47> SCONN288_H44441004_PIP-SCONN,HA   I185 @BASEBOARD_FAB2_LIB.BASEBOARD_FAB2(SCH_1):PAGE81
  J1G3  136 VSS<48> SCONN288_H44441004_PIP-SCONN,HA   I185 @BASEBOARD_FAB2_LIB.BASEBOARD_FAB2(SCH_1):PAGE81
  J1G3  134 VSS<49> SCONN288_H44441004_PIP-SCONN,HA   I185 @BASEBOARD_FAB2_LIB.BASEBOARD_FAB2(SCH_1):PAGE81
  J1G3  131 VSS<50> SCONN288_H44441004_PIP-SCONN,HA   I185 @BASEBOARD_FAB2_LIB.BASEBOARD_FAB2(SCH_1):PAGE81
  J1G3  129 VSS<51> SCONN288_H44441004_PIP-SCONN,HA   I185 @BASEBOARD_FAB2_LIB.BASEBOARD_FAB2(SCH_1):PAGE81
  J1G3  127 VSS<52> SCONN288_H44441004_PIP-SCONN,HA   I185 @BASEBOARD_FAB2_LIB.BASEBOARD_FAB2(SCH_1):PAGE81
  J1G3  125 VSS<53> SCONN288_H44441004_PIP-SCONN,HA   I185 @BASEBOARD_FAB2_LIB.BASEBOARD_FAB2(SCH_1):PAGE81
  J1G3  123 VSS<54> SCONN288_H44441004_PIP-SCONN,HA   I185 @BASEBOARD_FAB2_LIB.BASEBOARD_FAB2(SCH_1):PAGE81
  J1G3  120 VSS<55> SCONN288_H44441004_PIP-SCONN,HA   I185 @BASEBOARD_FAB2_LIB.BASEBOARD_FAB2(SCH_1):PAGE81
  J1G3  118 VSS<56> SCONN288_H44441004_PIP-SCONN,HA   I185 @BASEBOARD_FAB2_LIB.BASEBOARD_FAB2(SCH_1):PAGE81
  J1G3  116 VSS<57> SCONN288_H44441004_PIP-SCONN,HA   I185 @BASEBOARD_FAB2_LIB.BASEBOARD_FAB2(SCH_1):PAGE81
  J1G3  114 VSS<58> SCONN288_H44441004_PIP-SCONN,HA   I185 @BASEBOARD_FAB2_LIB.BASEBOARD_FAB2(SCH_1):PAGE81
  J1G3  112 VSS<59> SCONN288_H44441004_PIP-SCONN,HA   I185 @BASEBOARD_FAB2_LIB.BASEBOARD_FAB2(SCH_1):PAGE81
  J1G3  109 VSS<60> SCONN288_H44441004_PIP-SCONN,HA   I185 @BASEBOARD_FAB2_LIB.BASEBOARD_FAB2(SCH_1):PAGE81
  J1G3  107 VSS<61> SCONN288_H44441004_PIP-SCONN,HA   I185 @BASEBOARD_FAB2_LIB.BASEBOARD_FAB2(SCH_1):PAGE81
  J1G3  105 VSS<62> SCONN288_H44441004_PIP-SCONN,HA   I185 @BASEBOARD_FAB2_LIB.BASEBOARD_FAB2(SCH_1):PAGE81
  J1G3  103 VSS<63> SCONN288_H44441004_PIP-SCONN,HA   I185 @BASEBOARD_FAB2_LIB.BASEBOARD_FAB2(SCH_1):PAGE81
  J1G3  101 VSS<64> SCONN288_H44441004_PIP-SCONN,HA   I185 @BASEBOARD_FAB2_LIB.BASEBOARD_FAB2(SCH_1):PAGE81
  J1G3   98 VSS<65> SCONN288_H44441004_PIP-SCONN,HA   I185 @BASEBOARD_FAB2_LIB.BASEBOARD_FAB2(SCH_1):PAGE81
  J1G3   96 VSS<66> SCONN288_H44441004_PIP-SCONN,HA   I185 @BASEBOARD_FAB2_LIB.BASEBOARD_FAB2(SCH_1):PAGE81
  J1G3   94 VSS<67> SCONN288_H44441004_PIP-SCONN,HA   I185 @BASEBOARD_FAB2_LIB.BASEBOARD_FAB2(SCH_1):PAGE81
  J1G3   57 VSS<68> SCONN288_H44441004_PIP-SCONN,HA   I185 @BASEBOARD_FAB2_LIB.BASEBOARD_FAB2(SCH_1):PAGE81
  J1G3   55 VSS<69> SCONN288_H44441004_PIP-SCONN,HA   I185 @BASEBOARD_FAB2_LIB.BASEBOARD_FAB2(SCH_1):PAGE81
  J1G3   53 VSS<70> SCONN288_H44441004_PIP-SCONN,HA   I185 @BASEBOARD_FAB2_LIB.BASEBOARD_FAB2(SCH_1):PAGE81
  J1G3   50 VSS<71> SCONN288_H44441004_PIP-SCONN,HA   I185 @BASEBOARD_FAB2_LIB.BASEBOARD_FAB2(SCH_1):PAGE81
  J1G3   48 VSS<72> SCONN288_H44441004_PIP-SCONN,HA   I185 @BASEBOARD_FAB2_LIB.BASEBOARD_FAB2(SCH_1):PAGE81
  J1G3   46 VSS<73> SCONN288_H44441004_PIP-SCONN,HA   I185 @BASEBOARD_FAB2_LIB.BASEBOARD_FAB2(SCH_1):PAGE81
  J1G3   44 VSS<74> SCONN288_H44441004_PIP-SCONN,HA   I185 @BASEBOARD_FAB2_LIB.BASEBOARD_FAB2(SCH_1):PAGE81
  J1G3   42 VSS<75> SCONN288_H44441004_PIP-SCONN,HA   I185 @BASEBOARD_FAB2_LIB.BASEBOARD_FAB2(SCH_1):PAGE81
  J1G3   39 VSS<76> SCONN288_H44441004_PIP-SCONN,HA   I185 @BASEBOARD_FAB2_LIB.BASEBOARD_FAB2(SCH_1):PAGE81
  J1G3   37 VSS<77> SCONN288_H44441004_PIP-SCONN,HA   I185 @BASEBOARD_FAB2_LIB.BASEBOARD_FAB2(SCH_1):PAGE81
  J1G3   35 VSS<78> SCONN288_H44441004_PIP-SCONN,HA   I185 @BASEBOARD_FAB2_LIB.BASEBOARD_FAB2(SCH_1):PAGE81
  J1G3   33 VSS<79> SCONN288_H44441004_PIP-SCONN,HA   I185 @BASEBOARD_FAB2_LIB.BASEBOARD_FAB2(SCH_1):PAGE81
  J1G3   31 VSS<80> SCONN288_H44441004_PIP-SCONN,HA   I185 @BASEBOARD_FAB2_LIB.BASEBOARD_FAB2(SCH_1):PAGE81
  J1G3   28 VSS<81> SCONN288_H44441004_PIP-SCONN,HA   I185 @BASEBOARD_FAB2_LIB.BASEBOARD_FAB2(SCH_1):PAGE81
  J1G3   26 VSS<82> SCONN288_H44441004_PIP-SCONN,HA   I185 @BASEBOARD_FAB2_LIB.BASEBOARD_FAB2(SCH_1):PAGE81
  J1G3   24 VSS<83> SCONN288_H44441004_PIP-SCONN,HA   I185 @BASEBOARD_FAB2_LIB.BASEBOARD_FAB2(SCH_1):PAGE81
  J1G3   22 VSS<84> SCONN288_H44441004_PIP-SCONN,HA   I185 @BASEBOARD_FAB2_LIB.BASEBOARD_FAB2(SCH_1):PAGE81
  J1G3   20 VSS<85> SCONN288_H44441004_PIP-SCONN,HA   I185 @BASEBOARD_FAB2_LIB.BASEBOARD_FAB2(SCH_1):PAGE81
  J1G3   17 VSS<86> SCONN288_H44441004_PIP-SCONN,HA   I185 @BASEBOARD_FAB2_LIB.BASEBOARD_FAB2(SCH_1):PAGE81
  J1G3   15 VSS<87> SCONN288_H44441004_PIP-SCONN,HA   I185 @BASEBOARD_FAB2_LIB.BASEBOARD_FAB2(SCH_1):PAGE81
  J1G3   13 VSS<88> SCONN288_H44441004_PIP-SCONN,HA   I185 @BASEBOARD_FAB2_LIB.BASEBOARD_FAB2(SCH_1):PAGE81
  J1G3   11 VSS<89> SCONN288_H44441004_PIP-SCONN,HA   I185 @BASEBOARD_FAB2_LIB.BASEBOARD_FAB2(SCH_1):PAGE81
  J1G3    9 VSS<90> SCONN288_H44441004_PIP-SCONN,HA   I185 @BASEBOARD_FAB2_LIB.BASEBOARD_FAB2(SCH_1):PAGE81
  J1G3    6 VSS<91> SCONN288_H44441004_PIP-SCONN,HA   I185 @BASEBOARD_FAB2_LIB.BASEBOARD_FAB2(SCH_1):PAGE81
  J1G3    4 VSS<92> SCONN288_H44441004_PIP-SCONN,HA   I185 @BASEBOARD_FAB2_LIB.BASEBOARD_FAB2(SCH_1):PAGE81
  J1G3    2 VSS<93> SCONN288_H44441004_PIP-SCONN,HA   I185 @BASEBOARD_FAB2_LIB.BASEBOARD_FAB2(SCH_1):PAGE81
  J1G3  139  SA<0> SCONN288_H44441004_PIP-SCONN,HA   I186 @BASEBOARD_FAB2_LIB.BASEBOARD_FAB2(SCH_1):PAGE81
  J1G3  140  SA<1> SCONN288_H44441004_PIP-SCONN,HA   I186 @BASEBOARD_FAB2_LIB.BASEBOARD_FAB2(SCH_1):PAGE81
 C1G19    2      B CAP_A_0402V-0.01UF,25V,10%,X7RA   I180 @BASEBOARD_FAB2_LIB.BASEBOARD_FAB2(SCH_1):PAGE82
  J9U2  140  SA<1> SCONN288_H44441003_PIP-SCONN,HA   I187 @BASEBOARD_FAB2_LIB.BASEBOARD_FAB2(SCH_1):PAGE82
  J9U2  283 VSS<0> SCONN288_H44441003_PIP-SCONN,HA   I188 @BASEBOARD_FAB2_LIB.BASEBOARD_FAB2(SCH_1):PAGE82
  J9U2  281 VSS<1> SCONN288_H44441003_PIP-SCONN,HA   I188 @BASEBOARD_FAB2_LIB.BASEBOARD_FAB2(SCH_1):PAGE82
  J9U2  279 VSS<2> SCONN288_H44441003_PIP-SCONN,HA   I188 @BASEBOARD_FAB2_LIB.BASEBOARD_FAB2(SCH_1):PAGE82
  J9U2  276 VSS<3> SCONN288_H44441003_PIP-SCONN,HA   I188 @BASEBOARD_FAB2_LIB.BASEBOARD_FAB2(SCH_1):PAGE82
  J9U2  274 VSS<4> SCONN288_H44441003_PIP-SCONN,HA   I188 @BASEBOARD_FAB2_LIB.BASEBOARD_FAB2(SCH_1):PAGE82
  J9U2  272 VSS<5> SCONN288_H44441003_PIP-SCONN,HA   I188 @BASEBOARD_FAB2_LIB.BASEBOARD_FAB2(SCH_1):PAGE82
  J9U2  270 VSS<6> SCONN288_H44441003_PIP-SCONN,HA   I188 @BASEBOARD_FAB2_LIB.BASEBOARD_FAB2(SCH_1):PAGE82
  J9U2  268 VSS<7> SCONN288_H44441003_PIP-SCONN,HA   I188 @BASEBOARD_FAB2_LIB.BASEBOARD_FAB2(SCH_1):PAGE82
  J9U2  265 VSS<8> SCONN288_H44441003_PIP-SCONN,HA   I188 @BASEBOARD_FAB2_LIB.BASEBOARD_FAB2(SCH_1):PAGE82
  J9U2  263 VSS<9> SCONN288_H44441003_PIP-SCONN,HA   I188 @BASEBOARD_FAB2_LIB.BASEBOARD_FAB2(SCH_1):PAGE82
  J9U2  261 VSS<10> SCONN288_H44441003_PIP-SCONN,HA   I188 @BASEBOARD_FAB2_LIB.BASEBOARD_FAB2(SCH_1):PAGE82
  J9U2  259 VSS<11> SCONN288_H44441003_PIP-SCONN,HA   I188 @BASEBOARD_FAB2_LIB.BASEBOARD_FAB2(SCH_1):PAGE82
  J9U2  257 VSS<12> SCONN288_H44441003_PIP-SCONN,HA   I188 @BASEBOARD_FAB2_LIB.BASEBOARD_FAB2(SCH_1):PAGE82
  J9U2  254 VSS<13> SCONN288_H44441003_PIP-SCONN,HA   I188 @BASEBOARD_FAB2_LIB.BASEBOARD_FAB2(SCH_1):PAGE82
  J9U2  252 VSS<14> SCONN288_H44441003_PIP-SCONN,HA   I188 @BASEBOARD_FAB2_LIB.BASEBOARD_FAB2(SCH_1):PAGE82
  J9U2  250 VSS<15> SCONN288_H44441003_PIP-SCONN,HA   I188 @BASEBOARD_FAB2_LIB.BASEBOARD_FAB2(SCH_1):PAGE82
  J9U2  248 VSS<16> SCONN288_H44441003_PIP-SCONN,HA   I188 @BASEBOARD_FAB2_LIB.BASEBOARD_FAB2(SCH_1):PAGE82
  J9U2  246 VSS<17> SCONN288_H44441003_PIP-SCONN,HA   I188 @BASEBOARD_FAB2_LIB.BASEBOARD_FAB2(SCH_1):PAGE82
  J9U2  243 VSS<18> SCONN288_H44441003_PIP-SCONN,HA   I188 @BASEBOARD_FAB2_LIB.BASEBOARD_FAB2(SCH_1):PAGE82
  J9U2  241 VSS<19> SCONN288_H44441003_PIP-SCONN,HA   I188 @BASEBOARD_FAB2_LIB.BASEBOARD_FAB2(SCH_1):PAGE82
  J9U2  239 VSS<20> SCONN288_H44441003_PIP-SCONN,HA   I188 @BASEBOARD_FAB2_LIB.BASEBOARD_FAB2(SCH_1):PAGE82
  J9U2  202 VSS<21> SCONN288_H44441003_PIP-SCONN,HA   I188 @BASEBOARD_FAB2_LIB.BASEBOARD_FAB2(SCH_1):PAGE82
  J9U2  200 VSS<22> SCONN288_H44441003_PIP-SCONN,HA   I188 @BASEBOARD_FAB2_LIB.BASEBOARD_FAB2(SCH_1):PAGE82
  J9U2  198 VSS<23> SCONN288_H44441003_PIP-SCONN,HA   I188 @BASEBOARD_FAB2_LIB.BASEBOARD_FAB2(SCH_1):PAGE82
  J9U2  195 VSS<24> SCONN288_H44441003_PIP-SCONN,HA   I188 @BASEBOARD_FAB2_LIB.BASEBOARD_FAB2(SCH_1):PAGE82
  J9U2  193 VSS<25> SCONN288_H44441003_PIP-SCONN,HA   I188 @BASEBOARD_FAB2_LIB.BASEBOARD_FAB2(SCH_1):PAGE82
  J9U2  191 VSS<26> SCONN288_H44441003_PIP-SCONN,HA   I188 @BASEBOARD_FAB2_LIB.BASEBOARD_FAB2(SCH_1):PAGE82
  J9U2  189 VSS<27> SCONN288_H44441003_PIP-SCONN,HA   I188 @BASEBOARD_FAB2_LIB.BASEBOARD_FAB2(SCH_1):PAGE82
  J9U2  187 VSS<28> SCONN288_H44441003_PIP-SCONN,HA   I188 @BASEBOARD_FAB2_LIB.BASEBOARD_FAB2(SCH_1):PAGE82
  J9U2  184 VSS<29> SCONN288_H44441003_PIP-SCONN,HA   I188 @BASEBOARD_FAB2_LIB.BASEBOARD_FAB2(SCH_1):PAGE82
  J9U2  182 VSS<30> SCONN288_H44441003_PIP-SCONN,HA   I188 @BASEBOARD_FAB2_LIB.BASEBOARD_FAB2(SCH_1):PAGE82
  J9U2  180 VSS<31> SCONN288_H44441003_PIP-SCONN,HA   I188 @BASEBOARD_FAB2_LIB.BASEBOARD_FAB2(SCH_1):PAGE82
  J9U2  178 VSS<32> SCONN288_H44441003_PIP-SCONN,HA   I188 @BASEBOARD_FAB2_LIB.BASEBOARD_FAB2(SCH_1):PAGE82
  J9U2  176 VSS<33> SCONN288_H44441003_PIP-SCONN,HA   I188 @BASEBOARD_FAB2_LIB.BASEBOARD_FAB2(SCH_1):PAGE82
  J9U2  173 VSS<34> SCONN288_H44441003_PIP-SCONN,HA   I188 @BASEBOARD_FAB2_LIB.BASEBOARD_FAB2(SCH_1):PAGE82
  J9U2  171 VSS<35> SCONN288_H44441003_PIP-SCONN,HA   I188 @BASEBOARD_FAB2_LIB.BASEBOARD_FAB2(SCH_1):PAGE82
  J9U2  169 VSS<36> SCONN288_H44441003_PIP-SCONN,HA   I188 @BASEBOARD_FAB2_LIB.BASEBOARD_FAB2(SCH_1):PAGE82
  J9U2  167 VSS<37> SCONN288_H44441003_PIP-SCONN,HA   I188 @BASEBOARD_FAB2_LIB.BASEBOARD_FAB2(SCH_1):PAGE82
  J9U2  165 VSS<38> SCONN288_H44441003_PIP-SCONN,HA   I188 @BASEBOARD_FAB2_LIB.BASEBOARD_FAB2(SCH_1):PAGE82
  J9U2  162 VSS<39> SCONN288_H44441003_PIP-SCONN,HA   I188 @BASEBOARD_FAB2_LIB.BASEBOARD_FAB2(SCH_1):PAGE82
  J9U2  160 VSS<40> SCONN288_H44441003_PIP-SCONN,HA   I188 @BASEBOARD_FAB2_LIB.BASEBOARD_FAB2(SCH_1):PAGE82
  J9U2  158 VSS<41> SCONN288_H44441003_PIP-SCONN,HA   I188 @BASEBOARD_FAB2_LIB.BASEBOARD_FAB2(SCH_1):PAGE82
  J9U2  156 VSS<42> SCONN288_H44441003_PIP-SCONN,HA   I188 @BASEBOARD_FAB2_LIB.BASEBOARD_FAB2(SCH_1):PAGE82
  J9U2  154 VSS<43> SCONN288_H44441003_PIP-SCONN,HA   I188 @BASEBOARD_FAB2_LIB.BASEBOARD_FAB2(SCH_1):PAGE82
  J9U2  151 VSS<44> SCONN288_H44441003_PIP-SCONN,HA   I188 @BASEBOARD_FAB2_LIB.BASEBOARD_FAB2(SCH_1):PAGE82
  J9U2  149 VSS<45> SCONN288_H44441003_PIP-SCONN,HA   I188 @BASEBOARD_FAB2_LIB.BASEBOARD_FAB2(SCH_1):PAGE82
  J9U2  147 VSS<46> SCONN288_H44441003_PIP-SCONN,HA   I188 @BASEBOARD_FAB2_LIB.BASEBOARD_FAB2(SCH_1):PAGE82
  J9U2  138 VSS<47> SCONN288_H44441003_PIP-SCONN,HA   I188 @BASEBOARD_FAB2_LIB.BASEBOARD_FAB2(SCH_1):PAGE82
  J9U2  136 VSS<48> SCONN288_H44441003_PIP-SCONN,HA   I188 @BASEBOARD_FAB2_LIB.BASEBOARD_FAB2(SCH_1):PAGE82
  J9U2  134 VSS<49> SCONN288_H44441003_PIP-SCONN,HA   I188 @BASEBOARD_FAB2_LIB.BASEBOARD_FAB2(SCH_1):PAGE82
  J9U2  131 VSS<50> SCONN288_H44441003_PIP-SCONN,HA   I188 @BASEBOARD_FAB2_LIB.BASEBOARD_FAB2(SCH_1):PAGE82
  J9U2  129 VSS<51> SCONN288_H44441003_PIP-SCONN,HA   I188 @BASEBOARD_FAB2_LIB.BASEBOARD_FAB2(SCH_1):PAGE82
  J9U2  127 VSS<52> SCONN288_H44441003_PIP-SCONN,HA   I188 @BASEBOARD_FAB2_LIB.BASEBOARD_FAB2(SCH_1):PAGE82
  J9U2  125 VSS<53> SCONN288_H44441003_PIP-SCONN,HA   I188 @BASEBOARD_FAB2_LIB.BASEBOARD_FAB2(SCH_1):PAGE82
  J9U2  123 VSS<54> SCONN288_H44441003_PIP-SCONN,HA   I188 @BASEBOARD_FAB2_LIB.BASEBOARD_FAB2(SCH_1):PAGE82
  J9U2  120 VSS<55> SCONN288_H44441003_PIP-SCONN,HA   I188 @BASEBOARD_FAB2_LIB.BASEBOARD_FAB2(SCH_1):PAGE82
  J9U2  118 VSS<56> SCONN288_H44441003_PIP-SCONN,HA   I188 @BASEBOARD_FAB2_LIB.BASEBOARD_FAB2(SCH_1):PAGE82
  J9U2  116 VSS<57> SCONN288_H44441003_PIP-SCONN,HA   I188 @BASEBOARD_FAB2_LIB.BASEBOARD_FAB2(SCH_1):PAGE82
  J9U2  114 VSS<58> SCONN288_H44441003_PIP-SCONN,HA   I188 @BASEBOARD_FAB2_LIB.BASEBOARD_FAB2(SCH_1):PAGE82
  J9U2  112 VSS<59> SCONN288_H44441003_PIP-SCONN,HA   I188 @BASEBOARD_FAB2_LIB.BASEBOARD_FAB2(SCH_1):PAGE82
  J9U2  109 VSS<60> SCONN288_H44441003_PIP-SCONN,HA   I188 @BASEBOARD_FAB2_LIB.BASEBOARD_FAB2(SCH_1):PAGE82
  J9U2  107 VSS<61> SCONN288_H44441003_PIP-SCONN,HA   I188 @BASEBOARD_FAB2_LIB.BASEBOARD_FAB2(SCH_1):PAGE82
  J9U2  105 VSS<62> SCONN288_H44441003_PIP-SCONN,HA   I188 @BASEBOARD_FAB2_LIB.BASEBOARD_FAB2(SCH_1):PAGE82
  J9U2  103 VSS<63> SCONN288_H44441003_PIP-SCONN,HA   I188 @BASEBOARD_FAB2_LIB.BASEBOARD_FAB2(SCH_1):PAGE82
  J9U2  101 VSS<64> SCONN288_H44441003_PIP-SCONN,HA   I188 @BASEBOARD_FAB2_LIB.BASEBOARD_FAB2(SCH_1):PAGE82
  J9U2   98 VSS<65> SCONN288_H44441003_PIP-SCONN,HA   I188 @BASEBOARD_FAB2_LIB.BASEBOARD_FAB2(SCH_1):PAGE82
  J9U2   96 VSS<66> SCONN288_H44441003_PIP-SCONN,HA   I188 @BASEBOARD_FAB2_LIB.BASEBOARD_FAB2(SCH_1):PAGE82
  J9U2   94 VSS<67> SCONN288_H44441003_PIP-SCONN,HA   I188 @BASEBOARD_FAB2_LIB.BASEBOARD_FAB2(SCH_1):PAGE82
  J9U2   57 VSS<68> SCONN288_H44441003_PIP-SCONN,HA   I188 @BASEBOARD_FAB2_LIB.BASEBOARD_FAB2(SCH_1):PAGE82
  J9U2   55 VSS<69> SCONN288_H44441003_PIP-SCONN,HA   I188 @BASEBOARD_FAB2_LIB.BASEBOARD_FAB2(SCH_1):PAGE82
  J9U2   53 VSS<70> SCONN288_H44441003_PIP-SCONN,HA   I188 @BASEBOARD_FAB2_LIB.BASEBOARD_FAB2(SCH_1):PAGE82
  J9U2   50 VSS<71> SCONN288_H44441003_PIP-SCONN,HA   I188 @BASEBOARD_FAB2_LIB.BASEBOARD_FAB2(SCH_1):PAGE82
  J9U2   48 VSS<72> SCONN288_H44441003_PIP-SCONN,HA   I188 @BASEBOARD_FAB2_LIB.BASEBOARD_FAB2(SCH_1):PAGE82
  J9U2   46 VSS<73> SCONN288_H44441003_PIP-SCONN,HA   I188 @BASEBOARD_FAB2_LIB.BASEBOARD_FAB2(SCH_1):PAGE82
  J9U2   44 VSS<74> SCONN288_H44441003_PIP-SCONN,HA   I188 @BASEBOARD_FAB2_LIB.BASEBOARD_FAB2(SCH_1):PAGE82
  J9U2   42 VSS<75> SCONN288_H44441003_PIP-SCONN,HA   I188 @BASEBOARD_FAB2_LIB.BASEBOARD_FAB2(SCH_1):PAGE82
  J9U2   39 VSS<76> SCONN288_H44441003_PIP-SCONN,HA   I188 @BASEBOARD_FAB2_LIB.BASEBOARD_FAB2(SCH_1):PAGE82
  J9U2   37 VSS<77> SCONN288_H44441003_PIP-SCONN,HA   I188 @BASEBOARD_FAB2_LIB.BASEBOARD_FAB2(SCH_1):PAGE82
  J9U2   35 VSS<78> SCONN288_H44441003_PIP-SCONN,HA   I188 @BASEBOARD_FAB2_LIB.BASEBOARD_FAB2(SCH_1):PAGE82
  J9U2   33 VSS<79> SCONN288_H44441003_PIP-SCONN,HA   I188 @BASEBOARD_FAB2_LIB.BASEBOARD_FAB2(SCH_1):PAGE82
  J9U2   31 VSS<80> SCONN288_H44441003_PIP-SCONN,HA   I188 @BASEBOARD_FAB2_LIB.BASEBOARD_FAB2(SCH_1):PAGE82
  J9U2   28 VSS<81> SCONN288_H44441003_PIP-SCONN,HA   I188 @BASEBOARD_FAB2_LIB.BASEBOARD_FAB2(SCH_1):PAGE82
  J9U2   26 VSS<82> SCONN288_H44441003_PIP-SCONN,HA   I188 @BASEBOARD_FAB2_LIB.BASEBOARD_FAB2(SCH_1):PAGE82
  J9U2   24 VSS<83> SCONN288_H44441003_PIP-SCONN,HA   I188 @BASEBOARD_FAB2_LIB.BASEBOARD_FAB2(SCH_1):PAGE82
  J9U2   22 VSS<84> SCONN288_H44441003_PIP-SCONN,HA   I188 @BASEBOARD_FAB2_LIB.BASEBOARD_FAB2(SCH_1):PAGE82
  J9U2   20 VSS<85> SCONN288_H44441003_PIP-SCONN,HA   I188 @BASEBOARD_FAB2_LIB.BASEBOARD_FAB2(SCH_1):PAGE82
  J9U2   17 VSS<86> SCONN288_H44441003_PIP-SCONN,HA   I188 @BASEBOARD_FAB2_LIB.BASEBOARD_FAB2(SCH_1):PAGE82
  J9U2   15 VSS<87> SCONN288_H44441003_PIP-SCONN,HA   I188 @BASEBOARD_FAB2_LIB.BASEBOARD_FAB2(SCH_1):PAGE82
  J9U2   13 VSS<88> SCONN288_H44441003_PIP-SCONN,HA   I188 @BASEBOARD_FAB2_LIB.BASEBOARD_FAB2(SCH_1):PAGE82
  J9U2   11 VSS<89> SCONN288_H44441003_PIP-SCONN,HA   I188 @BASEBOARD_FAB2_LIB.BASEBOARD_FAB2(SCH_1):PAGE82
  J9U2    9 VSS<90> SCONN288_H44441003_PIP-SCONN,HA   I188 @BASEBOARD_FAB2_LIB.BASEBOARD_FAB2(SCH_1):PAGE82
  J9U2    6 VSS<91> SCONN288_H44441003_PIP-SCONN,HA   I188 @BASEBOARD_FAB2_LIB.BASEBOARD_FAB2(SCH_1):PAGE82
  J9U2    4 VSS<92> SCONN288_H44441003_PIP-SCONN,HA   I188 @BASEBOARD_FAB2_LIB.BASEBOARD_FAB2(SCH_1):PAGE82
  J9U2    2 VSS<93> SCONN288_H44441003_PIP-SCONN,HA   I188 @BASEBOARD_FAB2_LIB.BASEBOARD_FAB2(SCH_1):PAGE82
  J1B1  283 VSS<0> SCONN288_H44441004_PIP-SCONN,HA    I43 @BASEBOARD_FAB2_LIB.BASEBOARD_FAB2(SCH_1):PAGE83
  J1B1  281 VSS<1> SCONN288_H44441004_PIP-SCONN,HA    I43 @BASEBOARD_FAB2_LIB.BASEBOARD_FAB2(SCH_1):PAGE83
  J1B1  279 VSS<2> SCONN288_H44441004_PIP-SCONN,HA    I43 @BASEBOARD_FAB2_LIB.BASEBOARD_FAB2(SCH_1):PAGE83
  J1B1  276 VSS<3> SCONN288_H44441004_PIP-SCONN,HA    I43 @BASEBOARD_FAB2_LIB.BASEBOARD_FAB2(SCH_1):PAGE83
  J1B1  274 VSS<4> SCONN288_H44441004_PIP-SCONN,HA    I43 @BASEBOARD_FAB2_LIB.BASEBOARD_FAB2(SCH_1):PAGE83
  J1B1  272 VSS<5> SCONN288_H44441004_PIP-SCONN,HA    I43 @BASEBOARD_FAB2_LIB.BASEBOARD_FAB2(SCH_1):PAGE83
  J1B1  270 VSS<6> SCONN288_H44441004_PIP-SCONN,HA    I43 @BASEBOARD_FAB2_LIB.BASEBOARD_FAB2(SCH_1):PAGE83
  J1B1  268 VSS<7> SCONN288_H44441004_PIP-SCONN,HA    I43 @BASEBOARD_FAB2_LIB.BASEBOARD_FAB2(SCH_1):PAGE83
  J1B1  265 VSS<8> SCONN288_H44441004_PIP-SCONN,HA    I43 @BASEBOARD_FAB2_LIB.BASEBOARD_FAB2(SCH_1):PAGE83
  J1B1  263 VSS<9> SCONN288_H44441004_PIP-SCONN,HA    I43 @BASEBOARD_FAB2_LIB.BASEBOARD_FAB2(SCH_1):PAGE83
  J1B1  261 VSS<10> SCONN288_H44441004_PIP-SCONN,HA    I43 @BASEBOARD_FAB2_LIB.BASEBOARD_FAB2(SCH_1):PAGE83
  J1B1  259 VSS<11> SCONN288_H44441004_PIP-SCONN,HA    I43 @BASEBOARD_FAB2_LIB.BASEBOARD_FAB2(SCH_1):PAGE83
  J1B1  257 VSS<12> SCONN288_H44441004_PIP-SCONN,HA    I43 @BASEBOARD_FAB2_LIB.BASEBOARD_FAB2(SCH_1):PAGE83
  J1B1  254 VSS<13> SCONN288_H44441004_PIP-SCONN,HA    I43 @BASEBOARD_FAB2_LIB.BASEBOARD_FAB2(SCH_1):PAGE83
  J1B1  252 VSS<14> SCONN288_H44441004_PIP-SCONN,HA    I43 @BASEBOARD_FAB2_LIB.BASEBOARD_FAB2(SCH_1):PAGE83
  J1B1  250 VSS<15> SCONN288_H44441004_PIP-SCONN,HA    I43 @BASEBOARD_FAB2_LIB.BASEBOARD_FAB2(SCH_1):PAGE83
  J1B1  248 VSS<16> SCONN288_H44441004_PIP-SCONN,HA    I43 @BASEBOARD_FAB2_LIB.BASEBOARD_FAB2(SCH_1):PAGE83
  J1B1  246 VSS<17> SCONN288_H44441004_PIP-SCONN,HA    I43 @BASEBOARD_FAB2_LIB.BASEBOARD_FAB2(SCH_1):PAGE83
  J1B1  243 VSS<18> SCONN288_H44441004_PIP-SCONN,HA    I43 @BASEBOARD_FAB2_LIB.BASEBOARD_FAB2(SCH_1):PAGE83
  J1B1  241 VSS<19> SCONN288_H44441004_PIP-SCONN,HA    I43 @BASEBOARD_FAB2_LIB.BASEBOARD_FAB2(SCH_1):PAGE83
  J1B1  239 VSS<20> SCONN288_H44441004_PIP-SCONN,HA    I43 @BASEBOARD_FAB2_LIB.BASEBOARD_FAB2(SCH_1):PAGE83
  J1B1  202 VSS<21> SCONN288_H44441004_PIP-SCONN,HA    I43 @BASEBOARD_FAB2_LIB.BASEBOARD_FAB2(SCH_1):PAGE83
  J1B1  200 VSS<22> SCONN288_H44441004_PIP-SCONN,HA    I43 @BASEBOARD_FAB2_LIB.BASEBOARD_FAB2(SCH_1):PAGE83
  J1B1  198 VSS<23> SCONN288_H44441004_PIP-SCONN,HA    I43 @BASEBOARD_FAB2_LIB.BASEBOARD_FAB2(SCH_1):PAGE83
  J1B1  195 VSS<24> SCONN288_H44441004_PIP-SCONN,HA    I43 @BASEBOARD_FAB2_LIB.BASEBOARD_FAB2(SCH_1):PAGE83
  J1B1  193 VSS<25> SCONN288_H44441004_PIP-SCONN,HA    I43 @BASEBOARD_FAB2_LIB.BASEBOARD_FAB2(SCH_1):PAGE83
  J1B1  191 VSS<26> SCONN288_H44441004_PIP-SCONN,HA    I43 @BASEBOARD_FAB2_LIB.BASEBOARD_FAB2(SCH_1):PAGE83
  J1B1  189 VSS<27> SCONN288_H44441004_PIP-SCONN,HA    I43 @BASEBOARD_FAB2_LIB.BASEBOARD_FAB2(SCH_1):PAGE83
  J1B1  187 VSS<28> SCONN288_H44441004_PIP-SCONN,HA    I43 @BASEBOARD_FAB2_LIB.BASEBOARD_FAB2(SCH_1):PAGE83
  J1B1  184 VSS<29> SCONN288_H44441004_PIP-SCONN,HA    I43 @BASEBOARD_FAB2_LIB.BASEBOARD_FAB2(SCH_1):PAGE83
  J1B1  182 VSS<30> SCONN288_H44441004_PIP-SCONN,HA    I43 @BASEBOARD_FAB2_LIB.BASEBOARD_FAB2(SCH_1):PAGE83
  J1B1  180 VSS<31> SCONN288_H44441004_PIP-SCONN,HA    I43 @BASEBOARD_FAB2_LIB.BASEBOARD_FAB2(SCH_1):PAGE83
  J1B1  178 VSS<32> SCONN288_H44441004_PIP-SCONN,HA    I43 @BASEBOARD_FAB2_LIB.BASEBOARD_FAB2(SCH_1):PAGE83
  J1B1  176 VSS<33> SCONN288_H44441004_PIP-SCONN,HA    I43 @BASEBOARD_FAB2_LIB.BASEBOARD_FAB2(SCH_1):PAGE83
  J1B1  173 VSS<34> SCONN288_H44441004_PIP-SCONN,HA    I43 @BASEBOARD_FAB2_LIB.BASEBOARD_FAB2(SCH_1):PAGE83
  J1B1  171 VSS<35> SCONN288_H44441004_PIP-SCONN,HA    I43 @BASEBOARD_FAB2_LIB.BASEBOARD_FAB2(SCH_1):PAGE83
  J1B1  169 VSS<36> SCONN288_H44441004_PIP-SCONN,HA    I43 @BASEBOARD_FAB2_LIB.BASEBOARD_FAB2(SCH_1):PAGE83
  J1B1  167 VSS<37> SCONN288_H44441004_PIP-SCONN,HA    I43 @BASEBOARD_FAB2_LIB.BASEBOARD_FAB2(SCH_1):PAGE83
  J1B1  165 VSS<38> SCONN288_H44441004_PIP-SCONN,HA    I43 @BASEBOARD_FAB2_LIB.BASEBOARD_FAB2(SCH_1):PAGE83
  J1B1  162 VSS<39> SCONN288_H44441004_PIP-SCONN,HA    I43 @BASEBOARD_FAB2_LIB.BASEBOARD_FAB2(SCH_1):PAGE83
  J1B1  160 VSS<40> SCONN288_H44441004_PIP-SCONN,HA    I43 @BASEBOARD_FAB2_LIB.BASEBOARD_FAB2(SCH_1):PAGE83
  J1B1  158 VSS<41> SCONN288_H44441004_PIP-SCONN,HA    I43 @BASEBOARD_FAB2_LIB.BASEBOARD_FAB2(SCH_1):PAGE83
  J1B1  156 VSS<42> SCONN288_H44441004_PIP-SCONN,HA    I43 @BASEBOARD_FAB2_LIB.BASEBOARD_FAB2(SCH_1):PAGE83
  J1B1  154 VSS<43> SCONN288_H44441004_PIP-SCONN,HA    I43 @BASEBOARD_FAB2_LIB.BASEBOARD_FAB2(SCH_1):PAGE83
  J1B1  151 VSS<44> SCONN288_H44441004_PIP-SCONN,HA    I43 @BASEBOARD_FAB2_LIB.BASEBOARD_FAB2(SCH_1):PAGE83
  J1B1  149 VSS<45> SCONN288_H44441004_PIP-SCONN,HA    I43 @BASEBOARD_FAB2_LIB.BASEBOARD_FAB2(SCH_1):PAGE83
  J1B1  147 VSS<46> SCONN288_H44441004_PIP-SCONN,HA    I43 @BASEBOARD_FAB2_LIB.BASEBOARD_FAB2(SCH_1):PAGE83
  J1B1  138 VSS<47> SCONN288_H44441004_PIP-SCONN,HA    I43 @BASEBOARD_FAB2_LIB.BASEBOARD_FAB2(SCH_1):PAGE83
  J1B1  136 VSS<48> SCONN288_H44441004_PIP-SCONN,HA    I43 @BASEBOARD_FAB2_LIB.BASEBOARD_FAB2(SCH_1):PAGE83
  J1B1  134 VSS<49> SCONN288_H44441004_PIP-SCONN,HA    I43 @BASEBOARD_FAB2_LIB.BASEBOARD_FAB2(SCH_1):PAGE83
  J1B1  131 VSS<50> SCONN288_H44441004_PIP-SCONN,HA    I43 @BASEBOARD_FAB2_LIB.BASEBOARD_FAB2(SCH_1):PAGE83
  J1B1  129 VSS<51> SCONN288_H44441004_PIP-SCONN,HA    I43 @BASEBOARD_FAB2_LIB.BASEBOARD_FAB2(SCH_1):PAGE83
  J1B1  127 VSS<52> SCONN288_H44441004_PIP-SCONN,HA    I43 @BASEBOARD_FAB2_LIB.BASEBOARD_FAB2(SCH_1):PAGE83
  J1B1  125 VSS<53> SCONN288_H44441004_PIP-SCONN,HA    I43 @BASEBOARD_FAB2_LIB.BASEBOARD_FAB2(SCH_1):PAGE83
  J1B1  123 VSS<54> SCONN288_H44441004_PIP-SCONN,HA    I43 @BASEBOARD_FAB2_LIB.BASEBOARD_FAB2(SCH_1):PAGE83
  J1B1  120 VSS<55> SCONN288_H44441004_PIP-SCONN,HA    I43 @BASEBOARD_FAB2_LIB.BASEBOARD_FAB2(SCH_1):PAGE83
  J1B1  118 VSS<56> SCONN288_H44441004_PIP-SCONN,HA    I43 @BASEBOARD_FAB2_LIB.BASEBOARD_FAB2(SCH_1):PAGE83
  J1B1  116 VSS<57> SCONN288_H44441004_PIP-SCONN,HA    I43 @BASEBOARD_FAB2_LIB.BASEBOARD_FAB2(SCH_1):PAGE83
  J1B1  114 VSS<58> SCONN288_H44441004_PIP-SCONN,HA    I43 @BASEBOARD_FAB2_LIB.BASEBOARD_FAB2(SCH_1):PAGE83
  J1B1  112 VSS<59> SCONN288_H44441004_PIP-SCONN,HA    I43 @BASEBOARD_FAB2_LIB.BASEBOARD_FAB2(SCH_1):PAGE83
  J1B1  109 VSS<60> SCONN288_H44441004_PIP-SCONN,HA    I43 @BASEBOARD_FAB2_LIB.BASEBOARD_FAB2(SCH_1):PAGE83
  J1B1  107 VSS<61> SCONN288_H44441004_PIP-SCONN,HA    I43 @BASEBOARD_FAB2_LIB.BASEBOARD_FAB2(SCH_1):PAGE83
  J1B1  105 VSS<62> SCONN288_H44441004_PIP-SCONN,HA    I43 @BASEBOARD_FAB2_LIB.BASEBOARD_FAB2(SCH_1):PAGE83
  J1B1  103 VSS<63> SCONN288_H44441004_PIP-SCONN,HA    I43 @BASEBOARD_FAB2_LIB.BASEBOARD_FAB2(SCH_1):PAGE83
  J1B1  101 VSS<64> SCONN288_H44441004_PIP-SCONN,HA    I43 @BASEBOARD_FAB2_LIB.BASEBOARD_FAB2(SCH_1):PAGE83
  J1B1   98 VSS<65> SCONN288_H44441004_PIP-SCONN,HA    I43 @BASEBOARD_FAB2_LIB.BASEBOARD_FAB2(SCH_1):PAGE83
  J1B1   96 VSS<66> SCONN288_H44441004_PIP-SCONN,HA    I43 @BASEBOARD_FAB2_LIB.BASEBOARD_FAB2(SCH_1):PAGE83
  J1B1   94 VSS<67> SCONN288_H44441004_PIP-SCONN,HA    I43 @BASEBOARD_FAB2_LIB.BASEBOARD_FAB2(SCH_1):PAGE83
  J1B1   57 VSS<68> SCONN288_H44441004_PIP-SCONN,HA    I43 @BASEBOARD_FAB2_LIB.BASEBOARD_FAB2(SCH_1):PAGE83
  J1B1   55 VSS<69> SCONN288_H44441004_PIP-SCONN,HA    I43 @BASEBOARD_FAB2_LIB.BASEBOARD_FAB2(SCH_1):PAGE83
  J1B1   53 VSS<70> SCONN288_H44441004_PIP-SCONN,HA    I43 @BASEBOARD_FAB2_LIB.BASEBOARD_FAB2(SCH_1):PAGE83
  J1B1   50 VSS<71> SCONN288_H44441004_PIP-SCONN,HA    I43 @BASEBOARD_FAB2_LIB.BASEBOARD_FAB2(SCH_1):PAGE83
  J1B1   48 VSS<72> SCONN288_H44441004_PIP-SCONN,HA    I43 @BASEBOARD_FAB2_LIB.BASEBOARD_FAB2(SCH_1):PAGE83
  J1B1   46 VSS<73> SCONN288_H44441004_PIP-SCONN,HA    I43 @BASEBOARD_FAB2_LIB.BASEBOARD_FAB2(SCH_1):PAGE83
  J1B1   44 VSS<74> SCONN288_H44441004_PIP-SCONN,HA    I43 @BASEBOARD_FAB2_LIB.BASEBOARD_FAB2(SCH_1):PAGE83
  J1B1   42 VSS<75> SCONN288_H44441004_PIP-SCONN,HA    I43 @BASEBOARD_FAB2_LIB.BASEBOARD_FAB2(SCH_1):PAGE83
  J1B1   39 VSS<76> SCONN288_H44441004_PIP-SCONN,HA    I43 @BASEBOARD_FAB2_LIB.BASEBOARD_FAB2(SCH_1):PAGE83
  J1B1   37 VSS<77> SCONN288_H44441004_PIP-SCONN,HA    I43 @BASEBOARD_FAB2_LIB.BASEBOARD_FAB2(SCH_1):PAGE83
  J1B1   35 VSS<78> SCONN288_H44441004_PIP-SCONN,HA    I43 @BASEBOARD_FAB2_LIB.BASEBOARD_FAB2(SCH_1):PAGE83
  J1B1   33 VSS<79> SCONN288_H44441004_PIP-SCONN,HA    I43 @BASEBOARD_FAB2_LIB.BASEBOARD_FAB2(SCH_1):PAGE83
  J1B1   31 VSS<80> SCONN288_H44441004_PIP-SCONN,HA    I43 @BASEBOARD_FAB2_LIB.BASEBOARD_FAB2(SCH_1):PAGE83
  J1B1   28 VSS<81> SCONN288_H44441004_PIP-SCONN,HA    I43 @BASEBOARD_FAB2_LIB.BASEBOARD_FAB2(SCH_1):PAGE83
  J1B1   26 VSS<82> SCONN288_H44441004_PIP-SCONN,HA    I43 @BASEBOARD_FAB2_LIB.BASEBOARD_FAB2(SCH_1):PAGE83
  J1B1   24 VSS<83> SCONN288_H44441004_PIP-SCONN,HA    I43 @BASEBOARD_FAB2_LIB.BASEBOARD_FAB2(SCH_1):PAGE83
  J1B1   22 VSS<84> SCONN288_H44441004_PIP-SCONN,HA    I43 @BASEBOARD_FAB2_LIB.BASEBOARD_FAB2(SCH_1):PAGE83
  J1B1   20 VSS<85> SCONN288_H44441004_PIP-SCONN,HA    I43 @BASEBOARD_FAB2_LIB.BASEBOARD_FAB2(SCH_1):PAGE83
  J1B1   17 VSS<86> SCONN288_H44441004_PIP-SCONN,HA    I43 @BASEBOARD_FAB2_LIB.BASEBOARD_FAB2(SCH_1):PAGE83
  J1B1   15 VSS<87> SCONN288_H44441004_PIP-SCONN,HA    I43 @BASEBOARD_FAB2_LIB.BASEBOARD_FAB2(SCH_1):PAGE83
  J1B1   13 VSS<88> SCONN288_H44441004_PIP-SCONN,HA    I43 @BASEBOARD_FAB2_LIB.BASEBOARD_FAB2(SCH_1):PAGE83
  J1B1   11 VSS<89> SCONN288_H44441004_PIP-SCONN,HA    I43 @BASEBOARD_FAB2_LIB.BASEBOARD_FAB2(SCH_1):PAGE83
  J1B1    9 VSS<90> SCONN288_H44441004_PIP-SCONN,HA    I43 @BASEBOARD_FAB2_LIB.BASEBOARD_FAB2(SCH_1):PAGE83
  J1B1    6 VSS<91> SCONN288_H44441004_PIP-SCONN,HA    I43 @BASEBOARD_FAB2_LIB.BASEBOARD_FAB2(SCH_1):PAGE83
  J1B1    4 VSS<92> SCONN288_H44441004_PIP-SCONN,HA    I43 @BASEBOARD_FAB2_LIB.BASEBOARD_FAB2(SCH_1):PAGE83
  J1B1    2 VSS<93> SCONN288_H44441004_PIP-SCONN,HA    I43 @BASEBOARD_FAB2_LIB.BASEBOARD_FAB2(SCH_1):PAGE83
  J1B1  139  SA<0> SCONN288_H44441004_PIP-SCONN,HA   I111 @BASEBOARD_FAB2_LIB.BASEBOARD_FAB2(SCH_1):PAGE83
  J1B1  140  SA<1> SCONN288_H44441004_PIP-SCONN,HA   I111 @BASEBOARD_FAB2_LIB.BASEBOARD_FAB2(SCH_1):PAGE83
  J1B1  238  SA<2> SCONN288_H44441004_PIP-SCONN,HA   I111 @BASEBOARD_FAB2_LIB.BASEBOARD_FAB2(SCH_1):PAGE83
  C1B9    2      B CAP_A_0402V-0.01UF,25V,10%,X7RA   I176 @BASEBOARD_FAB2_LIB.BASEBOARD_FAB2(SCH_1):PAGE83
  C9M1    2      B CAP_A_0402V-0.01UF,25V,10%,X7RA     I4 @BASEBOARD_FAB2_LIB.BASEBOARD_FAB2(SCH_1):PAGE84
  J9M1  140  SA<1> SCONN288_H44441003_PIP-SCONN,HA    I14 @BASEBOARD_FAB2_LIB.BASEBOARD_FAB2(SCH_1):PAGE84
  J9M1  238  SA<2> SCONN288_H44441003_PIP-SCONN,HA    I14 @BASEBOARD_FAB2_LIB.BASEBOARD_FAB2(SCH_1):PAGE84
  J9M1  283 VSS<0> SCONN288_H44441003_PIP-SCONN,HA   I138 @BASEBOARD_FAB2_LIB.BASEBOARD_FAB2(SCH_1):PAGE84
  J9M1  281 VSS<1> SCONN288_H44441003_PIP-SCONN,HA   I138 @BASEBOARD_FAB2_LIB.BASEBOARD_FAB2(SCH_1):PAGE84
  J9M1  279 VSS<2> SCONN288_H44441003_PIP-SCONN,HA   I138 @BASEBOARD_FAB2_LIB.BASEBOARD_FAB2(SCH_1):PAGE84
  J9M1  276 VSS<3> SCONN288_H44441003_PIP-SCONN,HA   I138 @BASEBOARD_FAB2_LIB.BASEBOARD_FAB2(SCH_1):PAGE84
  J9M1  274 VSS<4> SCONN288_H44441003_PIP-SCONN,HA   I138 @BASEBOARD_FAB2_LIB.BASEBOARD_FAB2(SCH_1):PAGE84
  J9M1  272 VSS<5> SCONN288_H44441003_PIP-SCONN,HA   I138 @BASEBOARD_FAB2_LIB.BASEBOARD_FAB2(SCH_1):PAGE84
  J9M1  270 VSS<6> SCONN288_H44441003_PIP-SCONN,HA   I138 @BASEBOARD_FAB2_LIB.BASEBOARD_FAB2(SCH_1):PAGE84
  J9M1  268 VSS<7> SCONN288_H44441003_PIP-SCONN,HA   I138 @BASEBOARD_FAB2_LIB.BASEBOARD_FAB2(SCH_1):PAGE84
  J9M1  265 VSS<8> SCONN288_H44441003_PIP-SCONN,HA   I138 @BASEBOARD_FAB2_LIB.BASEBOARD_FAB2(SCH_1):PAGE84
  J9M1  263 VSS<9> SCONN288_H44441003_PIP-SCONN,HA   I138 @BASEBOARD_FAB2_LIB.BASEBOARD_FAB2(SCH_1):PAGE84
  J9M1  261 VSS<10> SCONN288_H44441003_PIP-SCONN,HA   I138 @BASEBOARD_FAB2_LIB.BASEBOARD_FAB2(SCH_1):PAGE84
  J9M1  259 VSS<11> SCONN288_H44441003_PIP-SCONN,HA   I138 @BASEBOARD_FAB2_LIB.BASEBOARD_FAB2(SCH_1):PAGE84
  J9M1  257 VSS<12> SCONN288_H44441003_PIP-SCONN,HA   I138 @BASEBOARD_FAB2_LIB.BASEBOARD_FAB2(SCH_1):PAGE84
  J9M1  254 VSS<13> SCONN288_H44441003_PIP-SCONN,HA   I138 @BASEBOARD_FAB2_LIB.BASEBOARD_FAB2(SCH_1):PAGE84
  J9M1  252 VSS<14> SCONN288_H44441003_PIP-SCONN,HA   I138 @BASEBOARD_FAB2_LIB.BASEBOARD_FAB2(SCH_1):PAGE84
  J9M1  250 VSS<15> SCONN288_H44441003_PIP-SCONN,HA   I138 @BASEBOARD_FAB2_LIB.BASEBOARD_FAB2(SCH_1):PAGE84
  J9M1  248 VSS<16> SCONN288_H44441003_PIP-SCONN,HA   I138 @BASEBOARD_FAB2_LIB.BASEBOARD_FAB2(SCH_1):PAGE84
  J9M1  246 VSS<17> SCONN288_H44441003_PIP-SCONN,HA   I138 @BASEBOARD_FAB2_LIB.BASEBOARD_FAB2(SCH_1):PAGE84
  J9M1  243 VSS<18> SCONN288_H44441003_PIP-SCONN,HA   I138 @BASEBOARD_FAB2_LIB.BASEBOARD_FAB2(SCH_1):PAGE84
  J9M1  241 VSS<19> SCONN288_H44441003_PIP-SCONN,HA   I138 @BASEBOARD_FAB2_LIB.BASEBOARD_FAB2(SCH_1):PAGE84
  J9M1  239 VSS<20> SCONN288_H44441003_PIP-SCONN,HA   I138 @BASEBOARD_FAB2_LIB.BASEBOARD_FAB2(SCH_1):PAGE84
  J9M1  202 VSS<21> SCONN288_H44441003_PIP-SCONN,HA   I138 @BASEBOARD_FAB2_LIB.BASEBOARD_FAB2(SCH_1):PAGE84
  J9M1  200 VSS<22> SCONN288_H44441003_PIP-SCONN,HA   I138 @BASEBOARD_FAB2_LIB.BASEBOARD_FAB2(SCH_1):PAGE84
  J9M1  198 VSS<23> SCONN288_H44441003_PIP-SCONN,HA   I138 @BASEBOARD_FAB2_LIB.BASEBOARD_FAB2(SCH_1):PAGE84
  J9M1  195 VSS<24> SCONN288_H44441003_PIP-SCONN,HA   I138 @BASEBOARD_FAB2_LIB.BASEBOARD_FAB2(SCH_1):PAGE84
  J9M1  193 VSS<25> SCONN288_H44441003_PIP-SCONN,HA   I138 @BASEBOARD_FAB2_LIB.BASEBOARD_FAB2(SCH_1):PAGE84
  J9M1  191 VSS<26> SCONN288_H44441003_PIP-SCONN,HA   I138 @BASEBOARD_FAB2_LIB.BASEBOARD_FAB2(SCH_1):PAGE84
  J9M1  189 VSS<27> SCONN288_H44441003_PIP-SCONN,HA   I138 @BASEBOARD_FAB2_LIB.BASEBOARD_FAB2(SCH_1):PAGE84
  J9M1  187 VSS<28> SCONN288_H44441003_PIP-SCONN,HA   I138 @BASEBOARD_FAB2_LIB.BASEBOARD_FAB2(SCH_1):PAGE84
  J9M1  184 VSS<29> SCONN288_H44441003_PIP-SCONN,HA   I138 @BASEBOARD_FAB2_LIB.BASEBOARD_FAB2(SCH_1):PAGE84
  J9M1  182 VSS<30> SCONN288_H44441003_PIP-SCONN,HA   I138 @BASEBOARD_FAB2_LIB.BASEBOARD_FAB2(SCH_1):PAGE84
  J9M1  180 VSS<31> SCONN288_H44441003_PIP-SCONN,HA   I138 @BASEBOARD_FAB2_LIB.BASEBOARD_FAB2(SCH_1):PAGE84
  J9M1  178 VSS<32> SCONN288_H44441003_PIP-SCONN,HA   I138 @BASEBOARD_FAB2_LIB.BASEBOARD_FAB2(SCH_1):PAGE84
  J9M1  176 VSS<33> SCONN288_H44441003_PIP-SCONN,HA   I138 @BASEBOARD_FAB2_LIB.BASEBOARD_FAB2(SCH_1):PAGE84
  J9M1  173 VSS<34> SCONN288_H44441003_PIP-SCONN,HA   I138 @BASEBOARD_FAB2_LIB.BASEBOARD_FAB2(SCH_1):PAGE84
  J9M1  171 VSS<35> SCONN288_H44441003_PIP-SCONN,HA   I138 @BASEBOARD_FAB2_LIB.BASEBOARD_FAB2(SCH_1):PAGE84
  J9M1  169 VSS<36> SCONN288_H44441003_PIP-SCONN,HA   I138 @BASEBOARD_FAB2_LIB.BASEBOARD_FAB2(SCH_1):PAGE84
  J9M1  167 VSS<37> SCONN288_H44441003_PIP-SCONN,HA   I138 @BASEBOARD_FAB2_LIB.BASEBOARD_FAB2(SCH_1):PAGE84
  J9M1  165 VSS<38> SCONN288_H44441003_PIP-SCONN,HA   I138 @BASEBOARD_FAB2_LIB.BASEBOARD_FAB2(SCH_1):PAGE84
  J9M1  162 VSS<39> SCONN288_H44441003_PIP-SCONN,HA   I138 @BASEBOARD_FAB2_LIB.BASEBOARD_FAB2(SCH_1):PAGE84
  J9M1  160 VSS<40> SCONN288_H44441003_PIP-SCONN,HA   I138 @BASEBOARD_FAB2_LIB.BASEBOARD_FAB2(SCH_1):PAGE84
  J9M1  158 VSS<41> SCONN288_H44441003_PIP-SCONN,HA   I138 @BASEBOARD_FAB2_LIB.BASEBOARD_FAB2(SCH_1):PAGE84
  J9M1  156 VSS<42> SCONN288_H44441003_PIP-SCONN,HA   I138 @BASEBOARD_FAB2_LIB.BASEBOARD_FAB2(SCH_1):PAGE84
  J9M1  154 VSS<43> SCONN288_H44441003_PIP-SCONN,HA   I138 @BASEBOARD_FAB2_LIB.BASEBOARD_FAB2(SCH_1):PAGE84
  J9M1  151 VSS<44> SCONN288_H44441003_PIP-SCONN,HA   I138 @BASEBOARD_FAB2_LIB.BASEBOARD_FAB2(SCH_1):PAGE84
  J9M1  149 VSS<45> SCONN288_H44441003_PIP-SCONN,HA   I138 @BASEBOARD_FAB2_LIB.BASEBOARD_FAB2(SCH_1):PAGE84
  J9M1  147 VSS<46> SCONN288_H44441003_PIP-SCONN,HA   I138 @BASEBOARD_FAB2_LIB.BASEBOARD_FAB2(SCH_1):PAGE84
  J9M1  138 VSS<47> SCONN288_H44441003_PIP-SCONN,HA   I138 @BASEBOARD_FAB2_LIB.BASEBOARD_FAB2(SCH_1):PAGE84
  J9M1  136 VSS<48> SCONN288_H44441003_PIP-SCONN,HA   I138 @BASEBOARD_FAB2_LIB.BASEBOARD_FAB2(SCH_1):PAGE84
  J9M1  134 VSS<49> SCONN288_H44441003_PIP-SCONN,HA   I138 @BASEBOARD_FAB2_LIB.BASEBOARD_FAB2(SCH_1):PAGE84
  J9M1  131 VSS<50> SCONN288_H44441003_PIP-SCONN,HA   I138 @BASEBOARD_FAB2_LIB.BASEBOARD_FAB2(SCH_1):PAGE84
  J9M1  129 VSS<51> SCONN288_H44441003_PIP-SCONN,HA   I138 @BASEBOARD_FAB2_LIB.BASEBOARD_FAB2(SCH_1):PAGE84
  J9M1  127 VSS<52> SCONN288_H44441003_PIP-SCONN,HA   I138 @BASEBOARD_FAB2_LIB.BASEBOARD_FAB2(SCH_1):PAGE84
  J9M1  125 VSS<53> SCONN288_H44441003_PIP-SCONN,HA   I138 @BASEBOARD_FAB2_LIB.BASEBOARD_FAB2(SCH_1):PAGE84
  J9M1  123 VSS<54> SCONN288_H44441003_PIP-SCONN,HA   I138 @BASEBOARD_FAB2_LIB.BASEBOARD_FAB2(SCH_1):PAGE84
  J9M1  120 VSS<55> SCONN288_H44441003_PIP-SCONN,HA   I138 @BASEBOARD_FAB2_LIB.BASEBOARD_FAB2(SCH_1):PAGE84
  J9M1  118 VSS<56> SCONN288_H44441003_PIP-SCONN,HA   I138 @BASEBOARD_FAB2_LIB.BASEBOARD_FAB2(SCH_1):PAGE84
  J9M1  116 VSS<57> SCONN288_H44441003_PIP-SCONN,HA   I138 @BASEBOARD_FAB2_LIB.BASEBOARD_FAB2(SCH_1):PAGE84
  J9M1  114 VSS<58> SCONN288_H44441003_PIP-SCONN,HA   I138 @BASEBOARD_FAB2_LIB.BASEBOARD_FAB2(SCH_1):PAGE84
  J9M1  112 VSS<59> SCONN288_H44441003_PIP-SCONN,HA   I138 @BASEBOARD_FAB2_LIB.BASEBOARD_FAB2(SCH_1):PAGE84
  J9M1  109 VSS<60> SCONN288_H44441003_PIP-SCONN,HA   I138 @BASEBOARD_FAB2_LIB.BASEBOARD_FAB2(SCH_1):PAGE84
  J9M1  107 VSS<61> SCONN288_H44441003_PIP-SCONN,HA   I138 @BASEBOARD_FAB2_LIB.BASEBOARD_FAB2(SCH_1):PAGE84
  J9M1  105 VSS<62> SCONN288_H44441003_PIP-SCONN,HA   I138 @BASEBOARD_FAB2_LIB.BASEBOARD_FAB2(SCH_1):PAGE84
  J9M1  103 VSS<63> SCONN288_H44441003_PIP-SCONN,HA   I138 @BASEBOARD_FAB2_LIB.BASEBOARD_FAB2(SCH_1):PAGE84
  J9M1  101 VSS<64> SCONN288_H44441003_PIP-SCONN,HA   I138 @BASEBOARD_FAB2_LIB.BASEBOARD_FAB2(SCH_1):PAGE84
  J9M1   98 VSS<65> SCONN288_H44441003_PIP-SCONN,HA   I138 @BASEBOARD_FAB2_LIB.BASEBOARD_FAB2(SCH_1):PAGE84
  J9M1   96 VSS<66> SCONN288_H44441003_PIP-SCONN,HA   I138 @BASEBOARD_FAB2_LIB.BASEBOARD_FAB2(SCH_1):PAGE84
  J9M1   94 VSS<67> SCONN288_H44441003_PIP-SCONN,HA   I138 @BASEBOARD_FAB2_LIB.BASEBOARD_FAB2(SCH_1):PAGE84
  J9M1   57 VSS<68> SCONN288_H44441003_PIP-SCONN,HA   I138 @BASEBOARD_FAB2_LIB.BASEBOARD_FAB2(SCH_1):PAGE84
  J9M1   55 VSS<69> SCONN288_H44441003_PIP-SCONN,HA   I138 @BASEBOARD_FAB2_LIB.BASEBOARD_FAB2(SCH_1):PAGE84
  J9M1   53 VSS<70> SCONN288_H44441003_PIP-SCONN,HA   I138 @BASEBOARD_FAB2_LIB.BASEBOARD_FAB2(SCH_1):PAGE84
  J9M1   50 VSS<71> SCONN288_H44441003_PIP-SCONN,HA   I138 @BASEBOARD_FAB2_LIB.BASEBOARD_FAB2(SCH_1):PAGE84
  J9M1   48 VSS<72> SCONN288_H44441003_PIP-SCONN,HA   I138 @BASEBOARD_FAB2_LIB.BASEBOARD_FAB2(SCH_1):PAGE84
  J9M1   46 VSS<73> SCONN288_H44441003_PIP-SCONN,HA   I138 @BASEBOARD_FAB2_LIB.BASEBOARD_FAB2(SCH_1):PAGE84
  J9M1   44 VSS<74> SCONN288_H44441003_PIP-SCONN,HA   I138 @BASEBOARD_FAB2_LIB.BASEBOARD_FAB2(SCH_1):PAGE84
  J9M1   42 VSS<75> SCONN288_H44441003_PIP-SCONN,HA   I138 @BASEBOARD_FAB2_LIB.BASEBOARD_FAB2(SCH_1):PAGE84
  J9M1   39 VSS<76> SCONN288_H44441003_PIP-SCONN,HA   I138 @BASEBOARD_FAB2_LIB.BASEBOARD_FAB2(SCH_1):PAGE84
  J9M1   37 VSS<77> SCONN288_H44441003_PIP-SCONN,HA   I138 @BASEBOARD_FAB2_LIB.BASEBOARD_FAB2(SCH_1):PAGE84
  J9M1   35 VSS<78> SCONN288_H44441003_PIP-SCONN,HA   I138 @BASEBOARD_FAB2_LIB.BASEBOARD_FAB2(SCH_1):PAGE84
  J9M1   33 VSS<79> SCONN288_H44441003_PIP-SCONN,HA   I138 @BASEBOARD_FAB2_LIB.BASEBOARD_FAB2(SCH_1):PAGE84
  J9M1   31 VSS<80> SCONN288_H44441003_PIP-SCONN,HA   I138 @BASEBOARD_FAB2_LIB.BASEBOARD_FAB2(SCH_1):PAGE84
  J9M1   28 VSS<81> SCONN288_H44441003_PIP-SCONN,HA   I138 @BASEBOARD_FAB2_LIB.BASEBOARD_FAB2(SCH_1):PAGE84
  J9M1   26 VSS<82> SCONN288_H44441003_PIP-SCONN,HA   I138 @BASEBOARD_FAB2_LIB.BASEBOARD_FAB2(SCH_1):PAGE84
  J9M1   24 VSS<83> SCONN288_H44441003_PIP-SCONN,HA   I138 @BASEBOARD_FAB2_LIB.BASEBOARD_FAB2(SCH_1):PAGE84
  J9M1   22 VSS<84> SCONN288_H44441003_PIP-SCONN,HA   I138 @BASEBOARD_FAB2_LIB.BASEBOARD_FAB2(SCH_1):PAGE84
  J9M1   20 VSS<85> SCONN288_H44441003_PIP-SCONN,HA   I138 @BASEBOARD_FAB2_LIB.BASEBOARD_FAB2(SCH_1):PAGE84
  J9M1   17 VSS<86> SCONN288_H44441003_PIP-SCONN,HA   I138 @BASEBOARD_FAB2_LIB.BASEBOARD_FAB2(SCH_1):PAGE84
  J9M1   15 VSS<87> SCONN288_H44441003_PIP-SCONN,HA   I138 @BASEBOARD_FAB2_LIB.BASEBOARD_FAB2(SCH_1):PAGE84
  J9M1   13 VSS<88> SCONN288_H44441003_PIP-SCONN,HA   I138 @BASEBOARD_FAB2_LIB.BASEBOARD_FAB2(SCH_1):PAGE84
  J9M1   11 VSS<89> SCONN288_H44441003_PIP-SCONN,HA   I138 @BASEBOARD_FAB2_LIB.BASEBOARD_FAB2(SCH_1):PAGE84
  J9M1    9 VSS<90> SCONN288_H44441003_PIP-SCONN,HA   I138 @BASEBOARD_FAB2_LIB.BASEBOARD_FAB2(SCH_1):PAGE84
  J9M1    6 VSS<91> SCONN288_H44441003_PIP-SCONN,HA   I138 @BASEBOARD_FAB2_LIB.BASEBOARD_FAB2(SCH_1):PAGE84
  J9M1    4 VSS<92> SCONN288_H44441003_PIP-SCONN,HA   I138 @BASEBOARD_FAB2_LIB.BASEBOARD_FAB2(SCH_1):PAGE84
  J9M1    2 VSS<93> SCONN288_H44441003_PIP-SCONN,HA   I138 @BASEBOARD_FAB2_LIB.BASEBOARD_FAB2(SCH_1):PAGE84
  J1A2  283 VSS<0> SCONN288_H44441004_PIP-SCONN,HA    I43 @BASEBOARD_FAB2_LIB.BASEBOARD_FAB2(SCH_1):PAGE85
  J1A2  281 VSS<1> SCONN288_H44441004_PIP-SCONN,HA    I43 @BASEBOARD_FAB2_LIB.BASEBOARD_FAB2(SCH_1):PAGE85
  J1A2  279 VSS<2> SCONN288_H44441004_PIP-SCONN,HA    I43 @BASEBOARD_FAB2_LIB.BASEBOARD_FAB2(SCH_1):PAGE85
  J1A2  276 VSS<3> SCONN288_H44441004_PIP-SCONN,HA    I43 @BASEBOARD_FAB2_LIB.BASEBOARD_FAB2(SCH_1):PAGE85
  J1A2  274 VSS<4> SCONN288_H44441004_PIP-SCONN,HA    I43 @BASEBOARD_FAB2_LIB.BASEBOARD_FAB2(SCH_1):PAGE85
  J1A2  272 VSS<5> SCONN288_H44441004_PIP-SCONN,HA    I43 @BASEBOARD_FAB2_LIB.BASEBOARD_FAB2(SCH_1):PAGE85
  J1A2  270 VSS<6> SCONN288_H44441004_PIP-SCONN,HA    I43 @BASEBOARD_FAB2_LIB.BASEBOARD_FAB2(SCH_1):PAGE85
  J1A2  268 VSS<7> SCONN288_H44441004_PIP-SCONN,HA    I43 @BASEBOARD_FAB2_LIB.BASEBOARD_FAB2(SCH_1):PAGE85
  J1A2  265 VSS<8> SCONN288_H44441004_PIP-SCONN,HA    I43 @BASEBOARD_FAB2_LIB.BASEBOARD_FAB2(SCH_1):PAGE85
  J1A2  263 VSS<9> SCONN288_H44441004_PIP-SCONN,HA    I43 @BASEBOARD_FAB2_LIB.BASEBOARD_FAB2(SCH_1):PAGE85
  J1A2  261 VSS<10> SCONN288_H44441004_PIP-SCONN,HA    I43 @BASEBOARD_FAB2_LIB.BASEBOARD_FAB2(SCH_1):PAGE85
  J1A2  259 VSS<11> SCONN288_H44441004_PIP-SCONN,HA    I43 @BASEBOARD_FAB2_LIB.BASEBOARD_FAB2(SCH_1):PAGE85
  J1A2  257 VSS<12> SCONN288_H44441004_PIP-SCONN,HA    I43 @BASEBOARD_FAB2_LIB.BASEBOARD_FAB2(SCH_1):PAGE85
  J1A2  254 VSS<13> SCONN288_H44441004_PIP-SCONN,HA    I43 @BASEBOARD_FAB2_LIB.BASEBOARD_FAB2(SCH_1):PAGE85
  J1A2  252 VSS<14> SCONN288_H44441004_PIP-SCONN,HA    I43 @BASEBOARD_FAB2_LIB.BASEBOARD_FAB2(SCH_1):PAGE85
  J1A2  250 VSS<15> SCONN288_H44441004_PIP-SCONN,HA    I43 @BASEBOARD_FAB2_LIB.BASEBOARD_FAB2(SCH_1):PAGE85
  J1A2  248 VSS<16> SCONN288_H44441004_PIP-SCONN,HA    I43 @BASEBOARD_FAB2_LIB.BASEBOARD_FAB2(SCH_1):PAGE85
  J1A2  246 VSS<17> SCONN288_H44441004_PIP-SCONN,HA    I43 @BASEBOARD_FAB2_LIB.BASEBOARD_FAB2(SCH_1):PAGE85
  J1A2  243 VSS<18> SCONN288_H44441004_PIP-SCONN,HA    I43 @BASEBOARD_FAB2_LIB.BASEBOARD_FAB2(SCH_1):PAGE85
  J1A2  241 VSS<19> SCONN288_H44441004_PIP-SCONN,HA    I43 @BASEBOARD_FAB2_LIB.BASEBOARD_FAB2(SCH_1):PAGE85
  J1A2  239 VSS<20> SCONN288_H44441004_PIP-SCONN,HA    I43 @BASEBOARD_FAB2_LIB.BASEBOARD_FAB2(SCH_1):PAGE85
  J1A2  202 VSS<21> SCONN288_H44441004_PIP-SCONN,HA    I43 @BASEBOARD_FAB2_LIB.BASEBOARD_FAB2(SCH_1):PAGE85
  J1A2  200 VSS<22> SCONN288_H44441004_PIP-SCONN,HA    I43 @BASEBOARD_FAB2_LIB.BASEBOARD_FAB2(SCH_1):PAGE85
  J1A2  198 VSS<23> SCONN288_H44441004_PIP-SCONN,HA    I43 @BASEBOARD_FAB2_LIB.BASEBOARD_FAB2(SCH_1):PAGE85
  J1A2  195 VSS<24> SCONN288_H44441004_PIP-SCONN,HA    I43 @BASEBOARD_FAB2_LIB.BASEBOARD_FAB2(SCH_1):PAGE85
  J1A2  193 VSS<25> SCONN288_H44441004_PIP-SCONN,HA    I43 @BASEBOARD_FAB2_LIB.BASEBOARD_FAB2(SCH_1):PAGE85
  J1A2  191 VSS<26> SCONN288_H44441004_PIP-SCONN,HA    I43 @BASEBOARD_FAB2_LIB.BASEBOARD_FAB2(SCH_1):PAGE85
  J1A2  189 VSS<27> SCONN288_H44441004_PIP-SCONN,HA    I43 @BASEBOARD_FAB2_LIB.BASEBOARD_FAB2(SCH_1):PAGE85
  J1A2  187 VSS<28> SCONN288_H44441004_PIP-SCONN,HA    I43 @BASEBOARD_FAB2_LIB.BASEBOARD_FAB2(SCH_1):PAGE85
  J1A2  184 VSS<29> SCONN288_H44441004_PIP-SCONN,HA    I43 @BASEBOARD_FAB2_LIB.BASEBOARD_FAB2(SCH_1):PAGE85
  J1A2  182 VSS<30> SCONN288_H44441004_PIP-SCONN,HA    I43 @BASEBOARD_FAB2_LIB.BASEBOARD_FAB2(SCH_1):PAGE85
  J1A2  180 VSS<31> SCONN288_H44441004_PIP-SCONN,HA    I43 @BASEBOARD_FAB2_LIB.BASEBOARD_FAB2(SCH_1):PAGE85
  J1A2  178 VSS<32> SCONN288_H44441004_PIP-SCONN,HA    I43 @BASEBOARD_FAB2_LIB.BASEBOARD_FAB2(SCH_1):PAGE85
  J1A2  176 VSS<33> SCONN288_H44441004_PIP-SCONN,HA    I43 @BASEBOARD_FAB2_LIB.BASEBOARD_FAB2(SCH_1):PAGE85
  J1A2  173 VSS<34> SCONN288_H44441004_PIP-SCONN,HA    I43 @BASEBOARD_FAB2_LIB.BASEBOARD_FAB2(SCH_1):PAGE85
  J1A2  171 VSS<35> SCONN288_H44441004_PIP-SCONN,HA    I43 @BASEBOARD_FAB2_LIB.BASEBOARD_FAB2(SCH_1):PAGE85
  J1A2  169 VSS<36> SCONN288_H44441004_PIP-SCONN,HA    I43 @BASEBOARD_FAB2_LIB.BASEBOARD_FAB2(SCH_1):PAGE85
  J1A2  167 VSS<37> SCONN288_H44441004_PIP-SCONN,HA    I43 @BASEBOARD_FAB2_LIB.BASEBOARD_FAB2(SCH_1):PAGE85
  J1A2  165 VSS<38> SCONN288_H44441004_PIP-SCONN,HA    I43 @BASEBOARD_FAB2_LIB.BASEBOARD_FAB2(SCH_1):PAGE85
  J1A2  162 VSS<39> SCONN288_H44441004_PIP-SCONN,HA    I43 @BASEBOARD_FAB2_LIB.BASEBOARD_FAB2(SCH_1):PAGE85
  J1A2  160 VSS<40> SCONN288_H44441004_PIP-SCONN,HA    I43 @BASEBOARD_FAB2_LIB.BASEBOARD_FAB2(SCH_1):PAGE85
  J1A2  158 VSS<41> SCONN288_H44441004_PIP-SCONN,HA    I43 @BASEBOARD_FAB2_LIB.BASEBOARD_FAB2(SCH_1):PAGE85
  J1A2  156 VSS<42> SCONN288_H44441004_PIP-SCONN,HA    I43 @BASEBOARD_FAB2_LIB.BASEBOARD_FAB2(SCH_1):PAGE85
  J1A2  154 VSS<43> SCONN288_H44441004_PIP-SCONN,HA    I43 @BASEBOARD_FAB2_LIB.BASEBOARD_FAB2(SCH_1):PAGE85
  J1A2  151 VSS<44> SCONN288_H44441004_PIP-SCONN,HA    I43 @BASEBOARD_FAB2_LIB.BASEBOARD_FAB2(SCH_1):PAGE85
  J1A2  149 VSS<45> SCONN288_H44441004_PIP-SCONN,HA    I43 @BASEBOARD_FAB2_LIB.BASEBOARD_FAB2(SCH_1):PAGE85
  J1A2  147 VSS<46> SCONN288_H44441004_PIP-SCONN,HA    I43 @BASEBOARD_FAB2_LIB.BASEBOARD_FAB2(SCH_1):PAGE85
  J1A2  138 VSS<47> SCONN288_H44441004_PIP-SCONN,HA    I43 @BASEBOARD_FAB2_LIB.BASEBOARD_FAB2(SCH_1):PAGE85
  J1A2  136 VSS<48> SCONN288_H44441004_PIP-SCONN,HA    I43 @BASEBOARD_FAB2_LIB.BASEBOARD_FAB2(SCH_1):PAGE85
  J1A2  134 VSS<49> SCONN288_H44441004_PIP-SCONN,HA    I43 @BASEBOARD_FAB2_LIB.BASEBOARD_FAB2(SCH_1):PAGE85
  J1A2  131 VSS<50> SCONN288_H44441004_PIP-SCONN,HA    I43 @BASEBOARD_FAB2_LIB.BASEBOARD_FAB2(SCH_1):PAGE85
  J1A2  129 VSS<51> SCONN288_H44441004_PIP-SCONN,HA    I43 @BASEBOARD_FAB2_LIB.BASEBOARD_FAB2(SCH_1):PAGE85
  J1A2  127 VSS<52> SCONN288_H44441004_PIP-SCONN,HA    I43 @BASEBOARD_FAB2_LIB.BASEBOARD_FAB2(SCH_1):PAGE85
  J1A2  125 VSS<53> SCONN288_H44441004_PIP-SCONN,HA    I43 @BASEBOARD_FAB2_LIB.BASEBOARD_FAB2(SCH_1):PAGE85
  J1A2  123 VSS<54> SCONN288_H44441004_PIP-SCONN,HA    I43 @BASEBOARD_FAB2_LIB.BASEBOARD_FAB2(SCH_1):PAGE85
  J1A2  120 VSS<55> SCONN288_H44441004_PIP-SCONN,HA    I43 @BASEBOARD_FAB2_LIB.BASEBOARD_FAB2(SCH_1):PAGE85
  J1A2  118 VSS<56> SCONN288_H44441004_PIP-SCONN,HA    I43 @BASEBOARD_FAB2_LIB.BASEBOARD_FAB2(SCH_1):PAGE85
  J1A2  116 VSS<57> SCONN288_H44441004_PIP-SCONN,HA    I43 @BASEBOARD_FAB2_LIB.BASEBOARD_FAB2(SCH_1):PAGE85
  J1A2  114 VSS<58> SCONN288_H44441004_PIP-SCONN,HA    I43 @BASEBOARD_FAB2_LIB.BASEBOARD_FAB2(SCH_1):PAGE85
  J1A2  112 VSS<59> SCONN288_H44441004_PIP-SCONN,HA    I43 @BASEBOARD_FAB2_LIB.BASEBOARD_FAB2(SCH_1):PAGE85
  J1A2  109 VSS<60> SCONN288_H44441004_PIP-SCONN,HA    I43 @BASEBOARD_FAB2_LIB.BASEBOARD_FAB2(SCH_1):PAGE85
  J1A2  107 VSS<61> SCONN288_H44441004_PIP-SCONN,HA    I43 @BASEBOARD_FAB2_LIB.BASEBOARD_FAB2(SCH_1):PAGE85
  J1A2  105 VSS<62> SCONN288_H44441004_PIP-SCONN,HA    I43 @BASEBOARD_FAB2_LIB.BASEBOARD_FAB2(SCH_1):PAGE85
  J1A2  103 VSS<63> SCONN288_H44441004_PIP-SCONN,HA    I43 @BASEBOARD_FAB2_LIB.BASEBOARD_FAB2(SCH_1):PAGE85
  J1A2  101 VSS<64> SCONN288_H44441004_PIP-SCONN,HA    I43 @BASEBOARD_FAB2_LIB.BASEBOARD_FAB2(SCH_1):PAGE85
  J1A2   98 VSS<65> SCONN288_H44441004_PIP-SCONN,HA    I43 @BASEBOARD_FAB2_LIB.BASEBOARD_FAB2(SCH_1):PAGE85
  J1A2   96 VSS<66> SCONN288_H44441004_PIP-SCONN,HA    I43 @BASEBOARD_FAB2_LIB.BASEBOARD_FAB2(SCH_1):PAGE85
  J1A2   94 VSS<67> SCONN288_H44441004_PIP-SCONN,HA    I43 @BASEBOARD_FAB2_LIB.BASEBOARD_FAB2(SCH_1):PAGE85
  J1A2   57 VSS<68> SCONN288_H44441004_PIP-SCONN,HA    I43 @BASEBOARD_FAB2_LIB.BASEBOARD_FAB2(SCH_1):PAGE85
  J1A2   55 VSS<69> SCONN288_H44441004_PIP-SCONN,HA    I43 @BASEBOARD_FAB2_LIB.BASEBOARD_FAB2(SCH_1):PAGE85
  J1A2   53 VSS<70> SCONN288_H44441004_PIP-SCONN,HA    I43 @BASEBOARD_FAB2_LIB.BASEBOARD_FAB2(SCH_1):PAGE85
  J1A2   50 VSS<71> SCONN288_H44441004_PIP-SCONN,HA    I43 @BASEBOARD_FAB2_LIB.BASEBOARD_FAB2(SCH_1):PAGE85
  J1A2   48 VSS<72> SCONN288_H44441004_PIP-SCONN,HA    I43 @BASEBOARD_FAB2_LIB.BASEBOARD_FAB2(SCH_1):PAGE85
  J1A2   46 VSS<73> SCONN288_H44441004_PIP-SCONN,HA    I43 @BASEBOARD_FAB2_LIB.BASEBOARD_FAB2(SCH_1):PAGE85
  J1A2   44 VSS<74> SCONN288_H44441004_PIP-SCONN,HA    I43 @BASEBOARD_FAB2_LIB.BASEBOARD_FAB2(SCH_1):PAGE85
  J1A2   42 VSS<75> SCONN288_H44441004_PIP-SCONN,HA    I43 @BASEBOARD_FAB2_LIB.BASEBOARD_FAB2(SCH_1):PAGE85
  J1A2   39 VSS<76> SCONN288_H44441004_PIP-SCONN,HA    I43 @BASEBOARD_FAB2_LIB.BASEBOARD_FAB2(SCH_1):PAGE85
  J1A2   37 VSS<77> SCONN288_H44441004_PIP-SCONN,HA    I43 @BASEBOARD_FAB2_LIB.BASEBOARD_FAB2(SCH_1):PAGE85
  J1A2   35 VSS<78> SCONN288_H44441004_PIP-SCONN,HA    I43 @BASEBOARD_FAB2_LIB.BASEBOARD_FAB2(SCH_1):PAGE85
  J1A2   33 VSS<79> SCONN288_H44441004_PIP-SCONN,HA    I43 @BASEBOARD_FAB2_LIB.BASEBOARD_FAB2(SCH_1):PAGE85
  J1A2   31 VSS<80> SCONN288_H44441004_PIP-SCONN,HA    I43 @BASEBOARD_FAB2_LIB.BASEBOARD_FAB2(SCH_1):PAGE85
  J1A2   28 VSS<81> SCONN288_H44441004_PIP-SCONN,HA    I43 @BASEBOARD_FAB2_LIB.BASEBOARD_FAB2(SCH_1):PAGE85
  J1A2   26 VSS<82> SCONN288_H44441004_PIP-SCONN,HA    I43 @BASEBOARD_FAB2_LIB.BASEBOARD_FAB2(SCH_1):PAGE85
  J1A2   24 VSS<83> SCONN288_H44441004_PIP-SCONN,HA    I43 @BASEBOARD_FAB2_LIB.BASEBOARD_FAB2(SCH_1):PAGE85
  J1A2   22 VSS<84> SCONN288_H44441004_PIP-SCONN,HA    I43 @BASEBOARD_FAB2_LIB.BASEBOARD_FAB2(SCH_1):PAGE85
  J1A2   20 VSS<85> SCONN288_H44441004_PIP-SCONN,HA    I43 @BASEBOARD_FAB2_LIB.BASEBOARD_FAB2(SCH_1):PAGE85
  J1A2   17 VSS<86> SCONN288_H44441004_PIP-SCONN,HA    I43 @BASEBOARD_FAB2_LIB.BASEBOARD_FAB2(SCH_1):PAGE85
  J1A2   15 VSS<87> SCONN288_H44441004_PIP-SCONN,HA    I43 @BASEBOARD_FAB2_LIB.BASEBOARD_FAB2(SCH_1):PAGE85
  J1A2   13 VSS<88> SCONN288_H44441004_PIP-SCONN,HA    I43 @BASEBOARD_FAB2_LIB.BASEBOARD_FAB2(SCH_1):PAGE85
  J1A2   11 VSS<89> SCONN288_H44441004_PIP-SCONN,HA    I43 @BASEBOARD_FAB2_LIB.BASEBOARD_FAB2(SCH_1):PAGE85
  J1A2    9 VSS<90> SCONN288_H44441004_PIP-SCONN,HA    I43 @BASEBOARD_FAB2_LIB.BASEBOARD_FAB2(SCH_1):PAGE85
  J1A2    6 VSS<91> SCONN288_H44441004_PIP-SCONN,HA    I43 @BASEBOARD_FAB2_LIB.BASEBOARD_FAB2(SCH_1):PAGE85
  J1A2    4 VSS<92> SCONN288_H44441004_PIP-SCONN,HA    I43 @BASEBOARD_FAB2_LIB.BASEBOARD_FAB2(SCH_1):PAGE85
  J1A2    2 VSS<93> SCONN288_H44441004_PIP-SCONN,HA    I43 @BASEBOARD_FAB2_LIB.BASEBOARD_FAB2(SCH_1):PAGE85
  J1A2  139  SA<0> SCONN288_H44441004_PIP-SCONN,HA   I111 @BASEBOARD_FAB2_LIB.BASEBOARD_FAB2(SCH_1):PAGE85
  J1A2  238  SA<2> SCONN288_H44441004_PIP-SCONN,HA   I111 @BASEBOARD_FAB2_LIB.BASEBOARD_FAB2(SCH_1):PAGE85
  C9L7    2      B CAP_A_0402V-0.01UF,25V,10%,X7RA   I181 @BASEBOARD_FAB2_LIB.BASEBOARD_FAB2(SCH_1):PAGE85
  J9L2  238  SA<2> SCONN288_H44441003_PIP-SCONN,HA    I12 @BASEBOARD_FAB2_LIB.BASEBOARD_FAB2(SCH_1):PAGE86
  J9L2  283 VSS<0> SCONN288_H44441003_PIP-SCONN,HA   I138 @BASEBOARD_FAB2_LIB.BASEBOARD_FAB2(SCH_1):PAGE86
  J9L2  281 VSS<1> SCONN288_H44441003_PIP-SCONN,HA   I138 @BASEBOARD_FAB2_LIB.BASEBOARD_FAB2(SCH_1):PAGE86
  J9L2  279 VSS<2> SCONN288_H44441003_PIP-SCONN,HA   I138 @BASEBOARD_FAB2_LIB.BASEBOARD_FAB2(SCH_1):PAGE86
  J9L2  276 VSS<3> SCONN288_H44441003_PIP-SCONN,HA   I138 @BASEBOARD_FAB2_LIB.BASEBOARD_FAB2(SCH_1):PAGE86
  J9L2  274 VSS<4> SCONN288_H44441003_PIP-SCONN,HA   I138 @BASEBOARD_FAB2_LIB.BASEBOARD_FAB2(SCH_1):PAGE86
  J9L2  272 VSS<5> SCONN288_H44441003_PIP-SCONN,HA   I138 @BASEBOARD_FAB2_LIB.BASEBOARD_FAB2(SCH_1):PAGE86
  J9L2  270 VSS<6> SCONN288_H44441003_PIP-SCONN,HA   I138 @BASEBOARD_FAB2_LIB.BASEBOARD_FAB2(SCH_1):PAGE86
  J9L2  268 VSS<7> SCONN288_H44441003_PIP-SCONN,HA   I138 @BASEBOARD_FAB2_LIB.BASEBOARD_FAB2(SCH_1):PAGE86
  J9L2  265 VSS<8> SCONN288_H44441003_PIP-SCONN,HA   I138 @BASEBOARD_FAB2_LIB.BASEBOARD_FAB2(SCH_1):PAGE86
  J9L2  263 VSS<9> SCONN288_H44441003_PIP-SCONN,HA   I138 @BASEBOARD_FAB2_LIB.BASEBOARD_FAB2(SCH_1):PAGE86
  J9L2  261 VSS<10> SCONN288_H44441003_PIP-SCONN,HA   I138 @BASEBOARD_FAB2_LIB.BASEBOARD_FAB2(SCH_1):PAGE86
  J9L2  259 VSS<11> SCONN288_H44441003_PIP-SCONN,HA   I138 @BASEBOARD_FAB2_LIB.BASEBOARD_FAB2(SCH_1):PAGE86
  J9L2  257 VSS<12> SCONN288_H44441003_PIP-SCONN,HA   I138 @BASEBOARD_FAB2_LIB.BASEBOARD_FAB2(SCH_1):PAGE86
  J9L2  254 VSS<13> SCONN288_H44441003_PIP-SCONN,HA   I138 @BASEBOARD_FAB2_LIB.BASEBOARD_FAB2(SCH_1):PAGE86
  J9L2  252 VSS<14> SCONN288_H44441003_PIP-SCONN,HA   I138 @BASEBOARD_FAB2_LIB.BASEBOARD_FAB2(SCH_1):PAGE86
  J9L2  250 VSS<15> SCONN288_H44441003_PIP-SCONN,HA   I138 @BASEBOARD_FAB2_LIB.BASEBOARD_FAB2(SCH_1):PAGE86
  J9L2  248 VSS<16> SCONN288_H44441003_PIP-SCONN,HA   I138 @BASEBOARD_FAB2_LIB.BASEBOARD_FAB2(SCH_1):PAGE86
  J9L2  246 VSS<17> SCONN288_H44441003_PIP-SCONN,HA   I138 @BASEBOARD_FAB2_LIB.BASEBOARD_FAB2(SCH_1):PAGE86
  J9L2  243 VSS<18> SCONN288_H44441003_PIP-SCONN,HA   I138 @BASEBOARD_FAB2_LIB.BASEBOARD_FAB2(SCH_1):PAGE86
  J9L2  241 VSS<19> SCONN288_H44441003_PIP-SCONN,HA   I138 @BASEBOARD_FAB2_LIB.BASEBOARD_FAB2(SCH_1):PAGE86
  J9L2  239 VSS<20> SCONN288_H44441003_PIP-SCONN,HA   I138 @BASEBOARD_FAB2_LIB.BASEBOARD_FAB2(SCH_1):PAGE86
  J9L2  202 VSS<21> SCONN288_H44441003_PIP-SCONN,HA   I138 @BASEBOARD_FAB2_LIB.BASEBOARD_FAB2(SCH_1):PAGE86
  J9L2  200 VSS<22> SCONN288_H44441003_PIP-SCONN,HA   I138 @BASEBOARD_FAB2_LIB.BASEBOARD_FAB2(SCH_1):PAGE86
  J9L2  198 VSS<23> SCONN288_H44441003_PIP-SCONN,HA   I138 @BASEBOARD_FAB2_LIB.BASEBOARD_FAB2(SCH_1):PAGE86
  J9L2  195 VSS<24> SCONN288_H44441003_PIP-SCONN,HA   I138 @BASEBOARD_FAB2_LIB.BASEBOARD_FAB2(SCH_1):PAGE86
  J9L2  193 VSS<25> SCONN288_H44441003_PIP-SCONN,HA   I138 @BASEBOARD_FAB2_LIB.BASEBOARD_FAB2(SCH_1):PAGE86
  J9L2  191 VSS<26> SCONN288_H44441003_PIP-SCONN,HA   I138 @BASEBOARD_FAB2_LIB.BASEBOARD_FAB2(SCH_1):PAGE86
  J9L2  189 VSS<27> SCONN288_H44441003_PIP-SCONN,HA   I138 @BASEBOARD_FAB2_LIB.BASEBOARD_FAB2(SCH_1):PAGE86
  J9L2  187 VSS<28> SCONN288_H44441003_PIP-SCONN,HA   I138 @BASEBOARD_FAB2_LIB.BASEBOARD_FAB2(SCH_1):PAGE86
  J9L2  184 VSS<29> SCONN288_H44441003_PIP-SCONN,HA   I138 @BASEBOARD_FAB2_LIB.BASEBOARD_FAB2(SCH_1):PAGE86
  J9L2  182 VSS<30> SCONN288_H44441003_PIP-SCONN,HA   I138 @BASEBOARD_FAB2_LIB.BASEBOARD_FAB2(SCH_1):PAGE86
  J9L2  180 VSS<31> SCONN288_H44441003_PIP-SCONN,HA   I138 @BASEBOARD_FAB2_LIB.BASEBOARD_FAB2(SCH_1):PAGE86
  J9L2  178 VSS<32> SCONN288_H44441003_PIP-SCONN,HA   I138 @BASEBOARD_FAB2_LIB.BASEBOARD_FAB2(SCH_1):PAGE86
  J9L2  176 VSS<33> SCONN288_H44441003_PIP-SCONN,HA   I138 @BASEBOARD_FAB2_LIB.BASEBOARD_FAB2(SCH_1):PAGE86
  J9L2  173 VSS<34> SCONN288_H44441003_PIP-SCONN,HA   I138 @BASEBOARD_FAB2_LIB.BASEBOARD_FAB2(SCH_1):PAGE86
  J9L2  171 VSS<35> SCONN288_H44441003_PIP-SCONN,HA   I138 @BASEBOARD_FAB2_LIB.BASEBOARD_FAB2(SCH_1):PAGE86
  J9L2  169 VSS<36> SCONN288_H44441003_PIP-SCONN,HA   I138 @BASEBOARD_FAB2_LIB.BASEBOARD_FAB2(SCH_1):PAGE86
  J9L2  167 VSS<37> SCONN288_H44441003_PIP-SCONN,HA   I138 @BASEBOARD_FAB2_LIB.BASEBOARD_FAB2(SCH_1):PAGE86
  J9L2  165 VSS<38> SCONN288_H44441003_PIP-SCONN,HA   I138 @BASEBOARD_FAB2_LIB.BASEBOARD_FAB2(SCH_1):PAGE86
  J9L2  162 VSS<39> SCONN288_H44441003_PIP-SCONN,HA   I138 @BASEBOARD_FAB2_LIB.BASEBOARD_FAB2(SCH_1):PAGE86
  J9L2  160 VSS<40> SCONN288_H44441003_PIP-SCONN,HA   I138 @BASEBOARD_FAB2_LIB.BASEBOARD_FAB2(SCH_1):PAGE86
  J9L2  158 VSS<41> SCONN288_H44441003_PIP-SCONN,HA   I138 @BASEBOARD_FAB2_LIB.BASEBOARD_FAB2(SCH_1):PAGE86
  J9L2  156 VSS<42> SCONN288_H44441003_PIP-SCONN,HA   I138 @BASEBOARD_FAB2_LIB.BASEBOARD_FAB2(SCH_1):PAGE86
  J9L2  154 VSS<43> SCONN288_H44441003_PIP-SCONN,HA   I138 @BASEBOARD_FAB2_LIB.BASEBOARD_FAB2(SCH_1):PAGE86
  J9L2  151 VSS<44> SCONN288_H44441003_PIP-SCONN,HA   I138 @BASEBOARD_FAB2_LIB.BASEBOARD_FAB2(SCH_1):PAGE86
  J9L2  149 VSS<45> SCONN288_H44441003_PIP-SCONN,HA   I138 @BASEBOARD_FAB2_LIB.BASEBOARD_FAB2(SCH_1):PAGE86
  J9L2  147 VSS<46> SCONN288_H44441003_PIP-SCONN,HA   I138 @BASEBOARD_FAB2_LIB.BASEBOARD_FAB2(SCH_1):PAGE86
  J9L2  138 VSS<47> SCONN288_H44441003_PIP-SCONN,HA   I138 @BASEBOARD_FAB2_LIB.BASEBOARD_FAB2(SCH_1):PAGE86
  J9L2  136 VSS<48> SCONN288_H44441003_PIP-SCONN,HA   I138 @BASEBOARD_FAB2_LIB.BASEBOARD_FAB2(SCH_1):PAGE86
  J9L2  134 VSS<49> SCONN288_H44441003_PIP-SCONN,HA   I138 @BASEBOARD_FAB2_LIB.BASEBOARD_FAB2(SCH_1):PAGE86
  J9L2  131 VSS<50> SCONN288_H44441003_PIP-SCONN,HA   I138 @BASEBOARD_FAB2_LIB.BASEBOARD_FAB2(SCH_1):PAGE86
  J9L2  129 VSS<51> SCONN288_H44441003_PIP-SCONN,HA   I138 @BASEBOARD_FAB2_LIB.BASEBOARD_FAB2(SCH_1):PAGE86
  J9L2  127 VSS<52> SCONN288_H44441003_PIP-SCONN,HA   I138 @BASEBOARD_FAB2_LIB.BASEBOARD_FAB2(SCH_1):PAGE86
  J9L2  125 VSS<53> SCONN288_H44441003_PIP-SCONN,HA   I138 @BASEBOARD_FAB2_LIB.BASEBOARD_FAB2(SCH_1):PAGE86
  J9L2  123 VSS<54> SCONN288_H44441003_PIP-SCONN,HA   I138 @BASEBOARD_FAB2_LIB.BASEBOARD_FAB2(SCH_1):PAGE86
  J9L2  120 VSS<55> SCONN288_H44441003_PIP-SCONN,HA   I138 @BASEBOARD_FAB2_LIB.BASEBOARD_FAB2(SCH_1):PAGE86
  J9L2  118 VSS<56> SCONN288_H44441003_PIP-SCONN,HA   I138 @BASEBOARD_FAB2_LIB.BASEBOARD_FAB2(SCH_1):PAGE86
  J9L2  116 VSS<57> SCONN288_H44441003_PIP-SCONN,HA   I138 @BASEBOARD_FAB2_LIB.BASEBOARD_FAB2(SCH_1):PAGE86
  J9L2  114 VSS<58> SCONN288_H44441003_PIP-SCONN,HA   I138 @BASEBOARD_FAB2_LIB.BASEBOARD_FAB2(SCH_1):PAGE86
  J9L2  112 VSS<59> SCONN288_H44441003_PIP-SCONN,HA   I138 @BASEBOARD_FAB2_LIB.BASEBOARD_FAB2(SCH_1):PAGE86
  J9L2  109 VSS<60> SCONN288_H44441003_PIP-SCONN,HA   I138 @BASEBOARD_FAB2_LIB.BASEBOARD_FAB2(SCH_1):PAGE86
  J9L2  107 VSS<61> SCONN288_H44441003_PIP-SCONN,HA   I138 @BASEBOARD_FAB2_LIB.BASEBOARD_FAB2(SCH_1):PAGE86
  J9L2  105 VSS<62> SCONN288_H44441003_PIP-SCONN,HA   I138 @BASEBOARD_FAB2_LIB.BASEBOARD_FAB2(SCH_1):PAGE86
  J9L2  103 VSS<63> SCONN288_H44441003_PIP-SCONN,HA   I138 @BASEBOARD_FAB2_LIB.BASEBOARD_FAB2(SCH_1):PAGE86
  J9L2  101 VSS<64> SCONN288_H44441003_PIP-SCONN,HA   I138 @BASEBOARD_FAB2_LIB.BASEBOARD_FAB2(SCH_1):PAGE86
  J9L2   98 VSS<65> SCONN288_H44441003_PIP-SCONN,HA   I138 @BASEBOARD_FAB2_LIB.BASEBOARD_FAB2(SCH_1):PAGE86
  J9L2   96 VSS<66> SCONN288_H44441003_PIP-SCONN,HA   I138 @BASEBOARD_FAB2_LIB.BASEBOARD_FAB2(SCH_1):PAGE86
  J9L2   94 VSS<67> SCONN288_H44441003_PIP-SCONN,HA   I138 @BASEBOARD_FAB2_LIB.BASEBOARD_FAB2(SCH_1):PAGE86
  J9L2   57 VSS<68> SCONN288_H44441003_PIP-SCONN,HA   I138 @BASEBOARD_FAB2_LIB.BASEBOARD_FAB2(SCH_1):PAGE86
  J9L2   55 VSS<69> SCONN288_H44441003_PIP-SCONN,HA   I138 @BASEBOARD_FAB2_LIB.BASEBOARD_FAB2(SCH_1):PAGE86
  J9L2   53 VSS<70> SCONN288_H44441003_PIP-SCONN,HA   I138 @BASEBOARD_FAB2_LIB.BASEBOARD_FAB2(SCH_1):PAGE86
  J9L2   50 VSS<71> SCONN288_H44441003_PIP-SCONN,HA   I138 @BASEBOARD_FAB2_LIB.BASEBOARD_FAB2(SCH_1):PAGE86
  J9L2   48 VSS<72> SCONN288_H44441003_PIP-SCONN,HA   I138 @BASEBOARD_FAB2_LIB.BASEBOARD_FAB2(SCH_1):PAGE86
  J9L2   46 VSS<73> SCONN288_H44441003_PIP-SCONN,HA   I138 @BASEBOARD_FAB2_LIB.BASEBOARD_FAB2(SCH_1):PAGE86
  J9L2   44 VSS<74> SCONN288_H44441003_PIP-SCONN,HA   I138 @BASEBOARD_FAB2_LIB.BASEBOARD_FAB2(SCH_1):PAGE86
  J9L2   42 VSS<75> SCONN288_H44441003_PIP-SCONN,HA   I138 @BASEBOARD_FAB2_LIB.BASEBOARD_FAB2(SCH_1):PAGE86
  J9L2   39 VSS<76> SCONN288_H44441003_PIP-SCONN,HA   I138 @BASEBOARD_FAB2_LIB.BASEBOARD_FAB2(SCH_1):PAGE86
  J9L2   37 VSS<77> SCONN288_H44441003_PIP-SCONN,HA   I138 @BASEBOARD_FAB2_LIB.BASEBOARD_FAB2(SCH_1):PAGE86
  J9L2   35 VSS<78> SCONN288_H44441003_PIP-SCONN,HA   I138 @BASEBOARD_FAB2_LIB.BASEBOARD_FAB2(SCH_1):PAGE86
  J9L2   33 VSS<79> SCONN288_H44441003_PIP-SCONN,HA   I138 @BASEBOARD_FAB2_LIB.BASEBOARD_FAB2(SCH_1):PAGE86
  J9L2   31 VSS<80> SCONN288_H44441003_PIP-SCONN,HA   I138 @BASEBOARD_FAB2_LIB.BASEBOARD_FAB2(SCH_1):PAGE86
  J9L2   28 VSS<81> SCONN288_H44441003_PIP-SCONN,HA   I138 @BASEBOARD_FAB2_LIB.BASEBOARD_FAB2(SCH_1):PAGE86
  J9L2   26 VSS<82> SCONN288_H44441003_PIP-SCONN,HA   I138 @BASEBOARD_FAB2_LIB.BASEBOARD_FAB2(SCH_1):PAGE86
  J9L2   24 VSS<83> SCONN288_H44441003_PIP-SCONN,HA   I138 @BASEBOARD_FAB2_LIB.BASEBOARD_FAB2(SCH_1):PAGE86
  J9L2   22 VSS<84> SCONN288_H44441003_PIP-SCONN,HA   I138 @BASEBOARD_FAB2_LIB.BASEBOARD_FAB2(SCH_1):PAGE86
  J9L2   20 VSS<85> SCONN288_H44441003_PIP-SCONN,HA   I138 @BASEBOARD_FAB2_LIB.BASEBOARD_FAB2(SCH_1):PAGE86
  J9L2   17 VSS<86> SCONN288_H44441003_PIP-SCONN,HA   I138 @BASEBOARD_FAB2_LIB.BASEBOARD_FAB2(SCH_1):PAGE86
  J9L2   15 VSS<87> SCONN288_H44441003_PIP-SCONN,HA   I138 @BASEBOARD_FAB2_LIB.BASEBOARD_FAB2(SCH_1):PAGE86
  J9L2   13 VSS<88> SCONN288_H44441003_PIP-SCONN,HA   I138 @BASEBOARD_FAB2_LIB.BASEBOARD_FAB2(SCH_1):PAGE86
  J9L2   11 VSS<89> SCONN288_H44441003_PIP-SCONN,HA   I138 @BASEBOARD_FAB2_LIB.BASEBOARD_FAB2(SCH_1):PAGE86
  J9L2    9 VSS<90> SCONN288_H44441003_PIP-SCONN,HA   I138 @BASEBOARD_FAB2_LIB.BASEBOARD_FAB2(SCH_1):PAGE86
  J9L2    6 VSS<91> SCONN288_H44441003_PIP-SCONN,HA   I138 @BASEBOARD_FAB2_LIB.BASEBOARD_FAB2(SCH_1):PAGE86
  J9L2    4 VSS<92> SCONN288_H44441003_PIP-SCONN,HA   I138 @BASEBOARD_FAB2_LIB.BASEBOARD_FAB2(SCH_1):PAGE86
  J9L2    2 VSS<93> SCONN288_H44441003_PIP-SCONN,HA   I138 @BASEBOARD_FAB2_LIB.BASEBOARD_FAB2(SCH_1):PAGE86
 C1A17    2      B CAP_A_0402V-0.01UF,25V,10%,X7RA   I182 @BASEBOARD_FAB2_LIB.BASEBOARD_FAB2(SCH_1):PAGE86
  C1A5    2      B CAP_A_0402V-0.01UF,25V,10%,X7RA   I178 @BASEBOARD_FAB2_LIB.BASEBOARD_FAB2(SCH_1):PAGE87
  J1A1  283 VSS<0> SCONN288_H44441004_PIP-SCONN,HA   I185 @BASEBOARD_FAB2_LIB.BASEBOARD_FAB2(SCH_1):PAGE87
  J1A1  281 VSS<1> SCONN288_H44441004_PIP-SCONN,HA   I185 @BASEBOARD_FAB2_LIB.BASEBOARD_FAB2(SCH_1):PAGE87
  J1A1  279 VSS<2> SCONN288_H44441004_PIP-SCONN,HA   I185 @BASEBOARD_FAB2_LIB.BASEBOARD_FAB2(SCH_1):PAGE87
  J1A1  276 VSS<3> SCONN288_H44441004_PIP-SCONN,HA   I185 @BASEBOARD_FAB2_LIB.BASEBOARD_FAB2(SCH_1):PAGE87
  J1A1  274 VSS<4> SCONN288_H44441004_PIP-SCONN,HA   I185 @BASEBOARD_FAB2_LIB.BASEBOARD_FAB2(SCH_1):PAGE87
  J1A1  272 VSS<5> SCONN288_H44441004_PIP-SCONN,HA   I185 @BASEBOARD_FAB2_LIB.BASEBOARD_FAB2(SCH_1):PAGE87
  J1A1  270 VSS<6> SCONN288_H44441004_PIP-SCONN,HA   I185 @BASEBOARD_FAB2_LIB.BASEBOARD_FAB2(SCH_1):PAGE87
  J1A1  268 VSS<7> SCONN288_H44441004_PIP-SCONN,HA   I185 @BASEBOARD_FAB2_LIB.BASEBOARD_FAB2(SCH_1):PAGE87
  J1A1  265 VSS<8> SCONN288_H44441004_PIP-SCONN,HA   I185 @BASEBOARD_FAB2_LIB.BASEBOARD_FAB2(SCH_1):PAGE87
  J1A1  263 VSS<9> SCONN288_H44441004_PIP-SCONN,HA   I185 @BASEBOARD_FAB2_LIB.BASEBOARD_FAB2(SCH_1):PAGE87
  J1A1  261 VSS<10> SCONN288_H44441004_PIP-SCONN,HA   I185 @BASEBOARD_FAB2_LIB.BASEBOARD_FAB2(SCH_1):PAGE87
  J1A1  259 VSS<11> SCONN288_H44441004_PIP-SCONN,HA   I185 @BASEBOARD_FAB2_LIB.BASEBOARD_FAB2(SCH_1):PAGE87
  J1A1  257 VSS<12> SCONN288_H44441004_PIP-SCONN,HA   I185 @BASEBOARD_FAB2_LIB.BASEBOARD_FAB2(SCH_1):PAGE87
  J1A1  254 VSS<13> SCONN288_H44441004_PIP-SCONN,HA   I185 @BASEBOARD_FAB2_LIB.BASEBOARD_FAB2(SCH_1):PAGE87
  J1A1  252 VSS<14> SCONN288_H44441004_PIP-SCONN,HA   I185 @BASEBOARD_FAB2_LIB.BASEBOARD_FAB2(SCH_1):PAGE87
  J1A1  250 VSS<15> SCONN288_H44441004_PIP-SCONN,HA   I185 @BASEBOARD_FAB2_LIB.BASEBOARD_FAB2(SCH_1):PAGE87
  J1A1  248 VSS<16> SCONN288_H44441004_PIP-SCONN,HA   I185 @BASEBOARD_FAB2_LIB.BASEBOARD_FAB2(SCH_1):PAGE87
  J1A1  246 VSS<17> SCONN288_H44441004_PIP-SCONN,HA   I185 @BASEBOARD_FAB2_LIB.BASEBOARD_FAB2(SCH_1):PAGE87
  J1A1  243 VSS<18> SCONN288_H44441004_PIP-SCONN,HA   I185 @BASEBOARD_FAB2_LIB.BASEBOARD_FAB2(SCH_1):PAGE87
  J1A1  241 VSS<19> SCONN288_H44441004_PIP-SCONN,HA   I185 @BASEBOARD_FAB2_LIB.BASEBOARD_FAB2(SCH_1):PAGE87
  J1A1  239 VSS<20> SCONN288_H44441004_PIP-SCONN,HA   I185 @BASEBOARD_FAB2_LIB.BASEBOARD_FAB2(SCH_1):PAGE87
  J1A1  202 VSS<21> SCONN288_H44441004_PIP-SCONN,HA   I185 @BASEBOARD_FAB2_LIB.BASEBOARD_FAB2(SCH_1):PAGE87
  J1A1  200 VSS<22> SCONN288_H44441004_PIP-SCONN,HA   I185 @BASEBOARD_FAB2_LIB.BASEBOARD_FAB2(SCH_1):PAGE87
  J1A1  198 VSS<23> SCONN288_H44441004_PIP-SCONN,HA   I185 @BASEBOARD_FAB2_LIB.BASEBOARD_FAB2(SCH_1):PAGE87
  J1A1  195 VSS<24> SCONN288_H44441004_PIP-SCONN,HA   I185 @BASEBOARD_FAB2_LIB.BASEBOARD_FAB2(SCH_1):PAGE87
  J1A1  193 VSS<25> SCONN288_H44441004_PIP-SCONN,HA   I185 @BASEBOARD_FAB2_LIB.BASEBOARD_FAB2(SCH_1):PAGE87
  J1A1  191 VSS<26> SCONN288_H44441004_PIP-SCONN,HA   I185 @BASEBOARD_FAB2_LIB.BASEBOARD_FAB2(SCH_1):PAGE87
  J1A1  189 VSS<27> SCONN288_H44441004_PIP-SCONN,HA   I185 @BASEBOARD_FAB2_LIB.BASEBOARD_FAB2(SCH_1):PAGE87
  J1A1  187 VSS<28> SCONN288_H44441004_PIP-SCONN,HA   I185 @BASEBOARD_FAB2_LIB.BASEBOARD_FAB2(SCH_1):PAGE87
  J1A1  184 VSS<29> SCONN288_H44441004_PIP-SCONN,HA   I185 @BASEBOARD_FAB2_LIB.BASEBOARD_FAB2(SCH_1):PAGE87
  J1A1  182 VSS<30> SCONN288_H44441004_PIP-SCONN,HA   I185 @BASEBOARD_FAB2_LIB.BASEBOARD_FAB2(SCH_1):PAGE87
  J1A1  180 VSS<31> SCONN288_H44441004_PIP-SCONN,HA   I185 @BASEBOARD_FAB2_LIB.BASEBOARD_FAB2(SCH_1):PAGE87
  J1A1  178 VSS<32> SCONN288_H44441004_PIP-SCONN,HA   I185 @BASEBOARD_FAB2_LIB.BASEBOARD_FAB2(SCH_1):PAGE87
  J1A1  176 VSS<33> SCONN288_H44441004_PIP-SCONN,HA   I185 @BASEBOARD_FAB2_LIB.BASEBOARD_FAB2(SCH_1):PAGE87
  J1A1  173 VSS<34> SCONN288_H44441004_PIP-SCONN,HA   I185 @BASEBOARD_FAB2_LIB.BASEBOARD_FAB2(SCH_1):PAGE87
  J1A1  171 VSS<35> SCONN288_H44441004_PIP-SCONN,HA   I185 @BASEBOARD_FAB2_LIB.BASEBOARD_FAB2(SCH_1):PAGE87
  J1A1  169 VSS<36> SCONN288_H44441004_PIP-SCONN,HA   I185 @BASEBOARD_FAB2_LIB.BASEBOARD_FAB2(SCH_1):PAGE87
  J1A1  167 VSS<37> SCONN288_H44441004_PIP-SCONN,HA   I185 @BASEBOARD_FAB2_LIB.BASEBOARD_FAB2(SCH_1):PAGE87
  J1A1  165 VSS<38> SCONN288_H44441004_PIP-SCONN,HA   I185 @BASEBOARD_FAB2_LIB.BASEBOARD_FAB2(SCH_1):PAGE87
  J1A1  162 VSS<39> SCONN288_H44441004_PIP-SCONN,HA   I185 @BASEBOARD_FAB2_LIB.BASEBOARD_FAB2(SCH_1):PAGE87
  J1A1  160 VSS<40> SCONN288_H44441004_PIP-SCONN,HA   I185 @BASEBOARD_FAB2_LIB.BASEBOARD_FAB2(SCH_1):PAGE87
  J1A1  158 VSS<41> SCONN288_H44441004_PIP-SCONN,HA   I185 @BASEBOARD_FAB2_LIB.BASEBOARD_FAB2(SCH_1):PAGE87
  J1A1  156 VSS<42> SCONN288_H44441004_PIP-SCONN,HA   I185 @BASEBOARD_FAB2_LIB.BASEBOARD_FAB2(SCH_1):PAGE87
  J1A1  154 VSS<43> SCONN288_H44441004_PIP-SCONN,HA   I185 @BASEBOARD_FAB2_LIB.BASEBOARD_FAB2(SCH_1):PAGE87
  J1A1  151 VSS<44> SCONN288_H44441004_PIP-SCONN,HA   I185 @BASEBOARD_FAB2_LIB.BASEBOARD_FAB2(SCH_1):PAGE87
  J1A1  149 VSS<45> SCONN288_H44441004_PIP-SCONN,HA   I185 @BASEBOARD_FAB2_LIB.BASEBOARD_FAB2(SCH_1):PAGE87
  J1A1  147 VSS<46> SCONN288_H44441004_PIP-SCONN,HA   I185 @BASEBOARD_FAB2_LIB.BASEBOARD_FAB2(SCH_1):PAGE87
  J1A1  138 VSS<47> SCONN288_H44441004_PIP-SCONN,HA   I185 @BASEBOARD_FAB2_LIB.BASEBOARD_FAB2(SCH_1):PAGE87
  J1A1  136 VSS<48> SCONN288_H44441004_PIP-SCONN,HA   I185 @BASEBOARD_FAB2_LIB.BASEBOARD_FAB2(SCH_1):PAGE87
  J1A1  134 VSS<49> SCONN288_H44441004_PIP-SCONN,HA   I185 @BASEBOARD_FAB2_LIB.BASEBOARD_FAB2(SCH_1):PAGE87
  J1A1  131 VSS<50> SCONN288_H44441004_PIP-SCONN,HA   I185 @BASEBOARD_FAB2_LIB.BASEBOARD_FAB2(SCH_1):PAGE87
  J1A1  129 VSS<51> SCONN288_H44441004_PIP-SCONN,HA   I185 @BASEBOARD_FAB2_LIB.BASEBOARD_FAB2(SCH_1):PAGE87
  J1A1  127 VSS<52> SCONN288_H44441004_PIP-SCONN,HA   I185 @BASEBOARD_FAB2_LIB.BASEBOARD_FAB2(SCH_1):PAGE87
  J1A1  125 VSS<53> SCONN288_H44441004_PIP-SCONN,HA   I185 @BASEBOARD_FAB2_LIB.BASEBOARD_FAB2(SCH_1):PAGE87
  J1A1  123 VSS<54> SCONN288_H44441004_PIP-SCONN,HA   I185 @BASEBOARD_FAB2_LIB.BASEBOARD_FAB2(SCH_1):PAGE87
  J1A1  120 VSS<55> SCONN288_H44441004_PIP-SCONN,HA   I185 @BASEBOARD_FAB2_LIB.BASEBOARD_FAB2(SCH_1):PAGE87
  J1A1  118 VSS<56> SCONN288_H44441004_PIP-SCONN,HA   I185 @BASEBOARD_FAB2_LIB.BASEBOARD_FAB2(SCH_1):PAGE87
  J1A1  116 VSS<57> SCONN288_H44441004_PIP-SCONN,HA   I185 @BASEBOARD_FAB2_LIB.BASEBOARD_FAB2(SCH_1):PAGE87
  J1A1  114 VSS<58> SCONN288_H44441004_PIP-SCONN,HA   I185 @BASEBOARD_FAB2_LIB.BASEBOARD_FAB2(SCH_1):PAGE87
  J1A1  112 VSS<59> SCONN288_H44441004_PIP-SCONN,HA   I185 @BASEBOARD_FAB2_LIB.BASEBOARD_FAB2(SCH_1):PAGE87
  J1A1  109 VSS<60> SCONN288_H44441004_PIP-SCONN,HA   I185 @BASEBOARD_FAB2_LIB.BASEBOARD_FAB2(SCH_1):PAGE87
  J1A1  107 VSS<61> SCONN288_H44441004_PIP-SCONN,HA   I185 @BASEBOARD_FAB2_LIB.BASEBOARD_FAB2(SCH_1):PAGE87
  J1A1  105 VSS<62> SCONN288_H44441004_PIP-SCONN,HA   I185 @BASEBOARD_FAB2_LIB.BASEBOARD_FAB2(SCH_1):PAGE87
  J1A1  103 VSS<63> SCONN288_H44441004_PIP-SCONN,HA   I185 @BASEBOARD_FAB2_LIB.BASEBOARD_FAB2(SCH_1):PAGE87
  J1A1  101 VSS<64> SCONN288_H44441004_PIP-SCONN,HA   I185 @BASEBOARD_FAB2_LIB.BASEBOARD_FAB2(SCH_1):PAGE87
  J1A1   98 VSS<65> SCONN288_H44441004_PIP-SCONN,HA   I185 @BASEBOARD_FAB2_LIB.BASEBOARD_FAB2(SCH_1):PAGE87
  J1A1   96 VSS<66> SCONN288_H44441004_PIP-SCONN,HA   I185 @BASEBOARD_FAB2_LIB.BASEBOARD_FAB2(SCH_1):PAGE87
  J1A1   94 VSS<67> SCONN288_H44441004_PIP-SCONN,HA   I185 @BASEBOARD_FAB2_LIB.BASEBOARD_FAB2(SCH_1):PAGE87
  J1A1   57 VSS<68> SCONN288_H44441004_PIP-SCONN,HA   I185 @BASEBOARD_FAB2_LIB.BASEBOARD_FAB2(SCH_1):PAGE87
  J1A1   55 VSS<69> SCONN288_H44441004_PIP-SCONN,HA   I185 @BASEBOARD_FAB2_LIB.BASEBOARD_FAB2(SCH_1):PAGE87
  J1A1   53 VSS<70> SCONN288_H44441004_PIP-SCONN,HA   I185 @BASEBOARD_FAB2_LIB.BASEBOARD_FAB2(SCH_1):PAGE87
  J1A1   50 VSS<71> SCONN288_H44441004_PIP-SCONN,HA   I185 @BASEBOARD_FAB2_LIB.BASEBOARD_FAB2(SCH_1):PAGE87
  J1A1   48 VSS<72> SCONN288_H44441004_PIP-SCONN,HA   I185 @BASEBOARD_FAB2_LIB.BASEBOARD_FAB2(SCH_1):PAGE87
  J1A1   46 VSS<73> SCONN288_H44441004_PIP-SCONN,HA   I185 @BASEBOARD_FAB2_LIB.BASEBOARD_FAB2(SCH_1):PAGE87
  J1A1   44 VSS<74> SCONN288_H44441004_PIP-SCONN,HA   I185 @BASEBOARD_FAB2_LIB.BASEBOARD_FAB2(SCH_1):PAGE87
  J1A1   42 VSS<75> SCONN288_H44441004_PIP-SCONN,HA   I185 @BASEBOARD_FAB2_LIB.BASEBOARD_FAB2(SCH_1):PAGE87
  J1A1   39 VSS<76> SCONN288_H44441004_PIP-SCONN,HA   I185 @BASEBOARD_FAB2_LIB.BASEBOARD_FAB2(SCH_1):PAGE87
  J1A1   37 VSS<77> SCONN288_H44441004_PIP-SCONN,HA   I185 @BASEBOARD_FAB2_LIB.BASEBOARD_FAB2(SCH_1):PAGE87
  J1A1   35 VSS<78> SCONN288_H44441004_PIP-SCONN,HA   I185 @BASEBOARD_FAB2_LIB.BASEBOARD_FAB2(SCH_1):PAGE87
  J1A1   33 VSS<79> SCONN288_H44441004_PIP-SCONN,HA   I185 @BASEBOARD_FAB2_LIB.BASEBOARD_FAB2(SCH_1):PAGE87
  J1A1   31 VSS<80> SCONN288_H44441004_PIP-SCONN,HA   I185 @BASEBOARD_FAB2_LIB.BASEBOARD_FAB2(SCH_1):PAGE87
  J1A1   28 VSS<81> SCONN288_H44441004_PIP-SCONN,HA   I185 @BASEBOARD_FAB2_LIB.BASEBOARD_FAB2(SCH_1):PAGE87
  J1A1   26 VSS<82> SCONN288_H44441004_PIP-SCONN,HA   I185 @BASEBOARD_FAB2_LIB.BASEBOARD_FAB2(SCH_1):PAGE87
  J1A1   24 VSS<83> SCONN288_H44441004_PIP-SCONN,HA   I185 @BASEBOARD_FAB2_LIB.BASEBOARD_FAB2(SCH_1):PAGE87
  J1A1   22 VSS<84> SCONN288_H44441004_PIP-SCONN,HA   I185 @BASEBOARD_FAB2_LIB.BASEBOARD_FAB2(SCH_1):PAGE87
  J1A1   20 VSS<85> SCONN288_H44441004_PIP-SCONN,HA   I185 @BASEBOARD_FAB2_LIB.BASEBOARD_FAB2(SCH_1):PAGE87
  J1A1   17 VSS<86> SCONN288_H44441004_PIP-SCONN,HA   I185 @BASEBOARD_FAB2_LIB.BASEBOARD_FAB2(SCH_1):PAGE87
  J1A1   15 VSS<87> SCONN288_H44441004_PIP-SCONN,HA   I185 @BASEBOARD_FAB2_LIB.BASEBOARD_FAB2(SCH_1):PAGE87
  J1A1   13 VSS<88> SCONN288_H44441004_PIP-SCONN,HA   I185 @BASEBOARD_FAB2_LIB.BASEBOARD_FAB2(SCH_1):PAGE87
  J1A1   11 VSS<89> SCONN288_H44441004_PIP-SCONN,HA   I185 @BASEBOARD_FAB2_LIB.BASEBOARD_FAB2(SCH_1):PAGE87
  J1A1    9 VSS<90> SCONN288_H44441004_PIP-SCONN,HA   I185 @BASEBOARD_FAB2_LIB.BASEBOARD_FAB2(SCH_1):PAGE87
  J1A1    6 VSS<91> SCONN288_H44441004_PIP-SCONN,HA   I185 @BASEBOARD_FAB2_LIB.BASEBOARD_FAB2(SCH_1):PAGE87
  J1A1    4 VSS<92> SCONN288_H44441004_PIP-SCONN,HA   I185 @BASEBOARD_FAB2_LIB.BASEBOARD_FAB2(SCH_1):PAGE87
  J1A1    2 VSS<93> SCONN288_H44441004_PIP-SCONN,HA   I185 @BASEBOARD_FAB2_LIB.BASEBOARD_FAB2(SCH_1):PAGE87
  J1A1  139  SA<0> SCONN288_H44441004_PIP-SCONN,HA   I186 @BASEBOARD_FAB2_LIB.BASEBOARD_FAB2(SCH_1):PAGE87
  J1A1  140  SA<1> SCONN288_H44441004_PIP-SCONN,HA   I186 @BASEBOARD_FAB2_LIB.BASEBOARD_FAB2(SCH_1):PAGE87
  J9L1  283 VSS<0> SCONN288_H44441003_PIP-SCONN,HA    I25 @BASEBOARD_FAB2_LIB.BASEBOARD_FAB2(SCH_1):PAGE88
  J9L1  281 VSS<1> SCONN288_H44441003_PIP-SCONN,HA    I25 @BASEBOARD_FAB2_LIB.BASEBOARD_FAB2(SCH_1):PAGE88
  J9L1  279 VSS<2> SCONN288_H44441003_PIP-SCONN,HA    I25 @BASEBOARD_FAB2_LIB.BASEBOARD_FAB2(SCH_1):PAGE88
  J9L1  276 VSS<3> SCONN288_H44441003_PIP-SCONN,HA    I25 @BASEBOARD_FAB2_LIB.BASEBOARD_FAB2(SCH_1):PAGE88
  J9L1  274 VSS<4> SCONN288_H44441003_PIP-SCONN,HA    I25 @BASEBOARD_FAB2_LIB.BASEBOARD_FAB2(SCH_1):PAGE88
  J9L1  272 VSS<5> SCONN288_H44441003_PIP-SCONN,HA    I25 @BASEBOARD_FAB2_LIB.BASEBOARD_FAB2(SCH_1):PAGE88
  J9L1  270 VSS<6> SCONN288_H44441003_PIP-SCONN,HA    I25 @BASEBOARD_FAB2_LIB.BASEBOARD_FAB2(SCH_1):PAGE88
  J9L1  268 VSS<7> SCONN288_H44441003_PIP-SCONN,HA    I25 @BASEBOARD_FAB2_LIB.BASEBOARD_FAB2(SCH_1):PAGE88
  J9L1  265 VSS<8> SCONN288_H44441003_PIP-SCONN,HA    I25 @BASEBOARD_FAB2_LIB.BASEBOARD_FAB2(SCH_1):PAGE88
  J9L1  263 VSS<9> SCONN288_H44441003_PIP-SCONN,HA    I25 @BASEBOARD_FAB2_LIB.BASEBOARD_FAB2(SCH_1):PAGE88
  J9L1  261 VSS<10> SCONN288_H44441003_PIP-SCONN,HA    I25 @BASEBOARD_FAB2_LIB.BASEBOARD_FAB2(SCH_1):PAGE88
  J9L1  259 VSS<11> SCONN288_H44441003_PIP-SCONN,HA    I25 @BASEBOARD_FAB2_LIB.BASEBOARD_FAB2(SCH_1):PAGE88
  J9L1  257 VSS<12> SCONN288_H44441003_PIP-SCONN,HA    I25 @BASEBOARD_FAB2_LIB.BASEBOARD_FAB2(SCH_1):PAGE88
  J9L1  254 VSS<13> SCONN288_H44441003_PIP-SCONN,HA    I25 @BASEBOARD_FAB2_LIB.BASEBOARD_FAB2(SCH_1):PAGE88
  J9L1  252 VSS<14> SCONN288_H44441003_PIP-SCONN,HA    I25 @BASEBOARD_FAB2_LIB.BASEBOARD_FAB2(SCH_1):PAGE88
  J9L1  250 VSS<15> SCONN288_H44441003_PIP-SCONN,HA    I25 @BASEBOARD_FAB2_LIB.BASEBOARD_FAB2(SCH_1):PAGE88
  J9L1  248 VSS<16> SCONN288_H44441003_PIP-SCONN,HA    I25 @BASEBOARD_FAB2_LIB.BASEBOARD_FAB2(SCH_1):PAGE88
  J9L1  246 VSS<17> SCONN288_H44441003_PIP-SCONN,HA    I25 @BASEBOARD_FAB2_LIB.BASEBOARD_FAB2(SCH_1):PAGE88
  J9L1  243 VSS<18> SCONN288_H44441003_PIP-SCONN,HA    I25 @BASEBOARD_FAB2_LIB.BASEBOARD_FAB2(SCH_1):PAGE88
  J9L1  241 VSS<19> SCONN288_H44441003_PIP-SCONN,HA    I25 @BASEBOARD_FAB2_LIB.BASEBOARD_FAB2(SCH_1):PAGE88
  J9L1  239 VSS<20> SCONN288_H44441003_PIP-SCONN,HA    I25 @BASEBOARD_FAB2_LIB.BASEBOARD_FAB2(SCH_1):PAGE88
  J9L1  202 VSS<21> SCONN288_H44441003_PIP-SCONN,HA    I25 @BASEBOARD_FAB2_LIB.BASEBOARD_FAB2(SCH_1):PAGE88
  J9L1  200 VSS<22> SCONN288_H44441003_PIP-SCONN,HA    I25 @BASEBOARD_FAB2_LIB.BASEBOARD_FAB2(SCH_1):PAGE88
  J9L1  198 VSS<23> SCONN288_H44441003_PIP-SCONN,HA    I25 @BASEBOARD_FAB2_LIB.BASEBOARD_FAB2(SCH_1):PAGE88
  J9L1  195 VSS<24> SCONN288_H44441003_PIP-SCONN,HA    I25 @BASEBOARD_FAB2_LIB.BASEBOARD_FAB2(SCH_1):PAGE88
  J9L1  193 VSS<25> SCONN288_H44441003_PIP-SCONN,HA    I25 @BASEBOARD_FAB2_LIB.BASEBOARD_FAB2(SCH_1):PAGE88
  J9L1  191 VSS<26> SCONN288_H44441003_PIP-SCONN,HA    I25 @BASEBOARD_FAB2_LIB.BASEBOARD_FAB2(SCH_1):PAGE88
  J9L1  189 VSS<27> SCONN288_H44441003_PIP-SCONN,HA    I25 @BASEBOARD_FAB2_LIB.BASEBOARD_FAB2(SCH_1):PAGE88
  J9L1  187 VSS<28> SCONN288_H44441003_PIP-SCONN,HA    I25 @BASEBOARD_FAB2_LIB.BASEBOARD_FAB2(SCH_1):PAGE88
  J9L1  184 VSS<29> SCONN288_H44441003_PIP-SCONN,HA    I25 @BASEBOARD_FAB2_LIB.BASEBOARD_FAB2(SCH_1):PAGE88
  J9L1  182 VSS<30> SCONN288_H44441003_PIP-SCONN,HA    I25 @BASEBOARD_FAB2_LIB.BASEBOARD_FAB2(SCH_1):PAGE88
  J9L1  180 VSS<31> SCONN288_H44441003_PIP-SCONN,HA    I25 @BASEBOARD_FAB2_LIB.BASEBOARD_FAB2(SCH_1):PAGE88
  J9L1  178 VSS<32> SCONN288_H44441003_PIP-SCONN,HA    I25 @BASEBOARD_FAB2_LIB.BASEBOARD_FAB2(SCH_1):PAGE88
  J9L1  176 VSS<33> SCONN288_H44441003_PIP-SCONN,HA    I25 @BASEBOARD_FAB2_LIB.BASEBOARD_FAB2(SCH_1):PAGE88
  J9L1  173 VSS<34> SCONN288_H44441003_PIP-SCONN,HA    I25 @BASEBOARD_FAB2_LIB.BASEBOARD_FAB2(SCH_1):PAGE88
  J9L1  171 VSS<35> SCONN288_H44441003_PIP-SCONN,HA    I25 @BASEBOARD_FAB2_LIB.BASEBOARD_FAB2(SCH_1):PAGE88
  J9L1  169 VSS<36> SCONN288_H44441003_PIP-SCONN,HA    I25 @BASEBOARD_FAB2_LIB.BASEBOARD_FAB2(SCH_1):PAGE88
  J9L1  167 VSS<37> SCONN288_H44441003_PIP-SCONN,HA    I25 @BASEBOARD_FAB2_LIB.BASEBOARD_FAB2(SCH_1):PAGE88
  J9L1  165 VSS<38> SCONN288_H44441003_PIP-SCONN,HA    I25 @BASEBOARD_FAB2_LIB.BASEBOARD_FAB2(SCH_1):PAGE88
  J9L1  162 VSS<39> SCONN288_H44441003_PIP-SCONN,HA    I25 @BASEBOARD_FAB2_LIB.BASEBOARD_FAB2(SCH_1):PAGE88
  J9L1  160 VSS<40> SCONN288_H44441003_PIP-SCONN,HA    I25 @BASEBOARD_FAB2_LIB.BASEBOARD_FAB2(SCH_1):PAGE88
  J9L1  158 VSS<41> SCONN288_H44441003_PIP-SCONN,HA    I25 @BASEBOARD_FAB2_LIB.BASEBOARD_FAB2(SCH_1):PAGE88
  J9L1  156 VSS<42> SCONN288_H44441003_PIP-SCONN,HA    I25 @BASEBOARD_FAB2_LIB.BASEBOARD_FAB2(SCH_1):PAGE88
  J9L1  154 VSS<43> SCONN288_H44441003_PIP-SCONN,HA    I25 @BASEBOARD_FAB2_LIB.BASEBOARD_FAB2(SCH_1):PAGE88
  J9L1  151 VSS<44> SCONN288_H44441003_PIP-SCONN,HA    I25 @BASEBOARD_FAB2_LIB.BASEBOARD_FAB2(SCH_1):PAGE88
  J9L1  149 VSS<45> SCONN288_H44441003_PIP-SCONN,HA    I25 @BASEBOARD_FAB2_LIB.BASEBOARD_FAB2(SCH_1):PAGE88
  J9L1  147 VSS<46> SCONN288_H44441003_PIP-SCONN,HA    I25 @BASEBOARD_FAB2_LIB.BASEBOARD_FAB2(SCH_1):PAGE88
  J9L1  138 VSS<47> SCONN288_H44441003_PIP-SCONN,HA    I25 @BASEBOARD_FAB2_LIB.BASEBOARD_FAB2(SCH_1):PAGE88
  J9L1  136 VSS<48> SCONN288_H44441003_PIP-SCONN,HA    I25 @BASEBOARD_FAB2_LIB.BASEBOARD_FAB2(SCH_1):PAGE88
  J9L1  134 VSS<49> SCONN288_H44441003_PIP-SCONN,HA    I25 @BASEBOARD_FAB2_LIB.BASEBOARD_FAB2(SCH_1):PAGE88
  J9L1  131 VSS<50> SCONN288_H44441003_PIP-SCONN,HA    I25 @BASEBOARD_FAB2_LIB.BASEBOARD_FAB2(SCH_1):PAGE88
  J9L1  129 VSS<51> SCONN288_H44441003_PIP-SCONN,HA    I25 @BASEBOARD_FAB2_LIB.BASEBOARD_FAB2(SCH_1):PAGE88
  J9L1  127 VSS<52> SCONN288_H44441003_PIP-SCONN,HA    I25 @BASEBOARD_FAB2_LIB.BASEBOARD_FAB2(SCH_1):PAGE88
  J9L1  125 VSS<53> SCONN288_H44441003_PIP-SCONN,HA    I25 @BASEBOARD_FAB2_LIB.BASEBOARD_FAB2(SCH_1):PAGE88
  J9L1  123 VSS<54> SCONN288_H44441003_PIP-SCONN,HA    I25 @BASEBOARD_FAB2_LIB.BASEBOARD_FAB2(SCH_1):PAGE88
  J9L1  120 VSS<55> SCONN288_H44441003_PIP-SCONN,HA    I25 @BASEBOARD_FAB2_LIB.BASEBOARD_FAB2(SCH_1):PAGE88
  J9L1  118 VSS<56> SCONN288_H44441003_PIP-SCONN,HA    I25 @BASEBOARD_FAB2_LIB.BASEBOARD_FAB2(SCH_1):PAGE88
  J9L1  116 VSS<57> SCONN288_H44441003_PIP-SCONN,HA    I25 @BASEBOARD_FAB2_LIB.BASEBOARD_FAB2(SCH_1):PAGE88
  J9L1  114 VSS<58> SCONN288_H44441003_PIP-SCONN,HA    I25 @BASEBOARD_FAB2_LIB.BASEBOARD_FAB2(SCH_1):PAGE88
  J9L1  112 VSS<59> SCONN288_H44441003_PIP-SCONN,HA    I25 @BASEBOARD_FAB2_LIB.BASEBOARD_FAB2(SCH_1):PAGE88
  J9L1  109 VSS<60> SCONN288_H44441003_PIP-SCONN,HA    I25 @BASEBOARD_FAB2_LIB.BASEBOARD_FAB2(SCH_1):PAGE88
  J9L1  107 VSS<61> SCONN288_H44441003_PIP-SCONN,HA    I25 @BASEBOARD_FAB2_LIB.BASEBOARD_FAB2(SCH_1):PAGE88
  J9L1  105 VSS<62> SCONN288_H44441003_PIP-SCONN,HA    I25 @BASEBOARD_FAB2_LIB.BASEBOARD_FAB2(SCH_1):PAGE88
  J9L1  103 VSS<63> SCONN288_H44441003_PIP-SCONN,HA    I25 @BASEBOARD_FAB2_LIB.BASEBOARD_FAB2(SCH_1):PAGE88
  J9L1  101 VSS<64> SCONN288_H44441003_PIP-SCONN,HA    I25 @BASEBOARD_FAB2_LIB.BASEBOARD_FAB2(SCH_1):PAGE88
  J9L1   98 VSS<65> SCONN288_H44441003_PIP-SCONN,HA    I25 @BASEBOARD_FAB2_LIB.BASEBOARD_FAB2(SCH_1):PAGE88
  J9L1   96 VSS<66> SCONN288_H44441003_PIP-SCONN,HA    I25 @BASEBOARD_FAB2_LIB.BASEBOARD_FAB2(SCH_1):PAGE88
  J9L1   94 VSS<67> SCONN288_H44441003_PIP-SCONN,HA    I25 @BASEBOARD_FAB2_LIB.BASEBOARD_FAB2(SCH_1):PAGE88
  J9L1   57 VSS<68> SCONN288_H44441003_PIP-SCONN,HA    I25 @BASEBOARD_FAB2_LIB.BASEBOARD_FAB2(SCH_1):PAGE88
  J9L1   55 VSS<69> SCONN288_H44441003_PIP-SCONN,HA    I25 @BASEBOARD_FAB2_LIB.BASEBOARD_FAB2(SCH_1):PAGE88
  J9L1   53 VSS<70> SCONN288_H44441003_PIP-SCONN,HA    I25 @BASEBOARD_FAB2_LIB.BASEBOARD_FAB2(SCH_1):PAGE88
  J9L1   50 VSS<71> SCONN288_H44441003_PIP-SCONN,HA    I25 @BASEBOARD_FAB2_LIB.BASEBOARD_FAB2(SCH_1):PAGE88
  J9L1   48 VSS<72> SCONN288_H44441003_PIP-SCONN,HA    I25 @BASEBOARD_FAB2_LIB.BASEBOARD_FAB2(SCH_1):PAGE88
  J9L1   46 VSS<73> SCONN288_H44441003_PIP-SCONN,HA    I25 @BASEBOARD_FAB2_LIB.BASEBOARD_FAB2(SCH_1):PAGE88
  J9L1   44 VSS<74> SCONN288_H44441003_PIP-SCONN,HA    I25 @BASEBOARD_FAB2_LIB.BASEBOARD_FAB2(SCH_1):PAGE88
  J9L1   42 VSS<75> SCONN288_H44441003_PIP-SCONN,HA    I25 @BASEBOARD_FAB2_LIB.BASEBOARD_FAB2(SCH_1):PAGE88
  J9L1   39 VSS<76> SCONN288_H44441003_PIP-SCONN,HA    I25 @BASEBOARD_FAB2_LIB.BASEBOARD_FAB2(SCH_1):PAGE88
  J9L1   37 VSS<77> SCONN288_H44441003_PIP-SCONN,HA    I25 @BASEBOARD_FAB2_LIB.BASEBOARD_FAB2(SCH_1):PAGE88
  J9L1   35 VSS<78> SCONN288_H44441003_PIP-SCONN,HA    I25 @BASEBOARD_FAB2_LIB.BASEBOARD_FAB2(SCH_1):PAGE88
  J9L1   33 VSS<79> SCONN288_H44441003_PIP-SCONN,HA    I25 @BASEBOARD_FAB2_LIB.BASEBOARD_FAB2(SCH_1):PAGE88
  J9L1   31 VSS<80> SCONN288_H44441003_PIP-SCONN,HA    I25 @BASEBOARD_FAB2_LIB.BASEBOARD_FAB2(SCH_1):PAGE88
  J9L1   28 VSS<81> SCONN288_H44441003_PIP-SCONN,HA    I25 @BASEBOARD_FAB2_LIB.BASEBOARD_FAB2(SCH_1):PAGE88
  J9L1   26 VSS<82> SCONN288_H44441003_PIP-SCONN,HA    I25 @BASEBOARD_FAB2_LIB.BASEBOARD_FAB2(SCH_1):PAGE88
  J9L1   24 VSS<83> SCONN288_H44441003_PIP-SCONN,HA    I25 @BASEBOARD_FAB2_LIB.BASEBOARD_FAB2(SCH_1):PAGE88
  J9L1   22 VSS<84> SCONN288_H44441003_PIP-SCONN,HA    I25 @BASEBOARD_FAB2_LIB.BASEBOARD_FAB2(SCH_1):PAGE88
  J9L1   20 VSS<85> SCONN288_H44441003_PIP-SCONN,HA    I25 @BASEBOARD_FAB2_LIB.BASEBOARD_FAB2(SCH_1):PAGE88
  J9L1   17 VSS<86> SCONN288_H44441003_PIP-SCONN,HA    I25 @BASEBOARD_FAB2_LIB.BASEBOARD_FAB2(SCH_1):PAGE88
  J9L1   15 VSS<87> SCONN288_H44441003_PIP-SCONN,HA    I25 @BASEBOARD_FAB2_LIB.BASEBOARD_FAB2(SCH_1):PAGE88
  J9L1   13 VSS<88> SCONN288_H44441003_PIP-SCONN,HA    I25 @BASEBOARD_FAB2_LIB.BASEBOARD_FAB2(SCH_1):PAGE88
  J9L1   11 VSS<89> SCONN288_H44441003_PIP-SCONN,HA    I25 @BASEBOARD_FAB2_LIB.BASEBOARD_FAB2(SCH_1):PAGE88
  J9L1    9 VSS<90> SCONN288_H44441003_PIP-SCONN,HA    I25 @BASEBOARD_FAB2_LIB.BASEBOARD_FAB2(SCH_1):PAGE88
  J9L1    6 VSS<91> SCONN288_H44441003_PIP-SCONN,HA    I25 @BASEBOARD_FAB2_LIB.BASEBOARD_FAB2(SCH_1):PAGE88
  J9L1    4 VSS<92> SCONN288_H44441003_PIP-SCONN,HA    I25 @BASEBOARD_FAB2_LIB.BASEBOARD_FAB2(SCH_1):PAGE88
  J9L1    2 VSS<93> SCONN288_H44441003_PIP-SCONN,HA    I25 @BASEBOARD_FAB2_LIB.BASEBOARD_FAB2(SCH_1):PAGE88
  J9L1  140  SA<1> SCONN288_H44441003_PIP-SCONN,HA   I111 @BASEBOARD_FAB2_LIB.BASEBOARD_FAB2(SCH_1):PAGE88
  C9L1    2      B CAP_A_0402V-0.01UF,25V,10%,X7RA   I177 @BASEBOARD_FAB2_LIB.BASEBOARD_FAB2(SCH_1):PAGE88
  Q6F1    2    SRC FET_N_SOT23-2N7002,FET,C79254-A    I18 @BASEBOARD_FAB2_LIB.BASEBOARD_FAB2(SCH_1):PAGE89
  Q8D1    4   E<0> NPN_DUAL_SSOPLF-MBT3904,XSTR,CA    I35 @BASEBOARD_FAB2_LIB.BASEBOARD_FAB2(SCH_1):PAGE89
  Q8D1    1   E<0> NPN_DUAL_SSOPLF-MBT3904,XSTR,CA    I36 @BASEBOARD_FAB2_LIB.BASEBOARD_FAB2(SCH_1):PAGE89
  R6D6    1      A RES_0402-240,1.0%,1/16W,CHIP,GA     I3 @BASEBOARD_FAB2_LIB.BASEBOARD_FAB2(SCH_1):PAGE90
  R4P1    1      A RES_0402-240,1.0%,1/16W,EMPTY,A     I4 @BASEBOARD_FAB2_LIB.BASEBOARD_FAB2(SCH_1):PAGE90
 R3D12    1      A RES_0402-240,1.0%,1/16W,CHIP,GA    I11 @BASEBOARD_FAB2_LIB.BASEBOARD_FAB2(SCH_1):PAGE90
 R3D13    1      A RES_0402-240,1.0%,1/16W,EMPTY,A    I12 @BASEBOARD_FAB2_LIB.BASEBOARD_FAB2(SCH_1):PAGE90
  R4P6    1      A RES_0402-240,1.0%,1/16W,EMPTY,A    I68 @BASEBOARD_FAB2_LIB.BASEBOARD_FAB2(SCH_1):PAGE90
 R7P14    1      A RES_0402-240,1.0%,1/16W,CHIP,GA    I70 @BASEBOARD_FAB2_LIB.BASEBOARD_FAB2(SCH_1):PAGE90
  R4P7    1      A RES_0402-240,1.0%,1/16W,EMPTY,A    I72 @BASEBOARD_FAB2_LIB.BASEBOARD_FAB2(SCH_1):PAGE90
 R7P15    1      A RES_0402-240,1.0%,1/16W,EMPTY,A    I74 @BASEBOARD_FAB2_LIB.BASEBOARD_FAB2(SCH_1):PAGE90
  R5P2    2      B RES_0402-49.9,1%,1/16W,CHIP,G2A    I79 @BASEBOARD_FAB2_LIB.BASEBOARD_FAB2(SCH_1):PAGE90
  R5P3    2      B RES_0402-49.9,1%,1/16W,CHIP,G2A    I80 @BASEBOARD_FAB2_LIB.BASEBOARD_FAB2(SCH_1):PAGE90
  R6D5    2      B RES_0402-49.9,1%,1/16W,CHIP,G2A    I81 @BASEBOARD_FAB2_LIB.BASEBOARD_FAB2(SCH_1):PAGE90
  R8P1    2      B RES_0402-49.9,1%,1/16W,CHIP,G2A    I85 @BASEBOARD_FAB2_LIB.BASEBOARD_FAB2(SCH_1):PAGE90
  R8P2    2      B RES_0402-49.9,1%,1/16W,CHIP,G2A    I86 @BASEBOARD_FAB2_LIB.BASEBOARD_FAB2(SCH_1):PAGE90
  R3D9    2      B RES_0402-49.9,1%,1/16W,CHIP,G2A    I88 @BASEBOARD_FAB2_LIB.BASEBOARD_FAB2(SCH_1):PAGE90
  J8B1    1    IO1 SCONN24_H46321001_SM-SCONN,H46A     I1 @BASEBOARD_FAB2_LIB.BASEBOARD_FAB2(SCH_1):PAGE91
  J8B1    7    IO7 SCONN24_H46321001_SM-SCONN,H46A     I1 @BASEBOARD_FAB2_LIB.BASEBOARD_FAB2(SCH_1):PAGE91
  J8B1    9    IO9 SCONN24_H46321001_SM-SCONN,H46A     I1 @BASEBOARD_FAB2_LIB.BASEBOARD_FAB2(SCH_1):PAGE91
  J8B1   15   IO15 SCONN24_H46321001_SM-SCONN,H46A     I1 @BASEBOARD_FAB2_LIB.BASEBOARD_FAB2(SCH_1):PAGE91
  J8B1   23   IO23 SCONN24_H46321001_SM-SCONN,H46A     I1 @BASEBOARD_FAB2_LIB.BASEBOARD_FAB2(SCH_1):PAGE91
  J8B1  MP1    MP1 SCONN24_H46321001_SM-SCONN,H46A     I1 @BASEBOARD_FAB2_LIB.BASEBOARD_FAB2(SCH_1):PAGE91
  J8B1  MP2    MP2 SCONN24_H46321001_SM-SCONN,H46A     I1 @BASEBOARD_FAB2_LIB.BASEBOARD_FAB2(SCH_1):PAGE91
  U3P2    7 GND<0> GTL2014_SM-IC,D66151-001     I1 @BASEBOARD_FAB2_LIB.BASEBOARD_FAB2(SCH_1):PAGE92
  U3P2    8 GND<1> GTL2014_SM-IC,D66151-001     I1 @BASEBOARD_FAB2_LIB.BASEBOARD_FAB2(SCH_1):PAGE92
  U3P2   11 GND<2> GTL2014_SM-IC,D66151-001     I1 @BASEBOARD_FAB2_LIB.BASEBOARD_FAB2(SCH_1):PAGE92
  U7D2    7 GND<0> GTL2014_SM-IC,D66151-001    I32 @BASEBOARD_FAB2_LIB.BASEBOARD_FAB2(SCH_1):PAGE92
  U7D2    8 GND<1> GTL2014_SM-IC,D66151-001    I32 @BASEBOARD_FAB2_LIB.BASEBOARD_FAB2(SCH_1):PAGE92
  U7D2   11 GND<2> GTL2014_SM-IC,D66151-001    I32 @BASEBOARD_FAB2_LIB.BASEBOARD_FAB2(SCH_1):PAGE92
 C3P49    2      B CAP_A_0402V-0.1UF,16V,10%,X7R,A    I37 @BASEBOARD_FAB2_LIB.BASEBOARD_FAB2(SCH_1):PAGE92
 R3P49    2      B RES_0402-100.0,1%,1/16W,CHIP,GA    I38 @BASEBOARD_FAB2_LIB.BASEBOARD_FAB2(SCH_1):PAGE92
  R3R1    2      B RES_0402-1.00K,1%,1/16W,CHIP,GA    I46 @BASEBOARD_FAB2_LIB.BASEBOARD_FAB2(SCH_1):PAGE92
 R7D32    2      B RES_0402-100.0,1%,1/16W,CHIP,GA    I48 @BASEBOARD_FAB2_LIB.BASEBOARD_FAB2(SCH_1):PAGE92
  C7D5    2      B CAP_A_0402V-0.1UF,16V,10%,X7R,A    I52 @BASEBOARD_FAB2_LIB.BASEBOARD_FAB2(SCH_1):PAGE92
 R7D26    2      B RES_0402-1.00K,1%,1/16W,CHIP,GA    I54 @BASEBOARD_FAB2_LIB.BASEBOARD_FAB2(SCH_1):PAGE92
  R3R2    2      B RES_0402-1.00K,1%,1/16W,CHIP,GA    I75 @BASEBOARD_FAB2_LIB.BASEBOARD_FAB2(SCH_1):PAGE92
  C7D4    2      B CAP_0402-1.0UF,16V,10%,X6S,D97A    I79 @BASEBOARD_FAB2_LIB.BASEBOARD_FAB2(SCH_1):PAGE92
 C3P50    2      B CAP_0402-1.0UF,16V,10%,X6S,D97A    I84 @BASEBOARD_FAB2_LIB.BASEBOARD_FAB2(SCH_1):PAGE92
  U2T4    7 GND<0> GTL2014_SM-IC,D66151-001    I30 @BASEBOARD_FAB2_LIB.BASEBOARD_FAB2(SCH_1):PAGE93
  U2T4    8 GND<1> GTL2014_SM-IC,D66151-001    I30 @BASEBOARD_FAB2_LIB.BASEBOARD_FAB2(SCH_1):PAGE93
  U2T4   11 GND<2> GTL2014_SM-IC,D66151-001    I30 @BASEBOARD_FAB2_LIB.BASEBOARD_FAB2(SCH_1):PAGE93
 C2T33    2      B CAP_A_0402V-1.0UF,6.3V,10%,X6SA    I72 @BASEBOARD_FAB2_LIB.BASEBOARD_FAB2(SCH_1):PAGE93
 C2T32    2      B CAP_A_0402V-0.1UF,16V,10%,X7R,A    I95 @BASEBOARD_FAB2_LIB.BASEBOARD_FAB2(SCH_1):PAGE93
 R2T39    2      B RES_0402-100.0,1%,1/16W,CHIP,GA    I98 @BASEBOARD_FAB2_LIB.BASEBOARD_FAB2(SCH_1):PAGE93
 R2T50    2      B RES_0402-1.00K,1%,1/16W,CHIP,GA   I127 @BASEBOARD_FAB2_LIB.BASEBOARD_FAB2(SCH_1):PAGE93
  Q3U1    1 SOURCE<0> FET_N_DUAL_SMLF-NTJD4001N,FET,A    I49 @BASEBOARD_FAB2_LIB.BASEBOARD_FAB2(SCH_1):PAGE94
  Q7E1    1 SOURCE<0> FET_N_DUAL_SMLF-NTJD4001N,FET,A    I60 @BASEBOARD_FAB2_LIB.BASEBOARD_FAB2(SCH_1):PAGE94
  Q7E1    4 SOURCE<0> FET_N_DUAL_SMLF-NTJD4001N,FET,A    I64 @BASEBOARD_FAB2_LIB.BASEBOARD_FAB2(SCH_1):PAGE94
  Q7E2    1 SOURCE<0> FET_N_DUAL_SMLF-NTJD4001N,FET,A    I69 @BASEBOARD_FAB2_LIB.BASEBOARD_FAB2(SCH_1):PAGE94
  Q7E2    4 SOURCE<0> FET_N_DUAL_SMLF-NTJD4001N,FET,A    I75 @BASEBOARD_FAB2_LIB.BASEBOARD_FAB2(SCH_1):PAGE94
  Q4B1    4 SOURCE<0> FET_N_DUAL_SMLF-NTJD4001N,FET,A    I77 @BASEBOARD_FAB2_LIB.BASEBOARD_FAB2(SCH_1):PAGE94
  Q4B1    1 SOURCE<0> FET_N_DUAL_SMLF-NTJD4001N,FET,A    I84 @BASEBOARD_FAB2_LIB.BASEBOARD_FAB2(SCH_1):PAGE94
  Q3U1    4 SOURCE<0> FET_N_DUAL_SMLF-NTJD4001N,FET,A    I89 @BASEBOARD_FAB2_LIB.BASEBOARD_FAB2(SCH_1):PAGE94
  Q4U1    1 SOURCE<0> FET_N_DUAL_SMLF-NTJD4001N,FET,A    I98 @BASEBOARD_FAB2_LIB.BASEBOARD_FAB2(SCH_1):PAGE94
  Q4U1    4 SOURCE<0> FET_N_DUAL_SMLF-NTJD4001N,FET,A   I102 @BASEBOARD_FAB2_LIB.BASEBOARD_FAB2(SCH_1):PAGE94
  R4U4    2      B RES_0402-33.0K,5%,1/16W,CHIP,GA   I104 @BASEBOARD_FAB2_LIB.BASEBOARD_FAB2(SCH_1):PAGE94
  Q2U1    1 SOURCE<0> FET_N_DUAL_SMLF-NTJD4001N,FET,A    I28 @BASEBOARD_FAB2_LIB.BASEBOARD_FAB2(SCH_1):PAGE95
  Q4B2    1 SOURCE<0> FET_N_DUAL_SMLF-NTJD4001N,FET,A    I32 @BASEBOARD_FAB2_LIB.BASEBOARD_FAB2(SCH_1):PAGE95
  Q4B2    4 SOURCE<0> FET_N_DUAL_SMLF-NTJD4001N,FET,A    I33 @BASEBOARD_FAB2_LIB.BASEBOARD_FAB2(SCH_1):PAGE95
  Q7E3    4 SOURCE<0> FET_N_DUAL_SMLF-NTJD4001N,FET,A    I51 @BASEBOARD_FAB2_LIB.BASEBOARD_FAB2(SCH_1):PAGE95
  Q7E3    1 SOURCE<0> FET_N_DUAL_SMLF-NTJD4001N,FET,A    I52 @BASEBOARD_FAB2_LIB.BASEBOARD_FAB2(SCH_1):PAGE95
  Q7E5    4 SOURCE<0> FET_N_DUAL_SMLF-NTJD4001N,FET,A    I59 @BASEBOARD_FAB2_LIB.BASEBOARD_FAB2(SCH_1):PAGE95
  Q7E6    4 SOURCE<0> FET_N_DUAL_SMLF-NTJD4001N,FET,A    I69 @BASEBOARD_FAB2_LIB.BASEBOARD_FAB2(SCH_1):PAGE95
  C7E3    2      B CAP_A_0402V-0.1UF,16V,10%,X7R,A    I92 @BASEBOARD_FAB2_LIB.BASEBOARD_FAB2(SCH_1):PAGE95
  Q7E4    2    SRC FET_N_SOT23-2N7002,FET,C79254-A   I104 @BASEBOARD_FAB2_LIB.BASEBOARD_FAB2(SCH_1):PAGE95
  Q7E5    1 SOURCE<0> FET_N_DUAL_SMLF-NTJD4001N,FET,A   I111 @BASEBOARD_FAB2_LIB.BASEBOARD_FAB2(SCH_1):PAGE95
  Q7E6    1 SOURCE<0> FET_N_DUAL_SMLF-NTJD4001N,FET,A   I112 @BASEBOARD_FAB2_LIB.BASEBOARD_FAB2(SCH_1):PAGE95
  Q2U1    4 SOURCE<0> FET_N_DUAL_SMLF-NTJD4001N,FET,A   I113 @BASEBOARD_FAB2_LIB.BASEBOARD_FAB2(SCH_1):PAGE95
  C7E4    2      B CAP_A_0402V-0.1UF,16V,10%,X7R,A   I115 @BASEBOARD_FAB2_LIB.BASEBOARD_FAB2(SCH_1):PAGE95
  Q7E8    2    SRC FET_N_SOT23-2N7002,FET,C79254-A   I119 @BASEBOARD_FAB2_LIB.BASEBOARD_FAB2(SCH_1):PAGE95
  U3P1    7 GND<0> GTL2014_SM-IC,D66151-001    I42 @BASEBOARD_FAB2_LIB.BASEBOARD_FAB2(SCH_1):PAGE96
  U3P1    8 GND<1> GTL2014_SM-IC,D66151-001    I42 @BASEBOARD_FAB2_LIB.BASEBOARD_FAB2(SCH_1):PAGE96
  U3P1   11 GND<2> GTL2014_SM-IC,D66151-001    I42 @BASEBOARD_FAB2_LIB.BASEBOARD_FAB2(SCH_1):PAGE96
  U4C2    7 GND<0> GTL2014_SM-IC,D66151-001    I46 @BASEBOARD_FAB2_LIB.BASEBOARD_FAB2(SCH_1):PAGE96
  U4C2    8 GND<1> GTL2014_SM-IC,D66151-001    I46 @BASEBOARD_FAB2_LIB.BASEBOARD_FAB2(SCH_1):PAGE96
  U4C2   11 GND<2> GTL2014_SM-IC,D66151-001    I46 @BASEBOARD_FAB2_LIB.BASEBOARD_FAB2(SCH_1):PAGE96
  R4C9    1      A RES_0402-1.00K,1%,1/16W,CHIP,GA    I69 @BASEBOARD_FAB2_LIB.BASEBOARD_FAB2(SCH_1):PAGE96
 R3P32    1      A RES_0402-1.00K,1%,1/16W,CHIP,GA    I71 @BASEBOARD_FAB2_LIB.BASEBOARD_FAB2(SCH_1):PAGE96
 C3P42    2      B CAP_A_0402V-1.0UF,6.3V,10%,X6SA    I73 @BASEBOARD_FAB2_LIB.BASEBOARD_FAB2(SCH_1):PAGE96
  C4C3    2      B CAP_A_0402V-1.0UF,6.3V,10%,X6SA    I75 @BASEBOARD_FAB2_LIB.BASEBOARD_FAB2(SCH_1):PAGE96
  R4P5    1      A RES_0402-10.0K,1%,1/16W,CHIP,GA    I80 @BASEBOARD_FAB2_LIB.BASEBOARD_FAB2(SCH_1):PAGE97
 R7P13    1      A RES_0402-10.0K,1%,1/16W,CHIP,GA    I81 @BASEBOARD_FAB2_LIB.BASEBOARD_FAB2(SCH_1):PAGE97
  R4F5    2      B RES_0402-1.00K,1%,1/16W,CHIP,GA     I4 @BASEBOARD_FAB2_LIB.BASEBOARD_FAB2(SCH_1):PAGE98
  C4F9    2      B CAP_A_0402V-0.01UF,25V,10%,X7RA     I7 @BASEBOARD_FAB2_LIB.BASEBOARD_FAB2(SCH_1):PAGE98
 R6L16    2      B RES_0402-1.00K,1%,1/16W,CHIP,GA    I12 @BASEBOARD_FAB2_LIB.BASEBOARD_FAB2(SCH_1):PAGE98
  C6M2    2      B CAP_A_0402V-0.01UF,25V,10%,X7RA    I33 @BASEBOARD_FAB2_LIB.BASEBOARD_FAB2(SCH_1):PAGE98
  R4G3    2      B RES_0402-1.00K,1%,1/16W,CHIP,GA    I40 @BASEBOARD_FAB2_LIB.BASEBOARD_FAB2(SCH_1):PAGE98
  C4G1    2      B CAP_A_0402V-0.01UF,25V,10%,X7RA    I43 @BASEBOARD_FAB2_LIB.BASEBOARD_FAB2(SCH_1):PAGE98
 R4G22    2      B RES_0402-1.00K,1%,1/16W,CHIP,GA    I48 @BASEBOARD_FAB2_LIB.BASEBOARD_FAB2(SCH_1):PAGE98
 C4G17    2      B CAP_A_0402V-0.01UF,25V,10%,X7RA    I51 @BASEBOARD_FAB2_LIB.BASEBOARD_FAB2(SCH_1):PAGE98
 R6L12    2      B RES_0402-1.00K,1%,1/16W,CHIP,GA    I56 @BASEBOARD_FAB2_LIB.BASEBOARD_FAB2(SCH_1):PAGE98
  C6L7    2      B CAP_A_0402V-0.01UF,25V,10%,X7RA    I59 @BASEBOARD_FAB2_LIB.BASEBOARD_FAB2(SCH_1):PAGE98
  R6L1    2      B RES_0402-1.00K,1%,1/16W,CHIP,GA    I64 @BASEBOARD_FAB2_LIB.BASEBOARD_FAB2(SCH_1):PAGE98
  C6L2    2      B CAP_A_0402V-0.01UF,25V,10%,X7RA    I67 @BASEBOARD_FAB2_LIB.BASEBOARD_FAB2(SCH_1):PAGE98
  C6F2    2      B CAP_A_0402V-0.1UF,16V,10%,X7R,A     I2 @BASEBOARD_FAB2_LIB.BASEBOARD_FAB2(SCH_1):PAGE99
  C6F3    2      B CAP_A_0402V-0.1UF,16V,10%,X7R,A     I7 @BASEBOARD_FAB2_LIB.BASEBOARD_FAB2(SCH_1):PAGE99
  C7E1    2      B CAP_A_0402V-0.1UF,16V,10%,X7R,A    I23 @BASEBOARD_FAB2_LIB.BASEBOARD_FAB2(SCH_1):PAGE99
 C4G22    2      B CAP_A_0402V-0.1UF,16V,10%,X7R,A    I27 @BASEBOARD_FAB2_LIB.BASEBOARD_FAB2(SCH_1):PAGE99
  C7E2    2      B CAP_A_0402V-0.1UF,16V,10%,X7R,A    I32 @BASEBOARD_FAB2_LIB.BASEBOARD_FAB2(SCH_1):PAGE99
 C4G25    2      B CAP_A_0402V-0.1UF,16V,10%,X7R,A    I41 @BASEBOARD_FAB2_LIB.BASEBOARD_FAB2(SCH_1):PAGE99
  C3B4    2      B CAP_A_0402V-0.1UF,16V,10%,X7R,A    I47 @BASEBOARD_FAB2_LIB.BASEBOARD_FAB2(SCH_1):PAGE99
  C3B5    2      B CAP_A_0402V-0.1UF,16V,10%,X7R,A    I53 @BASEBOARD_FAB2_LIB.BASEBOARD_FAB2(SCH_1):PAGE99
  R1F6    2      B RES_0402-1.00K,1%,1/16W,CHIP,GA     I2 @BASEBOARD_FAB2_LIB.BASEBOARD_FAB2(SCH_1):PAGE100
 R9L11    2      B RES_0402-1.00K,1%,1/16W,CHIP,GA     I4 @BASEBOARD_FAB2_LIB.BASEBOARD_FAB2(SCH_1):PAGE100
 C1F19    2      B CAP_A_0402V-0.01UF,25V,10%,X7RA     I8 @BASEBOARD_FAB2_LIB.BASEBOARD_FAB2(SCH_1):PAGE100
  C9M2    2      B CAP_A_0402V-0.01UF,25V,10%,X7RA    I15 @BASEBOARD_FAB2_LIB.BASEBOARD_FAB2(SCH_1):PAGE100
  R1G3    2      B RES_0402-1.00K,1%,1/16W,CHIP,GA    I20 @BASEBOARD_FAB2_LIB.BASEBOARD_FAB2(SCH_1):PAGE100
  R9L6    2      B RES_0402-1.00K,1%,1/16W,CHIP,GA    I24 @BASEBOARD_FAB2_LIB.BASEBOARD_FAB2(SCH_1):PAGE100
  C1G8    2      B CAP_A_0402V-0.01UF,25V,10%,X7RA    I26 @BASEBOARD_FAB2_LIB.BASEBOARD_FAB2(SCH_1):PAGE100
  C9L8    2      B CAP_A_0402V-0.01UF,25V,10%,X7RA    I30 @BASEBOARD_FAB2_LIB.BASEBOARD_FAB2(SCH_1):PAGE100
 R1G17    2      B RES_0402-1.00K,1%,1/16W,CHIP,GA    I36 @BASEBOARD_FAB2_LIB.BASEBOARD_FAB2(SCH_1):PAGE100
  R9L1    2      B RES_0402-1.00K,1%,1/16W,CHIP,GA    I40 @BASEBOARD_FAB2_LIB.BASEBOARD_FAB2(SCH_1):PAGE100
 C1G18    2      B CAP_A_0402V-0.01UF,25V,10%,X7RA    I42 @BASEBOARD_FAB2_LIB.BASEBOARD_FAB2(SCH_1):PAGE100
  C9L3    2      B CAP_A_0402V-0.01UF,25V,10%,X7RA    I46 @BASEBOARD_FAB2_LIB.BASEBOARD_FAB2(SCH_1):PAGE100
 R8F25    2      B RES_0402-475.0,1%,1/16W,CHIP,GA    I28 @BASEBOARD_FAB2_LIB.BASEBOARD_FAB2(SCH_1):PAGE101
 EU8F2    1 GND<0> ICS9FGP204_MLFP-IC,E95226-001    I34 @BASEBOARD_FAB2_LIB.BASEBOARD_FAB2(SCH_1):PAGE101
 EU8F2   41 GND<1> ICS9FGP204_MLFP-IC,E95226-001    I34 @BASEBOARD_FAB2_LIB.BASEBOARD_FAB2(SCH_1):PAGE101
 EU8F2   14 GND32K ICS9FGP204_MLFP-IC,E95226-001    I34 @BASEBOARD_FAB2_LIB.BASEBOARD_FAB2(SCH_1):PAGE101
 EU8F2   21  GND33 ICS9FGP204_MLFP-IC,E95226-001    I34 @BASEBOARD_FAB2_LIB.BASEBOARD_FAB2(SCH_1):PAGE101
 EU8F2   35 GND_RGMII ICS9FGP204_MLFP-IC,E95226-001    I34 @BASEBOARD_FAB2_LIB.BASEBOARD_FAB2(SCH_1):PAGE101
 EU8F2   10 GNDCPU ICS9FGP204_MLFP-IC,E95226-001    I34 @BASEBOARD_FAB2_LIB.BASEBOARD_FAB2(SCH_1):PAGE101
 EU8F2   18 GNDREF ICS9FGP204_MLFP-IC,E95226-001    I34 @BASEBOARD_FAB2_LIB.BASEBOARD_FAB2(SCH_1):PAGE101
 EU8F2   27 GNDRMII<0> ICS9FGP204_MLFP-IC,E95226-001    I34 @BASEBOARD_FAB2_LIB.BASEBOARD_FAB2(SCH_1):PAGE101
 EU8F2   30 GNDRMII<1> ICS9FGP204_MLFP-IC,E95226-001    I34 @BASEBOARD_FAB2_LIB.BASEBOARD_FAB2(SCH_1):PAGE101
 R2T25    2      B RES_0402-1.00K,1%,1/16W,CHIP,GA    I48 @BASEBOARD_FAB2_LIB.BASEBOARD_FAB2(SCH_1):PAGE101
 C8F18    2      B CAP_0402LF-27.0PF,50V,5%,COG,AA    I49 @BASEBOARD_FAB2_LIB.BASEBOARD_FAB2(SCH_1):PAGE101
 C8F19    2      B CAP_0402LF-27.0PF,50V,5%,COG,AA    I53 @BASEBOARD_FAB2_LIB.BASEBOARD_FAB2(SCH_1):PAGE101
 C2T31    2      B CAP_A_0402V-1.0UF,6.3V,10%,X6SA    I89 @BASEBOARD_FAB2_LIB.BASEBOARD_FAB2(SCH_1):PAGE101
 C2T27    2      B CAP_A_0402V-0.01UF,25V,10%,X7RA    I90 @BASEBOARD_FAB2_LIB.BASEBOARD_FAB2(SCH_1):PAGE101
 C2T38    2      B CAP_A_0402V-1.0UF,6.3V,10%,X6SA    I97 @BASEBOARD_FAB2_LIB.BASEBOARD_FAB2(SCH_1):PAGE101
 C2T37    2      B CAP_A_0402V-0.01UF,25V,10%,X7RA    I99 @BASEBOARD_FAB2_LIB.BASEBOARD_FAB2(SCH_1):PAGE101
 C2T18    2      B CAP_A_0402V-0.01UF,25V,10%,X7RA   I104 @BASEBOARD_FAB2_LIB.BASEBOARD_FAB2(SCH_1):PAGE101
 C2T19    2      B CAP_A_0402V-1.0UF,6.3V,10%,X6SA   I106 @BASEBOARD_FAB2_LIB.BASEBOARD_FAB2(SCH_1):PAGE101
 C2T34    2      B CAP_A_0402V-0.1UF,16V,10%,X7R,A   I109 @BASEBOARD_FAB2_LIB.BASEBOARD_FAB2(SCH_1):PAGE101
 C2T30    2      B CAP_A_0402V-0.1UF,16V,10%,X7R,A   I110 @BASEBOARD_FAB2_LIB.BASEBOARD_FAB2(SCH_1):PAGE101
 C2T25    2      B CAP_A_0402V-0.1UF,16V,10%,X7R,A   I111 @BASEBOARD_FAB2_LIB.BASEBOARD_FAB2(SCH_1):PAGE101
 C2T17    2      B CAP_A_0402V-0.1UF,16V,10%,X7R,A   I112 @BASEBOARD_FAB2_LIB.BASEBOARD_FAB2(SCH_1):PAGE101
 C2T22    2      B CAP_0805-10UF,16V,10%,X6S,C953A   I113 @BASEBOARD_FAB2_LIB.BASEBOARD_FAB2(SCH_1):PAGE101
 C2T28    2      B CAP_A_0402V-1.0UF,6.3V,10%,X6SA   I116 @BASEBOARD_FAB2_LIB.BASEBOARD_FAB2(SCH_1):PAGE101
 EU4D2    7 GND<0> NB3W1200L_LCC-IC,H13585-001     I1 @BASEBOARD_FAB2_LIB.BASEBOARD_FAB2(SCH_1):PAGE102
 EU4D2   23 GND<1> NB3W1200L_LCC-IC,H13585-001     I1 @BASEBOARD_FAB2_LIB.BASEBOARD_FAB2(SCH_1):PAGE102
 EU4D2   33 GND<2> NB3W1200L_LCC-IC,H13585-001     I1 @BASEBOARD_FAB2_LIB.BASEBOARD_FAB2(SCH_1):PAGE102
 EU4D2   41 GND<3> NB3W1200L_LCC-IC,H13585-001     I1 @BASEBOARD_FAB2_LIB.BASEBOARD_FAB2(SCH_1):PAGE102
 EU4D2   48 GND<4> NB3W1200L_LCC-IC,H13585-001     I1 @BASEBOARD_FAB2_LIB.BASEBOARD_FAB2(SCH_1):PAGE102
 EU4D2   58 GND<5> NB3W1200L_LCC-IC,H13585-001     I1 @BASEBOARD_FAB2_LIB.BASEBOARD_FAB2(SCH_1):PAGE102
 EU4D2    2   GNDA NB3W1200L_LCC-IC,H13585-001     I1 @BASEBOARD_FAB2_LIB.BASEBOARD_FAB2(SCH_1):PAGE102
 EU4D2   65  THPAD NB3W1200L_LCC-IC,H13585-001     I1 @BASEBOARD_FAB2_LIB.BASEBOARD_FAB2(SCH_1):PAGE102
 C3D22    2      B CAP_0805-10UF,16V,10%,X7R,G106A    I10 @BASEBOARD_FAB2_LIB.BASEBOARD_FAB2(SCH_1):PAGE102
  C6P4    2      B CAP_A_0402V-0.1UF,16V,10%,X7R,A    I11 @BASEBOARD_FAB2_LIB.BASEBOARD_FAB2(SCH_1):PAGE102
  C6P6    2      B CAP_A_0402V-0.1UF,16V,10%,X7R,A    I12 @BASEBOARD_FAB2_LIB.BASEBOARD_FAB2(SCH_1):PAGE102
 C6P10    2      B CAP_A_0402V-0.1UF,16V,10%,X7R,A    I13 @BASEBOARD_FAB2_LIB.BASEBOARD_FAB2(SCH_1):PAGE102
  C6P5    2      B CAP_A_0402V-0.1UF,16V,10%,X7R,A    I14 @BASEBOARD_FAB2_LIB.BASEBOARD_FAB2(SCH_1):PAGE102
 C6P12    2      B CAP_A_0402V-0.1UF,16V,10%,X7R,A    I15 @BASEBOARD_FAB2_LIB.BASEBOARD_FAB2(SCH_1):PAGE102
 C6P11    2      B CAP_A_0402V-0.1UF,16V,10%,X7R,A    I16 @BASEBOARD_FAB2_LIB.BASEBOARD_FAB2(SCH_1):PAGE102
 C4D24    2      B CAP_A_0402V-0.1UF,16V,10%,X7R,A    I18 @BASEBOARD_FAB2_LIB.BASEBOARD_FAB2(SCH_1):PAGE102
 C4D23    2      B CAP_A_0402V-1.0UF,6.3V,10%,X6SA    I19 @BASEBOARD_FAB2_LIB.BASEBOARD_FAB2(SCH_1):PAGE102
 C4D22    2      B CAP_A_0402V-0.1UF,16V,10%,X7R,A    I28 @BASEBOARD_FAB2_LIB.BASEBOARD_FAB2(SCH_1):PAGE102
 C4D27    2      B CAP_A_0402V-1.0UF,6.3V,10%,X6SA    I30 @BASEBOARD_FAB2_LIB.BASEBOARD_FAB2(SCH_1):PAGE102
 R6P23    2      B RES_0402-4.75K,1%,1/16W,EMPTY,A    I46 @BASEBOARD_FAB2_LIB.BASEBOARD_FAB2(SCH_1):PAGE102
 R6P22    2      B RES_0402-4.75K,1%,1/16W,EMPTY,A    I47 @BASEBOARD_FAB2_LIB.BASEBOARD_FAB2(SCH_1):PAGE102
  C6P9    2      B CAP_A_0402V-0.1UF,16V,10%,X7R,A    I79 @BASEBOARD_FAB2_LIB.BASEBOARD_FAB2(SCH_1):PAGE102
 R6P21    2      B RES_0402-1.00K,1%,1/16W,CHIP,GA    I80 @BASEBOARD_FAB2_LIB.BASEBOARD_FAB2(SCH_1):PAGE102
 R6P20    2      B RES_0402-1.00K,1%,1/16W,CHIP,GA    I81 @BASEBOARD_FAB2_LIB.BASEBOARD_FAB2(SCH_1):PAGE102
  R7P9    2      B RES_0402-42.2,1.0%,1/16W,EMPTYA   I121 @BASEBOARD_FAB2_LIB.BASEBOARD_FAB2(SCH_1):PAGE103
 R7P12    2      B RES_0402-42.2,1.0%,1/16W,EMPTYA   I123 @BASEBOARD_FAB2_LIB.BASEBOARD_FAB2(SCH_1):PAGE103
  R7P6    2      B RES_0402-42.2,1.0%,1/16W,EMPTYA   I125 @BASEBOARD_FAB2_LIB.BASEBOARD_FAB2(SCH_1):PAGE103
  R7P7    2      B RES_0402-42.2,1.0%,1/16W,EMPTYA   I127 @BASEBOARD_FAB2_LIB.BASEBOARD_FAB2(SCH_1):PAGE103
  R7P3    2      B RES_0402-42.2,1.0%,1/16W,EMPTYA   I129 @BASEBOARD_FAB2_LIB.BASEBOARD_FAB2(SCH_1):PAGE103
  R7P4    2      B RES_0402-42.2,1.0%,1/16W,EMPTYA   I131 @BASEBOARD_FAB2_LIB.BASEBOARD_FAB2(SCH_1):PAGE103
  R7P1    2      B RES_0402-42.2,1.0%,1/16W,EMPTYA   I133 @BASEBOARD_FAB2_LIB.BASEBOARD_FAB2(SCH_1):PAGE103
  R7P2    2      B RES_0402-42.2,1.0%,1/16W,EMPTYA   I135 @BASEBOARD_FAB2_LIB.BASEBOARD_FAB2(SCH_1):PAGE103
  R6P7    2      B RES_0402-42.2,1.0%,1/16W,EMPTYA   I137 @BASEBOARD_FAB2_LIB.BASEBOARD_FAB2(SCH_1):PAGE103
  R6P8    2      B RES_0402-42.2,1.0%,1/16W,EMPTYA   I139 @BASEBOARD_FAB2_LIB.BASEBOARD_FAB2(SCH_1):PAGE103
  R6P5    2      B RES_0402-42.2,1.0%,1/16W,EMPTYA   I141 @BASEBOARD_FAB2_LIB.BASEBOARD_FAB2(SCH_1):PAGE103
  R6P6    2      B RES_0402-42.2,1.0%,1/16W,EMPTYA   I143 @BASEBOARD_FAB2_LIB.BASEBOARD_FAB2(SCH_1):PAGE103
  R6P3    2      B RES_0402-42.2,1.0%,1/16W,EMPTYA   I145 @BASEBOARD_FAB2_LIB.BASEBOARD_FAB2(SCH_1):PAGE103
  R6P4    2      B RES_0402-42.2,1.0%,1/16W,EMPTYA   I147 @BASEBOARD_FAB2_LIB.BASEBOARD_FAB2(SCH_1):PAGE103
  R6P1    2      B RES_0402-42.2,1.0%,1/16W,EMPTYA   I149 @BASEBOARD_FAB2_LIB.BASEBOARD_FAB2(SCH_1):PAGE103
  R6P2    2      B RES_0402-42.2,1.0%,1/16W,EMPTYA   I151 @BASEBOARD_FAB2_LIB.BASEBOARD_FAB2(SCH_1):PAGE103
 R6P11    2      B RES_0402-42.2,1.0%,1/16W,EMPTYA   I153 @BASEBOARD_FAB2_LIB.BASEBOARD_FAB2(SCH_1):PAGE103
  R6P9    2      B RES_0402-42.2,1.0%,1/16W,EMPTYA   I155 @BASEBOARD_FAB2_LIB.BASEBOARD_FAB2(SCH_1):PAGE103
 R6P13    2      B RES_0402-42.2,1.0%,1/16W,EMPTYA   I157 @BASEBOARD_FAB2_LIB.BASEBOARD_FAB2(SCH_1):PAGE103
 R6P12    2      B RES_0402-42.2,1.0%,1/16W,EMPTYA   I159 @BASEBOARD_FAB2_LIB.BASEBOARD_FAB2(SCH_1):PAGE103
 R4D24    2      B RES_0402-42.2,1.0%,1/16W,EMPTYA   I161 @BASEBOARD_FAB2_LIB.BASEBOARD_FAB2(SCH_1):PAGE103
 R4D18    2      B RES_0402-42.2,1.0%,1/16W,EMPTYA   I163 @BASEBOARD_FAB2_LIB.BASEBOARD_FAB2(SCH_1):PAGE103
 R6P17    2      B RES_0402-42.2,1.0%,1/16W,EMPTYA   I165 @BASEBOARD_FAB2_LIB.BASEBOARD_FAB2(SCH_1):PAGE103
 R6P15    2      B RES_0402-42.2,1.0%,1/16W,EMPTYA   I167 @BASEBOARD_FAB2_LIB.BASEBOARD_FAB2(SCH_1):PAGE103
  C6F1    2      B CAP_A_0402V-0.1UF,16V,10%,X7R,A    I25 @BASEBOARD_FAB2_LIB.BASEBOARD_FAB2(SCH_1):PAGE104
  C3F2    2      B CAP_A_0402V-0.1UF,16V,10%,X7R,A    I34 @BASEBOARD_FAB2_LIB.BASEBOARD_FAB2(SCH_1):PAGE104
  Y6F1    3    GND OSC_C_6P10-156.25MHZ,OSC,G6383A    I71 @BASEBOARD_FAB2_LIB.BASEBOARD_FAB2(SCH_1):PAGE104
  Y3F1    3    GND OSC_C_6P10-156.25MHZ,OSC,G6383A    I72 @BASEBOARD_FAB2_LIB.BASEBOARD_FAB2(SCH_1):PAGE104
 C2U20    2      B CAP_A_0402V-0.1UF,16V,10%,X7R,A     I1 @BASEBOARD_FAB2_LIB.BASEBOARD_FAB2(SCH_1):PAGE108
 C2U24    2      B CAP_A_0402V-0.1UF,16V,10%,X7R,A     I2 @BASEBOARD_FAB2_LIB.BASEBOARD_FAB2(SCH_1):PAGE108
 C2U21    2      B CAP_A_0402V-0.1UF,16V,10%,X7R,A     I5 @BASEBOARD_FAB2_LIB.BASEBOARD_FAB2(SCH_1):PAGE108
 C2U25    2      B CAP_A_0402V-0.1UF,16V,10%,X7R,A     I7 @BASEBOARD_FAB2_LIB.BASEBOARD_FAB2(SCH_1):PAGE108
  J8G1   13   IO13 SCONN200_H68296001_SM-CONN,H68A   I258 @BASEBOARD_FAB2_LIB.BASEBOARD_FAB2(SCH_1):PAGE108
  J8G1   14   IO14 SCONN200_H68296001_SM-CONN,H68A   I258 @BASEBOARD_FAB2_LIB.BASEBOARD_FAB2(SCH_1):PAGE108
  J8G1   26   IO26 SCONN200_H68296001_SM-CONN,H68A   I258 @BASEBOARD_FAB2_LIB.BASEBOARD_FAB2(SCH_1):PAGE108
  J8G1   31   IO31 SCONN200_H68296001_SM-CONN,H68A   I258 @BASEBOARD_FAB2_LIB.BASEBOARD_FAB2(SCH_1):PAGE108
  J8G1   34   IO34 SCONN200_H68296001_SM-CONN,H68A   I258 @BASEBOARD_FAB2_LIB.BASEBOARD_FAB2(SCH_1):PAGE108
  J8G1   37   IO37 SCONN200_H68296001_SM-CONN,H68A   I258 @BASEBOARD_FAB2_LIB.BASEBOARD_FAB2(SCH_1):PAGE108
  J8G1   40   IO40 SCONN200_H68296001_SM-CONN,H68A   I258 @BASEBOARD_FAB2_LIB.BASEBOARD_FAB2(SCH_1):PAGE108
  J8G1   43   IO43 SCONN200_H68296001_SM-CONN,H68A   I258 @BASEBOARD_FAB2_LIB.BASEBOARD_FAB2(SCH_1):PAGE108
  J8G1   46   IO46 SCONN200_H68296001_SM-CONN,H68A   I258 @BASEBOARD_FAB2_LIB.BASEBOARD_FAB2(SCH_1):PAGE108
  J8G1   49   IO49 SCONN200_H68296001_SM-CONN,H68A   I258 @BASEBOARD_FAB2_LIB.BASEBOARD_FAB2(SCH_1):PAGE108
  J8G1   52   IO52 SCONN200_H68296001_SM-CONN,H68A   I258 @BASEBOARD_FAB2_LIB.BASEBOARD_FAB2(SCH_1):PAGE108
  J8G1   55   IO55 SCONN200_H68296001_SM-CONN,H68A   I258 @BASEBOARD_FAB2_LIB.BASEBOARD_FAB2(SCH_1):PAGE108
  J8G1   58   IO58 SCONN200_H68296001_SM-CONN,H68A   I258 @BASEBOARD_FAB2_LIB.BASEBOARD_FAB2(SCH_1):PAGE108
  J8G1   61   IO61 SCONN200_H68296001_SM-CONN,H68A   I258 @BASEBOARD_FAB2_LIB.BASEBOARD_FAB2(SCH_1):PAGE108
  J8G1   64   IO64 SCONN200_H68296001_SM-CONN,H68A   I258 @BASEBOARD_FAB2_LIB.BASEBOARD_FAB2(SCH_1):PAGE108
  J8G1   65   IO65 SCONN200_H68296001_SM-CONN,H68A   I258 @BASEBOARD_FAB2_LIB.BASEBOARD_FAB2(SCH_1):PAGE108
  J8G1   68   IO68 SCONN200_H68296001_SM-CONN,H68A   I258 @BASEBOARD_FAB2_LIB.BASEBOARD_FAB2(SCH_1):PAGE108
  J8G1   71   IO71 SCONN200_H68296001_SM-CONN,H68A   I258 @BASEBOARD_FAB2_LIB.BASEBOARD_FAB2(SCH_1):PAGE108
  J8G1   74   IO74 SCONN200_H68296001_SM-CONN,H68A   I258 @BASEBOARD_FAB2_LIB.BASEBOARD_FAB2(SCH_1):PAGE108
  J8G1   77   IO77 SCONN200_H68296001_SM-CONN,H68A   I258 @BASEBOARD_FAB2_LIB.BASEBOARD_FAB2(SCH_1):PAGE108
  J8G1   80   IO80 SCONN200_H68296001_SM-CONN,H68A   I258 @BASEBOARD_FAB2_LIB.BASEBOARD_FAB2(SCH_1):PAGE108
  J8G1   83   IO83 SCONN200_H68296001_SM-CONN,H68A   I258 @BASEBOARD_FAB2_LIB.BASEBOARD_FAB2(SCH_1):PAGE108
  J8G1   86   IO86 SCONN200_H68296001_SM-CONN,H68A   I258 @BASEBOARD_FAB2_LIB.BASEBOARD_FAB2(SCH_1):PAGE108
  J8G1   89   IO89 SCONN200_H68296001_SM-CONN,H68A   I258 @BASEBOARD_FAB2_LIB.BASEBOARD_FAB2(SCH_1):PAGE108
  J8G1   92   IO92 SCONN200_H68296001_SM-CONN,H68A   I258 @BASEBOARD_FAB2_LIB.BASEBOARD_FAB2(SCH_1):PAGE108
  J8G1   95   IO95 SCONN200_H68296001_SM-CONN,H68A   I258 @BASEBOARD_FAB2_LIB.BASEBOARD_FAB2(SCH_1):PAGE108
  J8G1   98   IO98 SCONN200_H68296001_SM-CONN,H68A   I258 @BASEBOARD_FAB2_LIB.BASEBOARD_FAB2(SCH_1):PAGE108
  J8G1  MH1    MH1 SCONN200_H68296001_SM-CONN,H68A   I258 @BASEBOARD_FAB2_LIB.BASEBOARD_FAB2(SCH_1):PAGE108
  J8G1  MH2    MH2 SCONN200_H68296001_SM-CONN,H68A   I258 @BASEBOARD_FAB2_LIB.BASEBOARD_FAB2(SCH_1):PAGE108
 C2U23    2      B CAP_A_0402V-0.1UF,16V,10%,X7R,A   I315 @BASEBOARD_FAB2_LIB.BASEBOARD_FAB2(SCH_1):PAGE108
 C2U22    2      B CAP_A_0402V-0.1UF,16V,10%,X7R,A   I318 @BASEBOARD_FAB2_LIB.BASEBOARD_FAB2(SCH_1):PAGE108
 TC9F1    1    GND RCC_DFX1940_ID4-EMPTY,N_A     I1 @BASEBOARD_FAB2_LIB.BASEBOARD_FAB2(SCH_1):PAGE110
 TC1G1    1    GND RCC_DFX1940_ID4-EMPTY,N_A     I3 @BASEBOARD_FAB2_LIB.BASEBOARD_FAB2(SCH_1):PAGE110
 TC1A1    1    GND RCC_DFX1940_ID4-EMPTY,N_A     I7 @BASEBOARD_FAB2_LIB.BASEBOARD_FAB2(SCH_1):PAGE110
 TC9A1    1    GND RCC_DFX1940_ID4-EMPTY,N_A     I9 @BASEBOARD_FAB2_LIB.BASEBOARD_FAB2(SCH_1):PAGE110
  C9A2    2      B CAP_A_0402V-0.1UF,16V,10%,X7R,A    I10 @BASEBOARD_FAB2_LIB.BASEBOARD_FAB2(SCH_1):PAGE111
  C9A5    2      B CAP_A_0402V-0.1UF,16V,10%,X7R,A    I12 @BASEBOARD_FAB2_LIB.BASEBOARD_FAB2(SCH_1):PAGE111
  C1L8    2      B CAP_A_0402V-0.1UF,16V,10%,X7R,A    I14 @BASEBOARD_FAB2_LIB.BASEBOARD_FAB2(SCH_1):PAGE111
  C9A6    2      B CAP_A_0402V-1.0UF,6.3V,10%,X6SA    I25 @BASEBOARD_FAB2_LIB.BASEBOARD_FAB2(SCH_1):PAGE111
  J9A3    2    IO2 SCONN60_C21100002_SMLF-CONN,C2A    I26 @BASEBOARD_FAB2_LIB.BASEBOARD_FAB2(SCH_1):PAGE111
  J9A3    7    IO7 SCONN60_C21100002_SMLF-CONN,C2A    I26 @BASEBOARD_FAB2_LIB.BASEBOARD_FAB2(SCH_1):PAGE111
  J9A3    8    IO8 SCONN60_C21100002_SMLF-CONN,C2A    I26 @BASEBOARD_FAB2_LIB.BASEBOARD_FAB2(SCH_1):PAGE111
  J9A3   13   IO13 SCONN60_C21100002_SMLF-CONN,C2A    I26 @BASEBOARD_FAB2_LIB.BASEBOARD_FAB2(SCH_1):PAGE111
  J9A3   14   IO14 SCONN60_C21100002_SMLF-CONN,C2A    I26 @BASEBOARD_FAB2_LIB.BASEBOARD_FAB2(SCH_1):PAGE111
  J9A3   19   IO19 SCONN60_C21100002_SMLF-CONN,C2A    I26 @BASEBOARD_FAB2_LIB.BASEBOARD_FAB2(SCH_1):PAGE111
  J9A3   20   IO20 SCONN60_C21100002_SMLF-CONN,C2A    I26 @BASEBOARD_FAB2_LIB.BASEBOARD_FAB2(SCH_1):PAGE111
  J9A3   25   IO25 SCONN60_C21100002_SMLF-CONN,C2A    I26 @BASEBOARD_FAB2_LIB.BASEBOARD_FAB2(SCH_1):PAGE111
  J9A3   26   IO26 SCONN60_C21100002_SMLF-CONN,C2A    I26 @BASEBOARD_FAB2_LIB.BASEBOARD_FAB2(SCH_1):PAGE111
  J9A3   31   IO31 SCONN60_C21100002_SMLF-CONN,C2A    I26 @BASEBOARD_FAB2_LIB.BASEBOARD_FAB2(SCH_1):PAGE111
  J9A3   32   IO32 SCONN60_C21100002_SMLF-CONN,C2A    I26 @BASEBOARD_FAB2_LIB.BASEBOARD_FAB2(SCH_1):PAGE111
  J9A3   37   IO37 SCONN60_C21100002_SMLF-CONN,C2A    I26 @BASEBOARD_FAB2_LIB.BASEBOARD_FAB2(SCH_1):PAGE111
  J9A3   38   IO38 SCONN60_C21100002_SMLF-CONN,C2A    I26 @BASEBOARD_FAB2_LIB.BASEBOARD_FAB2(SCH_1):PAGE111
  J9A3   49   IO49 SCONN60_C21100002_SMLF-CONN,C2A    I26 @BASEBOARD_FAB2_LIB.BASEBOARD_FAB2(SCH_1):PAGE111
  J9A3   50   IO50 SCONN60_C21100002_SMLF-CONN,C2A    I26 @BASEBOARD_FAB2_LIB.BASEBOARD_FAB2(SCH_1):PAGE111
  J9A3   59   IO59 SCONN60_C21100002_SMLF-CONN,C2A    I26 @BASEBOARD_FAB2_LIB.BASEBOARD_FAB2(SCH_1):PAGE111
  C1L5    2      B CAP_A_0402V-1.0UF,6.3V,10%,X6SA    I30 @BASEBOARD_FAB2_LIB.BASEBOARD_FAB2(SCH_1):PAGE111
  C9A4    2      B CAP_A_0402V-0.1UF,16V,10%,X7R,A    I59 @BASEBOARD_FAB2_LIB.BASEBOARD_FAB2(SCH_1):PAGE111
 C1L11    2      B CAP_A_0402V-0.1UF,16V,10%,X7R,A    I87 @BASEBOARD_FAB2_LIB.BASEBOARD_FAB2(SCH_1):PAGE111
  U1M7    2    GND NC7SB3157_SMLF-IC,C99406-001    I40 @BASEBOARD_FAB2_LIB.BASEBOARD_FAB2(SCH_1):PAGE112
 C1M36    2      B CAP_A_0402V-0.01UF,25V,10%,X7RA    I42 @BASEBOARD_FAB2_LIB.BASEBOARD_FAB2(SCH_1):PAGE112
 C1M37    2      B CAP_A_0402V-1.0UF,6.3V,10%,X6SA    I47 @BASEBOARD_FAB2_LIB.BASEBOARD_FAB2(SCH_1):PAGE112
 R7P29    2      B RES_0402-51.1,1.0%,1/16W,CHIP,A    I61 @BASEBOARD_FAB2_LIB.BASEBOARD_FAB2(SCH_1):PAGE112
  R6T5    2      B RES_0402-1.00K,1%,1/16W,CHIP,GA    I62 @BASEBOARD_FAB2_LIB.BASEBOARD_FAB2(SCH_1):PAGE112
 R3M10    2      B RES_0402-1.00K,1%,1/16W,CHIP,GA    I85 @BASEBOARD_FAB2_LIB.BASEBOARD_FAB2(SCH_1):PAGE112
  R8B2    2      B RES_0402-1.00K,1%,1/16W,CHIP,GA    I94 @BASEBOARD_FAB2_LIB.BASEBOARD_FAB2(SCH_1):PAGE112
  R8B1    2      B RES_0402-51.1,1.0%,1/16W,CHIP,A    I95 @BASEBOARD_FAB2_LIB.BASEBOARD_FAB2(SCH_1):PAGE112
 C1M30    2      B CAP_A_0402V-0.01UF,25V,10%,X7RA   I131 @BASEBOARD_FAB2_LIB.BASEBOARD_FAB2(SCH_1):PAGE112
  C1L1    2      B CAP_0402-1.0UF,16V,10%,X6S,D97A   I136 @BASEBOARD_FAB2_LIB.BASEBOARD_FAB2(SCH_1):PAGE112
 C1L19    2      B CAP_0402-1.0UF,16V,10%,X6S,D97A   I140 @BASEBOARD_FAB2_LIB.BASEBOARD_FAB2(SCH_1):PAGE112
  U1M2    2    GND NC7SB3157_SMLF-IC,C99406-001   I107 @BASEBOARD_FAB2_LIB.BASEBOARD_FAB2(SCH_1):PAGE113
 C1M31    2      B CAP_A_0402V-0.01UF,25V,10%,X7RA   I116 @BASEBOARD_FAB2_LIB.BASEBOARD_FAB2(SCH_1):PAGE113
 C1M32    2      B CAP_A_0402V-1.0UF,6.3V,10%,X6SA   I117 @BASEBOARD_FAB2_LIB.BASEBOARD_FAB2(SCH_1):PAGE113
 C1M28    2      B CAP_A_0402V-0.01UF,25V,10%,X7RA   I119 @BASEBOARD_FAB2_LIB.BASEBOARD_FAB2(SCH_1):PAGE113
 C1M29    2      B CAP_A_0402V-0.1UF,16V,10%,X7R,A   I147 @BASEBOARD_FAB2_LIB.BASEBOARD_FAB2(SCH_1):PAGE113
  J9B4    2    IO2 SCONN10_C12536004_SMLF-CONN,C1A   I175 @BASEBOARD_FAB2_LIB.BASEBOARD_FAB2(SCH_1):PAGE113
  J9B4   10   IO10 SCONN10_C12536004_SMLF-CONN,C1A   I175 @BASEBOARD_FAB2_LIB.BASEBOARD_FAB2(SCH_1):PAGE113
  R9B9    2      B RES_0402-1.00K,1%,1/16W,CHIP,GA   I179 @BASEBOARD_FAB2_LIB.BASEBOARD_FAB2(SCH_1):PAGE113
  U9A5    4      B 74CBTLV1G125_SMLF-IC,C88177-00A   I185 @BASEBOARD_FAB2_LIB.BASEBOARD_FAB2(SCH_1):PAGE113
 R1M23    2      B RES_0402-1.00K,1%,1/16W,EMPTY,A   I199 @BASEBOARD_FAB2_LIB.BASEBOARD_FAB2(SCH_1):PAGE113
  C4R2    2      B CAP_A_0402V-0.1UF,16V,10%,X7R,A   I246 @BASEBOARD_FAB2_LIB.BASEBOARD_FAB2(SCH_1):PAGE113
 C1M33    2      B CAP_A_0402V-0.1UF,16V,10%,X7R,A   I248 @BASEBOARD_FAB2_LIB.BASEBOARD_FAB2(SCH_1):PAGE113
  C6M6    2      B CAP_A_0402V-0.1UF,16V,10%,X7R,A   I250 @BASEBOARD_FAB2_LIB.BASEBOARD_FAB2(SCH_1):PAGE113
  U2M1    2    GND NC7SB3157_SMLF-IC,C99406-001   I255 @BASEBOARD_FAB2_LIB.BASEBOARD_FAB2(SCH_1):PAGE113
 C1M34    2      B CAP_A_0402V-0.01UF,25V,10%,X7RA   I265 @BASEBOARD_FAB2_LIB.BASEBOARD_FAB2(SCH_1):PAGE113
 C1M35    2      B CAP_A_0402V-0.01UF,25V,10%,X7RA   I266 @BASEBOARD_FAB2_LIB.BASEBOARD_FAB2(SCH_1):PAGE113
 C1L20    2      B CAP_A_0402V-0.01UF,25V,10%,X7RA   I267 @BASEBOARD_FAB2_LIB.BASEBOARD_FAB2(SCH_1):PAGE113
 C7C15    2      B CAP_0402LF-18PF,50V,5%,C0G,A36A    I46 @BASEBOARD_FAB2_LIB.BASEBOARD_FAB2(SCH_1):PAGE114
  C7C5    2      B CAP_0402LF-15.0PF,50V,5%,COG,AA    I47 @BASEBOARD_FAB2_LIB.BASEBOARD_FAB2(SCH_1):PAGE114
  C7C4    2      B CAP_0402LF-15.0PF,50V,5%,COG,AA    I50 @BASEBOARD_FAB2_LIB.BASEBOARD_FAB2(SCH_1):PAGE114
 C7C13    2      B CAP_0402LF-18PF,50V,5%,C0G,A36A    I56 @BASEBOARD_FAB2_LIB.BASEBOARD_FAB2(SCH_1):PAGE114
 R8B21    2      B RES_0402-49.9,1%,1/16W,EMPTY,GA   I124 @BASEBOARD_FAB2_LIB.BASEBOARD_FAB2(SCH_1):PAGE114
  R3N1    2      B RES_0402-169,1.0%,1/16W,CHIP,GA   I149 @BASEBOARD_FAB2_LIB.BASEBOARD_FAB2(SCH_1):PAGE114
  R8B9    2      B RES_0402-113,1%,1/16W,CHIP,G21A    I90 @BASEBOARD_FAB2_LIB.BASEBOARD_FAB2(SCH_1):PAGE115
 R8B32    2      B RES_0402-10.0K,1%,1/16W,CHIP,GA   I114 @BASEBOARD_FAB2_LIB.BASEBOARD_FAB2(SCH_1):PAGE115
  R7B8    2      B RES_0402-10.0K,1%,1/16W,EMPTY,A   I229 @BASEBOARD_FAB2_LIB.BASEBOARD_FAB2(SCH_1):PAGE116
  R7B7    2      B RES_0402-10.0K,1%,1/16W,EMPTY,A   I230 @BASEBOARD_FAB2_LIB.BASEBOARD_FAB2(SCH_1):PAGE116
  R3M9    2      B RES_0402-100.0K,1%,1/16W,CHIP,A   I234 @BASEBOARD_FAB2_LIB.BASEBOARD_FAB2(SCH_1):PAGE116
  R3M8    2      B RES_0402-100.0K,1%,1/16W,CHIP,A   I235 @BASEBOARD_FAB2_LIB.BASEBOARD_FAB2(SCH_1):PAGE116
 R3N14    2      B RES_0402-49.9,1%,1/16W,EMPTY,GA    I67 @BASEBOARD_FAB2_LIB.BASEBOARD_FAB2(SCH_1):PAGE118
  C8C2    2      B CAP_0402LF-33.0PF,50V,5%,COG,AA    I77 @BASEBOARD_FAB2_LIB.BASEBOARD_FAB2(SCH_1):PAGE118
  C8C1    2      B CAP_0402LF-33.0PF,50V,5%,COG,AA    I79 @BASEBOARD_FAB2_LIB.BASEBOARD_FAB2(SCH_1):PAGE118
  C7D1    2      B CAP_A_0402V-0.1UF,16V,10%,X7R,A   I136 @BASEBOARD_FAB2_LIB.BASEBOARD_FAB2(SCH_1):PAGE118
  Q9A2    1 SOURCE<0> FET_N_DUAL_SMLF-NTJD4001N,FET,A   I175 @BASEBOARD_FAB2_LIB.BASEBOARD_FAB2(SCH_1):PAGE119
  Q9A2    4 SOURCE<0> FET_N_DUAL_SMLF-NTJD4001N,FET,A   I180 @BASEBOARD_FAB2_LIB.BASEBOARD_FAB2(SCH_1):PAGE119
 R8C21    2      B RES_0402-100.0,1%,1/16W,CHIP,GA   I148 @BASEBOARD_FAB2_LIB.BASEBOARD_FAB2(SCH_1):PAGE120
 R8C26    2      B RES_0402-100.0,1%,1/16W,CHIP,GA    I35 @BASEBOARD_FAB2_LIB.BASEBOARD_FAB2(SCH_1):PAGE121
 R7C20    2      B RES_0402-10.0K,1%,1/16W,CHIP,GA    I73 @BASEBOARD_FAB2_LIB.BASEBOARD_FAB2(SCH_1):PAGE121
  U7C1  N31 VSS<355> LBG_CORE_QAT_EXT_D_BGA1-IC,H91A    I13 @BASEBOARD_FAB2_LIB.BASEBOARD_FAB2(SCH_1):PAGE123
  U7C1  N27 VSS<356> LBG_CORE_QAT_EXT_D_BGA1-IC,H91A    I13 @BASEBOARD_FAB2_LIB.BASEBOARD_FAB2(SCH_1):PAGE123
  U7C1  N24 VSS<357> LBG_CORE_QAT_EXT_D_BGA1-IC,H91A    I13 @BASEBOARD_FAB2_LIB.BASEBOARD_FAB2(SCH_1):PAGE123
  U7C1  N20 VSS<358> LBG_CORE_QAT_EXT_D_BGA1-IC,H91A    I13 @BASEBOARD_FAB2_LIB.BASEBOARD_FAB2(SCH_1):PAGE123
  U7C1  N17 VSS<359> LBG_CORE_QAT_EXT_D_BGA1-IC,H91A    I13 @BASEBOARD_FAB2_LIB.BASEBOARD_FAB2(SCH_1):PAGE123
  U7C1  N13 VSS<360> LBG_CORE_QAT_EXT_D_BGA1-IC,H91A    I13 @BASEBOARD_FAB2_LIB.BASEBOARD_FAB2(SCH_1):PAGE123
  U7C1  M48 VSS<361> LBG_CORE_QAT_EXT_D_BGA1-IC,H91A    I13 @BASEBOARD_FAB2_LIB.BASEBOARD_FAB2(SCH_1):PAGE123
  U7C1  M44 VSS<362> LBG_CORE_QAT_EXT_D_BGA1-IC,H91A    I13 @BASEBOARD_FAB2_LIB.BASEBOARD_FAB2(SCH_1):PAGE123
  U7C1  N50 VSS<363> LBG_CORE_QAT_EXT_D_BGA1-IC,H91A    I13 @BASEBOARD_FAB2_LIB.BASEBOARD_FAB2(SCH_1):PAGE123
  U7C1  N42 VSS<364> LBG_CORE_QAT_EXT_D_BGA1-IC,H91A    I13 @BASEBOARD_FAB2_LIB.BASEBOARD_FAB2(SCH_1):PAGE123
  U7C1  M40 VSS<365> LBG_CORE_QAT_EXT_D_BGA1-IC,H91A    I13 @BASEBOARD_FAB2_LIB.BASEBOARD_FAB2(SCH_1):PAGE123
  U7C1   M4 VSS<366> LBG_CORE_QAT_EXT_D_BGA1-IC,H91A    I13 @BASEBOARD_FAB2_LIB.BASEBOARD_FAB2(SCH_1):PAGE123
  U7C1  M37 VSS<367> LBG_CORE_QAT_EXT_D_BGA1-IC,H91A    I13 @BASEBOARD_FAB2_LIB.BASEBOARD_FAB2(SCH_1):PAGE123
  U7C1  M33 VSS<368> LBG_CORE_QAT_EXT_D_BGA1-IC,H91A    I13 @BASEBOARD_FAB2_LIB.BASEBOARD_FAB2(SCH_1):PAGE123
  U7C1  M29 VSS<369> LBG_CORE_QAT_EXT_D_BGA1-IC,H91A    I13 @BASEBOARD_FAB2_LIB.BASEBOARD_FAB2(SCH_1):PAGE123
  U7C1  M26 VSS<370> LBG_CORE_QAT_EXT_D_BGA1-IC,H91A    I13 @BASEBOARD_FAB2_LIB.BASEBOARD_FAB2(SCH_1):PAGE123
  U7C1  M22 VSS<371> LBG_CORE_QAT_EXT_D_BGA1-IC,H91A    I13 @BASEBOARD_FAB2_LIB.BASEBOARD_FAB2(SCH_1):PAGE123
  U7C1   M2 VSS<372> LBG_CORE_QAT_EXT_D_BGA1-IC,H91A    I13 @BASEBOARD_FAB2_LIB.BASEBOARD_FAB2(SCH_1):PAGE123
  U7C1  L68 VSS<373> LBG_CORE_QAT_EXT_D_BGA1-IC,H91A    I13 @BASEBOARD_FAB2_LIB.BASEBOARD_FAB2(SCH_1):PAGE123
  U7C1   L5 VSS<374> LBG_CORE_QAT_EXT_D_BGA1-IC,H91A    I13 @BASEBOARD_FAB2_LIB.BASEBOARD_FAB2(SCH_1):PAGE123
  U7C1  K71 VSS<375> LBG_CORE_QAT_EXT_D_BGA1-IC,H91A    I13 @BASEBOARD_FAB2_LIB.BASEBOARD_FAB2(SCH_1):PAGE123
  U7C1  K69 VSS<376> LBG_CORE_QAT_EXT_D_BGA1-IC,H91A    I13 @BASEBOARD_FAB2_LIB.BASEBOARD_FAB2(SCH_1):PAGE123
  U7C1  K54 VSS<377> LBG_CORE_QAT_EXT_D_BGA1-IC,H91A    I13 @BASEBOARD_FAB2_LIB.BASEBOARD_FAB2(SCH_1):PAGE123
  U7C1  J70 VSS<378> LBG_CORE_QAT_EXT_D_BGA1-IC,H91A    I13 @BASEBOARD_FAB2_LIB.BASEBOARD_FAB2(SCH_1):PAGE123
  U7C1  J68 VSS<379> LBG_CORE_QAT_EXT_D_BGA1-IC,H91A    I13 @BASEBOARD_FAB2_LIB.BASEBOARD_FAB2(SCH_1):PAGE123
  U7C1  J59 VSS<380> LBG_CORE_QAT_EXT_D_BGA1-IC,H91A    I13 @BASEBOARD_FAB2_LIB.BASEBOARD_FAB2(SCH_1):PAGE123
  U7C1  J44 VSS<381> LBG_CORE_QAT_EXT_D_BGA1-IC,H91A    I13 @BASEBOARD_FAB2_LIB.BASEBOARD_FAB2(SCH_1):PAGE123
  U7C1  J37 VSS<382> LBG_CORE_QAT_EXT_D_BGA1-IC,H91A    I13 @BASEBOARD_FAB2_LIB.BASEBOARD_FAB2(SCH_1):PAGE123
  U7C1  J22 VSS<383> LBG_CORE_QAT_EXT_D_BGA1-IC,H91A    I13 @BASEBOARD_FAB2_LIB.BASEBOARD_FAB2(SCH_1):PAGE123
  U7C1  J15 VSS<384> LBG_CORE_QAT_EXT_D_BGA1-IC,H91A    I13 @BASEBOARD_FAB2_LIB.BASEBOARD_FAB2(SCH_1):PAGE123
  U7C1  J11 VSS<385> LBG_CORE_QAT_EXT_D_BGA1-IC,H91A    I13 @BASEBOARD_FAB2_LIB.BASEBOARD_FAB2(SCH_1):PAGE123
  U7C1  H65 VSS<386> LBG_CORE_QAT_EXT_D_BGA1-IC,H91A    I13 @BASEBOARD_FAB2_LIB.BASEBOARD_FAB2(SCH_1):PAGE123
  U7C1   J7 VSS<387> LBG_CORE_QAT_EXT_D_BGA1-IC,H91A    I13 @BASEBOARD_FAB2_LIB.BASEBOARD_FAB2(SCH_1):PAGE123
  U7C1   J5 VSS<388> LBG_CORE_QAT_EXT_D_BGA1-IC,H91A    I13 @BASEBOARD_FAB2_LIB.BASEBOARD_FAB2(SCH_1):PAGE123
  U7C1  J29 VSS<389> LBG_CORE_QAT_EXT_D_BGA1-IC,H91A    I13 @BASEBOARD_FAB2_LIB.BASEBOARD_FAB2(SCH_1):PAGE123
  U7C1  H58 VSS<390> LBG_CORE_QAT_EXT_D_BGA1-IC,H91A    I13 @BASEBOARD_FAB2_LIB.BASEBOARD_FAB2(SCH_1):PAGE123
  U7C1  G66 VSS<391> LBG_CORE_QAT_EXT_D_BGA1-IC,H91A    I13 @BASEBOARD_FAB2_LIB.BASEBOARD_FAB2(SCH_1):PAGE123
  U7C1  G63 VSS<392> LBG_CORE_QAT_EXT_D_BGA1-IC,H91A    I13 @BASEBOARD_FAB2_LIB.BASEBOARD_FAB2(SCH_1):PAGE123
  U7C1   G6 VSS<393> LBG_CORE_QAT_EXT_D_BGA1-IC,H91A    I13 @BASEBOARD_FAB2_LIB.BASEBOARD_FAB2(SCH_1):PAGE123
  U7C1  G48 VSS<394> LBG_CORE_QAT_EXT_D_BGA1-IC,H91A    I13 @BASEBOARD_FAB2_LIB.BASEBOARD_FAB2(SCH_1):PAGE123
  U7C1  G37 VSS<395> LBG_CORE_QAT_EXT_D_BGA1-IC,H91A    I13 @BASEBOARD_FAB2_LIB.BASEBOARD_FAB2(SCH_1):PAGE123
  U7C1  G29 VSS<396> LBG_CORE_QAT_EXT_D_BGA1-IC,H91A    I13 @BASEBOARD_FAB2_LIB.BASEBOARD_FAB2(SCH_1):PAGE123
  U7C1  G22 VSS<397> LBG_CORE_QAT_EXT_D_BGA1-IC,H91A    I13 @BASEBOARD_FAB2_LIB.BASEBOARD_FAB2(SCH_1):PAGE123
  U7C1   E9 VSS<398> LBG_CORE_QAT_EXT_D_BGA1-IC,H91A    I13 @BASEBOARD_FAB2_LIB.BASEBOARD_FAB2(SCH_1):PAGE123
  U7C1  G59 VSS<399> LBG_CORE_QAT_EXT_D_BGA1-IC,H91A    I13 @BASEBOARD_FAB2_LIB.BASEBOARD_FAB2(SCH_1):PAGE123
  U7C1  E63 VSS<400> LBG_CORE_QAT_EXT_D_BGA1-IC,H91A    I13 @BASEBOARD_FAB2_LIB.BASEBOARD_FAB2(SCH_1):PAGE123
  U7C1  E61 VSS<401> LBG_CORE_QAT_EXT_D_BGA1-IC,H91A    I13 @BASEBOARD_FAB2_LIB.BASEBOARD_FAB2(SCH_1):PAGE123
  U7C1   E6 VSS<402> LBG_CORE_QAT_EXT_D_BGA1-IC,H91A    I13 @BASEBOARD_FAB2_LIB.BASEBOARD_FAB2(SCH_1):PAGE123
  U7C1  E57 VSS<403> LBG_CORE_QAT_EXT_D_BGA1-IC,H91A    I13 @BASEBOARD_FAB2_LIB.BASEBOARD_FAB2(SCH_1):PAGE123
  U7C1  E54 VSS<404> LBG_CORE_QAT_EXT_D_BGA1-IC,H91A    I13 @BASEBOARD_FAB2_LIB.BASEBOARD_FAB2(SCH_1):PAGE123
  U7C1  E52 VSS<405> LBG_CORE_QAT_EXT_D_BGA1-IC,H91A    I13 @BASEBOARD_FAB2_LIB.BASEBOARD_FAB2(SCH_1):PAGE123
  U7C1  E50 VSS<406> LBG_CORE_QAT_EXT_D_BGA1-IC,H91A    I13 @BASEBOARD_FAB2_LIB.BASEBOARD_FAB2(SCH_1):PAGE123
  U7C1  E48 VSS<407> LBG_CORE_QAT_EXT_D_BGA1-IC,H91A    I13 @BASEBOARD_FAB2_LIB.BASEBOARD_FAB2(SCH_1):PAGE123
  U7C1  E45 VSS<408> LBG_CORE_QAT_EXT_D_BGA1-IC,H91A    I13 @BASEBOARD_FAB2_LIB.BASEBOARD_FAB2(SCH_1):PAGE123
  U7C1  E43 VSS<409> LBG_CORE_QAT_EXT_D_BGA1-IC,H91A    I13 @BASEBOARD_FAB2_LIB.BASEBOARD_FAB2(SCH_1):PAGE123
  U7C1  E41 VSS<410> LBG_CORE_QAT_EXT_D_BGA1-IC,H91A    I13 @BASEBOARD_FAB2_LIB.BASEBOARD_FAB2(SCH_1):PAGE123
  U7C1  E39 VSS<411> LBG_CORE_QAT_EXT_D_BGA1-IC,H91A    I13 @BASEBOARD_FAB2_LIB.BASEBOARD_FAB2(SCH_1):PAGE123
  U7C1  E37 VSS<412> LBG_CORE_QAT_EXT_D_BGA1-IC,H91A    I13 @BASEBOARD_FAB2_LIB.BASEBOARD_FAB2(SCH_1):PAGE123
  U7C1  E34 VSS<413> LBG_CORE_QAT_EXT_D_BGA1-IC,H91A    I13 @BASEBOARD_FAB2_LIB.BASEBOARD_FAB2(SCH_1):PAGE123
  U7C1  E32 VSS<414> LBG_CORE_QAT_EXT_D_BGA1-IC,H91A    I13 @BASEBOARD_FAB2_LIB.BASEBOARD_FAB2(SCH_1):PAGE123
  U7C1  E30 VSS<415> LBG_CORE_QAT_EXT_D_BGA1-IC,H91A    I13 @BASEBOARD_FAB2_LIB.BASEBOARD_FAB2(SCH_1):PAGE123
  U7C1  E28 VSS<416> LBG_CORE_QAT_EXT_D_BGA1-IC,H91A    I13 @BASEBOARD_FAB2_LIB.BASEBOARD_FAB2(SCH_1):PAGE123
  U7C1  E26 VSS<417> LBG_CORE_QAT_EXT_D_BGA1-IC,H91A    I13 @BASEBOARD_FAB2_LIB.BASEBOARD_FAB2(SCH_1):PAGE123
  U7C1  E24 VSS<418> LBG_CORE_QAT_EXT_D_BGA1-IC,H91A    I13 @BASEBOARD_FAB2_LIB.BASEBOARD_FAB2(SCH_1):PAGE123
  U7C1  E22 VSS<419> LBG_CORE_QAT_EXT_D_BGA1-IC,H91A    I13 @BASEBOARD_FAB2_LIB.BASEBOARD_FAB2(SCH_1):PAGE123
  U7C1  E20 VSS<420> LBG_CORE_QAT_EXT_D_BGA1-IC,H91A    I13 @BASEBOARD_FAB2_LIB.BASEBOARD_FAB2(SCH_1):PAGE123
  U7C1  E15 VSS<421> LBG_CORE_QAT_EXT_D_BGA1-IC,H91A    I13 @BASEBOARD_FAB2_LIB.BASEBOARD_FAB2(SCH_1):PAGE123
  U7C1  E13 VSS<422> LBG_CORE_QAT_EXT_D_BGA1-IC,H91A    I13 @BASEBOARD_FAB2_LIB.BASEBOARD_FAB2(SCH_1):PAGE123
  U7C1  E11 VSS<423> LBG_CORE_QAT_EXT_D_BGA1-IC,H91A    I13 @BASEBOARD_FAB2_LIB.BASEBOARD_FAB2(SCH_1):PAGE123
  U7C1  D47 VSS<424> LBG_CORE_QAT_EXT_D_BGA1-IC,H91A    I13 @BASEBOARD_FAB2_LIB.BASEBOARD_FAB2(SCH_1):PAGE123
  U7C1  E65 VSS<425> LBG_CORE_QAT_EXT_D_BGA1-IC,H91A    I13 @BASEBOARD_FAB2_LIB.BASEBOARD_FAB2(SCH_1):PAGE123
  U7C1  E59 VSS<426> LBG_CORE_QAT_EXT_D_BGA1-IC,H91A    I13 @BASEBOARD_FAB2_LIB.BASEBOARD_FAB2(SCH_1):PAGE123
  U7C1  D27 VSS<427> LBG_CORE_QAT_EXT_D_BGA1-IC,H91A    I13 @BASEBOARD_FAB2_LIB.BASEBOARD_FAB2(SCH_1):PAGE123
  U7C1  D25 VSS<428> LBG_CORE_QAT_EXT_D_BGA1-IC,H91A    I13 @BASEBOARD_FAB2_LIB.BASEBOARD_FAB2(SCH_1):PAGE123
  U7C1  D19 VSS<429> LBG_CORE_QAT_EXT_D_BGA1-IC,H91A    I13 @BASEBOARD_FAB2_LIB.BASEBOARD_FAB2(SCH_1):PAGE123
  U7C1  D16 VSS<430> LBG_CORE_QAT_EXT_D_BGA1-IC,H91A    I13 @BASEBOARD_FAB2_LIB.BASEBOARD_FAB2(SCH_1):PAGE123
  U7C1  D12 VSS<431> LBG_CORE_QAT_EXT_D_BGA1-IC,H91A    I13 @BASEBOARD_FAB2_LIB.BASEBOARD_FAB2(SCH_1):PAGE123
  U7C1  C65 VSS<432> LBG_CORE_QAT_EXT_D_BGA1-IC,H91A    I13 @BASEBOARD_FAB2_LIB.BASEBOARD_FAB2(SCH_1):PAGE123
  U7C1  C41 VSS<433> LBG_CORE_QAT_EXT_D_BGA1-IC,H91A    I13 @BASEBOARD_FAB2_LIB.BASEBOARD_FAB2(SCH_1):PAGE123
  U7C1  C37 VSS<434> LBG_CORE_QAT_EXT_D_BGA1-IC,H91A    I13 @BASEBOARD_FAB2_LIB.BASEBOARD_FAB2(SCH_1):PAGE123
  U7C1  C34 VSS<435> LBG_CORE_QAT_EXT_D_BGA1-IC,H91A    I13 @BASEBOARD_FAB2_LIB.BASEBOARD_FAB2(SCH_1):PAGE123
  U7C1  C30 VSS<436> LBG_CORE_QAT_EXT_D_BGA1-IC,H91A    I13 @BASEBOARD_FAB2_LIB.BASEBOARD_FAB2(SCH_1):PAGE123
  U7C1  C22 VSS<437> LBG_CORE_QAT_EXT_D_BGA1-IC,H91A    I13 @BASEBOARD_FAB2_LIB.BASEBOARD_FAB2(SCH_1):PAGE123
  U7C1  B47 VSS<438> LBG_CORE_QAT_EXT_D_BGA1-IC,H91A    I13 @BASEBOARD_FAB2_LIB.BASEBOARD_FAB2(SCH_1):PAGE123
  U7C1  B27 VSS<439> LBG_CORE_QAT_EXT_D_BGA1-IC,H91A    I13 @BASEBOARD_FAB2_LIB.BASEBOARD_FAB2(SCH_1):PAGE123
  U7C1  B25 VSS<440> LBG_CORE_QAT_EXT_D_BGA1-IC,H91A    I13 @BASEBOARD_FAB2_LIB.BASEBOARD_FAB2(SCH_1):PAGE123
  U7C1  B19 VSS<441> LBG_CORE_QAT_EXT_D_BGA1-IC,H91A    I13 @BASEBOARD_FAB2_LIB.BASEBOARD_FAB2(SCH_1):PAGE123
  U7C1  B12 VSS<442> LBG_CORE_QAT_EXT_D_BGA1-IC,H91A    I13 @BASEBOARD_FAB2_LIB.BASEBOARD_FAB2(SCH_1):PAGE123
  U7C1  A41 VSS<443> LBG_CORE_QAT_EXT_D_BGA1-IC,H91A    I13 @BASEBOARD_FAB2_LIB.BASEBOARD_FAB2(SCH_1):PAGE123
  U7C1  A37 VSS<444> LBG_CORE_QAT_EXT_D_BGA1-IC,H91A    I13 @BASEBOARD_FAB2_LIB.BASEBOARD_FAB2(SCH_1):PAGE123
  U7C1  A34 VSS<445> LBG_CORE_QAT_EXT_D_BGA1-IC,H91A    I13 @BASEBOARD_FAB2_LIB.BASEBOARD_FAB2(SCH_1):PAGE123
  U7C1  A30 VSS<446> LBG_CORE_QAT_EXT_D_BGA1-IC,H91A    I13 @BASEBOARD_FAB2_LIB.BASEBOARD_FAB2(SCH_1):PAGE123
  U7C1  A22 VSS<447> LBG_CORE_QAT_EXT_D_BGA1-IC,H91A    I13 @BASEBOARD_FAB2_LIB.BASEBOARD_FAB2(SCH_1):PAGE123
  U7C1  A18 VSS<448> LBG_CORE_QAT_EXT_D_BGA1-IC,H91A    I13 @BASEBOARD_FAB2_LIB.BASEBOARD_FAB2(SCH_1):PAGE123
  U7C1  Y70 VSS<449> LBG_CORE_QAT_EXT_D_BGA1-IC,H91A    I13 @BASEBOARD_FAB2_LIB.BASEBOARD_FAB2(SCH_1):PAGE123
  U7C1  Y72 VSS<450> LBG_CORE_QAT_EXT_D_BGA1-IC,H91A    I13 @BASEBOARD_FAB2_LIB.BASEBOARD_FAB2(SCH_1):PAGE123
  U7C1 AT37 VSS<451> LBG_CORE_QAT_EXT_D_BGA1-IC,H91A    I13 @BASEBOARD_FAB2_LIB.BASEBOARD_FAB2(SCH_1):PAGE123
  U7C1 BB48 VSS<452> LBG_CORE_QAT_EXT_D_BGA1-IC,H91A    I13 @BASEBOARD_FAB2_LIB.BASEBOARD_FAB2(SCH_1):PAGE123
  U7C1 CA70 VSS<453> LBG_CORE_QAT_EXT_D_BGA1-IC,H91A    I13 @BASEBOARD_FAB2_LIB.BASEBOARD_FAB2(SCH_1):PAGE123
  U7C1 BW72 VSS<454> LBG_CORE_QAT_EXT_D_BGA1-IC,H91A    I13 @BASEBOARD_FAB2_LIB.BASEBOARD_FAB2(SCH_1):PAGE123
  U7C1 BW70 VSS<455> LBG_CORE_QAT_EXT_D_BGA1-IC,H91A    I13 @BASEBOARD_FAB2_LIB.BASEBOARD_FAB2(SCH_1):PAGE123
  U7C1 BU72 VSS<456> LBG_CORE_QAT_EXT_D_BGA1-IC,H91A    I13 @BASEBOARD_FAB2_LIB.BASEBOARD_FAB2(SCH_1):PAGE123
  U7C1 BR72 VSS<457> LBG_CORE_QAT_EXT_D_BGA1-IC,H91A    I13 @BASEBOARD_FAB2_LIB.BASEBOARD_FAB2(SCH_1):PAGE123
  U7C1  G72 VSS<458> LBG_CORE_QAT_EXT_D_BGA1-IC,H91A    I13 @BASEBOARD_FAB2_LIB.BASEBOARD_FAB2(SCH_1):PAGE123
  U7C1   G1 VSS<459> LBG_CORE_QAT_EXT_D_BGA1-IC,H91A    I13 @BASEBOARD_FAB2_LIB.BASEBOARD_FAB2(SCH_1):PAGE123
  U7C1  E72 VSS<460> LBG_CORE_QAT_EXT_D_BGA1-IC,H91A    I13 @BASEBOARD_FAB2_LIB.BASEBOARD_FAB2(SCH_1):PAGE123
  U7C1   E1 VSS<461> LBG_CORE_QAT_EXT_D_BGA1-IC,H91A    I13 @BASEBOARD_FAB2_LIB.BASEBOARD_FAB2(SCH_1):PAGE123
  U7C1  C72 VSS<462> LBG_CORE_QAT_EXT_D_BGA1-IC,H91A    I13 @BASEBOARD_FAB2_LIB.BASEBOARD_FAB2(SCH_1):PAGE123
  U7C1   C3 VSS<463> LBG_CORE_QAT_EXT_D_BGA1-IC,H91A    I13 @BASEBOARD_FAB2_LIB.BASEBOARD_FAB2(SCH_1):PAGE123
  U7C1  BR1 VSS<464> LBG_CORE_QAT_EXT_D_BGA1-IC,H91A    I13 @BASEBOARD_FAB2_LIB.BASEBOARD_FAB2(SCH_1):PAGE123
  U7C1  BU1 VSS<465> LBG_CORE_QAT_EXT_D_BGA1-IC,H91A    I13 @BASEBOARD_FAB2_LIB.BASEBOARD_FAB2(SCH_1):PAGE123
  U7C1  BW1 VSS<466> LBG_CORE_QAT_EXT_D_BGA1-IC,H91A    I13 @BASEBOARD_FAB2_LIB.BASEBOARD_FAB2(SCH_1):PAGE123
  U7C1  CA3 VSS<467> LBG_CORE_QAT_EXT_D_BGA1-IC,H91A    I13 @BASEBOARD_FAB2_LIB.BASEBOARD_FAB2(SCH_1):PAGE123
  U7C1  A70 VSS<468> LBG_CORE_QAT_EXT_D_BGA1-IC,H91A    I13 @BASEBOARD_FAB2_LIB.BASEBOARD_FAB2(SCH_1):PAGE123
  U7C1  CA5 VSS<469> LBG_CORE_QAT_EXT_D_BGA1-IC,H91A    I13 @BASEBOARD_FAB2_LIB.BASEBOARD_FAB2(SCH_1):PAGE123
  U7C1  CA7 VSS<470> LBG_CORE_QAT_EXT_D_BGA1-IC,H91A    I13 @BASEBOARD_FAB2_LIB.BASEBOARD_FAB2(SCH_1):PAGE123
  U7C1  CA9 VSS<471> LBG_CORE_QAT_EXT_D_BGA1-IC,H91A    I13 @BASEBOARD_FAB2_LIB.BASEBOARD_FAB2(SCH_1):PAGE123
  U7C1 CA65 VSS<472> LBG_CORE_QAT_EXT_D_BGA1-IC,H91A    I13 @BASEBOARD_FAB2_LIB.BASEBOARD_FAB2(SCH_1):PAGE123
  U7C1 CA66 VSS<473> LBG_CORE_QAT_EXT_D_BGA1-IC,H91A    I13 @BASEBOARD_FAB2_LIB.BASEBOARD_FAB2(SCH_1):PAGE123
  U7C1 CA68 VSS<474> LBG_CORE_QAT_EXT_D_BGA1-IC,H91A    I13 @BASEBOARD_FAB2_LIB.BASEBOARD_FAB2(SCH_1):PAGE123
  U7C1 BN72 VSS<475> LBG_CORE_QAT_EXT_D_BGA1-IC,H91A    I13 @BASEBOARD_FAB2_LIB.BASEBOARD_FAB2(SCH_1):PAGE123
  U7C1  BN1 VSS<476> LBG_CORE_QAT_EXT_D_BGA1-IC,H91A    I13 @BASEBOARD_FAB2_LIB.BASEBOARD_FAB2(SCH_1):PAGE123
  U7C1  J72 VSS<477> LBG_CORE_QAT_EXT_D_BGA1-IC,H91A    I13 @BASEBOARD_FAB2_LIB.BASEBOARD_FAB2(SCH_1):PAGE123
  U7C1   J1 VSS<478> LBG_CORE_QAT_EXT_D_BGA1-IC,H91A    I13 @BASEBOARD_FAB2_LIB.BASEBOARD_FAB2(SCH_1):PAGE123
  U7C1  A68 VSS<479> LBG_CORE_QAT_EXT_D_BGA1-IC,H91A    I13 @BASEBOARD_FAB2_LIB.BASEBOARD_FAB2(SCH_1):PAGE123
  U7C1  A66 VSS<480> LBG_CORE_QAT_EXT_D_BGA1-IC,H91A    I13 @BASEBOARD_FAB2_LIB.BASEBOARD_FAB2(SCH_1):PAGE123
  U7C1  A65 VSS<481> LBG_CORE_QAT_EXT_D_BGA1-IC,H91A    I13 @BASEBOARD_FAB2_LIB.BASEBOARD_FAB2(SCH_1):PAGE123
  U7C1   A9 VSS<482> LBG_CORE_QAT_EXT_D_BGA1-IC,H91A    I13 @BASEBOARD_FAB2_LIB.BASEBOARD_FAB2(SCH_1):PAGE123
  U7C1   A7 VSS<483> LBG_CORE_QAT_EXT_D_BGA1-IC,H91A    I13 @BASEBOARD_FAB2_LIB.BASEBOARD_FAB2(SCH_1):PAGE123
  U7C1   A5 VSS<484> LBG_CORE_QAT_EXT_D_BGA1-IC,H91A    I13 @BASEBOARD_FAB2_LIB.BASEBOARD_FAB2(SCH_1):PAGE123
  U7C1   E3 VSS<485> LBG_CORE_QAT_EXT_D_BGA1-IC,H91A    I13 @BASEBOARD_FAB2_LIB.BASEBOARD_FAB2(SCH_1):PAGE123
  U7C1   F3 VSS<486> LBG_CORE_QAT_EXT_D_BGA1-IC,H91A    I13 @BASEBOARD_FAB2_LIB.BASEBOARD_FAB2(SCH_1):PAGE123
  U7C1  BR3 VSS<487> LBG_CORE_QAT_EXT_D_BGA1-IC,H91A    I13 @BASEBOARD_FAB2_LIB.BASEBOARD_FAB2(SCH_1):PAGE123
  U7C1  BU3 VSS<488> LBG_CORE_QAT_EXT_D_BGA1-IC,H91A    I13 @BASEBOARD_FAB2_LIB.BASEBOARD_FAB2(SCH_1):PAGE123
  U7C1  E70 VSS<489> LBG_CORE_QAT_EXT_D_BGA1-IC,H91A    I13 @BASEBOARD_FAB2_LIB.BASEBOARD_FAB2(SCH_1):PAGE123
  U7C1  F70 VSS<490> LBG_CORE_QAT_EXT_D_BGA1-IC,H91A    I13 @BASEBOARD_FAB2_LIB.BASEBOARD_FAB2(SCH_1):PAGE123
  U7C1 BR70 VSS<491> LBG_CORE_QAT_EXT_D_BGA1-IC,H91A    I13 @BASEBOARD_FAB2_LIB.BASEBOARD_FAB2(SCH_1):PAGE123
  U7C1 BU70 VSS<492> LBG_CORE_QAT_EXT_D_BGA1-IC,H91A    I13 @BASEBOARD_FAB2_LIB.BASEBOARD_FAB2(SCH_1):PAGE123
  U7C1 BT69 VSS<493> LBG_CORE_QAT_EXT_D_BGA1-IC,H91A    I13 @BASEBOARD_FAB2_LIB.BASEBOARD_FAB2(SCH_1):PAGE123
  U7C1 BP69 VSS<494> LBG_CORE_QAT_EXT_D_BGA1-IC,H91A    I13 @BASEBOARD_FAB2_LIB.BASEBOARD_FAB2(SCH_1):PAGE123
  U7C1 CA52 VSS<0> LBG_CORE_QAT_EXT_D_BGA1-IC,H91A    I15 @BASEBOARD_FAB2_LIB.BASEBOARD_FAB2(SCH_1):PAGE124
  U7C1 CA50 VSS<1> LBG_CORE_QAT_EXT_D_BGA1-IC,H91A    I15 @BASEBOARD_FAB2_LIB.BASEBOARD_FAB2(SCH_1):PAGE124
  U7C1 CA26 VSS<2> LBG_CORE_QAT_EXT_D_BGA1-IC,H91A    I15 @BASEBOARD_FAB2_LIB.BASEBOARD_FAB2(SCH_1):PAGE124
  U7C1 CA18 VSS<3> LBG_CORE_QAT_EXT_D_BGA1-IC,H91A    I15 @BASEBOARD_FAB2_LIB.BASEBOARD_FAB2(SCH_1):PAGE124
  U7C1 CA15 VSS<4> LBG_CORE_QAT_EXT_D_BGA1-IC,H91A    I15 @BASEBOARD_FAB2_LIB.BASEBOARD_FAB2(SCH_1):PAGE124
  U7C1 BY49 VSS<5> LBG_CORE_QAT_EXT_D_BGA1-IC,H91A    I15 @BASEBOARD_FAB2_LIB.BASEBOARD_FAB2(SCH_1):PAGE124
  U7C1 BY40 VSS<6> LBG_CORE_QAT_EXT_D_BGA1-IC,H91A    I15 @BASEBOARD_FAB2_LIB.BASEBOARD_FAB2(SCH_1):PAGE124
  U7C1 BW52 VSS<7> LBG_CORE_QAT_EXT_D_BGA1-IC,H91A    I15 @BASEBOARD_FAB2_LIB.BASEBOARD_FAB2(SCH_1):PAGE124
  U7C1 BW26 VSS<8> LBG_CORE_QAT_EXT_D_BGA1-IC,H91A    I15 @BASEBOARD_FAB2_LIB.BASEBOARD_FAB2(SCH_1):PAGE124
  U7C1 BW18 VSS<9> LBG_CORE_QAT_EXT_D_BGA1-IC,H91A    I15 @BASEBOARD_FAB2_LIB.BASEBOARD_FAB2(SCH_1):PAGE124
  U7C1 BW15 VSS<10> LBG_CORE_QAT_EXT_D_BGA1-IC,H91A    I15 @BASEBOARD_FAB2_LIB.BASEBOARD_FAB2(SCH_1):PAGE124
  U7C1 BV40 VSS<11> LBG_CORE_QAT_EXT_D_BGA1-IC,H91A    I15 @BASEBOARD_FAB2_LIB.BASEBOARD_FAB2(SCH_1):PAGE124
  U7C1  BU9 VSS<12> LBG_CORE_QAT_EXT_D_BGA1-IC,H91A    I15 @BASEBOARD_FAB2_LIB.BASEBOARD_FAB2(SCH_1):PAGE124
  U7C1 BU63 VSS<13> LBG_CORE_QAT_EXT_D_BGA1-IC,H91A    I15 @BASEBOARD_FAB2_LIB.BASEBOARD_FAB2(SCH_1):PAGE124
  U7C1 BU61 VSS<14> LBG_CORE_QAT_EXT_D_BGA1-IC,H91A    I15 @BASEBOARD_FAB2_LIB.BASEBOARD_FAB2(SCH_1):PAGE124
  U7C1 BU59 VSS<15> LBG_CORE_QAT_EXT_D_BGA1-IC,H91A    I15 @BASEBOARD_FAB2_LIB.BASEBOARD_FAB2(SCH_1):PAGE124
  U7C1 BU57 VSS<16> LBG_CORE_QAT_EXT_D_BGA1-IC,H91A    I15 @BASEBOARD_FAB2_LIB.BASEBOARD_FAB2(SCH_1):PAGE124
  U7C1 BU54 VSS<17> LBG_CORE_QAT_EXT_D_BGA1-IC,H91A    I15 @BASEBOARD_FAB2_LIB.BASEBOARD_FAB2(SCH_1):PAGE124
  U7C1 BU52 VSS<18> LBG_CORE_QAT_EXT_D_BGA1-IC,H91A    I15 @BASEBOARD_FAB2_LIB.BASEBOARD_FAB2(SCH_1):PAGE124
  U7C1 BU50 VSS<19> LBG_CORE_QAT_EXT_D_BGA1-IC,H91A    I15 @BASEBOARD_FAB2_LIB.BASEBOARD_FAB2(SCH_1):PAGE124
  U7C1 BU48 VSS<20> LBG_CORE_QAT_EXT_D_BGA1-IC,H91A    I15 @BASEBOARD_FAB2_LIB.BASEBOARD_FAB2(SCH_1):PAGE124
  U7C1 BU45 VSS<21> LBG_CORE_QAT_EXT_D_BGA1-IC,H91A    I15 @BASEBOARD_FAB2_LIB.BASEBOARD_FAB2(SCH_1):PAGE124
  U7C1 BU43 VSS<22> LBG_CORE_QAT_EXT_D_BGA1-IC,H91A    I15 @BASEBOARD_FAB2_LIB.BASEBOARD_FAB2(SCH_1):PAGE124
  U7C1 BU41 VSS<23> LBG_CORE_QAT_EXT_D_BGA1-IC,H91A    I15 @BASEBOARD_FAB2_LIB.BASEBOARD_FAB2(SCH_1):PAGE124
  U7C1 BU39 VSS<24> LBG_CORE_QAT_EXT_D_BGA1-IC,H91A    I15 @BASEBOARD_FAB2_LIB.BASEBOARD_FAB2(SCH_1):PAGE124
  U7C1 BU37 VSS<25> LBG_CORE_QAT_EXT_D_BGA1-IC,H91A    I15 @BASEBOARD_FAB2_LIB.BASEBOARD_FAB2(SCH_1):PAGE124
  U7C1 BU34 VSS<26> LBG_CORE_QAT_EXT_D_BGA1-IC,H91A    I15 @BASEBOARD_FAB2_LIB.BASEBOARD_FAB2(SCH_1):PAGE124
  U7C1 BU32 VSS<27> LBG_CORE_QAT_EXT_D_BGA1-IC,H91A    I15 @BASEBOARD_FAB2_LIB.BASEBOARD_FAB2(SCH_1):PAGE124
  U7C1 BU30 VSS<28> LBG_CORE_QAT_EXT_D_BGA1-IC,H91A    I15 @BASEBOARD_FAB2_LIB.BASEBOARD_FAB2(SCH_1):PAGE124
  U7C1 BU28 VSS<29> LBG_CORE_QAT_EXT_D_BGA1-IC,H91A    I15 @BASEBOARD_FAB2_LIB.BASEBOARD_FAB2(SCH_1):PAGE124
  U7C1 BU26 VSS<30> LBG_CORE_QAT_EXT_D_BGA1-IC,H91A    I15 @BASEBOARD_FAB2_LIB.BASEBOARD_FAB2(SCH_1):PAGE124
  U7C1 BU24 VSS<31> LBG_CORE_QAT_EXT_D_BGA1-IC,H91A    I15 @BASEBOARD_FAB2_LIB.BASEBOARD_FAB2(SCH_1):PAGE124
  U7C1 BU22 VSS<32> LBG_CORE_QAT_EXT_D_BGA1-IC,H91A    I15 @BASEBOARD_FAB2_LIB.BASEBOARD_FAB2(SCH_1):PAGE124
  U7C1 BU20 VSS<33> LBG_CORE_QAT_EXT_D_BGA1-IC,H91A    I15 @BASEBOARD_FAB2_LIB.BASEBOARD_FAB2(SCH_1):PAGE124
  U7C1 BU18 VSS<34> LBG_CORE_QAT_EXT_D_BGA1-IC,H91A    I15 @BASEBOARD_FAB2_LIB.BASEBOARD_FAB2(SCH_1):PAGE124
  U7C1 BU15 VSS<35> LBG_CORE_QAT_EXT_D_BGA1-IC,H91A    I15 @BASEBOARD_FAB2_LIB.BASEBOARD_FAB2(SCH_1):PAGE124
  U7C1 BV49 VSS<36> LBG_CORE_QAT_EXT_D_BGA1-IC,H91A    I15 @BASEBOARD_FAB2_LIB.BASEBOARD_FAB2(SCH_1):PAGE124
  U7C1 BU11 VSS<37> LBG_CORE_QAT_EXT_D_BGA1-IC,H91A    I15 @BASEBOARD_FAB2_LIB.BASEBOARD_FAB2(SCH_1):PAGE124
  U7C1 BU13 VSS<38> LBG_CORE_QAT_EXT_D_BGA1-IC,H91A    I15 @BASEBOARD_FAB2_LIB.BASEBOARD_FAB2(SCH_1):PAGE124
  U7C1 BT66 VSS<39> LBG_CORE_QAT_EXT_D_BGA1-IC,H91A    I15 @BASEBOARD_FAB2_LIB.BASEBOARD_FAB2(SCH_1):PAGE124
  U7C1  BR6 VSS<40> LBG_CORE_QAT_EXT_D_BGA1-IC,H91A    I15 @BASEBOARD_FAB2_LIB.BASEBOARD_FAB2(SCH_1):PAGE124
  U7C1 BR58 VSS<41> LBG_CORE_QAT_EXT_D_BGA1-IC,H91A    I15 @BASEBOARD_FAB2_LIB.BASEBOARD_FAB2(SCH_1):PAGE124
  U7C1 BR54 VSS<42> LBG_CORE_QAT_EXT_D_BGA1-IC,H91A    I15 @BASEBOARD_FAB2_LIB.BASEBOARD_FAB2(SCH_1):PAGE124
  U7C1  BT8 VSS<43> LBG_CORE_QAT_EXT_D_BGA1-IC,H91A    I15 @BASEBOARD_FAB2_LIB.BASEBOARD_FAB2(SCH_1):PAGE124
  U7C1 BR50 VSS<44> LBG_CORE_QAT_EXT_D_BGA1-IC,H91A    I15 @BASEBOARD_FAB2_LIB.BASEBOARD_FAB2(SCH_1):PAGE124
  U7C1 BR20 VSS<45> LBG_CORE_QAT_EXT_D_BGA1-IC,H91A    I15 @BASEBOARD_FAB2_LIB.BASEBOARD_FAB2(SCH_1):PAGE124
  U7C1 BN66 VSS<46> LBG_CORE_QAT_EXT_D_BGA1-IC,H91A    I15 @BASEBOARD_FAB2_LIB.BASEBOARD_FAB2(SCH_1):PAGE124
  U7C1 BN52 VSS<47> LBG_CORE_QAT_EXT_D_BGA1-IC,H91A    I15 @BASEBOARD_FAB2_LIB.BASEBOARD_FAB2(SCH_1):PAGE124
  U7C1  BN5 VSS<48> LBG_CORE_QAT_EXT_D_BGA1-IC,H91A    I15 @BASEBOARD_FAB2_LIB.BASEBOARD_FAB2(SCH_1):PAGE124
  U7C1 BN59 VSS<49> LBG_CORE_QAT_EXT_D_BGA1-IC,H91A    I15 @BASEBOARD_FAB2_LIB.BASEBOARD_FAB2(SCH_1):PAGE124
  U7C1 BN22 VSS<50> LBG_CORE_QAT_EXT_D_BGA1-IC,H91A    I15 @BASEBOARD_FAB2_LIB.BASEBOARD_FAB2(SCH_1):PAGE124
  U7C1  BM9 VSS<51> LBG_CORE_QAT_EXT_D_BGA1-IC,H91A    I15 @BASEBOARD_FAB2_LIB.BASEBOARD_FAB2(SCH_1):PAGE124
  U7C1 BM71 VSS<52> LBG_CORE_QAT_EXT_D_BGA1-IC,H91A    I15 @BASEBOARD_FAB2_LIB.BASEBOARD_FAB2(SCH_1):PAGE124
  U7C1 BM69 VSS<53> LBG_CORE_QAT_EXT_D_BGA1-IC,H91A    I15 @BASEBOARD_FAB2_LIB.BASEBOARD_FAB2(SCH_1):PAGE124
  U7C1 BM58 VSS<54> LBG_CORE_QAT_EXT_D_BGA1-IC,H91A    I15 @BASEBOARD_FAB2_LIB.BASEBOARD_FAB2(SCH_1):PAGE124
  U7C1 BM50 VSS<55> LBG_CORE_QAT_EXT_D_BGA1-IC,H91A    I15 @BASEBOARD_FAB2_LIB.BASEBOARD_FAB2(SCH_1):PAGE124
  U7C1 BM46 VSS<56> LBG_CORE_QAT_EXT_D_BGA1-IC,H91A    I15 @BASEBOARD_FAB2_LIB.BASEBOARD_FAB2(SCH_1):PAGE124
  U7C1 BN37 VSS<57> LBG_CORE_QAT_EXT_D_BGA1-IC,H91A    I15 @BASEBOARD_FAB2_LIB.BASEBOARD_FAB2(SCH_1):PAGE124
  U7C1 BM17 VSS<58> LBG_CORE_QAT_EXT_D_BGA1-IC,H91A    I15 @BASEBOARD_FAB2_LIB.BASEBOARD_FAB2(SCH_1):PAGE124
  U7C1 BM13 VSS<59> LBG_CORE_QAT_EXT_D_BGA1-IC,H91A    I15 @BASEBOARD_FAB2_LIB.BASEBOARD_FAB2(SCH_1):PAGE124
  U7C1 BL72 VSS<60> LBG_CORE_QAT_EXT_D_BGA1-IC,H91A    I15 @BASEBOARD_FAB2_LIB.BASEBOARD_FAB2(SCH_1):PAGE124
  U7C1 BL70 VSS<61> LBG_CORE_QAT_EXT_D_BGA1-IC,H91A    I15 @BASEBOARD_FAB2_LIB.BASEBOARD_FAB2(SCH_1):PAGE124
  U7C1 BL63 VSS<62> LBG_CORE_QAT_EXT_D_BGA1-IC,H91A    I15 @BASEBOARD_FAB2_LIB.BASEBOARD_FAB2(SCH_1):PAGE124
  U7C1  BL5 VSS<63> LBG_CORE_QAT_EXT_D_BGA1-IC,H91A    I15 @BASEBOARD_FAB2_LIB.BASEBOARD_FAB2(SCH_1):PAGE124
  U7C1 BL37 VSS<64> LBG_CORE_QAT_EXT_D_BGA1-IC,H91A    I15 @BASEBOARD_FAB2_LIB.BASEBOARD_FAB2(SCH_1):PAGE124
  U7C1 BL68 VSS<65> LBG_CORE_QAT_EXT_D_BGA1-IC,H91A    I15 @BASEBOARD_FAB2_LIB.BASEBOARD_FAB2(SCH_1):PAGE124
  U7C1 BL40 VSS<66> LBG_CORE_QAT_EXT_D_BGA1-IC,H91A    I15 @BASEBOARD_FAB2_LIB.BASEBOARD_FAB2(SCH_1):PAGE124
  U7C1 BL22 VSS<67> LBG_CORE_QAT_EXT_D_BGA1-IC,H91A    I15 @BASEBOARD_FAB2_LIB.BASEBOARD_FAB2(SCH_1):PAGE124
  U7C1 BK50 VSS<68> LBG_CORE_QAT_EXT_D_BGA1-IC,H91A    I15 @BASEBOARD_FAB2_LIB.BASEBOARD_FAB2(SCH_1):PAGE124
  U7C1 BK42 VSS<69> LBG_CORE_QAT_EXT_D_BGA1-IC,H91A    I15 @BASEBOARD_FAB2_LIB.BASEBOARD_FAB2(SCH_1):PAGE124
  U7C1 BK38 VSS<70> LBG_CORE_QAT_EXT_D_BGA1-IC,H91A    I15 @BASEBOARD_FAB2_LIB.BASEBOARD_FAB2(SCH_1):PAGE124
  U7C1 BK35 VSS<71> LBG_CORE_QAT_EXT_D_BGA1-IC,H91A    I15 @BASEBOARD_FAB2_LIB.BASEBOARD_FAB2(SCH_1):PAGE124
  U7C1 BK31 VSS<72> LBG_CORE_QAT_EXT_D_BGA1-IC,H91A    I15 @BASEBOARD_FAB2_LIB.BASEBOARD_FAB2(SCH_1):PAGE124
  U7C1 BK27 VSS<73> LBG_CORE_QAT_EXT_D_BGA1-IC,H91A    I15 @BASEBOARD_FAB2_LIB.BASEBOARD_FAB2(SCH_1):PAGE124
  U7C1 BK24 VSS<74> LBG_CORE_QAT_EXT_D_BGA1-IC,H91A    I15 @BASEBOARD_FAB2_LIB.BASEBOARD_FAB2(SCH_1):PAGE124
  U7C1 BJ68 VSS<75> LBG_CORE_QAT_EXT_D_BGA1-IC,H91A    I16 @BASEBOARD_FAB2_LIB.BASEBOARD_FAB2(SCH_1):PAGE124
  U7C1 BJ52 VSS<76> LBG_CORE_QAT_EXT_D_BGA1-IC,H91A    I16 @BASEBOARD_FAB2_LIB.BASEBOARD_FAB2(SCH_1):PAGE124
  U7C1 BJ33 VSS<77> LBG_CORE_QAT_EXT_D_BGA1-IC,H91A    I16 @BASEBOARD_FAB2_LIB.BASEBOARD_FAB2(SCH_1):PAGE124
  U7C1  BJ3 VSS<78> LBG_CORE_QAT_EXT_D_BGA1-IC,H91A    I16 @BASEBOARD_FAB2_LIB.BASEBOARD_FAB2(SCH_1):PAGE124
  U7C1 BJ26 VSS<79> LBG_CORE_QAT_EXT_D_BGA1-IC,H91A    I16 @BASEBOARD_FAB2_LIB.BASEBOARD_FAB2(SCH_1):PAGE124
  U7C1 BJ18 VSS<80> LBG_CORE_QAT_EXT_D_BGA1-IC,H91A    I16 @BASEBOARD_FAB2_LIB.BASEBOARD_FAB2(SCH_1):PAGE124
  U7C1 BJ15 VSS<81> LBG_CORE_QAT_EXT_D_BGA1-IC,H91A    I16 @BASEBOARD_FAB2_LIB.BASEBOARD_FAB2(SCH_1):PAGE124
  U7C1  BJ7 VSS<82> LBG_CORE_QAT_EXT_D_BGA1-IC,H91A    I16 @BASEBOARD_FAB2_LIB.BASEBOARD_FAB2(SCH_1):PAGE124
  U7C1  BJ5 VSS<83> LBG_CORE_QAT_EXT_D_BGA1-IC,H91A    I16 @BASEBOARD_FAB2_LIB.BASEBOARD_FAB2(SCH_1):PAGE124
  U7C1 BJ11 VSS<84> LBG_CORE_QAT_EXT_D_BGA1-IC,H91A    I16 @BASEBOARD_FAB2_LIB.BASEBOARD_FAB2(SCH_1):PAGE124
  U7C1  BJ1 VSS<85> LBG_CORE_QAT_EXT_D_BGA1-IC,H91A    I16 @BASEBOARD_FAB2_LIB.BASEBOARD_FAB2(SCH_1):PAGE124
  U7C1 BH54 VSS<86> LBG_CORE_QAT_EXT_D_BGA1-IC,H91A    I16 @BASEBOARD_FAB2_LIB.BASEBOARD_FAB2(SCH_1):PAGE124
  U7C1 BH46 VSS<87> LBG_CORE_QAT_EXT_D_BGA1-IC,H91A    I16 @BASEBOARD_FAB2_LIB.BASEBOARD_FAB2(SCH_1):PAGE124
  U7C1 BH42 VSS<88> LBG_CORE_QAT_EXT_D_BGA1-IC,H91A    I16 @BASEBOARD_FAB2_LIB.BASEBOARD_FAB2(SCH_1):PAGE124
  U7C1 BH38 VSS<89> LBG_CORE_QAT_EXT_D_BGA1-IC,H91A    I16 @BASEBOARD_FAB2_LIB.BASEBOARD_FAB2(SCH_1):PAGE124
  U7C1 BH27 VSS<90> LBG_CORE_QAT_EXT_D_BGA1-IC,H91A    I16 @BASEBOARD_FAB2_LIB.BASEBOARD_FAB2(SCH_1):PAGE124
  U7C1 BG63 VSS<91> LBG_CORE_QAT_EXT_D_BGA1-IC,H91A    I16 @BASEBOARD_FAB2_LIB.BASEBOARD_FAB2(SCH_1):PAGE124
  U7C1 BG59 VSS<92> LBG_CORE_QAT_EXT_D_BGA1-IC,H91A    I16 @BASEBOARD_FAB2_LIB.BASEBOARD_FAB2(SCH_1):PAGE124
  U7C1 BG48 VSS<93> LBG_CORE_QAT_EXT_D_BGA1-IC,H91A    I16 @BASEBOARD_FAB2_LIB.BASEBOARD_FAB2(SCH_1):PAGE124
  U7C1 BG33 VSS<94> LBG_CORE_QAT_EXT_D_BGA1-IC,H91A    I16 @BASEBOARD_FAB2_LIB.BASEBOARD_FAB2(SCH_1):PAGE124
  U7C1  BF9 VSS<95> LBG_CORE_QAT_EXT_D_BGA1-IC,H91A    I16 @BASEBOARD_FAB2_LIB.BASEBOARD_FAB2(SCH_1):PAGE124
  U7C1 BF68 VSS<96> LBG_CORE_QAT_EXT_D_BGA1-IC,H91A    I16 @BASEBOARD_FAB2_LIB.BASEBOARD_FAB2(SCH_1):PAGE124
  U7C1 BF65 VSS<97> LBG_CORE_QAT_EXT_D_BGA1-IC,H91A    I16 @BASEBOARD_FAB2_LIB.BASEBOARD_FAB2(SCH_1):PAGE124
  U7C1 BF61 VSS<98> LBG_CORE_QAT_EXT_D_BGA1-IC,H91A    I16 @BASEBOARD_FAB2_LIB.BASEBOARD_FAB2(SCH_1):PAGE124
  U7C1 BF58 VSS<99> LBG_CORE_QAT_EXT_D_BGA1-IC,H91A    I16 @BASEBOARD_FAB2_LIB.BASEBOARD_FAB2(SCH_1):PAGE124
  U7C1 BF50 VSS<100> LBG_CORE_QAT_EXT_D_BGA1-IC,H91A    I16 @BASEBOARD_FAB2_LIB.BASEBOARD_FAB2(SCH_1):PAGE124
  U7C1  BF5 VSS<101> LBG_CORE_QAT_EXT_D_BGA1-IC,H91A    I16 @BASEBOARD_FAB2_LIB.BASEBOARD_FAB2(SCH_1):PAGE124
  U7C1 BF42 VSS<102> LBG_CORE_QAT_EXT_D_BGA1-IC,H91A    I16 @BASEBOARD_FAB2_LIB.BASEBOARD_FAB2(SCH_1):PAGE124
  U7C1 BF38 VSS<103> LBG_CORE_QAT_EXT_D_BGA1-IC,H91A    I16 @BASEBOARD_FAB2_LIB.BASEBOARD_FAB2(SCH_1):PAGE124
  U7C1 BF27 VSS<104> LBG_CORE_QAT_EXT_D_BGA1-IC,H91A    I16 @BASEBOARD_FAB2_LIB.BASEBOARD_FAB2(SCH_1):PAGE124
  U7C1 BF24 VSS<105> LBG_CORE_QAT_EXT_D_BGA1-IC,H91A    I16 @BASEBOARD_FAB2_LIB.BASEBOARD_FAB2(SCH_1):PAGE124
  U7C1 BF20 VSS<106> LBG_CORE_QAT_EXT_D_BGA1-IC,H91A    I16 @BASEBOARD_FAB2_LIB.BASEBOARD_FAB2(SCH_1):PAGE124
  U7C1 BG44 VSS<107> LBG_CORE_QAT_EXT_D_BGA1-IC,H91A    I16 @BASEBOARD_FAB2_LIB.BASEBOARD_FAB2(SCH_1):PAGE124
  U7C1 BF54 VSS<108> LBG_CORE_QAT_EXT_D_BGA1-IC,H91A    I16 @BASEBOARD_FAB2_LIB.BASEBOARD_FAB2(SCH_1):PAGE124
  U7C1 BF17 VSS<109> LBG_CORE_QAT_EXT_D_BGA1-IC,H91A    I16 @BASEBOARD_FAB2_LIB.BASEBOARD_FAB2(SCH_1):PAGE124
  U7C1 BF13 VSS<110> LBG_CORE_QAT_EXT_D_BGA1-IC,H91A    I16 @BASEBOARD_FAB2_LIB.BASEBOARD_FAB2(SCH_1):PAGE124
  U7C1 BE66 VSS<111> LBG_CORE_QAT_EXT_D_BGA1-IC,H91A    I16 @BASEBOARD_FAB2_LIB.BASEBOARD_FAB2(SCH_1):PAGE124
  U7C1 BE63 VSS<112> LBG_CORE_QAT_EXT_D_BGA1-IC,H91A    I16 @BASEBOARD_FAB2_LIB.BASEBOARD_FAB2(SCH_1):PAGE124
  U7C1 BE59 VSS<113> LBG_CORE_QAT_EXT_D_BGA1-IC,H91A    I16 @BASEBOARD_FAB2_LIB.BASEBOARD_FAB2(SCH_1):PAGE124
  U7C1 BE56 VSS<114> LBG_CORE_QAT_EXT_D_BGA1-IC,H91A    I16 @BASEBOARD_FAB2_LIB.BASEBOARD_FAB2(SCH_1):PAGE124
  U7C1 BE37 VSS<115> LBG_CORE_QAT_EXT_D_BGA1-IC,H91A    I16 @BASEBOARD_FAB2_LIB.BASEBOARD_FAB2(SCH_1):PAGE124
  U7C1 BE33 VSS<116> LBG_CORE_QAT_EXT_D_BGA1-IC,H91A    I16 @BASEBOARD_FAB2_LIB.BASEBOARD_FAB2(SCH_1):PAGE124
  U7C1 BE29 VSS<117> LBG_CORE_QAT_EXT_D_BGA1-IC,H91A    I16 @BASEBOARD_FAB2_LIB.BASEBOARD_FAB2(SCH_1):PAGE124
  U7C1 BD68 VSS<118> LBG_CORE_QAT_EXT_D_BGA1-IC,H91A    I16 @BASEBOARD_FAB2_LIB.BASEBOARD_FAB2(SCH_1):PAGE124
  U7C1 BD54 VSS<119> LBG_CORE_QAT_EXT_D_BGA1-IC,H91A    I16 @BASEBOARD_FAB2_LIB.BASEBOARD_FAB2(SCH_1):PAGE124
  U7C1 BD50 VSS<120> LBG_CORE_QAT_EXT_D_BGA1-IC,H91A    I16 @BASEBOARD_FAB2_LIB.BASEBOARD_FAB2(SCH_1):PAGE124
  U7C1  BD5 VSS<121> LBG_CORE_QAT_EXT_D_BGA1-IC,H91A    I16 @BASEBOARD_FAB2_LIB.BASEBOARD_FAB2(SCH_1):PAGE124
  U7C1 BD35 VSS<122> LBG_CORE_QAT_EXT_D_BGA1-IC,H91A    I16 @BASEBOARD_FAB2_LIB.BASEBOARD_FAB2(SCH_1):PAGE124
  U7C1 BD31 VSS<123> LBG_CORE_QAT_EXT_D_BGA1-IC,H91A    I16 @BASEBOARD_FAB2_LIB.BASEBOARD_FAB2(SCH_1):PAGE124
  U7C1 BD27 VSS<124> LBG_CORE_QAT_EXT_D_BGA1-IC,H91A    I16 @BASEBOARD_FAB2_LIB.BASEBOARD_FAB2(SCH_1):PAGE124
  U7C1 BD24 VSS<125> LBG_CORE_QAT_EXT_D_BGA1-IC,H91A    I16 @BASEBOARD_FAB2_LIB.BASEBOARD_FAB2(SCH_1):PAGE124
  U7C1 BC71 VSS<126> LBG_CORE_QAT_EXT_D_BGA1-IC,H91A    I16 @BASEBOARD_FAB2_LIB.BASEBOARD_FAB2(SCH_1):PAGE124
  U7C1 BC69 VSS<127> LBG_CORE_QAT_EXT_D_BGA1-IC,H91A    I16 @BASEBOARD_FAB2_LIB.BASEBOARD_FAB2(SCH_1):PAGE124
  U7C1 BB72 VSS<128> LBG_CORE_QAT_EXT_D_BGA1-IC,H91A    I16 @BASEBOARD_FAB2_LIB.BASEBOARD_FAB2(SCH_1):PAGE124
  U7C1 BB70 VSS<129> LBG_CORE_QAT_EXT_D_BGA1-IC,H91A    I16 @BASEBOARD_FAB2_LIB.BASEBOARD_FAB2(SCH_1):PAGE124
  U7C1 BB68 VSS<130> LBG_CORE_QAT_EXT_D_BGA1-IC,H91A    I16 @BASEBOARD_FAB2_LIB.BASEBOARD_FAB2(SCH_1):PAGE124
  U7C1 BB66 VSS<131> LBG_CORE_QAT_EXT_D_BGA1-IC,H91A    I16 @BASEBOARD_FAB2_LIB.BASEBOARD_FAB2(SCH_1):PAGE124
  U7C1 BB59 VSS<132> LBG_CORE_QAT_EXT_D_BGA1-IC,H91A    I16 @BASEBOARD_FAB2_LIB.BASEBOARD_FAB2(SCH_1):PAGE124
  U7C1 BB44 VSS<133> LBG_CORE_QAT_EXT_D_BGA1-IC,H91A    I16 @BASEBOARD_FAB2_LIB.BASEBOARD_FAB2(SCH_1):PAGE124
  U7C1 BB22 VSS<134> LBG_CORE_QAT_EXT_D_BGA1-IC,H91A    I16 @BASEBOARD_FAB2_LIB.BASEBOARD_FAB2(SCH_1):PAGE124
  U7C1 BB18 VSS<135> LBG_CORE_QAT_EXT_D_BGA1-IC,H91A    I16 @BASEBOARD_FAB2_LIB.BASEBOARD_FAB2(SCH_1):PAGE124
  U7C1 BB15 VSS<136> LBG_CORE_QAT_EXT_D_BGA1-IC,H91A    I16 @BASEBOARD_FAB2_LIB.BASEBOARD_FAB2(SCH_1):PAGE124
  U7C1 BB11 VSS<137> LBG_CORE_QAT_EXT_D_BGA1-IC,H91A    I16 @BASEBOARD_FAB2_LIB.BASEBOARD_FAB2(SCH_1):PAGE124
  U7C1  BB7 VSS<138> LBG_CORE_QAT_EXT_D_BGA1-IC,H91A    I16 @BASEBOARD_FAB2_LIB.BASEBOARD_FAB2(SCH_1):PAGE124
  U7C1  BB5 VSS<139> LBG_CORE_QAT_EXT_D_BGA1-IC,H91A    I16 @BASEBOARD_FAB2_LIB.BASEBOARD_FAB2(SCH_1):PAGE124
  U7C1 BA58 VSS<140> LBG_CORE_QAT_EXT_D_BGA1-IC,H91A    I16 @BASEBOARD_FAB2_LIB.BASEBOARD_FAB2(SCH_1):PAGE124
  U7C1 BA54 VSS<141> LBG_CORE_QAT_EXT_D_BGA1-IC,H91A    I16 @BASEBOARD_FAB2_LIB.BASEBOARD_FAB2(SCH_1):PAGE124
  U7C1 BA50 VSS<142> LBG_CORE_QAT_EXT_D_BGA1-IC,H91A    I16 @BASEBOARD_FAB2_LIB.BASEBOARD_FAB2(SCH_1):PAGE124
  U7C1 AY68 VSS<143> LBG_CORE_QAT_EXT_D_BGA1-IC,H91A    I16 @BASEBOARD_FAB2_LIB.BASEBOARD_FAB2(SCH_1):PAGE124
  U7C1 AY63 VSS<144> LBG_CORE_QAT_EXT_D_BGA1-IC,H91A    I16 @BASEBOARD_FAB2_LIB.BASEBOARD_FAB2(SCH_1):PAGE124
  U7C1 AY56 VSS<145> LBG_CORE_QAT_EXT_D_BGA1-IC,H91A    I16 @BASEBOARD_FAB2_LIB.BASEBOARD_FAB2(SCH_1):PAGE124
  U7C1 AY22 VSS<146> LBG_CORE_QAT_EXT_D_BGA1-IC,H91A    I16 @BASEBOARD_FAB2_LIB.BASEBOARD_FAB2(SCH_1):PAGE124
  U7C1  AY5 VSS<147> LBG_CORE_QAT_EXT_D_BGA1-IC,H91A    I16 @BASEBOARD_FAB2_LIB.BASEBOARD_FAB2(SCH_1):PAGE124
  U7C1 AW61 VSS<148> LBG_CORE_QAT_EXT_D_BGA1-IC,H91A    I16 @BASEBOARD_FAB2_LIB.BASEBOARD_FAB2(SCH_1):PAGE124
  U7C1 AW58 VSS<149> LBG_CORE_QAT_EXT_D_BGA1-IC,H91A    I16 @BASEBOARD_FAB2_LIB.BASEBOARD_FAB2(SCH_1):PAGE124
  U7C1 AW50 VSS<150> LBG_CORE_QAT_EXT_D_BGA1-IC,H91A    I16 @BASEBOARD_FAB2_LIB.BASEBOARD_FAB2(SCH_1):PAGE124
  U7C1 AW46 VSS<151> LBG_CORE_QAT_EXT_D_BGA1-IC,H91A    I16 @BASEBOARD_FAB2_LIB.BASEBOARD_FAB2(SCH_1):PAGE124
  U7C1 AW41 VSS<152> LBG_CORE_QAT_EXT_D_BGA1-IC,H91A    I16 @BASEBOARD_FAB2_LIB.BASEBOARD_FAB2(SCH_1):PAGE124
  U7C1 AW39 VSS<153> LBG_CORE_QAT_EXT_D_BGA1-IC,H91A    I16 @BASEBOARD_FAB2_LIB.BASEBOARD_FAB2(SCH_1):PAGE124
  U7C1 AW37 VSS<154> LBG_CORE_QAT_EXT_D_BGA1-IC,H91A    I16 @BASEBOARD_FAB2_LIB.BASEBOARD_FAB2(SCH_1):PAGE124
  U7C1 AW36 VSS<155> LBG_CORE_QAT_EXT_D_BGA1-IC,H91A    I16 @BASEBOARD_FAB2_LIB.BASEBOARD_FAB2(SCH_1):PAGE124
  U7C1 AW34 VSS<156> LBG_CORE_QAT_EXT_D_BGA1-IC,H91A    I16 @BASEBOARD_FAB2_LIB.BASEBOARD_FAB2(SCH_1):PAGE124
  U7C1 AW32 VSS<157> LBG_CORE_QAT_EXT_D_BGA1-IC,H91A    I16 @BASEBOARD_FAB2_LIB.BASEBOARD_FAB2(SCH_1):PAGE124
  U7C1 AW30 VSS<158> LBG_CORE_QAT_EXT_D_BGA1-IC,H91A    I16 @BASEBOARD_FAB2_LIB.BASEBOARD_FAB2(SCH_1):PAGE124
  U7C1 AW26 VSS<159> LBG_CORE_QAT_EXT_D_BGA1-IC,H91A    I16 @BASEBOARD_FAB2_LIB.BASEBOARD_FAB2(SCH_1):PAGE124
  U7C1 AW17 VSS<160> LBG_CORE_QAT_EXT_D_BGA1-IC,H91A    I16 @BASEBOARD_FAB2_LIB.BASEBOARD_FAB2(SCH_1):PAGE124
  U7C1 AW13 VSS<161> LBG_CORE_QAT_EXT_D_BGA1-IC,H91A    I16 @BASEBOARD_FAB2_LIB.BASEBOARD_FAB2(SCH_1):PAGE124
  U7C1  AW9 VSS<162> LBG_CORE_QAT_EXT_D_BGA1-IC,H91A    I16 @BASEBOARD_FAB2_LIB.BASEBOARD_FAB2(SCH_1):PAGE124
  U7C1 AV68 VSS<163> LBG_CORE_QAT_EXT_D_BGA1-IC,H91A    I16 @BASEBOARD_FAB2_LIB.BASEBOARD_FAB2(SCH_1):PAGE124
  U7C1 AV59 VSS<164> LBG_CORE_QAT_EXT_D_BGA1-IC,H91A    I16 @BASEBOARD_FAB2_LIB.BASEBOARD_FAB2(SCH_1):PAGE124
  U7C1 AV22 VSS<165> LBG_CORE_QAT_EXT_D_BGA1-IC,H91A    I16 @BASEBOARD_FAB2_LIB.BASEBOARD_FAB2(SCH_1):PAGE124
  U7C1  AV5 VSS<166> LBG_CORE_QAT_EXT_D_BGA1-IC,H91A    I16 @BASEBOARD_FAB2_LIB.BASEBOARD_FAB2(SCH_1):PAGE124
  U7C1 AU61 VSS<167> LBG_CORE_QAT_EXT_D_BGA1-IC,H91A    I16 @BASEBOARD_FAB2_LIB.BASEBOARD_FAB2(SCH_1):PAGE124
  U7C1 AU54 VSS<168> LBG_CORE_QAT_EXT_D_BGA1-IC,H91A    I16 @BASEBOARD_FAB2_LIB.BASEBOARD_FAB2(SCH_1):PAGE124
  U7C1 AU50 VSS<169> LBG_CORE_QAT_EXT_D_BGA1-IC,H91A    I16 @BASEBOARD_FAB2_LIB.BASEBOARD_FAB2(SCH_1):PAGE124
  U7C1 AU46 VSS<170> LBG_CORE_QAT_EXT_D_BGA1-IC,H91A    I16 @BASEBOARD_FAB2_LIB.BASEBOARD_FAB2(SCH_1):PAGE124
  U7C1 AU41 VSS<171> LBG_CORE_QAT_EXT_D_BGA1-IC,H91A    I16 @BASEBOARD_FAB2_LIB.BASEBOARD_FAB2(SCH_1):PAGE124
  U7C1 AE22 VSS<172> LBG_CORE_QAT_EXT_D_BGA1-IC,H91A    I16 @BASEBOARD_FAB2_LIB.BASEBOARD_FAB2(SCH_1):PAGE124
  U7C1 AU30 VSS<173> LBG_CORE_QAT_EXT_D_BGA1-IC,H91A    I16 @BASEBOARD_FAB2_LIB.BASEBOARD_FAB2(SCH_1):PAGE124
  U7C1 AU26 VSS<174> LBG_CORE_QAT_EXT_D_BGA1-IC,H91A    I16 @BASEBOARD_FAB2_LIB.BASEBOARD_FAB2(SCH_1):PAGE124
  U7C1 AT59 VSS<175> LBG_CORE_QAT_EXT_D_BGA1-IC,H91A    I16 @BASEBOARD_FAB2_LIB.BASEBOARD_FAB2(SCH_1):PAGE124
  U7C1 AT46 VSS<176> LBG_CORE_QAT_EXT_D_BGA1-IC,H91A    I16 @BASEBOARD_FAB2_LIB.BASEBOARD_FAB2(SCH_1):PAGE124
  U7C1 AT41 VSS<177> LBG_CORE_QAT_EXT_D_BGA1-IC,H91A    I16 @BASEBOARD_FAB2_LIB.BASEBOARD_FAB2(SCH_1):PAGE124
  U7C1 AT30 VSS<178> LBG_CORE_QAT_EXT_D_BGA1-IC,H91A    I16 @BASEBOARD_FAB2_LIB.BASEBOARD_FAB2(SCH_1):PAGE124
  U7C1 AT26 VSS<179> LBG_CORE_QAT_EXT_D_BGA1-IC,H91A    I16 @BASEBOARD_FAB2_LIB.BASEBOARD_FAB2(SCH_1):PAGE124
  U7C1 AT22 VSS<180> LBG_CORE_QAT_EXT_D_BGA1-IC,H91A    I16 @BASEBOARD_FAB2_LIB.BASEBOARD_FAB2(SCH_1):PAGE124
  U7C1 AT18 VSS<181> LBG_CORE_QAT_EXT_D_BGA1-IC,H91A    I16 @BASEBOARD_FAB2_LIB.BASEBOARD_FAB2(SCH_1):PAGE124
  U7C1 AT15 VSS<182> LBG_CORE_QAT_EXT_D_BGA1-IC,H91A    I16 @BASEBOARD_FAB2_LIB.BASEBOARD_FAB2(SCH_1):PAGE124
  U7C1 AT11 VSS<183> LBG_CORE_QAT_EXT_D_BGA1-IC,H91A    I16 @BASEBOARD_FAB2_LIB.BASEBOARD_FAB2(SCH_1):PAGE124
  U7C1  AT7 VSS<184> LBG_CORE_QAT_EXT_D_BGA1-IC,H91A    I16 @BASEBOARD_FAB2_LIB.BASEBOARD_FAB2(SCH_1):PAGE124
  U7C1 AR72 VSS<185> LBG_CORE_QAT_EXT_D_BGA1-IC,H91A    I16 @BASEBOARD_FAB2_LIB.BASEBOARD_FAB2(SCH_1):PAGE124
  U7C1 AR70 VSS<186> LBG_CORE_QAT_EXT_D_BGA1-IC,H91A    I16 @BASEBOARD_FAB2_LIB.BASEBOARD_FAB2(SCH_1):PAGE124
  U7C1 AR68 VSS<187> LBG_CORE_QAT_EXT_D_BGA1-IC,H91A    I16 @BASEBOARD_FAB2_LIB.BASEBOARD_FAB2(SCH_1):PAGE124
  U7C1 AR65 VSS<188> LBG_CORE_QAT_EXT_D_BGA1-IC,H91A    I16 @BASEBOARD_FAB2_LIB.BASEBOARD_FAB2(SCH_1):PAGE124
  U7C1 AR58 VSS<189> LBG_CORE_QAT_EXT_D_BGA1-IC,H91A    I16 @BASEBOARD_FAB2_LIB.BASEBOARD_FAB2(SCH_1):PAGE124
  U7C1 AR50 VSS<190> LBG_CORE_QAT_EXT_D_BGA1-IC,H91A    I16 @BASEBOARD_FAB2_LIB.BASEBOARD_FAB2(SCH_1):PAGE124
  U7C1  AR5 VSS<191> LBG_CORE_QAT_EXT_D_BGA1-IC,H91A    I16 @BASEBOARD_FAB2_LIB.BASEBOARD_FAB2(SCH_1):PAGE124
  U7C1 AP66 VSS<192> LBG_CORE_QAT_EXT_D_BGA1-IC,H91A    I16 @BASEBOARD_FAB2_LIB.BASEBOARD_FAB2(SCH_1):PAGE124
  U7C1 AP52 VSS<193> LBG_CORE_QAT_EXT_D_BGA1-IC,H91A    I16 @BASEBOARD_FAB2_LIB.BASEBOARD_FAB2(SCH_1):PAGE124
  U7C1 AP46 VSS<194> LBG_CORE_QAT_EXT_D_BGA1-IC,H91A    I16 @BASEBOARD_FAB2_LIB.BASEBOARD_FAB2(SCH_1):PAGE124
  U7C1 AP41 VSS<195> LBG_CORE_QAT_EXT_D_BGA1-IC,H91A    I16 @BASEBOARD_FAB2_LIB.BASEBOARD_FAB2(SCH_1):PAGE124
  U7C1  AP4 VSS<196> LBG_CORE_QAT_EXT_D_BGA1-IC,H91A    I16 @BASEBOARD_FAB2_LIB.BASEBOARD_FAB2(SCH_1):PAGE124
  U7C1 AP30 VSS<197> LBG_CORE_QAT_EXT_D_BGA1-IC,H91A    I16 @BASEBOARD_FAB2_LIB.BASEBOARD_FAB2(SCH_1):PAGE124
  U7C1 AP26 VSS<198> LBG_CORE_QAT_EXT_D_BGA1-IC,H91A    I16 @BASEBOARD_FAB2_LIB.BASEBOARD_FAB2(SCH_1):PAGE124
  U7C1  AP2 VSS<199> LBG_CORE_QAT_EXT_D_BGA1-IC,H91A    I16 @BASEBOARD_FAB2_LIB.BASEBOARD_FAB2(SCH_1):PAGE124
  U7C1  AN9 VSS<200> LBG_CORE_QAT_EXT_D_BGA1-IC,H91A    I16 @BASEBOARD_FAB2_LIB.BASEBOARD_FAB2(SCH_1):PAGE124
  U7C1 AN58 VSS<201> LBG_CORE_QAT_EXT_D_BGA1-IC,H91A    I16 @BASEBOARD_FAB2_LIB.BASEBOARD_FAB2(SCH_1):PAGE124
  U7C1  AN5 VSS<202> LBG_CORE_QAT_EXT_D_BGA1-IC,H91A    I16 @BASEBOARD_FAB2_LIB.BASEBOARD_FAB2(SCH_1):PAGE124
  U7C1 AN20 VSS<203> LBG_CORE_QAT_EXT_D_BGA1-IC,H91A    I16 @BASEBOARD_FAB2_LIB.BASEBOARD_FAB2(SCH_1):PAGE124
  U7C1 AP22 VSS<204> LBG_CORE_QAT_EXT_D_BGA1-IC,H91A    I16 @BASEBOARD_FAB2_LIB.BASEBOARD_FAB2(SCH_1):PAGE124
  U7C1 AN68 VSS<205> LBG_CORE_QAT_EXT_D_BGA1-IC,H91A    I16 @BASEBOARD_FAB2_LIB.BASEBOARD_FAB2(SCH_1):PAGE124
  U7C1 AN17 VSS<206> LBG_CORE_QAT_EXT_D_BGA1-IC,H91A    I16 @BASEBOARD_FAB2_LIB.BASEBOARD_FAB2(SCH_1):PAGE124
  U7C1 AN13 VSS<207> LBG_CORE_QAT_EXT_D_BGA1-IC,H91A    I16 @BASEBOARD_FAB2_LIB.BASEBOARD_FAB2(SCH_1):PAGE124
  U7C1 AM46 VSS<208> LBG_CORE_QAT_EXT_D_BGA1-IC,H91A    I16 @BASEBOARD_FAB2_LIB.BASEBOARD_FAB2(SCH_1):PAGE124
  U7C1 AM41 VSS<209> LBG_CORE_QAT_EXT_D_BGA1-IC,H91A    I16 @BASEBOARD_FAB2_LIB.BASEBOARD_FAB2(SCH_1):PAGE124
  U7C1 AM30 VSS<210> LBG_CORE_QAT_EXT_D_BGA1-IC,H91A    I16 @BASEBOARD_FAB2_LIB.BASEBOARD_FAB2(SCH_1):PAGE124
  U7C1 AM26 VSS<211> LBG_CORE_QAT_EXT_D_BGA1-IC,H91A    I16 @BASEBOARD_FAB2_LIB.BASEBOARD_FAB2(SCH_1):PAGE124
  U7C1 AL72 VSS<212> LBG_CORE_QAT_EXT_D_BGA1-IC,H91A    I16 @BASEBOARD_FAB2_LIB.BASEBOARD_FAB2(SCH_1):PAGE124
  U7C1 AL70 VSS<213> LBG_CORE_QAT_EXT_D_BGA1-IC,H91A    I16 @BASEBOARD_FAB2_LIB.BASEBOARD_FAB2(SCH_1):PAGE124
  U7C1 AL68 VSS<214> LBG_CORE_QAT_EXT_D_BGA1-IC,H91A    I16 @BASEBOARD_FAB2_LIB.BASEBOARD_FAB2(SCH_1):PAGE124
  U7C1 AL59 VSS<215> LBG_CORE_QAT_EXT_D_BGA1-IC,H91A    I17 @BASEBOARD_FAB2_LIB.BASEBOARD_FAB2(SCH_1):PAGE124
  U7C1 AL52 VSS<216> LBG_CORE_QAT_EXT_D_BGA1-IC,H91A    I17 @BASEBOARD_FAB2_LIB.BASEBOARD_FAB2(SCH_1):PAGE124
  U7C1  AL5 VSS<217> LBG_CORE_QAT_EXT_D_BGA1-IC,H91A    I17 @BASEBOARD_FAB2_LIB.BASEBOARD_FAB2(SCH_1):PAGE124
  U7C1 AL22 VSS<218> LBG_CORE_QAT_EXT_D_BGA1-IC,H91A    I17 @BASEBOARD_FAB2_LIB.BASEBOARD_FAB2(SCH_1):PAGE124
  U7C1 AK71 VSS<219> LBG_CORE_QAT_EXT_D_BGA1-IC,H91A    I17 @BASEBOARD_FAB2_LIB.BASEBOARD_FAB2(SCH_1):PAGE124
  U7C1 AK69 VSS<220> LBG_CORE_QAT_EXT_D_BGA1-IC,H91A    I17 @BASEBOARD_FAB2_LIB.BASEBOARD_FAB2(SCH_1):PAGE124
  U7C1 AK61 VSS<221> LBG_CORE_QAT_EXT_D_BGA1-IC,H91A    I17 @BASEBOARD_FAB2_LIB.BASEBOARD_FAB2(SCH_1):PAGE124
  U7C1 AK58 VSS<222> LBG_CORE_QAT_EXT_D_BGA1-IC,H91A    I17 @BASEBOARD_FAB2_LIB.BASEBOARD_FAB2(SCH_1):PAGE124
  U7C1 AK48 VSS<223> LBG_CORE_QAT_EXT_D_BGA1-IC,H91A    I17 @BASEBOARD_FAB2_LIB.BASEBOARD_FAB2(SCH_1):PAGE124
  U7C1 AK46 VSS<224> LBG_CORE_QAT_EXT_D_BGA1-IC,H91A    I17 @BASEBOARD_FAB2_LIB.BASEBOARD_FAB2(SCH_1):PAGE124
  U7C1 AK41 VSS<225> LBG_CORE_QAT_EXT_D_BGA1-IC,H91A    I17 @BASEBOARD_FAB2_LIB.BASEBOARD_FAB2(SCH_1):PAGE124
  U7C1 AK26 VSS<226> LBG_CORE_QAT_EXT_D_BGA1-IC,H91A    I17 @BASEBOARD_FAB2_LIB.BASEBOARD_FAB2(SCH_1):PAGE124
  U7C1  AJ7 VSS<227> LBG_CORE_QAT_EXT_D_BGA1-IC,H91A    I17 @BASEBOARD_FAB2_LIB.BASEBOARD_FAB2(SCH_1):PAGE124
  U7C1 AJ68 VSS<228> LBG_CORE_QAT_EXT_D_BGA1-IC,H91A    I17 @BASEBOARD_FAB2_LIB.BASEBOARD_FAB2(SCH_1):PAGE124
  U7C1 AJ66 VSS<229> LBG_CORE_QAT_EXT_D_BGA1-IC,H91A    I17 @BASEBOARD_FAB2_LIB.BASEBOARD_FAB2(SCH_1):PAGE124
  U7C1 AJ59 VSS<230> LBG_CORE_QAT_EXT_D_BGA1-IC,H91A    I17 @BASEBOARD_FAB2_LIB.BASEBOARD_FAB2(SCH_1):PAGE124
  U7C1 AJ52 VSS<231> LBG_CORE_QAT_EXT_D_BGA1-IC,H91A    I17 @BASEBOARD_FAB2_LIB.BASEBOARD_FAB2(SCH_1):PAGE124
  U7C1  AJ5 VSS<232> LBG_CORE_QAT_EXT_D_BGA1-IC,H91A    I17 @BASEBOARD_FAB2_LIB.BASEBOARD_FAB2(SCH_1):PAGE124
  U7C1 AJ41 VSS<233> LBG_CORE_QAT_EXT_D_BGA1-IC,H91A    I17 @BASEBOARD_FAB2_LIB.BASEBOARD_FAB2(SCH_1):PAGE124
  U7C1 AJ39 VSS<234> LBG_CORE_QAT_EXT_D_BGA1-IC,H91A    I17 @BASEBOARD_FAB2_LIB.BASEBOARD_FAB2(SCH_1):PAGE124
  U7C1 AJ37 VSS<235> LBG_CORE_QAT_EXT_D_BGA1-IC,H91A    I17 @BASEBOARD_FAB2_LIB.BASEBOARD_FAB2(SCH_1):PAGE124
  U7C1 AJ36 VSS<236> LBG_CORE_QAT_EXT_D_BGA1-IC,H91A    I17 @BASEBOARD_FAB2_LIB.BASEBOARD_FAB2(SCH_1):PAGE124
  U7C1 AJ34 VSS<237> LBG_CORE_QAT_EXT_D_BGA1-IC,H91A    I17 @BASEBOARD_FAB2_LIB.BASEBOARD_FAB2(SCH_1):PAGE124
  U7C1 AJ30 VSS<238> LBG_CORE_QAT_EXT_D_BGA1-IC,H91A    I17 @BASEBOARD_FAB2_LIB.BASEBOARD_FAB2(SCH_1):PAGE124
  U7C1 AJ26 VSS<239> LBG_CORE_QAT_EXT_D_BGA1-IC,H91A    I17 @BASEBOARD_FAB2_LIB.BASEBOARD_FAB2(SCH_1):PAGE124
  U7C1 AJ22 VSS<240> LBG_CORE_QAT_EXT_D_BGA1-IC,H91A    I17 @BASEBOARD_FAB2_LIB.BASEBOARD_FAB2(SCH_1):PAGE124
  U7C1 AJ18 VSS<241> LBG_CORE_QAT_EXT_D_BGA1-IC,H91A    I17 @BASEBOARD_FAB2_LIB.BASEBOARD_FAB2(SCH_1):PAGE124
  U7C1 AJ15 VSS<242> LBG_CORE_QAT_EXT_D_BGA1-IC,H91A    I17 @BASEBOARD_FAB2_LIB.BASEBOARD_FAB2(SCH_1):PAGE124
  U7C1 AK30 VSS<243> LBG_CORE_QAT_EXT_D_BGA1-IC,H91A    I17 @BASEBOARD_FAB2_LIB.BASEBOARD_FAB2(SCH_1):PAGE124
  U7C1 AJ56 VSS<244> LBG_CORE_QAT_EXT_D_BGA1-IC,H91A    I17 @BASEBOARD_FAB2_LIB.BASEBOARD_FAB2(SCH_1):PAGE124
  U7C1 AJ32 VSS<245> LBG_CORE_QAT_EXT_D_BGA1-IC,H91A    I17 @BASEBOARD_FAB2_LIB.BASEBOARD_FAB2(SCH_1):PAGE124
  U7C1 AJ11 VSS<246> LBG_CORE_QAT_EXT_D_BGA1-IC,H91A    I17 @BASEBOARD_FAB2_LIB.BASEBOARD_FAB2(SCH_1):PAGE124
  U7C1 AH20 VSS<247> LBG_CORE_QAT_EXT_D_BGA1-IC,H91A    I17 @BASEBOARD_FAB2_LIB.BASEBOARD_FAB2(SCH_1):PAGE124
  U7C1 AG66 VSS<248> LBG_CORE_QAT_EXT_D_BGA1-IC,H91A    I17 @BASEBOARD_FAB2_LIB.BASEBOARD_FAB2(SCH_1):PAGE124
  U7C1 AG59 VSS<249> LBG_CORE_QAT_EXT_D_BGA1-IC,H91A    I17 @BASEBOARD_FAB2_LIB.BASEBOARD_FAB2(SCH_1):PAGE124
  U7C1 AG56 VSS<250> LBG_CORE_QAT_EXT_D_BGA1-IC,H91A    I17 @BASEBOARD_FAB2_LIB.BASEBOARD_FAB2(SCH_1):PAGE124
  U7C1 AG52 VSS<251> LBG_CORE_QAT_EXT_D_BGA1-IC,H91A    I17 @BASEBOARD_FAB2_LIB.BASEBOARD_FAB2(SCH_1):PAGE124
  U7C1 AG43 VSS<252> LBG_CORE_QAT_EXT_D_BGA1-IC,H91A    I17 @BASEBOARD_FAB2_LIB.BASEBOARD_FAB2(SCH_1):PAGE124
  U7C1 AG41 VSS<253> LBG_CORE_QAT_EXT_D_BGA1-IC,H91A    I17 @BASEBOARD_FAB2_LIB.BASEBOARD_FAB2(SCH_1):PAGE124
  U7C1 AG30 VSS<254> LBG_CORE_QAT_EXT_D_BGA1-IC,H91A    I17 @BASEBOARD_FAB2_LIB.BASEBOARD_FAB2(SCH_1):PAGE124
  U7C1 AG26 VSS<255> LBG_CORE_QAT_EXT_D_BGA1-IC,H91A    I17 @BASEBOARD_FAB2_LIB.BASEBOARD_FAB2(SCH_1):PAGE124
  U7C1 AF68 VSS<256> LBG_CORE_QAT_EXT_D_BGA1-IC,H91A    I17 @BASEBOARD_FAB2_LIB.BASEBOARD_FAB2(SCH_1):PAGE124
  U7C1  AF3 VSS<257> LBG_CORE_QAT_EXT_D_BGA1-IC,H91A    I17 @BASEBOARD_FAB2_LIB.BASEBOARD_FAB2(SCH_1):PAGE124
  U7C1 AF24 VSS<258> LBG_CORE_QAT_EXT_D_BGA1-IC,H91A    I17 @BASEBOARD_FAB2_LIB.BASEBOARD_FAB2(SCH_1):PAGE124
  U7C1 AF17 VSS<259> LBG_CORE_QAT_EXT_D_BGA1-IC,H91A    I17 @BASEBOARD_FAB2_LIB.BASEBOARD_FAB2(SCH_1):PAGE124
  U7C1  AF9 VSS<260> LBG_CORE_QAT_EXT_D_BGA1-IC,H91A    I17 @BASEBOARD_FAB2_LIB.BASEBOARD_FAB2(SCH_1):PAGE124
  U7C1  AF5 VSS<261> LBG_CORE_QAT_EXT_D_BGA1-IC,H91A    I17 @BASEBOARD_FAB2_LIB.BASEBOARD_FAB2(SCH_1):PAGE124
  U7C1 AF13 VSS<262> LBG_CORE_QAT_EXT_D_BGA1-IC,H91A    I17 @BASEBOARD_FAB2_LIB.BASEBOARD_FAB2(SCH_1):PAGE124
  U7C1  AF1 VSS<263> LBG_CORE_QAT_EXT_D_BGA1-IC,H91A    I17 @BASEBOARD_FAB2_LIB.BASEBOARD_FAB2(SCH_1):PAGE124
  U7C1 AE66 VSS<264> LBG_CORE_QAT_EXT_D_BGA1-IC,H91A    I17 @BASEBOARD_FAB2_LIB.BASEBOARD_FAB2(SCH_1):PAGE124
  U7C1 AE63 VSS<265> LBG_CORE_QAT_EXT_D_BGA1-IC,H91A    I17 @BASEBOARD_FAB2_LIB.BASEBOARD_FAB2(SCH_1):PAGE124
  U7C1 AE59 VSS<266> LBG_CORE_QAT_EXT_D_BGA1-IC,H91A    I17 @BASEBOARD_FAB2_LIB.BASEBOARD_FAB2(SCH_1):PAGE124
  U7C1 AE56 VSS<267> LBG_CORE_QAT_EXT_D_BGA1-IC,H91A    I17 @BASEBOARD_FAB2_LIB.BASEBOARD_FAB2(SCH_1):PAGE124
  U7C1 AE52 VSS<268> LBG_CORE_QAT_EXT_D_BGA1-IC,H91A    I17 @BASEBOARD_FAB2_LIB.BASEBOARD_FAB2(SCH_1):PAGE124
  U7C1 AE48 VSS<269> LBG_CORE_QAT_EXT_D_BGA1-IC,H91A    I17 @BASEBOARD_FAB2_LIB.BASEBOARD_FAB2(SCH_1):PAGE124
  U7C1  J18 VSS<270> LBG_CORE_QAT_EXT_D_BGA1-IC,H91A    I17 @BASEBOARD_FAB2_LIB.BASEBOARD_FAB2(SCH_1):PAGE124
  U7C1 AE29 VSS<271> LBG_CORE_QAT_EXT_D_BGA1-IC,H91A    I17 @BASEBOARD_FAB2_LIB.BASEBOARD_FAB2(SCH_1):PAGE124
  U7C1 AD68 VSS<272> LBG_CORE_QAT_EXT_D_BGA1-IC,H91A    I17 @BASEBOARD_FAB2_LIB.BASEBOARD_FAB2(SCH_1):PAGE124
  U7C1 AD65 VSS<273> LBG_CORE_QAT_EXT_D_BGA1-IC,H91A    I17 @BASEBOARD_FAB2_LIB.BASEBOARD_FAB2(SCH_1):PAGE124
  U7C1  AD5 VSS<274> LBG_CORE_QAT_EXT_D_BGA1-IC,H91A    I17 @BASEBOARD_FAB2_LIB.BASEBOARD_FAB2(SCH_1):PAGE124
  U7C1  AC7 VSS<275> LBG_CORE_QAT_EXT_D_BGA1-IC,H91A    I17 @BASEBOARD_FAB2_LIB.BASEBOARD_FAB2(SCH_1):PAGE124
  U7C1 AC66 VSS<276> LBG_CORE_QAT_EXT_D_BGA1-IC,H91A    I17 @BASEBOARD_FAB2_LIB.BASEBOARD_FAB2(SCH_1):PAGE124
  U7C1 AC63 VSS<277> LBG_CORE_QAT_EXT_D_BGA1-IC,H91A    I17 @BASEBOARD_FAB2_LIB.BASEBOARD_FAB2(SCH_1):PAGE124
  U7C1 AC59 VSS<278> LBG_CORE_QAT_EXT_D_BGA1-IC,H91A    I17 @BASEBOARD_FAB2_LIB.BASEBOARD_FAB2(SCH_1):PAGE124
  U7C1 AC52 VSS<279> LBG_CORE_QAT_EXT_D_BGA1-IC,H91A    I17 @BASEBOARD_FAB2_LIB.BASEBOARD_FAB2(SCH_1):PAGE124
  U7C1 AC48 VSS<280> LBG_CORE_QAT_EXT_D_BGA1-IC,H91A    I17 @BASEBOARD_FAB2_LIB.BASEBOARD_FAB2(SCH_1):PAGE124
  U7C1 AC46 VSS<281> LBG_CORE_QAT_EXT_D_BGA1-IC,H91A    I17 @BASEBOARD_FAB2_LIB.BASEBOARD_FAB2(SCH_1):PAGE124
  U7C1 AC43 VSS<282> LBG_CORE_QAT_EXT_D_BGA1-IC,H91A    I17 @BASEBOARD_FAB2_LIB.BASEBOARD_FAB2(SCH_1):PAGE124
  U7C1 AC27 VSS<283> LBG_CORE_QAT_EXT_D_BGA1-IC,H91A    I17 @BASEBOARD_FAB2_LIB.BASEBOARD_FAB2(SCH_1):PAGE124
  U7C1 AD58 VSS<284> LBG_CORE_QAT_EXT_D_BGA1-IC,H91A    I17 @BASEBOARD_FAB2_LIB.BASEBOARD_FAB2(SCH_1):PAGE124
  U7C1 AC45 VSS<285> LBG_CORE_QAT_EXT_D_BGA1-IC,H91A    I17 @BASEBOARD_FAB2_LIB.BASEBOARD_FAB2(SCH_1):PAGE124
  U7C1 AC22 VSS<286> LBG_CORE_QAT_EXT_D_BGA1-IC,H91A    I17 @BASEBOARD_FAB2_LIB.BASEBOARD_FAB2(SCH_1):PAGE124
  U7C1 AC18 VSS<287> LBG_CORE_QAT_EXT_D_BGA1-IC,H91A    I17 @BASEBOARD_FAB2_LIB.BASEBOARD_FAB2(SCH_1):PAGE124
  U7C1 AC15 VSS<288> LBG_CORE_QAT_EXT_D_BGA1-IC,H91A    I17 @BASEBOARD_FAB2_LIB.BASEBOARD_FAB2(SCH_1):PAGE124
  U7C1 AC11 VSS<289> LBG_CORE_QAT_EXT_D_BGA1-IC,H91A    I17 @BASEBOARD_FAB2_LIB.BASEBOARD_FAB2(SCH_1):PAGE124
  U7C1 AB72 VSS<290> LBG_CORE_QAT_EXT_D_BGA1-IC,H91A    I17 @BASEBOARD_FAB2_LIB.BASEBOARD_FAB2(SCH_1):PAGE124
  U7C1 AB70 VSS<291> LBG_CORE_QAT_EXT_D_BGA1-IC,H91A    I17 @BASEBOARD_FAB2_LIB.BASEBOARD_FAB2(SCH_1):PAGE124
  U7C1 AB68 VSS<292> LBG_CORE_QAT_EXT_D_BGA1-IC,H91A    I17 @BASEBOARD_FAB2_LIB.BASEBOARD_FAB2(SCH_1):PAGE124
  U7C1  AB5 VSS<293> LBG_CORE_QAT_EXT_D_BGA1-IC,H91A    I17 @BASEBOARD_FAB2_LIB.BASEBOARD_FAB2(SCH_1):PAGE124
  U7C1 AA48 VSS<294> LBG_CORE_QAT_EXT_D_BGA1-IC,H91A    I17 @BASEBOARD_FAB2_LIB.BASEBOARD_FAB2(SCH_1):PAGE124
  U7C1 AA43 VSS<295> LBG_CORE_QAT_EXT_D_BGA1-IC,H91A    I17 @BASEBOARD_FAB2_LIB.BASEBOARD_FAB2(SCH_1):PAGE124
  U7C1 AA27 VSS<296> LBG_CORE_QAT_EXT_D_BGA1-IC,H91A    I17 @BASEBOARD_FAB2_LIB.BASEBOARD_FAB2(SCH_1):PAGE124
  U7C1 AA26 VSS<297> LBG_CORE_QAT_EXT_D_BGA1-IC,H91A    I17 @BASEBOARD_FAB2_LIB.BASEBOARD_FAB2(SCH_1):PAGE124
  U7C1  Y68 VSS<298> LBG_CORE_QAT_EXT_D_BGA1-IC,H91A    I17 @BASEBOARD_FAB2_LIB.BASEBOARD_FAB2(SCH_1):PAGE124
  U7C1  Y63 VSS<299> LBG_CORE_QAT_EXT_D_BGA1-IC,H91A    I17 @BASEBOARD_FAB2_LIB.BASEBOARD_FAB2(SCH_1):PAGE124
  U7C1  Y59 VSS<300> LBG_CORE_QAT_EXT_D_BGA1-IC,H91A    I17 @BASEBOARD_FAB2_LIB.BASEBOARD_FAB2(SCH_1):PAGE124
  U7C1  Y52 VSS<301> LBG_CORE_QAT_EXT_D_BGA1-IC,H91A    I17 @BASEBOARD_FAB2_LIB.BASEBOARD_FAB2(SCH_1):PAGE124
  U7C1   Y5 VSS<302> LBG_CORE_QAT_EXT_D_BGA1-IC,H91A    I17 @BASEBOARD_FAB2_LIB.BASEBOARD_FAB2(SCH_1):PAGE124
  U7C1  Y48 VSS<303> LBG_CORE_QAT_EXT_D_BGA1-IC,H91A    I17 @BASEBOARD_FAB2_LIB.BASEBOARD_FAB2(SCH_1):PAGE124
  U7C1  Y27 VSS<304> LBG_CORE_QAT_EXT_D_BGA1-IC,H91A    I17 @BASEBOARD_FAB2_LIB.BASEBOARD_FAB2(SCH_1):PAGE124
  U7C1  Y22 VSS<305> LBG_CORE_QAT_EXT_D_BGA1-IC,H91A    I17 @BASEBOARD_FAB2_LIB.BASEBOARD_FAB2(SCH_1):PAGE124
  U7C1   W9 VSS<306> LBG_CORE_QAT_EXT_D_BGA1-IC,H91A    I17 @BASEBOARD_FAB2_LIB.BASEBOARD_FAB2(SCH_1):PAGE124
  U7C1  W61 VSS<307> LBG_CORE_QAT_EXT_D_BGA1-IC,H91A    I17 @BASEBOARD_FAB2_LIB.BASEBOARD_FAB2(SCH_1):PAGE124
  U7C1  Y43 VSS<308> LBG_CORE_QAT_EXT_D_BGA1-IC,H91A    I17 @BASEBOARD_FAB2_LIB.BASEBOARD_FAB2(SCH_1):PAGE124
  U7C1 AA50 VSS<309> LBG_CORE_QAT_EXT_D_BGA1-IC,H91A    I17 @BASEBOARD_FAB2_LIB.BASEBOARD_FAB2(SCH_1):PAGE124
  U7C1  W24 VSS<310> LBG_CORE_QAT_EXT_D_BGA1-IC,H91A    I17 @BASEBOARD_FAB2_LIB.BASEBOARD_FAB2(SCH_1):PAGE124
  U7C1  W20 VSS<311> LBG_CORE_QAT_EXT_D_BGA1-IC,H91A    I17 @BASEBOARD_FAB2_LIB.BASEBOARD_FAB2(SCH_1):PAGE124
  U7C1  W17 VSS<312> LBG_CORE_QAT_EXT_D_BGA1-IC,H91A    I17 @BASEBOARD_FAB2_LIB.BASEBOARD_FAB2(SCH_1):PAGE124
  U7C1  W13 VSS<313> LBG_CORE_QAT_EXT_D_BGA1-IC,H91A    I17 @BASEBOARD_FAB2_LIB.BASEBOARD_FAB2(SCH_1):PAGE124
  U7C1  V68 VSS<314> LBG_CORE_QAT_EXT_D_BGA1-IC,H91A    I17 @BASEBOARD_FAB2_LIB.BASEBOARD_FAB2(SCH_1):PAGE124
  U7C1  V66 VSS<315> LBG_CORE_QAT_EXT_D_BGA1-IC,H91A    I17 @BASEBOARD_FAB2_LIB.BASEBOARD_FAB2(SCH_1):PAGE124
  U7C1  W58 VSS<316> LBG_CORE_QAT_EXT_D_BGA1-IC,H91A    I17 @BASEBOARD_FAB2_LIB.BASEBOARD_FAB2(SCH_1):PAGE124
  U7C1  V52 VSS<317> LBG_CORE_QAT_EXT_D_BGA1-IC,H91A    I17 @BASEBOARD_FAB2_LIB.BASEBOARD_FAB2(SCH_1):PAGE124
  U7C1   V5 VSS<318> LBG_CORE_QAT_EXT_D_BGA1-IC,H91A    I17 @BASEBOARD_FAB2_LIB.BASEBOARD_FAB2(SCH_1):PAGE124
  U7C1  V48 VSS<319> LBG_CORE_QAT_EXT_D_BGA1-IC,H91A    I17 @BASEBOARD_FAB2_LIB.BASEBOARD_FAB2(SCH_1):PAGE124
  U7C1  V26 VSS<320> LBG_CORE_QAT_EXT_D_BGA1-IC,H91A    I17 @BASEBOARD_FAB2_LIB.BASEBOARD_FAB2(SCH_1):PAGE124
  U7C1  U58 VSS<321> LBG_CORE_QAT_EXT_D_BGA1-IC,H91A    I17 @BASEBOARD_FAB2_LIB.BASEBOARD_FAB2(SCH_1):PAGE124
  U7C1 AG46 VSS<322> LBG_CORE_QAT_EXT_D_BGA1-IC,H91A    I17 @BASEBOARD_FAB2_LIB.BASEBOARD_FAB2(SCH_1):PAGE124
  U7C1 AF50 VSS<323> LBG_CORE_QAT_EXT_D_BGA1-IC,H91A    I17 @BASEBOARD_FAB2_LIB.BASEBOARD_FAB2(SCH_1):PAGE124
  U7C1   T7 VSS<324> LBG_CORE_QAT_EXT_D_BGA1-IC,H91A    I17 @BASEBOARD_FAB2_LIB.BASEBOARD_FAB2(SCH_1):PAGE124
  U7C1  T66 VSS<325> LBG_CORE_QAT_EXT_D_BGA1-IC,H91A    I17 @BASEBOARD_FAB2_LIB.BASEBOARD_FAB2(SCH_1):PAGE124
  U7C1  T52 VSS<326> LBG_CORE_QAT_EXT_D_BGA1-IC,H91A    I17 @BASEBOARD_FAB2_LIB.BASEBOARD_FAB2(SCH_1):PAGE124
  U7C1  T48 VSS<327> LBG_CORE_QAT_EXT_D_BGA1-IC,H91A    I17 @BASEBOARD_FAB2_LIB.BASEBOARD_FAB2(SCH_1):PAGE124
  U7C1 AJ45 VSS<328> LBG_CORE_QAT_EXT_D_BGA1-IC,H91A    I17 @BASEBOARD_FAB2_LIB.BASEBOARD_FAB2(SCH_1):PAGE124
  U7C1  T40 VSS<329> LBG_CORE_QAT_EXT_D_BGA1-IC,H91A    I17 @BASEBOARD_FAB2_LIB.BASEBOARD_FAB2(SCH_1):PAGE124
  U7C1  T37 VSS<330> LBG_CORE_QAT_EXT_D_BGA1-IC,H91A    I17 @BASEBOARD_FAB2_LIB.BASEBOARD_FAB2(SCH_1):PAGE124
  U7C1  T33 VSS<331> LBG_CORE_QAT_EXT_D_BGA1-IC,H91A    I17 @BASEBOARD_FAB2_LIB.BASEBOARD_FAB2(SCH_1):PAGE124
  U7C1  T29 VSS<332> LBG_CORE_QAT_EXT_D_BGA1-IC,H91A    I17 @BASEBOARD_FAB2_LIB.BASEBOARD_FAB2(SCH_1):PAGE124
  U7C1  T26 VSS<333> LBG_CORE_QAT_EXT_D_BGA1-IC,H91A    I17 @BASEBOARD_FAB2_LIB.BASEBOARD_FAB2(SCH_1):PAGE124
  U7C1  T22 VSS<334> LBG_CORE_QAT_EXT_D_BGA1-IC,H91A    I17 @BASEBOARD_FAB2_LIB.BASEBOARD_FAB2(SCH_1):PAGE124
  U7C1  T18 VSS<335> LBG_CORE_QAT_EXT_D_BGA1-IC,H91A    I17 @BASEBOARD_FAB2_LIB.BASEBOARD_FAB2(SCH_1):PAGE124
  U7C1  T15 VSS<336> LBG_CORE_QAT_EXT_D_BGA1-IC,H91A    I17 @BASEBOARD_FAB2_LIB.BASEBOARD_FAB2(SCH_1):PAGE124
  U7C1  T11 VSS<337> LBG_CORE_QAT_EXT_D_BGA1-IC,H91A    I17 @BASEBOARD_FAB2_LIB.BASEBOARD_FAB2(SCH_1):PAGE124
  U7C1  R68 VSS<338> LBG_CORE_QAT_EXT_D_BGA1-IC,H91A    I17 @BASEBOARD_FAB2_LIB.BASEBOARD_FAB2(SCH_1):PAGE124
  U7C1  R58 VSS<339> LBG_CORE_QAT_EXT_D_BGA1-IC,H91A    I17 @BASEBOARD_FAB2_LIB.BASEBOARD_FAB2(SCH_1):PAGE124
  U7C1  T56 VSS<340> LBG_CORE_QAT_EXT_D_BGA1-IC,H91A    I17 @BASEBOARD_FAB2_LIB.BASEBOARD_FAB2(SCH_1):PAGE124
  U7C1  R54 VSS<341> LBG_CORE_QAT_EXT_D_BGA1-IC,H91A    I17 @BASEBOARD_FAB2_LIB.BASEBOARD_FAB2(SCH_1):PAGE124
  U7C1  R50 VSS<342> LBG_CORE_QAT_EXT_D_BGA1-IC,H91A    I17 @BASEBOARD_FAB2_LIB.BASEBOARD_FAB2(SCH_1):PAGE124
  U7C1   R5 VSS<343> LBG_CORE_QAT_EXT_D_BGA1-IC,H91A    I17 @BASEBOARD_FAB2_LIB.BASEBOARD_FAB2(SCH_1):PAGE124
  U7C1  U42 VSS<344> LBG_CORE_QAT_EXT_D_BGA1-IC,H91A    I17 @BASEBOARD_FAB2_LIB.BASEBOARD_FAB2(SCH_1):PAGE124
  U7C1  R27 VSS<345> LBG_CORE_QAT_EXT_D_BGA1-IC,H91A    I17 @BASEBOARD_FAB2_LIB.BASEBOARD_FAB2(SCH_1):PAGE124
  U7C1  P63 VSS<346> LBG_CORE_QAT_EXT_D_BGA1-IC,H91A    I17 @BASEBOARD_FAB2_LIB.BASEBOARD_FAB2(SCH_1):PAGE124
  U7C1 AE43 VSS<347> LBG_CORE_QAT_EXT_D_BGA1-IC,H91A    I17 @BASEBOARD_FAB2_LIB.BASEBOARD_FAB2(SCH_1):PAGE124
  U7C1   N9 VSS<348> LBG_CORE_QAT_EXT_D_BGA1-IC,H91A    I17 @BASEBOARD_FAB2_LIB.BASEBOARD_FAB2(SCH_1):PAGE124
  U7C1  N68 VSS<349> LBG_CORE_QAT_EXT_D_BGA1-IC,H91A    I17 @BASEBOARD_FAB2_LIB.BASEBOARD_FAB2(SCH_1):PAGE124
  U7C1  R38 VSS<350> LBG_CORE_QAT_EXT_D_BGA1-IC,H91A    I17 @BASEBOARD_FAB2_LIB.BASEBOARD_FAB2(SCH_1):PAGE124
  U7C1   N5 VSS<351> LBG_CORE_QAT_EXT_D_BGA1-IC,H91A    I17 @BASEBOARD_FAB2_LIB.BASEBOARD_FAB2(SCH_1):PAGE124
  U7C1  N46 VSS<352> LBG_CORE_QAT_EXT_D_BGA1-IC,H91A    I17 @BASEBOARD_FAB2_LIB.BASEBOARD_FAB2(SCH_1):PAGE124
  U7C1  N38 VSS<353> LBG_CORE_QAT_EXT_D_BGA1-IC,H91A    I17 @BASEBOARD_FAB2_LIB.BASEBOARD_FAB2(SCH_1):PAGE124
  U7C1  N35 VSS<354> LBG_CORE_QAT_EXT_D_BGA1-IC,H91A    I17 @BASEBOARD_FAB2_LIB.BASEBOARD_FAB2(SCH_1):PAGE124
 R2R11    2      B RES_0402-1.00K,1%,1/16W,EMPTY,A    I11 @BASEBOARD_FAB2_LIB.BASEBOARD_FAB2(SCH_1):PAGE125
  R2T1    2      B RES_0402-1.00K,1%,1/16W,CHIP,GA    I15 @BASEBOARD_FAB2_LIB.BASEBOARD_FAB2(SCH_1):PAGE125
  R8E4    2      B RES_0402-1.00K,1%,1/16W,EMPTY,A    I24 @BASEBOARD_FAB2_LIB.BASEBOARD_FAB2(SCH_1):PAGE125
 R8C17    2      B RES_0402-1.00K,1%,1/16W,EMPTY,A    I41 @BASEBOARD_FAB2_LIB.BASEBOARD_FAB2(SCH_1):PAGE125
  R8D5    2      B RES_0402-1.00K,1%,1/16W,EMPTY,A    I50 @BASEBOARD_FAB2_LIB.BASEBOARD_FAB2(SCH_1):PAGE125
  R7D1    2      B RES_0402-1.00K,1%,1/16W,CHIP,GA    I70 @BASEBOARD_FAB2_LIB.BASEBOARD_FAB2(SCH_1):PAGE125
 R7D19    2      B RES_0402-1.00K,1%,1/16W,EMPTY,A     I6 @BASEBOARD_FAB2_LIB.BASEBOARD_FAB2(SCH_1):PAGE126
  Q8E2    2    SRC FET_N_SOT23LF-2N7002,FET,C7925A    I13 @BASEBOARD_FAB2_LIB.BASEBOARD_FAB2(SCH_1):PAGE126
 R3P64    2      B RES_0402-1.00K,1%,1/16W,EMPTY,A    I23 @BASEBOARD_FAB2_LIB.BASEBOARD_FAB2(SCH_1):PAGE126
 C3M21    2      B CAP_A_0402V-1.0UF,6.3V,10%,X6SA     I9 @BASEBOARD_FAB2_LIB.BASEBOARD_FAB2(SCH_1):PAGE127
 C3M22    2      B CAP_A_0402V-1.0UF,6.3V,10%,X6SA    I18 @BASEBOARD_FAB2_LIB.BASEBOARD_FAB2(SCH_1):PAGE127
 C3M30    2      B CAP_A_0402V-1.0UF,6.3V,10%,X6SA    I27 @BASEBOARD_FAB2_LIB.BASEBOARD_FAB2(SCH_1):PAGE127
  C2M5    2      B CAP_0603LF-10UF,4V,20%,X6S,E15A    I43 @BASEBOARD_FAB2_LIB.BASEBOARD_FAB2(SCH_1):PAGE127
  C2M7    2      B CAP_A_0402V-1.0UF,6.3V,10%,X6SA    I44 @BASEBOARD_FAB2_LIB.BASEBOARD_FAB2(SCH_1):PAGE127
 C2M10    2      B CAP_0603LF-10UF,4V,20%,X6S,E15A    I49 @BASEBOARD_FAB2_LIB.BASEBOARD_FAB2(SCH_1):PAGE127
  C2M9    2      B CAP_A_0402V-1.0UF,6.3V,10%,X6SA    I50 @BASEBOARD_FAB2_LIB.BASEBOARD_FAB2(SCH_1):PAGE127
 C3M31    2      B CAP_A_0402V-1.0UF,6.3V,10%,X6SA    I57 @BASEBOARD_FAB2_LIB.BASEBOARD_FAB2(SCH_1):PAGE127
  C2N6    2      B CAP_0603LF-10UF,4V,20%,X6S,E15A    I64 @BASEBOARD_FAB2_LIB.BASEBOARD_FAB2(SCH_1):PAGE127
  C2N5    2      B CAP_A_0402V-1.0UF,6.3V,10%,X6SA    I65 @BASEBOARD_FAB2_LIB.BASEBOARD_FAB2(SCH_1):PAGE127
  C2M8    2      B CAP_A_0402V-1.0UF,6.3V,10%,X6SA    I74 @BASEBOARD_FAB2_LIB.BASEBOARD_FAB2(SCH_1):PAGE127
  C2M6    2      B CAP_A_0402V-1.0UF,6.3V,10%,X6SA    I76 @BASEBOARD_FAB2_LIB.BASEBOARD_FAB2(SCH_1):PAGE127
 C2M25    2      B CAP_A_0402V-1.0UF,6.3V,10%,X6SA    I78 @BASEBOARD_FAB2_LIB.BASEBOARD_FAB2(SCH_1):PAGE127
 C3M29    2      B CAP_A_0402V-1.0UF,6.3V,10%,X6SA    I80 @BASEBOARD_FAB2_LIB.BASEBOARD_FAB2(SCH_1):PAGE127
 C3M24    2      B CAP_0603LF-10UF,4V,20%,X6S,E15A    I81 @BASEBOARD_FAB2_LIB.BASEBOARD_FAB2(SCH_1):PAGE127
 C3M23    2      B CAP_0603LF-10UF,4V,20%,X6S,E15A    I82 @BASEBOARD_FAB2_LIB.BASEBOARD_FAB2(SCH_1):PAGE127
 C3M27    2      B CAP_A_0402V-1.0UF,6.3V,10%,X6SA    I83 @BASEBOARD_FAB2_LIB.BASEBOARD_FAB2(SCH_1):PAGE127
 C3M20    2      B CAP_A_0402V-1.0UF,6.3V,10%,X6SA    I84 @BASEBOARD_FAB2_LIB.BASEBOARD_FAB2(SCH_1):PAGE127
 C3M18    2      B CAP_0603LF-10UF,4V,20%,X6S,E15A    I85 @BASEBOARD_FAB2_LIB.BASEBOARD_FAB2(SCH_1):PAGE127
 C3M17    2      B CAP_0603LF-10UF,4V,20%,X6S,E15A    I86 @BASEBOARD_FAB2_LIB.BASEBOARD_FAB2(SCH_1):PAGE127
 C3M19    2      B CAP_A_0402V-1.0UF,6.3V,10%,X6SA    I87 @BASEBOARD_FAB2_LIB.BASEBOARD_FAB2(SCH_1):PAGE127
  C7D2    2      B CAP_0603-10UF,6.3V,20%,X6S,E15A     I2 @BASEBOARD_FAB2_LIB.BASEBOARD_FAB2(SCH_1):PAGE130
 C2N26    2      B CAP_A_0402V-1.0UF,6.3V,10%,X6SA     I4 @BASEBOARD_FAB2_LIB.BASEBOARD_FAB2(SCH_1):PAGE130
 C2N19    2      B CAP_A_0402V-1.0UF,6.3V,10%,X6SA     I7 @BASEBOARD_FAB2_LIB.BASEBOARD_FAB2(SCH_1):PAGE130
 C2N24    2      B CAP_0603-10UF,6.3V,20%,X6S,E15A     I8 @BASEBOARD_FAB2_LIB.BASEBOARD_FAB2(SCH_1):PAGE130
 C2N22    2      B CAP_0603-10UF,6.3V,20%,X6S,E15A     I9 @BASEBOARD_FAB2_LIB.BASEBOARD_FAB2(SCH_1):PAGE130
 C2N20    2      B CAP_A_0402V-1.0UF,6.3V,10%,X6SA    I12 @BASEBOARD_FAB2_LIB.BASEBOARD_FAB2(SCH_1):PAGE130
 C2N21    2      B CAP_0603-10UF,6.3V,20%,X6S,E15A    I15 @BASEBOARD_FAB2_LIB.BASEBOARD_FAB2(SCH_1):PAGE130
 C3N29    2      B CAP_A_0402V-0.1UF,16V,10%,X7R,A    I16 @BASEBOARD_FAB2_LIB.BASEBOARD_FAB2(SCH_1):PAGE130
  C8C3    2      B CAP_0603-10UF,6.3V,20%,X6S,E15A    I19 @BASEBOARD_FAB2_LIB.BASEBOARD_FAB2(SCH_1):PAGE130
  C8C4    2      B CAP_0603-10UF,6.3V,20%,X6S,E15A    I20 @BASEBOARD_FAB2_LIB.BASEBOARD_FAB2(SCH_1):PAGE130
  C8C5    2      B CAP_0603-10UF,6.3V,20%,X6S,E15A    I21 @BASEBOARD_FAB2_LIB.BASEBOARD_FAB2(SCH_1):PAGE130
  C8C6    2      B CAP_0603-10UF,6.3V,20%,X6S,E15A    I22 @BASEBOARD_FAB2_LIB.BASEBOARD_FAB2(SCH_1):PAGE130
 C2N23    2      B CAP_0603-10UF,6.3V,20%,X6S,E15A    I24 @BASEBOARD_FAB2_LIB.BASEBOARD_FAB2(SCH_1):PAGE130
 C2N14    2      B CAP_0603-10UF,6.3V,20%,X6S,E15A    I25 @BASEBOARD_FAB2_LIB.BASEBOARD_FAB2(SCH_1):PAGE130
 C2N17    2      B CAP_0603-10UF,6.3V,20%,X6S,E15A    I28 @BASEBOARD_FAB2_LIB.BASEBOARD_FAB2(SCH_1):PAGE130
 C2N18    2      B CAP_A_0402V-1.0UF,6.3V,10%,X6SA    I29 @BASEBOARD_FAB2_LIB.BASEBOARD_FAB2(SCH_1):PAGE130
  C8B2    2      B CAP_A_0603V-22.0UF,4V,20%,X6S,A    I30 @BASEBOARD_FAB2_LIB.BASEBOARD_FAB2(SCH_1):PAGE130
  C8B3    2      B CAP_A_0603V-22.0UF,4V,20%,X6S,A    I32 @BASEBOARD_FAB2_LIB.BASEBOARD_FAB2(SCH_1):PAGE130
 C2N25    2      B CAP_A_0402V-1.0UF,6.3V,10%,X6SA    I34 @BASEBOARD_FAB2_LIB.BASEBOARD_FAB2(SCH_1):PAGE130
 C2M16    2      B CAP_A_0402V-1.0UF,6.3V,10%,X6SA    I37 @BASEBOARD_FAB2_LIB.BASEBOARD_FAB2(SCH_1):PAGE130
  C7D3    2      B CAP_A_0603V-22.0UF,4V,20%,X6S,A    I38 @BASEBOARD_FAB2_LIB.BASEBOARD_FAB2(SCH_1):PAGE130
  C8B4    2      B CAP_A_0603V-22.0UF,4V,20%,X6S,A    I39 @BASEBOARD_FAB2_LIB.BASEBOARD_FAB2(SCH_1):PAGE130
  C8B1    2      B CAP_A_0603V-22.0UF,4V,20%,X6S,A    I41 @BASEBOARD_FAB2_LIB.BASEBOARD_FAB2(SCH_1):PAGE130
 C3N23    2      B CAP_A_0402V-1.0UF,6.3V,10%,X6SA    I42 @BASEBOARD_FAB2_LIB.BASEBOARD_FAB2(SCH_1):PAGE130
  C2M1    2      B CAP_A_0603V-22.0UF,4V,20%,X6S,A    I43 @BASEBOARD_FAB2_LIB.BASEBOARD_FAB2(SCH_1):PAGE130
  C2M2    2      B CAP_A_0603V-22.0UF,4V,20%,X6S,A    I45 @BASEBOARD_FAB2_LIB.BASEBOARD_FAB2(SCH_1):PAGE130
 C2N15    2      B CAP_A_0402V-1.0UF,6.3V,10%,X6SA    I47 @BASEBOARD_FAB2_LIB.BASEBOARD_FAB2(SCH_1):PAGE130
 C3N21    2      B CAP_A_0402V-1.0UF,6.3V,10%,X6SA    I49 @BASEBOARD_FAB2_LIB.BASEBOARD_FAB2(SCH_1):PAGE130
 C3N25    2      B CAP_A_0402V-1.0UF,6.3V,10%,X6SA    I50 @BASEBOARD_FAB2_LIB.BASEBOARD_FAB2(SCH_1):PAGE130
 C2N16    2      B CAP_A_0402V-1.0UF,6.3V,10%,X6SA    I52 @BASEBOARD_FAB2_LIB.BASEBOARD_FAB2(SCH_1):PAGE130
 C3N22    2      B CAP_A_0402V-1.0UF,6.3V,10%,X6SA    I53 @BASEBOARD_FAB2_LIB.BASEBOARD_FAB2(SCH_1):PAGE130
 C7B15    2      B CAP_A_0603V-22.0UF,4V,20%,X6S,A     I1 @BASEBOARD_FAB2_LIB.BASEBOARD_FAB2(SCH_1):PAGE131
 C7B19    2      B CAP_A_0603V-22.0UF,4V,20%,X6S,A     I2 @BASEBOARD_FAB2_LIB.BASEBOARD_FAB2(SCH_1):PAGE131
 C7B16    2      B CAP_A_0603V-22.0UF,4V,20%,X6S,A     I3 @BASEBOARD_FAB2_LIB.BASEBOARD_FAB2(SCH_1):PAGE131
 C7B21    2      B CAP_A_0603V-22.0UF,4V,20%,X6S,A     I4 @BASEBOARD_FAB2_LIB.BASEBOARD_FAB2(SCH_1):PAGE131
 C7B20    2      B CAP_A_0603V-22.0UF,4V,20%,X6S,A     I6 @BASEBOARD_FAB2_LIB.BASEBOARD_FAB2(SCH_1):PAGE131
 C7B23    2      B CAP_A_0603V-22.0UF,4V,20%,X6S,A     I7 @BASEBOARD_FAB2_LIB.BASEBOARD_FAB2(SCH_1):PAGE131
 C8B10    2      B CAP_A_0603V-22.0UF,4V,20%,X6S,A     I8 @BASEBOARD_FAB2_LIB.BASEBOARD_FAB2(SCH_1):PAGE131
 C7B22    2      B CAP_A_0603V-22.0UF,4V,20%,X6S,A    I10 @BASEBOARD_FAB2_LIB.BASEBOARD_FAB2(SCH_1):PAGE131
 C7B24    2      B CAP_A_0603V-22.0UF,4V,20%,X6S,A    I11 @BASEBOARD_FAB2_LIB.BASEBOARD_FAB2(SCH_1):PAGE131
 C7B18    2      B CAP_A_0603V-22.0UF,4V,20%,X6S,A    I12 @BASEBOARD_FAB2_LIB.BASEBOARD_FAB2(SCH_1):PAGE131
  C8B9    2      B CAP_A_0603V-22.0UF,4V,20%,X6S,A    I14 @BASEBOARD_FAB2_LIB.BASEBOARD_FAB2(SCH_1):PAGE131
 C8B11    2      B CAP_A_0603V-22.0UF,4V,20%,X6S,A    I15 @BASEBOARD_FAB2_LIB.BASEBOARD_FAB2(SCH_1):PAGE131
 C8B14    2      B CAP_A_0603V-22.0UF,4V,20%,X6S,A    I16 @BASEBOARD_FAB2_LIB.BASEBOARD_FAB2(SCH_1):PAGE131
 C7B17    2      B CAP_A_0603V-22.0UF,4V,20%,X6S,A    I18 @BASEBOARD_FAB2_LIB.BASEBOARD_FAB2(SCH_1):PAGE131
 C8B13    2      B CAP_A_0603V-22.0UF,4V,20%,X6S,A    I20 @BASEBOARD_FAB2_LIB.BASEBOARD_FAB2(SCH_1):PAGE131
 C8B16    2      B CAP_0805-47UF,4V,20%,X6S,C9533A    I22 @BASEBOARD_FAB2_LIB.BASEBOARD_FAB2(SCH_1):PAGE131
 C8B15    2      B CAP_0805-47UF,4V,20%,X6S,C9533A    I24 @BASEBOARD_FAB2_LIB.BASEBOARD_FAB2(SCH_1):PAGE131
 C2M22    2      B CAP_A_0402V-1.0UF,6.3V,10%,X6SA    I27 @BASEBOARD_FAB2_LIB.BASEBOARD_FAB2(SCH_1):PAGE131
 C2M21    2      B CAP_A_0402V-1.0UF,6.3V,10%,X6SA    I28 @BASEBOARD_FAB2_LIB.BASEBOARD_FAB2(SCH_1):PAGE131
 C2M18    2      B CAP_A_0402V-1.0UF,6.3V,10%,X6SA    I29 @BASEBOARD_FAB2_LIB.BASEBOARD_FAB2(SCH_1):PAGE131
 C2M19    2      B CAP_A_0402V-1.0UF,6.3V,10%,X6SA    I31 @BASEBOARD_FAB2_LIB.BASEBOARD_FAB2(SCH_1):PAGE131
 C3M38    2      B CAP_A_0402V-1.0UF,6.3V,10%,X6SA    I32 @BASEBOARD_FAB2_LIB.BASEBOARD_FAB2(SCH_1):PAGE131
 C2M17    2      B CAP_0805-47UF,4V,20%,X6S,C9533A    I34 @BASEBOARD_FAB2_LIB.BASEBOARD_FAB2(SCH_1):PAGE131
 C2M11    2      B CAP_0805-47UF,4V,20%,X6S,C9533A    I35 @BASEBOARD_FAB2_LIB.BASEBOARD_FAB2(SCH_1):PAGE131
 C8A13    2      B CAP_0805-47UF,4V,20%,X6S,C9533A    I37 @BASEBOARD_FAB2_LIB.BASEBOARD_FAB2(SCH_1):PAGE131
 C2M20    2      B CAP_A_0402V-1.0UF,6.3V,10%,X6SA    I39 @BASEBOARD_FAB2_LIB.BASEBOARD_FAB2(SCH_1):PAGE131
 C2N13    2      B CAP_A_0402V-1.0UF,6.3V,10%,X6SA    I40 @BASEBOARD_FAB2_LIB.BASEBOARD_FAB2(SCH_1):PAGE131
  C2N2    2      B CAP_A_0402V-1.0UF,6.3V,10%,X6SA    I41 @BASEBOARD_FAB2_LIB.BASEBOARD_FAB2(SCH_1):PAGE131
 C3M43    2      B CAP_A_0402V-1.0UF,6.3V,10%,X6SA    I42 @BASEBOARD_FAB2_LIB.BASEBOARD_FAB2(SCH_1):PAGE131
  C2N7    2      B CAP_A_0402V-1.0UF,6.3V,10%,X6SA    I43 @BASEBOARD_FAB2_LIB.BASEBOARD_FAB2(SCH_1):PAGE131
 C3M39    2      B CAP_A_0402V-1.0UF,6.3V,10%,X6SA    I44 @BASEBOARD_FAB2_LIB.BASEBOARD_FAB2(SCH_1):PAGE131
 C3M42    2      B CAP_A_0402V-1.0UF,6.3V,10%,X6SA    I45 @BASEBOARD_FAB2_LIB.BASEBOARD_FAB2(SCH_1):PAGE131
  C2N8    2      B CAP_A_0402V-1.0UF,6.3V,10%,X6SA    I47 @BASEBOARD_FAB2_LIB.BASEBOARD_FAB2(SCH_1):PAGE131
 C2M13    2      B CAP_A_0603V-22.0UF,4V,20%,X6S,A    I48 @BASEBOARD_FAB2_LIB.BASEBOARD_FAB2(SCH_1):PAGE131
 C2N10    2      B CAP_A_0603V-22.0UF,4V,20%,X6S,A    I50 @BASEBOARD_FAB2_LIB.BASEBOARD_FAB2(SCH_1):PAGE131
 C2M12    2      B CAP_A_0603V-22.0UF,4V,20%,X6S,A    I52 @BASEBOARD_FAB2_LIB.BASEBOARD_FAB2(SCH_1):PAGE131
 C3L25    2      B CAP_A_0603V-22.0UF,4V,20%,X6S,A     I1 @BASEBOARD_FAB2_LIB.BASEBOARD_FAB2(SCH_1):PAGE132
  C3M7    2      B CAP_A_0603V-22.0UF,4V,20%,X6S,A     I2 @BASEBOARD_FAB2_LIB.BASEBOARD_FAB2(SCH_1):PAGE132
 C3L26    2      B CAP_A_0603V-22.0UF,4V,20%,X6S,A     I3 @BASEBOARD_FAB2_LIB.BASEBOARD_FAB2(SCH_1):PAGE132
 C3L27    2      B CAP_A_0603V-22.0UF,4V,20%,X6S,A     I4 @BASEBOARD_FAB2_LIB.BASEBOARD_FAB2(SCH_1):PAGE132
  C3M6    2      B CAP_A_0603V-22.0UF,4V,20%,X6S,A     I6 @BASEBOARD_FAB2_LIB.BASEBOARD_FAB2(SCH_1):PAGE132
  C7C9    2      B CAP_A_0603V-22.0UF,4V,20%,X6S,A     I7 @BASEBOARD_FAB2_LIB.BASEBOARD_FAB2(SCH_1):PAGE132
 C3N27    2      B CAP_A_0603V-22.0UF,4V,20%,X6S,A     I8 @BASEBOARD_FAB2_LIB.BASEBOARD_FAB2(SCH_1):PAGE132
 C3N30    2      B CAP_A_0603V-22.0UF,4V,20%,X6S,A     I9 @BASEBOARD_FAB2_LIB.BASEBOARD_FAB2(SCH_1):PAGE132
 C7A36    2      B CAP_A_0603V-22.0UF,4V,20%,X6S,A    I11 @BASEBOARD_FAB2_LIB.BASEBOARD_FAB2(SCH_1):PAGE132
 C3N12    2      B CAP_A_0603V-22.0UF,4V,20%,X6S,A    I12 @BASEBOARD_FAB2_LIB.BASEBOARD_FAB2(SCH_1):PAGE132
 C3N10    2      B CAP_A_0603V-22.0UF,4V,20%,X6S,A    I13 @BASEBOARD_FAB2_LIB.BASEBOARD_FAB2(SCH_1):PAGE132
 C3N24    2      B CAP_A_0603V-22.0UF,4V,20%,X6S,A    I16 @BASEBOARD_FAB2_LIB.BASEBOARD_FAB2(SCH_1):PAGE132
 C3N28    2      B CAP_A_0603V-22.0UF,4V,20%,X6S,A    I17 @BASEBOARD_FAB2_LIB.BASEBOARD_FAB2(SCH_1):PAGE132
 C3N11    2      B CAP_A_0603V-22.0UF,4V,20%,X6S,A    I19 @BASEBOARD_FAB2_LIB.BASEBOARD_FAB2(SCH_1):PAGE132
 C3N31    2      B CAP_A_0603V-22.0UF,4V,20%,X6S,A    I20 @BASEBOARD_FAB2_LIB.BASEBOARD_FAB2(SCH_1):PAGE132
 C7A33    2      B CAP_0805-47UF,4V,20%,X6S,C9533A    I23 @BASEBOARD_FAB2_LIB.BASEBOARD_FAB2(SCH_1):PAGE132
  C7B4    2      B CAP_0805-47UF,4V,20%,X6S,C9533A    I24 @BASEBOARD_FAB2_LIB.BASEBOARD_FAB2(SCH_1):PAGE132
  C2N9    2      B CAP_A_0402V-1.0UF,6.3V,10%,X6SA    I26 @BASEBOARD_FAB2_LIB.BASEBOARD_FAB2(SCH_1):PAGE132
  C2N3    2      B CAP_A_0402V-1.0UF,6.3V,10%,X6SA    I27 @BASEBOARD_FAB2_LIB.BASEBOARD_FAB2(SCH_1):PAGE132
  C2N4    2      B CAP_A_0402V-1.0UF,6.3V,10%,X6SA    I28 @BASEBOARD_FAB2_LIB.BASEBOARD_FAB2(SCH_1):PAGE132
 C2N12    2      B CAP_A_0402V-1.0UF,6.3V,10%,X6SA    I29 @BASEBOARD_FAB2_LIB.BASEBOARD_FAB2(SCH_1):PAGE132
 C2N11    2      B CAP_A_0402V-1.0UF,6.3V,10%,X6SA    I30 @BASEBOARD_FAB2_LIB.BASEBOARD_FAB2(SCH_1):PAGE132
 C3N19    2      B CAP_A_0402V-1.0UF,6.3V,10%,X6SA    I31 @BASEBOARD_FAB2_LIB.BASEBOARD_FAB2(SCH_1):PAGE132
  C3N3    2      B CAP_A_0402V-1.0UF,6.3V,10%,X6SA    I32 @BASEBOARD_FAB2_LIB.BASEBOARD_FAB2(SCH_1):PAGE132
  C3N1    2      B CAP_A_0402V-1.0UF,6.3V,10%,X6SA    I34 @BASEBOARD_FAB2_LIB.BASEBOARD_FAB2(SCH_1):PAGE132
  C3N7    2      B CAP_A_0402V-1.0UF,6.3V,10%,X6SA    I35 @BASEBOARD_FAB2_LIB.BASEBOARD_FAB2(SCH_1):PAGE132
 C3N16    2      B CAP_A_0402V-1.0UF,6.3V,10%,X6SA    I36 @BASEBOARD_FAB2_LIB.BASEBOARD_FAB2(SCH_1):PAGE132
 C7A32    2      B CAP_0805-47UF,4V,20%,X6S,C9533A    I38 @BASEBOARD_FAB2_LIB.BASEBOARD_FAB2(SCH_1):PAGE132
 C7A31    2      B CAP_0805-47UF,4V,20%,X6S,C9533A    I40 @BASEBOARD_FAB2_LIB.BASEBOARD_FAB2(SCH_1):PAGE132
 C3N18    2      B CAP_A_0402V-1.0UF,6.3V,10%,X6SA    I42 @BASEBOARD_FAB2_LIB.BASEBOARD_FAB2(SCH_1):PAGE132
  C3N2    2      B CAP_A_0402V-1.0UF,6.3V,10%,X6SA    I43 @BASEBOARD_FAB2_LIB.BASEBOARD_FAB2(SCH_1):PAGE132
  C3N6    2      B CAP_A_0402V-1.0UF,6.3V,10%,X6SA    I44 @BASEBOARD_FAB2_LIB.BASEBOARD_FAB2(SCH_1):PAGE132
 C3N17    2      B CAP_A_0402V-1.0UF,6.3V,10%,X6SA    I45 @BASEBOARD_FAB2_LIB.BASEBOARD_FAB2(SCH_1):PAGE132
  C3N4    2      B CAP_A_0402V-1.0UF,6.3V,10%,X6SA    I46 @BASEBOARD_FAB2_LIB.BASEBOARD_FAB2(SCH_1):PAGE132
  C3N5    2      B CAP_A_0402V-1.0UF,6.3V,10%,X6SA    I48 @BASEBOARD_FAB2_LIB.BASEBOARD_FAB2(SCH_1):PAGE132
 C3N15    2      B CAP_A_0402V-1.0UF,6.3V,10%,X6SA    I49 @BASEBOARD_FAB2_LIB.BASEBOARD_FAB2(SCH_1):PAGE132
 C3N20    2      B CAP_A_0402V-1.0UF,6.3V,10%,X6SA    I51 @BASEBOARD_FAB2_LIB.BASEBOARD_FAB2(SCH_1):PAGE132
 C3L23    2      B CAP_A_0603V-22.0UF,4V,20%,X6S,A    I52 @BASEBOARD_FAB2_LIB.BASEBOARD_FAB2(SCH_1):PAGE132
 C3L22    2      B CAP_A_0603V-22.0UF,4V,20%,X6S,A    I54 @BASEBOARD_FAB2_LIB.BASEBOARD_FAB2(SCH_1):PAGE132
 C3L24    2      B CAP_A_0603V-22.0UF,4V,20%,X6S,A    I56 @BASEBOARD_FAB2_LIB.BASEBOARD_FAB2(SCH_1):PAGE132
  R3N3    1      A RES_0402-2.0K,1%,1/16W,CHIP,G2A   I120 @BASEBOARD_FAB2_LIB.BASEBOARD_FAB2(SCH_1):PAGE133
 R2N12    1      A RES_0402-10.0K,1%,1/16W,EMPTY,A   I122 @BASEBOARD_FAB2_LIB.BASEBOARD_FAB2(SCH_1):PAGE133
  Q7D1    2    SRC FET_N_SOT23-2N7002,FET,C79254-A    I10 @BASEBOARD_FAB2_LIB.BASEBOARD_FAB2(SCH_1):PAGE134
 R2N24    2      B RES_0402-1.00K,1%,1/16W,EMPTY,A   I113 @BASEBOARD_FAB2_LIB.BASEBOARD_FAB2(SCH_1):PAGE135
  J8G2    5    IO5 CONN12_C73564003_PIP-CONN,C735A   I124 @BASEBOARD_FAB2_LIB.BASEBOARD_FAB2(SCH_1):PAGE135
  J8G2    6    IO6 CONN12_C73564003_PIP-CONN,C735A   I124 @BASEBOARD_FAB2_LIB.BASEBOARD_FAB2(SCH_1):PAGE135
  J8G2   11   IO11 CONN12_C73564003_PIP-CONN,C735A   I124 @BASEBOARD_FAB2_LIB.BASEBOARD_FAB2(SCH_1):PAGE135
  J8G2   12   IO12 CONN12_C73564003_PIP-CONN,C735A   I124 @BASEBOARD_FAB2_LIB.BASEBOARD_FAB2(SCH_1):PAGE135
  J9A1    1    IO1 CONN4_D42317002_PIP-CONN,D4231A   I131 @BASEBOARD_FAB2_LIB.BASEBOARD_FAB2(SCH_1):PAGE135
  J9A1    3    IO3 CONN4_D42317002_PIP-CONN,D4231A   I131 @BASEBOARD_FAB2_LIB.BASEBOARD_FAB2(SCH_1):PAGE135
 R7G28    2      B RES_0402-1.00K,1%,1/16W,CHIP,GA   I102 @BASEBOARD_FAB2_LIB.BASEBOARD_FAB2(SCH_1):PAGE136
  C8E8    2      B CAP_A_0402V-0.1UF,16V,10%,X7R,A   I128 @BASEBOARD_FAB2_LIB.BASEBOARD_FAB2(SCH_1):PAGE136
  Q8E1    2    SRC FET_N_SOT23LF-2N7002,FET,C7925A   I134 @BASEBOARD_FAB2_LIB.BASEBOARD_FAB2(SCH_1):PAGE136
 R8E16    2      B RES_0402-20.0K,1%,1/16W,CHIP,GA   I140 @BASEBOARD_FAB2_LIB.BASEBOARD_FAB2(SCH_1):PAGE136
 R7G29    2      B RES_0402-1.00K,1%,1/16W,CHIP,GA   I148 @BASEBOARD_FAB2_LIB.BASEBOARD_FAB2(SCH_1):PAGE136
 R3T14    2      B RES_0402-10.0K,1%,1/16W,CHIP,GA   I156 @BASEBOARD_FAB2_LIB.BASEBOARD_FAB2(SCH_1):PAGE136
 R7C11    1      A RES_0402-1.0M,1%,1/16W,EMPTY,GA    I11 @BASEBOARD_FAB2_LIB.BASEBOARD_FAB2(SCH_1):PAGE137
 C7C19    2      B CAP_A_0402V-1.0UF,6.3V,10%,X6SA    I14 @BASEBOARD_FAB2_LIB.BASEBOARD_FAB2(SCH_1):PAGE137
 R1U63    2      B RES_0402-1.00K,1%,1/16W,CHIP,GA    I15 @BASEBOARD_FAB2_LIB.BASEBOARD_FAB2(SCH_1):PAGE137
 C3N32    2      B CAP_A_0402V-1.0UF,6.3V,10%,X6SA    I20 @BASEBOARD_FAB2_LIB.BASEBOARD_FAB2(SCH_1):PAGE137
 R1U64    2      B RES_0402-1.00K,1%,1/16W,CHIP,GA    I69 @BASEBOARD_FAB2_LIB.BASEBOARD_FAB2(SCH_1):PAGE137
 EU9E1   65    GND SPRINGVILLE_SM1-IC,G47144-004    I72 @BASEBOARD_FAB2_LIB.BASEBOARD_FAB2(SCH_1):PAGE139
  C9E8    2      B CAP_0402LF-22.0PF,50V,5%,COG,AA   I111 @BASEBOARD_FAB2_LIB.BASEBOARD_FAB2(SCH_1):PAGE139
  C9E9    2      B CAP_0402LF-22.0PF,50V,5%,COG,AA   I112 @BASEBOARD_FAB2_LIB.BASEBOARD_FAB2(SCH_1):PAGE139
  C1T4    2      B CAP_0603-10UF,6.3V,20%,X6S,E15A   I134 @BASEBOARD_FAB2_LIB.BASEBOARD_FAB2(SCH_1):PAGE139
 C1R30    2      B CAP_0603-10UF,6.3V,20%,X6S,E15A   I135 @BASEBOARD_FAB2_LIB.BASEBOARD_FAB2(SCH_1):PAGE139
 C1R22    2      B CAP_0603-10UF,6.3V,20%,X6S,E15A   I136 @BASEBOARD_FAB2_LIB.BASEBOARD_FAB2(SCH_1):PAGE139
  C9F2    2      B CAP_1210-47UF,16V,20%,EMPTY,D3A   I140 @BASEBOARD_FAB2_LIB.BASEBOARD_FAB2(SCH_1):PAGE139
 C1R13    2      B CAP_0603-10UF,6.3V,20%,X6S,E15A   I142 @BASEBOARD_FAB2_LIB.BASEBOARD_FAB2(SCH_1):PAGE139
 C1R20    2      B CAP_A_0402V-0.1UF,16V,10%,X7R,A   I143 @BASEBOARD_FAB2_LIB.BASEBOARD_FAB2(SCH_1):PAGE139
  C1T3    2      B CAP_A_0402V-0.1UF,16V,10%,X7R,A   I144 @BASEBOARD_FAB2_LIB.BASEBOARD_FAB2(SCH_1):PAGE139
 C1R14    2      B CAP_A_0402V-0.1UF,16V,10%,X7R,A   I145 @BASEBOARD_FAB2_LIB.BASEBOARD_FAB2(SCH_1):PAGE139
 C1R21    2      B CAP_A_0402V-0.1UF,16V,10%,X7R,A   I146 @BASEBOARD_FAB2_LIB.BASEBOARD_FAB2(SCH_1):PAGE139
 C1R26    2      B CAP_A_0402V-0.1UF,16V,10%,X7R,A   I149 @BASEBOARD_FAB2_LIB.BASEBOARD_FAB2(SCH_1):PAGE139
 C1R29    2      B CAP_A_0402V-0.1UF,16V,10%,X7R,A   I150 @BASEBOARD_FAB2_LIB.BASEBOARD_FAB2(SCH_1):PAGE139
 C1R19    2      B CAP_A_0402V-0.1UF,16V,10%,X7R,A   I151 @BASEBOARD_FAB2_LIB.BASEBOARD_FAB2(SCH_1):PAGE139
 C1R31    2      B CAP_A_0402V-0.1UF,16V,10%,X7R,A   I152 @BASEBOARD_FAB2_LIB.BASEBOARD_FAB2(SCH_1):PAGE139
 C1R17    2      B CAP_0603-10UF,6.3V,20%,X6S,E15A   I153 @BASEBOARD_FAB2_LIB.BASEBOARD_FAB2(SCH_1):PAGE139
  C9E6    2      B CAP_1210-47UF,16V,20%,EMPTY,D3A   I155 @BASEBOARD_FAB2_LIB.BASEBOARD_FAB2(SCH_1):PAGE139
 C1R18    2      B CAP_A_0402V-0.1UF,16V,10%,X7R,A   I157 @BASEBOARD_FAB2_LIB.BASEBOARD_FAB2(SCH_1):PAGE139
  C1T5    2      B CAP_A_0402V-0.1UF,16V,10%,X7R,A   I158 @BASEBOARD_FAB2_LIB.BASEBOARD_FAB2(SCH_1):PAGE139
 C1R24    2      B CAP_A_0402V-0.1UF,16V,10%,X7R,A   I159 @BASEBOARD_FAB2_LIB.BASEBOARD_FAB2(SCH_1):PAGE139
 C1R15    2      B CAP_A_0402V-0.1UF,16V,10%,X7R,A   I160 @BASEBOARD_FAB2_LIB.BASEBOARD_FAB2(SCH_1):PAGE139
 C1R16    2      B CAP_0603-10UF,6.3V,20%,X6S,E15A   I161 @BASEBOARD_FAB2_LIB.BASEBOARD_FAB2(SCH_1):PAGE139
  C9E1    2      B CAP_A_0603V-22.0UF,4V,20%,EMPTA   I163 @BASEBOARD_FAB2_LIB.BASEBOARD_FAB2(SCH_1):PAGE139
 R9E23    2      B RES_0402-4.99K,1%,1/16W,CHIP,GA   I174 @BASEBOARD_FAB2_LIB.BASEBOARD_FAB2(SCH_1):PAGE139
 R9E13    2      B RES_0402-10.0K,1%,1/16W,CHIP,GA   I212 @BASEBOARD_FAB2_LIB.BASEBOARD_FAB2(SCH_1):PAGE139
 R1R12    2      B RES_0402-10.0K,1%,1/16W,CHIP,GA   I213 @BASEBOARD_FAB2_LIB.BASEBOARD_FAB2(SCH_1):PAGE139
  R1T1    2      B RES_0402-10.0K,1%,1/16W,CHIP,GA   I214 @BASEBOARD_FAB2_LIB.BASEBOARD_FAB2(SCH_1):PAGE139
 C9E12    2      B CAP_A_0603V-22.0UF,4V,20%,EMPTA   I241 @BASEBOARD_FAB2_LIB.BASEBOARD_FAB2(SCH_1):PAGE139
  U9E1    4    VSS M25PE16_SM-IC,H77797-001     I1 @BASEBOARD_FAB2_LIB.BASEBOARD_FAB2(SCH_1):PAGE140
 C1R25    2      B CAP_A_0402V-0.1UF,16V,10%,X7R,A     I3 @BASEBOARD_FAB2_LIB.BASEBOARD_FAB2(SCH_1):PAGE140
  R1R6    2      B RES_0402-3.32K,1%,1/16W,EMPTY,A    I14 @BASEBOARD_FAB2_LIB.BASEBOARD_FAB2(SCH_1):PAGE140
  C9G7    2      B CAP_A_0402V-0.1UF,16V,10%,X7R,A    I33 @BASEBOARD_FAB2_LIB.BASEBOARD_FAB2(SCH_1):PAGE141
  C9G2    2      B CAP_0402LF-470PF,50V,10%,X7R,AA    I36 @BASEBOARD_FAB2_LIB.BASEBOARD_FAB2(SCH_1):PAGE141
  C9G4    2      B CAP_A_0402V-0.1UF,16V,10%,X7R,A    I46 @BASEBOARD_FAB2_LIB.BASEBOARD_FAB2(SCH_1):PAGE141
  C9G6    2      B CAP_A_0402V-0.1UF,16V,10%,X7R,A    I47 @BASEBOARD_FAB2_LIB.BASEBOARD_FAB2(SCH_1):PAGE141
  C9G5    2      B CAP_0402-1.0UF,16V,10%,X7S,G71A    I48 @BASEBOARD_FAB2_LIB.BASEBOARD_FAB2(SCH_1):PAGE141
  C9G1    2      B CAP_0402LF-470PF,50V,10%,X7R,AA    I58 @BASEBOARD_FAB2_LIB.BASEBOARD_FAB2(SCH_1):PAGE141
  C9G3    2      B CAP_0402LF-470PF,50V,10%,X7R,AA    I59 @BASEBOARD_FAB2_LIB.BASEBOARD_FAB2(SCH_1):PAGE141
 C9F22    2      B CAP_0402LF-470PF,50V,10%,X7R,AA    I60 @BASEBOARD_FAB2_LIB.BASEBOARD_FAB2(SCH_1):PAGE141
 R1U51    1      A RES_0402-0.0,5%,1/16W,CHIP,G21A   I112 @BASEBOARD_FAB2_LIB.BASEBOARD_FAB2(SCH_1):PAGE141
  R1U3    1      A RES_0402-0.0,5%,1/16W,CHIP,G21A   I114 @BASEBOARD_FAB2_LIB.BASEBOARD_FAB2(SCH_1):PAGE141
  C8E5    2      B CAP_A_0402V-0.1UF,16V,10%,X7R,A    I20 @BASEBOARD_FAB2_LIB.BASEBOARD_FAB2(SCH_1):PAGE142
  U9G1    7 GND<0> GTL2014_SM-IC,D66151-001     I1 @BASEBOARD_FAB2_LIB.BASEBOARD_FAB2(SCH_1):PAGE152
  U9G1    8 GND<1> GTL2014_SM-IC,D66151-001     I1 @BASEBOARD_FAB2_LIB.BASEBOARD_FAB2(SCH_1):PAGE152
  U9G1   11 GND<2> GTL2014_SM-IC,D66151-001     I1 @BASEBOARD_FAB2_LIB.BASEBOARD_FAB2(SCH_1):PAGE152
 R1U30    2      B RES_0402-1.00K,1%,1/16W,CHIP,GA     I2 @BASEBOARD_FAB2_LIB.BASEBOARD_FAB2(SCH_1):PAGE152
 C1U19    2      B CAP_0402-1.0UF,16V,10%,X6S,D97A    I18 @BASEBOARD_FAB2_LIB.BASEBOARD_FAB2(SCH_1):PAGE152
 R1U37    2      B RES_0402-100.0,1%,1/16W,CHIP,GA    I26 @BASEBOARD_FAB2_LIB.BASEBOARD_FAB2(SCH_1):PAGE152
 C1U22    2      B CAP_A_0402V-0.1UF,16V,10%,X7R,A    I27 @BASEBOARD_FAB2_LIB.BASEBOARD_FAB2(SCH_1):PAGE152
  C7F2    2      B CAP_A_0402V-1.0UF,6.3V,10%,X6SA   I130 @BASEBOARD_FAB2_LIB.BASEBOARD_FAB2(SCH_1):PAGE153
  C7F1    2      B CAP_A_0402V-0.01UF,25V,10%,X7RA   I131 @BASEBOARD_FAB2_LIB.BASEBOARD_FAB2(SCH_1):PAGE153
  C3T5    2      B CAP_A_0402V-0.01UF,25V,10%,X7RA   I136 @BASEBOARD_FAB2_LIB.BASEBOARD_FAB2(SCH_1):PAGE153
  C3T4    2      B CAP_A_0402V-1.0UF,6.3V,10%,X6SA   I138 @BASEBOARD_FAB2_LIB.BASEBOARD_FAB2(SCH_1):PAGE153
  U7F1   10    GND W25Q256_XSOI-IC,H25002-001   I146 @BASEBOARD_FAB2_LIB.BASEBOARD_FAB2(SCH_1):PAGE153
  U3T1   10    GND W25Q256_XSOI-IC,H25002-001   I165 @BASEBOARD_FAB2_LIB.BASEBOARD_FAB2(SCH_1):PAGE153
 R7F30    2      B RES_0402-10.0K,1%,1/16W,EMPTY,A   I170 @BASEBOARD_FAB2_LIB.BASEBOARD_FAB2(SCH_1):PAGE153
  R3T9    2      B RES_0402-10.0K,1%,1/16W,EMPTY,A   I179 @BASEBOARD_FAB2_LIB.BASEBOARD_FAB2(SCH_1):PAGE153
 C8E18    2      B CAP_A_0402V-0.1UF,16V,10%,X7R,A    I14 @BASEBOARD_FAB2_LIB.BASEBOARD_FAB2(SCH_1):PAGE154
  U8F1   15     EN PI3B3257A_TSSOPLF-IC,E16801-001    I74 @BASEBOARD_FAB2_LIB.BASEBOARD_FAB2(SCH_1):PAGE154
  U8F1    8    GND PI3B3257A_TSSOPLF-IC,E16801-001    I74 @BASEBOARD_FAB2_LIB.BASEBOARD_FAB2(SCH_1):PAGE154
  U2T1   15     EN PI3B3257A_TSSOPLF-IC,E16801-001    I75 @BASEBOARD_FAB2_LIB.BASEBOARD_FAB2(SCH_1):PAGE154
  U2T1    8    GND PI3B3257A_TSSOPLF-IC,E16801-001    I75 @BASEBOARD_FAB2_LIB.BASEBOARD_FAB2(SCH_1):PAGE154
  C2T1    2      B CAP_A_0402V-0.1UF,16V,10%,X7R,A    I94 @BASEBOARD_FAB2_LIB.BASEBOARD_FAB2(SCH_1):PAGE154
  Q8F1    2    SRC FET_N_SOT23LF-2N7002,FET,C7925A   I126 @BASEBOARD_FAB2_LIB.BASEBOARD_FAB2(SCH_1):PAGE154
  R1U6    2      B RES_0402-10.0K,1%,1/16W,CHIP,GA   I128 @BASEBOARD_FAB2_LIB.BASEBOARD_FAB2(SCH_1):PAGE154
 C2T12    2      B CAP_A_0402V-0.1UF,16V,10%,X7R,A   I132 @BASEBOARD_FAB2_LIB.BASEBOARD_FAB2(SCH_1):PAGE154
  C2T8    2      B CAP_A_0402V-0.1UF,16V,10%,X7R,A   I135 @BASEBOARD_FAB2_LIB.BASEBOARD_FAB2(SCH_1):PAGE154
  C9A1    2      B CAP_A_0402V-0.1UF,16V,10%,X7R,A   I127 @BASEBOARD_FAB2_LIB.BASEBOARD_FAB2(SCH_1):PAGE155
  J9A2   13   IO13 CONN14_H54902001_PIP-CONN,H549A   I171 @BASEBOARD_FAB2_LIB.BASEBOARD_FAB2(SCH_1):PAGE155
 C1T56    2      B CAP_A_0402V-0.1UF,16V,10%,X7R,A   I184 @BASEBOARD_FAB2_LIB.BASEBOARD_FAB2(SCH_1):PAGE155
  Q1L2    4 SOURCE<0> FET_N_DUAL_SMLF-NTJD4001N,FET,A   I187 @BASEBOARD_FAB2_LIB.BASEBOARD_FAB2(SCH_1):PAGE155
 C2T35    2      B CAP_A_0402V-0.1UF,16V,10%,X7R,A   I273 @BASEBOARD_FAB2_LIB.BASEBOARD_FAB2(SCH_1):PAGE156
 C8F16    2      B CAP_A_0402V-0.1UF,16V,10%,X7R,A   I275 @BASEBOARD_FAB2_LIB.BASEBOARD_FAB2(SCH_1):PAGE156
  J9B2    2    IO2 CONN3_C95678002_PIP-CONN,C9567A   I281 @BASEBOARD_FAB2_LIB.BASEBOARD_FAB2(SCH_1):PAGE156
  J8C1    2    IO2 CONN3_C95678002_PIP-CONN,C9567A   I285 @BASEBOARD_FAB2_LIB.BASEBOARD_FAB2(SCH_1):PAGE156
 R6N14    1      A RES_0402-1.00K,1%,1/16W,CHIP,GA   I302 @BASEBOARD_FAB2_LIB.BASEBOARD_FAB2(SCH_1):PAGE156
 R6N13    1      A RES_0402-1.00K,1%,1/16W,CHIP,GA   I303 @BASEBOARD_FAB2_LIB.BASEBOARD_FAB2(SCH_1):PAGE156
 R6N15    1      A RES_0402-1.00K,1%,1/16W,CHIP,GA   I304 @BASEBOARD_FAB2_LIB.BASEBOARD_FAB2(SCH_1):PAGE156
 R1C32    1      A RES_0402-1.00K,1%,1/16W,CHIP,GA   I312 @BASEBOARD_FAB2_LIB.BASEBOARD_FAB2(SCH_1):PAGE156
 R1C33    1      A RES_0402-1.00K,1%,1/16W,CHIP,GA   I313 @BASEBOARD_FAB2_LIB.BASEBOARD_FAB2(SCH_1):PAGE156
 R3P56    2      B RES_0402-1.00K,1%,1/16W,CHIP,GA   I333 @BASEBOARD_FAB2_LIB.BASEBOARD_FAB2(SCH_1):PAGE156
 R1C36    2      B RES_0402-1.00K,1%,1/16W,CHIP,GA   I337 @BASEBOARD_FAB2_LIB.BASEBOARD_FAB2(SCH_1):PAGE156
  Q2T1    2      E NPN_SM-MMBT3904,IC,C52245-001   I330 @BASEBOARD_FAB2_LIB.BASEBOARD_FAB2(SCH_1):PAGE157
  Q2T2    2    SRC FET_N_SOT23LF-2N7002,FET,C7925A   I340 @BASEBOARD_FAB2_LIB.BASEBOARD_FAB2(SCH_1):PAGE157
  S8E1    1      A SWITCH_D90553001_SMLF-IC,D9055A   I351 @BASEBOARD_FAB2_LIB.BASEBOARD_FAB2(SCH_1):PAGE157
 C2R12    2      B CAP_A_0402V-1.0UF,6.3V,10%,X6SA   I353 @BASEBOARD_FAB2_LIB.BASEBOARD_FAB2(SCH_1):PAGE157
  C2T3    2      B CAP_A_0402V-0.1UF,16V,10%,X7R,A   I370 @BASEBOARD_FAB2_LIB.BASEBOARD_FAB2(SCH_1):PAGE157
  C8D1    2      B CAP_A_0402V-0.1UF,16V,10%,X7R,A   I376 @BASEBOARD_FAB2_LIB.BASEBOARD_FAB2(SCH_1):PAGE157
 C1T10    2      B CAP_A_0402V-0.1UF,16V,10%,X7R,A    I70 @BASEBOARD_FAB2_LIB.BASEBOARD_FAB2(SCH_1):PAGE158
  U9F2    4    GND FSA3357_SM-IC,C63273-001    I74 @BASEBOARD_FAB2_LIB.BASEBOARD_FAB2(SCH_1):PAGE158
  U9F1    4    GND FSA3357_SM-IC,C63273-001    I75 @BASEBOARD_FAB2_LIB.BASEBOARD_FAB2(SCH_1):PAGE158
 C1T11    2      B CAP_A_0402V-0.1UF,16V,10%,X7R,A    I97 @BASEBOARD_FAB2_LIB.BASEBOARD_FAB2(SCH_1):PAGE158
  J1F2    1    IO1 CONN6_C74770005_PIP-HDR,C74770A     I1 @BASEBOARD_FAB2_LIB.BASEBOARD_FAB2(SCH_1):PAGE161
 C1E21    2      B CAP_0805-10UF,16V,10%,X6S,C953A     I3 @BASEBOARD_FAB2_LIB.BASEBOARD_FAB2(SCH_1):PAGE161
 C1E20    2      B CAP_A_0402V-0.1UF,16V,10%,X7R,A     I4 @BASEBOARD_FAB2_LIB.BASEBOARD_FAB2(SCH_1):PAGE161
  C9M5    2      B CAP_A_0402V-0.1UF,16V,10%,X7R,A    I26 @BASEBOARD_FAB2_LIB.BASEBOARD_FAB2(SCH_1):PAGE161
  C9M4    2      B CAP_0805-10UF,16V,10%,X6S,C953A    I27 @BASEBOARD_FAB2_LIB.BASEBOARD_FAB2(SCH_1):PAGE161
  J1B2    1    IO1 CONN6_C74770005_PIP-HDR,C74770A    I32 @BASEBOARD_FAB2_LIB.BASEBOARD_FAB2(SCH_1):PAGE161
  C1F9    2      B CAP_A_0402V-0.01UF,25V,10%,X7RA    I46 @BASEBOARD_FAB2_LIB.BASEBOARD_FAB2(SCH_1):PAGE161
 C1B15    2      B CAP_A_0402V-0.01UF,25V,10%,X7RA    I68 @BASEBOARD_FAB2_LIB.BASEBOARD_FAB2(SCH_1):PAGE161
 C2U27    2      B CAP_A_0402V-0.1UF,16V,10%,X7R,A    I90 @BASEBOARD_FAB2_LIB.BASEBOARD_FAB2(SCH_1):PAGE161
 C2U28    2      B CAP_A_0402V-0.1UF,16V,10%,X7R,A    I93 @BASEBOARD_FAB2_LIB.BASEBOARD_FAB2(SCH_1):PAGE161
 C1E22    2      B CAP_A_0402V-0.1UF,16V,10%,X7R,A   I113 @BASEBOARD_FAB2_LIB.BASEBOARD_FAB2(SCH_1):PAGE161
 C1B17    2      B CAP_A_0402V-0.01UF,25V,10%,X7RA   I128 @BASEBOARD_FAB2_LIB.BASEBOARD_FAB2(SCH_1):PAGE161
  C9T1    2      B CAP_A_0402V-0.01UF,25V,10%,X7RA   I137 @BASEBOARD_FAB2_LIB.BASEBOARD_FAB2(SCH_1):PAGE161
 R8F35    2      B RES_0402-1.00K,1%,1/16W,EMPTY,A    I24 @BASEBOARD_FAB2_LIB.BASEBOARD_FAB2(SCH_1):PAGE162
  C8F5    2      B CAP_A_0402V-0.01UF,25V,10%,X7RA    I28 @BASEBOARD_FAB2_LIB.BASEBOARD_FAB2(SCH_1):PAGE162
  C8F4    2      B CAP_A_0402V-1.0UF,6.3V,10%,X6SA    I30 @BASEBOARD_FAB2_LIB.BASEBOARD_FAB2(SCH_1):PAGE162
  U8F2   10    GND W25Q128_SKT16-IC,H12709-001    I32 @BASEBOARD_FAB2_LIB.BASEBOARD_FAB2(SCH_1):PAGE162
  C9M8    2      B CAP_A_0402V-0.1UF,16V,10%,X7R,A    I10 @BASEBOARD_FAB2_LIB.BASEBOARD_FAB2(SCH_1):PAGE163
  C9M7    2      B CAP_A_0402V-0.1UF,16V,10%,X7R,A    I12 @BASEBOARD_FAB2_LIB.BASEBOARD_FAB2(SCH_1):PAGE163
 R1T10    2      B RES_0402-1.00K,1%,1/16W,EMPTY,A     I5 @BASEBOARD_FAB2_LIB.BASEBOARD_FAB2(SCH_1):PAGE164
 R1T12    2      B RES_0402-1.00K,1%,1/16W,CHIP,GA     I6 @BASEBOARD_FAB2_LIB.BASEBOARD_FAB2(SCH_1):PAGE164
 R1T11    2      B RES_0402-1.00K,1%,1/16W,CHIP,GA     I7 @BASEBOARD_FAB2_LIB.BASEBOARD_FAB2(SCH_1):PAGE164
 R1U18    2      B RES_0402-1.00K,1%,1/16W,CHIP,GA    I19 @BASEBOARD_FAB2_LIB.BASEBOARD_FAB2(SCH_1):PAGE164
 R1U16    2      B RES_0402-1.00K,1%,1/16W,EMPTY,A    I20 @BASEBOARD_FAB2_LIB.BASEBOARD_FAB2(SCH_1):PAGE164
 R1U17    2      B RES_0402-1.00K,1%,1/16W,CHIP,GA    I21 @BASEBOARD_FAB2_LIB.BASEBOARD_FAB2(SCH_1):PAGE164
 R1U15    2      B RES_0402-1.00K,1%,1/16W,EMPTY,A    I22 @BASEBOARD_FAB2_LIB.BASEBOARD_FAB2(SCH_1):PAGE164
 R2N18    2      B RES_0402-1.00K,1%,1/16W,CHIP,GA    I32 @BASEBOARD_FAB2_LIB.BASEBOARD_FAB2(SCH_1):PAGE164
 EU9G1    4    GND ADC128D818_SM-IC,H63642-001    I52 @BASEBOARD_FAB2_LIB.BASEBOARD_FAB2(SCH_1):PAGE165
 R1U45    2      B RES_0402-4.75K,1%,1/16W,CHIP,GA    I55 @BASEBOARD_FAB2_LIB.BASEBOARD_FAB2(SCH_1):PAGE165
 R1U48    2      B RES_0402-4.75K,1%,1/16W,CHIP,GA    I56 @BASEBOARD_FAB2_LIB.BASEBOARD_FAB2(SCH_1):PAGE165
 C9G19    2      B CAP_A_0402V-0.1UF,16V,10%,X7R,A    I61 @BASEBOARD_FAB2_LIB.BASEBOARD_FAB2(SCH_1):PAGE165
 C1U20    2      B CAP_0805-10UF,16V,10%,X7R,G106A    I67 @BASEBOARD_FAB2_LIB.BASEBOARD_FAB2(SCH_1):PAGE165
 R7D15    2      B RES_0402-348,1%,1/16W,CHIP,G21A    I32 @BASEBOARD_FAB2_LIB.BASEBOARD_FAB2(SCH_1):PAGE166
  U9B4    5    GND TMP421_TSSOP-IC,G62962-001     I1 @BASEBOARD_FAB2_LIB.BASEBOARD_FAB2(SCH_1):PAGE167
  R9B8    2      B RES_0402-1.00K,1%,1/16W,CHIP,GA    I10 @BASEBOARD_FAB2_LIB.BASEBOARD_FAB2(SCH_1):PAGE167
  U1E1    5    GND TMP421_TSSOP-IC,G62962-001    I30 @BASEBOARD_FAB2_LIB.BASEBOARD_FAB2(SCH_1):PAGE167
  C9B7    2      B CAP_A_0402V-0.1UF,16V,10%,X7R,A    I39 @BASEBOARD_FAB2_LIB.BASEBOARD_FAB2(SCH_1):PAGE167
 C9R14    2      B CAP_A_0402V-0.1UF,16V,10%,X7R,A    I41 @BASEBOARD_FAB2_LIB.BASEBOARD_FAB2(SCH_1):PAGE167
 C9R13    2      B CAP_A_0402V-0.1UF,16V,10%,X7R,A    I42 @BASEBOARD_FAB2_LIB.BASEBOARD_FAB2(SCH_1):PAGE167
  U8D4    1     A0 AT24C64_SOICLF-IC,C47049-001-GA    I49 @BASEBOARD_FAB2_LIB.BASEBOARD_FAB2(SCH_1):PAGE167
  U8D4    2     A1 AT24C64_SOICLF-IC,C47049-001-GA    I49 @BASEBOARD_FAB2_LIB.BASEBOARD_FAB2(SCH_1):PAGE167
 R8D27    2      B RES_0402-1.00K,1%,1/16W,CHIP,GA    I50 @BASEBOARD_FAB2_LIB.BASEBOARD_FAB2(SCH_1):PAGE167
  Q1L3    2      E NPN_SM-MMBT3904,IC,C52245-001     I8 @BASEBOARD_FAB2_LIB.BASEBOARD_FAB2(SCH_1):PAGE168
  Q1L4    1 SOURCE<0> FET_N_DUAL_SMLF-2N7002DW,FET,DA    I19 @BASEBOARD_FAB2_LIB.BASEBOARD_FAB2(SCH_1):PAGE168
 C1U21    2      B CAP_0402LF-47.0PF,50V,5%,COG,AA    I56 @BASEBOARD_FAB2_LIB.BASEBOARD_FAB2(SCH_1):PAGE169
 C9G21    2      B CAP_0402LF-47.0PF,50V,5%,COG,AA    I68 @BASEBOARD_FAB2_LIB.BASEBOARD_FAB2(SCH_1):PAGE169
 C9G17    2      B CAP_0402LF-47.0PF,50V,5%,COG,AA    I80 @BASEBOARD_FAB2_LIB.BASEBOARD_FAB2(SCH_1):PAGE169
 R1U33    2      B RES_0402-1.00K,1%,1/16W,CHIP,GA    I83 @BASEBOARD_FAB2_LIB.BASEBOARD_FAB2(SCH_1):PAGE169
 C9G20    2      B CAP_0402LF-47.0PF,50V,5%,COG,AA    I86 @BASEBOARD_FAB2_LIB.BASEBOARD_FAB2(SCH_1):PAGE169
 R9G26    2      B RES_0402-100.0K,1%,1/16W,CHIP,A   I106 @BASEBOARD_FAB2_LIB.BASEBOARD_FAB2(SCH_1):PAGE169
 C9G22    2      B CAP_0402LF-10.0PF,50V,5%,COG,AA   I108 @BASEBOARD_FAB2_LIB.BASEBOARD_FAB2(SCH_1):PAGE169
 R1U38    2      B RES_0402-8.2K,1%,1/16W,CHIP,G2A   I114 @BASEBOARD_FAB2_LIB.BASEBOARD_FAB2(SCH_1):PAGE169
 R1U44    2      B RES_0402-3.48K,1.0%,1/16W,CHIPA   I116 @BASEBOARD_FAB2_LIB.BASEBOARD_FAB2(SCH_1):PAGE169
 C9G15    2      B CAP_0402LF-47.0PF,50V,5%,COG,AA   I139 @BASEBOARD_FAB2_LIB.BASEBOARD_FAB2(SCH_1):PAGE169
 R1U28    2      B RES_0402-3.48K,1.0%,1/16W,CHIPA   I142 @BASEBOARD_FAB2_LIB.BASEBOARD_FAB2(SCH_1):PAGE169
 C9G14    2      B CAP_0402LF-47.0PF,50V,5%,COG,AA   I146 @BASEBOARD_FAB2_LIB.BASEBOARD_FAB2(SCH_1):PAGE169
 R1U27    2      B RES_0402-8.2K,1%,1/16W,CHIP,G2A   I149 @BASEBOARD_FAB2_LIB.BASEBOARD_FAB2(SCH_1):PAGE169
 C9G18    2      B CAP_0402LF-47.0PF,50V,5%,COG,AA   I153 @BASEBOARD_FAB2_LIB.BASEBOARD_FAB2(SCH_1):PAGE169
  Q9G1    1 SOURCE<0> FET_N_DUAL_SMLF-NTJD4001N,FET,A   I162 @BASEBOARD_FAB2_LIB.BASEBOARD_FAB2(SCH_1):PAGE169
  C2P1    2      B CAP_A_0402V-0.1UF,16V,10%,X7R,A     I8 @BASEBOARD_FAB2_LIB.BASEBOARD_FAB2(SCH_1):PAGE170
 C1R27    2      B CAP_A_0402V-0.1UF,16V,10%,X7R,A    I30 @BASEBOARD_FAB2_LIB.BASEBOARD_FAB2(SCH_1):PAGE170
  C8D2    2      B CAP_A_0402V-0.1UF,16V,10%,X7R,A    I33 @BASEBOARD_FAB2_LIB.BASEBOARD_FAB2(SCH_1):PAGE170
  C8E2    2      B CAP_A_0402V-0.1UF,16V,10%,X7R,A    I40 @BASEBOARD_FAB2_LIB.BASEBOARD_FAB2(SCH_1):PAGE170
  C8D3    2      B CAP_0402LF-470PF,50V,10%,EMPTYA    I42 @BASEBOARD_FAB2_LIB.BASEBOARD_FAB2(SCH_1):PAGE170
 C1R28    2      B CAP_A_0402V-0.1UF,16V,10%,X7R,A    I49 @BASEBOARD_FAB2_LIB.BASEBOARD_FAB2(SCH_1):PAGE170
  Q2P1    2    SRC FET_N_SOT23LF-2N7002,FET,C7925A    I58 @BASEBOARD_FAB2_LIB.BASEBOARD_FAB2(SCH_1):PAGE170
 R2P11    2      B RES_0402-1.00K,1%,1/16W,EMPTY,A    I63 @BASEBOARD_FAB2_LIB.BASEBOARD_FAB2(SCH_1):PAGE170
  Q8F2    2    SRC FET_N_SOT23LF-2N7002,FET,C7925A    I67 @BASEBOARD_FAB2_LIB.BASEBOARD_FAB2(SCH_1):PAGE170
  J8A3    7 GND<0> CONN7_E82125014_PIP_TH-EMPTY,EA    I17 @BASEBOARD_FAB2_LIB.BASEBOARD_FAB2(SCH_1):PAGE172
  J8A3    4 GND<1> CONN7_E82125014_PIP_TH-EMPTY,EA    I17 @BASEBOARD_FAB2_LIB.BASEBOARD_FAB2(SCH_1):PAGE172
  J8A3    1 GND<2> CONN7_E82125014_PIP_TH-EMPTY,EA    I17 @BASEBOARD_FAB2_LIB.BASEBOARD_FAB2(SCH_1):PAGE172
  J8A3  MH1    MH1 CONN7_E82125014_PIP_TH-EMPTY,EA    I17 @BASEBOARD_FAB2_LIB.BASEBOARD_FAB2(SCH_1):PAGE172
  J8A3  MH2    MH2 CONN7_E82125014_PIP_TH-EMPTY,EA    I17 @BASEBOARD_FAB2_LIB.BASEBOARD_FAB2(SCH_1):PAGE172
  J8A4    2    IO2 CONN4_H73295001_PIP-EMPTY,H732A    I25 @BASEBOARD_FAB2_LIB.BASEBOARD_FAB2(SCH_1):PAGE172
  J8A4    3    IO3 CONN4_H73295001_PIP-EMPTY,H732A    I25 @BASEBOARD_FAB2_LIB.BASEBOARD_FAB2(SCH_1):PAGE172
  C9B2    2      B CAP_0805-10UF,16V,10%,X6S,C953A    I36 @BASEBOARD_FAB2_LIB.BASEBOARD_FAB2(SCH_1):PAGE172
  C9B1    2      B CAP_0805-10UF,16V,10%,X6S,C953A    I39 @BASEBOARD_FAB2_LIB.BASEBOARD_FAB2(SCH_1):PAGE172
  J2M1    7 GND<0> CONN7_E82125014_PIP_TH-CONN,E8A    I52 @BASEBOARD_FAB2_LIB.BASEBOARD_FAB2(SCH_1):PAGE172
  J2M1    4 GND<1> CONN7_E82125014_PIP_TH-CONN,E8A    I52 @BASEBOARD_FAB2_LIB.BASEBOARD_FAB2(SCH_1):PAGE172
  J2M1    1 GND<2> CONN7_E82125014_PIP_TH-CONN,E8A    I52 @BASEBOARD_FAB2_LIB.BASEBOARD_FAB2(SCH_1):PAGE172
  J2M1  MH1    MH1 CONN7_E82125014_PIP_TH-CONN,E8A    I52 @BASEBOARD_FAB2_LIB.BASEBOARD_FAB2(SCH_1):PAGE172
  J2M1  MH2    MH2 CONN7_E82125014_PIP_TH-CONN,E8A    I52 @BASEBOARD_FAB2_LIB.BASEBOARD_FAB2(SCH_1):PAGE172
  J2L1    2    IO2 CONN4_H73295001_PIP-CONN,H7329A    I53 @BASEBOARD_FAB2_LIB.BASEBOARD_FAB2(SCH_1):PAGE172
  J2L1    3    IO3 CONN4_H73295001_PIP-CONN,H7329A    I53 @BASEBOARD_FAB2_LIB.BASEBOARD_FAB2(SCH_1):PAGE172
  J8A1  2D9 GND<0> CONN72_G97614002_A_CP-CONN,G97A   I163 @BASEBOARD_FAB2_LIB.BASEBOARD_FAB2(SCH_1):PAGE173
  J8A1  2D6 GND<1> CONN72_G97614002_A_CP-CONN,G97A   I163 @BASEBOARD_FAB2_LIB.BASEBOARD_FAB2(SCH_1):PAGE173
  J8A1  2D3 GND<2> CONN72_G97614002_A_CP-CONN,G97A   I163 @BASEBOARD_FAB2_LIB.BASEBOARD_FAB2(SCH_1):PAGE173
  J8A1  2C9 GND<3> CONN72_G97614002_A_CP-CONN,G97A   I163 @BASEBOARD_FAB2_LIB.BASEBOARD_FAB2(SCH_1):PAGE173
  J8A1  2C6 GND<4> CONN72_G97614002_A_CP-CONN,G97A   I163 @BASEBOARD_FAB2_LIB.BASEBOARD_FAB2(SCH_1):PAGE173
  J8A1  2C3 GND<5> CONN72_G97614002_A_CP-CONN,G97A   I163 @BASEBOARD_FAB2_LIB.BASEBOARD_FAB2(SCH_1):PAGE173
  J8A1  2B9 GND<6> CONN72_G97614002_A_CP-CONN,G97A   I163 @BASEBOARD_FAB2_LIB.BASEBOARD_FAB2(SCH_1):PAGE173
  J8A1  2B6 GND<7> CONN72_G97614002_A_CP-CONN,G97A   I163 @BASEBOARD_FAB2_LIB.BASEBOARD_FAB2(SCH_1):PAGE173
  J8A1  2B3 GND<8> CONN72_G97614002_A_CP-CONN,G97A   I163 @BASEBOARD_FAB2_LIB.BASEBOARD_FAB2(SCH_1):PAGE173
  J8A1  2A9 GND<9> CONN72_G97614002_A_CP-CONN,G97A   I163 @BASEBOARD_FAB2_LIB.BASEBOARD_FAB2(SCH_1):PAGE173
  J8A1  2A6 GND<10> CONN72_G97614002_A_CP-CONN,G97A   I163 @BASEBOARD_FAB2_LIB.BASEBOARD_FAB2(SCH_1):PAGE173
  J8A1  2A3 GND<11> CONN72_G97614002_A_CP-CONN,G97A   I163 @BASEBOARD_FAB2_LIB.BASEBOARD_FAB2(SCH_1):PAGE173
  J8A1  1D9 GND<12> CONN72_G97614002_A_CP-CONN,G97A   I163 @BASEBOARD_FAB2_LIB.BASEBOARD_FAB2(SCH_1):PAGE173
  J8A1  1D6 GND<13> CONN72_G97614002_A_CP-CONN,G97A   I163 @BASEBOARD_FAB2_LIB.BASEBOARD_FAB2(SCH_1):PAGE173
  J8A1  1D3 GND<14> CONN72_G97614002_A_CP-CONN,G97A   I163 @BASEBOARD_FAB2_LIB.BASEBOARD_FAB2(SCH_1):PAGE173
  J8A1  1C9 GND<15> CONN72_G97614002_A_CP-CONN,G97A   I163 @BASEBOARD_FAB2_LIB.BASEBOARD_FAB2(SCH_1):PAGE173
  J8A1  1C6 GND<16> CONN72_G97614002_A_CP-CONN,G97A   I163 @BASEBOARD_FAB2_LIB.BASEBOARD_FAB2(SCH_1):PAGE173
  J8A1  1C3 GND<17> CONN72_G97614002_A_CP-CONN,G97A   I163 @BASEBOARD_FAB2_LIB.BASEBOARD_FAB2(SCH_1):PAGE173
  J8A1  1B9 GND<18> CONN72_G97614002_A_CP-CONN,G97A   I163 @BASEBOARD_FAB2_LIB.BASEBOARD_FAB2(SCH_1):PAGE173
  J8A1  1B6 GND<19> CONN72_G97614002_A_CP-CONN,G97A   I163 @BASEBOARD_FAB2_LIB.BASEBOARD_FAB2(SCH_1):PAGE173
  J8A1  1B3 GND<20> CONN72_G97614002_A_CP-CONN,G97A   I163 @BASEBOARD_FAB2_LIB.BASEBOARD_FAB2(SCH_1):PAGE173
  J8A1  1A9 GND<21> CONN72_G97614002_A_CP-CONN,G97A   I163 @BASEBOARD_FAB2_LIB.BASEBOARD_FAB2(SCH_1):PAGE173
  J8A1  1A6 GND<22> CONN72_G97614002_A_CP-CONN,G97A   I163 @BASEBOARD_FAB2_LIB.BASEBOARD_FAB2(SCH_1):PAGE173
  J8A1  1A3 GND<23> CONN72_G97614002_A_CP-CONN,G97A   I163 @BASEBOARD_FAB2_LIB.BASEBOARD_FAB2(SCH_1):PAGE173
  J8A1  1C2 SIDEBANDA_2 CONN72_G97614002_A_CP-CONN,G97A   I163 @BASEBOARD_FAB2_LIB.BASEBOARD_FAB2(SCH_1):PAGE173
  J8A1  1B1 SIDEBANDA_3 CONN72_G97614002_A_CP-CONN,G97A   I163 @BASEBOARD_FAB2_LIB.BASEBOARD_FAB2(SCH_1):PAGE173
  J8A1  2C2 SIDEBANDB_2 CONN72_G97614002_A_CP-CONN,G97A   I163 @BASEBOARD_FAB2_LIB.BASEBOARD_FAB2(SCH_1):PAGE173
  J8A1  2B1 SIDEBANDB_3 CONN72_G97614002_A_CP-CONN,G97A   I163 @BASEBOARD_FAB2_LIB.BASEBOARD_FAB2(SCH_1):PAGE173
 R2L22    2      B RES_0402-1.00K,1%,1/16W,CHIP,GA   I264 @BASEBOARD_FAB2_LIB.BASEBOARD_FAB2(SCH_1):PAGE173
 R2L18    2      B RES_0402-1.00K,1%,1/16W,CHIP,GA   I266 @BASEBOARD_FAB2_LIB.BASEBOARD_FAB2(SCH_1):PAGE173
  R1L3    2      B RES_0402-1.00K,1%,1/16W,CHIP,GA     I5 @BASEBOARD_FAB2_LIB.BASEBOARD_FAB2(SCH_1):PAGE174
  J8A2   A3   GND1 CONN36_G97614001_CP-CONN,G9761A    I26 @BASEBOARD_FAB2_LIB.BASEBOARD_FAB2(SCH_1):PAGE174
  J8A2   A6   GND2 CONN36_G97614001_CP-CONN,G9761A    I26 @BASEBOARD_FAB2_LIB.BASEBOARD_FAB2(SCH_1):PAGE174
  J8A2   A9   GND3 CONN36_G97614001_CP-CONN,G9761A    I26 @BASEBOARD_FAB2_LIB.BASEBOARD_FAB2(SCH_1):PAGE174
  J8A2   B3   GND4 CONN36_G97614001_CP-CONN,G9761A    I26 @BASEBOARD_FAB2_LIB.BASEBOARD_FAB2(SCH_1):PAGE174
  J8A2   B6   GND5 CONN36_G97614001_CP-CONN,G9761A    I26 @BASEBOARD_FAB2_LIB.BASEBOARD_FAB2(SCH_1):PAGE174
  J8A2   B9   GND6 CONN36_G97614001_CP-CONN,G9761A    I26 @BASEBOARD_FAB2_LIB.BASEBOARD_FAB2(SCH_1):PAGE174
  J8A2   C3   GND7 CONN36_G97614001_CP-CONN,G9761A    I26 @BASEBOARD_FAB2_LIB.BASEBOARD_FAB2(SCH_1):PAGE174
  J8A2   C6   GND8 CONN36_G97614001_CP-CONN,G9761A    I26 @BASEBOARD_FAB2_LIB.BASEBOARD_FAB2(SCH_1):PAGE174
  J8A2   C9   GND9 CONN36_G97614001_CP-CONN,G9761A    I26 @BASEBOARD_FAB2_LIB.BASEBOARD_FAB2(SCH_1):PAGE174
  J8A2   D3  GND10 CONN36_G97614001_CP-CONN,G9761A    I26 @BASEBOARD_FAB2_LIB.BASEBOARD_FAB2(SCH_1):PAGE174
  J8A2   D6  GND11 CONN36_G97614001_CP-CONN,G9761A    I26 @BASEBOARD_FAB2_LIB.BASEBOARD_FAB2(SCH_1):PAGE174
  J8A2   D9  GND12 CONN36_G97614001_CP-CONN,G9761A    I26 @BASEBOARD_FAB2_LIB.BASEBOARD_FAB2(SCH_1):PAGE174
  J8A2   C2 SIDEBAND2 CONN36_G97614001_CP-CONN,G9761A    I26 @BASEBOARD_FAB2_LIB.BASEBOARD_FAB2(SCH_1):PAGE174
  J8A2   B1 SIDEBAND3 CONN36_G97614001_CP-CONN,G9761A    I26 @BASEBOARD_FAB2_LIB.BASEBOARD_FAB2(SCH_1):PAGE174
 C1L18    2      B CAP_A_0402V-1.0UF,6.3V,10%,X6SA    I11 @BASEBOARD_FAB2_LIB.BASEBOARD_FAB2(SCH_1):PAGE175
 C1L10    2      B CAP_A_0402V-1.0UF,6.3V,10%,X6SA    I19 @BASEBOARD_FAB2_LIB.BASEBOARD_FAB2(SCH_1):PAGE175
 C1L17    2      B CAP_A_0402V-0.1UF,16V,10%,X7R,A    I37 @BASEBOARD_FAB2_LIB.BASEBOARD_FAB2(SCH_1):PAGE175
  C1L9    2      B CAP_A_0402V-0.1UF,16V,10%,X7R,A    I38 @BASEBOARD_FAB2_LIB.BASEBOARD_FAB2(SCH_1):PAGE175
  C9A3    2      B CAP_A_0402V-0.1UF,16V,10%,X7R,A    I40 @BASEBOARD_FAB2_LIB.BASEBOARD_FAB2(SCH_1):PAGE175
  Q9A3    2    SRC FET_N_SOT23LF-2N7002,FET,C7925A    I49 @BASEBOARD_FAB2_LIB.BASEBOARD_FAB2(SCH_1):PAGE175
  C1L4    2      B CAP_A_0402V-0.1UF,16V,10%,X7R,A    I64 @BASEBOARD_FAB2_LIB.BASEBOARD_FAB2(SCH_1):PAGE175
  S9A1    3   PIN3 SWITCH_D37771002_SM-IC,D37771-A    I78 @BASEBOARD_FAB2_LIB.BASEBOARD_FAB2(SCH_1):PAGE175
  S9A1    4   PIN4 SWITCH_D37771002_SM-IC,D37771-A    I78 @BASEBOARD_FAB2_LIB.BASEBOARD_FAB2(SCH_1):PAGE175
  S9A2    3    IO3 SW_H67881001_SM-IC,H67881-001    I84 @BASEBOARD_FAB2_LIB.BASEBOARD_FAB2(SCH_1):PAGE175
  S9A2    4    IO4 SW_H67881001_SM-IC,H67881-001    I84 @BASEBOARD_FAB2_LIB.BASEBOARD_FAB2(SCH_1):PAGE175
  J9B1    4    GND CONN9_H51826001_PIP2-CONN,H518A    I69 @BASEBOARD_FAB2_LIB.BASEBOARD_FAB2(SCH_1):PAGE176
  J9B1  MH1    MH1 CONN9_H51826001_PIP2-CONN,H518A    I69 @BASEBOARD_FAB2_LIB.BASEBOARD_FAB2(SCH_1):PAGE176
  J9B1  MH2    MH2 CONN9_H51826001_PIP2-CONN,H518A    I69 @BASEBOARD_FAB2_LIB.BASEBOARD_FAB2(SCH_1):PAGE176
  J9B1  MH3    MH3 CONN9_H51826001_PIP2-CONN,H518A    I69 @BASEBOARD_FAB2_LIB.BASEBOARD_FAB2(SCH_1):PAGE176
  J9B1  MH4    MH4 CONN9_H51826001_PIP2-CONN,H518A    I69 @BASEBOARD_FAB2_LIB.BASEBOARD_FAB2(SCH_1):PAGE176
 CR1M2    3 GND<0> DIODEAC_DUAL_ARRAY_SM9-ESD3V3UA    I98 @BASEBOARD_FAB2_LIB.BASEBOARD_FAB2(SCH_1):PAGE176
  U1M3    2    GND TPS2061_SM-IC,H66405-001   I100 @BASEBOARD_FAB2_LIB.BASEBOARD_FAB2(SCH_1):PAGE176
 C1M38    2      B CAP_A_0402V-0.1UF,16V,10%,X7R,A   I108 @BASEBOARD_FAB2_LIB.BASEBOARD_FAB2(SCH_1):PAGE176
 R1M25    2      B RES_0402-10.0K,1%,1/16W,CHIP,GA   I111 @BASEBOARD_FAB2_LIB.BASEBOARD_FAB2(SCH_1):PAGE176
  C9B8    2      B CAPP_7343HLF-330UF,10V,20%,POSA   I113 @BASEBOARD_FAB2_LIB.BASEBOARD_FAB2(SCH_1):PAGE176
  C1M3    2      B CAP_A_0402V-1.0UF,6.3V,10%,X6SA    I20 @BASEBOARD_FAB2_LIB.BASEBOARD_FAB2(SCH_1):PAGE177
 DS9A6    2      C LED_A1LF-GREEN,IC,C97278-010    I31 @BASEBOARD_FAB2_LIB.BASEBOARD_FAB2(SCH_1):PAGE177
  Q9F1    4 SOURCE<0> FET_N_DUAL_SMLF-NTJD4001N,FET,A    I79 @BASEBOARD_FAB2_LIB.BASEBOARD_FAB2(SCH_1):PAGE177
  Q9F1    1 SOURCE<0> FET_N_DUAL_SMLF-NTJD4001N,FET,A    I80 @BASEBOARD_FAB2_LIB.BASEBOARD_FAB2(SCH_1):PAGE177
  J1F1   A2  GNDA2 CONN76_H22707001_THMT1-CONN,H2A   I111 @BASEBOARD_FAB2_LIB.BASEBOARD_FAB2(SCH_1):PAGE181
  J1F1   A8  GNDA8 CONN76_H22707001_THMT1-CONN,H2A   I111 @BASEBOARD_FAB2_LIB.BASEBOARD_FAB2(SCH_1):PAGE181
  J1F1   C1  GNDC1 CONN76_H22707001_THMT1-CONN,H2A   I111 @BASEBOARD_FAB2_LIB.BASEBOARD_FAB2(SCH_1):PAGE181
  J1F1   C3  GNDC3 CONN76_H22707001_THMT1-CONN,H2A   I111 @BASEBOARD_FAB2_LIB.BASEBOARD_FAB2(SCH_1):PAGE181
  J1F1   C5  GNDC5 CONN76_H22707001_THMT1-CONN,H2A   I111 @BASEBOARD_FAB2_LIB.BASEBOARD_FAB2(SCH_1):PAGE181
  J1F1   C7  GNDC7 CONN76_H22707001_THMT1-CONN,H2A   I111 @BASEBOARD_FAB2_LIB.BASEBOARD_FAB2(SCH_1):PAGE181
  J1F1   D2  GNDD2 CONN76_H22707001_THMT1-CONN,H2A   I111 @BASEBOARD_FAB2_LIB.BASEBOARD_FAB2(SCH_1):PAGE181
  J1F1   D6  GNDD6 CONN76_H22707001_THMT1-CONN,H2A   I111 @BASEBOARD_FAB2_LIB.BASEBOARD_FAB2(SCH_1):PAGE181
  J1F1   D8  GNDD8 CONN76_H22707001_THMT1-CONN,H2A   I111 @BASEBOARD_FAB2_LIB.BASEBOARD_FAB2(SCH_1):PAGE181
  J1F1   F1  GNDF1 CONN76_H22707001_THMT1-CONN,H2A   I111 @BASEBOARD_FAB2_LIB.BASEBOARD_FAB2(SCH_1):PAGE181
  J1F1   F3  GNDF3 CONN76_H22707001_THMT1-CONN,H2A   I111 @BASEBOARD_FAB2_LIB.BASEBOARD_FAB2(SCH_1):PAGE181
  J1F1   F7  GNDF7 CONN76_H22707001_THMT1-CONN,H2A   I111 @BASEBOARD_FAB2_LIB.BASEBOARD_FAB2(SCH_1):PAGE181
  J1F1   G2  GNDG2 CONN76_H22707001_THMT1-CONN,H2A   I111 @BASEBOARD_FAB2_LIB.BASEBOARD_FAB2(SCH_1):PAGE181
  J1F1   G4  GNDG4 CONN76_H22707001_THMT1-CONN,H2A   I111 @BASEBOARD_FAB2_LIB.BASEBOARD_FAB2(SCH_1):PAGE181
  J1F1   G6  GNDG6 CONN76_H22707001_THMT1-CONN,H2A   I111 @BASEBOARD_FAB2_LIB.BASEBOARD_FAB2(SCH_1):PAGE181
  J1F1   G8  GNDG8 CONN76_H22707001_THMT1-CONN,H2A   I111 @BASEBOARD_FAB2_LIB.BASEBOARD_FAB2(SCH_1):PAGE181
  J1F1   I1  GNDI1 CONN76_H22707001_THMT1-CONN,H2A   I111 @BASEBOARD_FAB2_LIB.BASEBOARD_FAB2(SCH_1):PAGE181
  J1F1   I7  GNDI7 CONN76_H22707001_THMT1-CONN,H2A   I111 @BASEBOARD_FAB2_LIB.BASEBOARD_FAB2(SCH_1):PAGE181
  J1F1   J2  GNDJ2 CONN76_H22707001_THMT1-CONN,H2A   I111 @BASEBOARD_FAB2_LIB.BASEBOARD_FAB2(SCH_1):PAGE181
  J1F1   J4  GNDJ4 CONN76_H22707001_THMT1-CONN,H2A   I111 @BASEBOARD_FAB2_LIB.BASEBOARD_FAB2(SCH_1):PAGE181
  J1F1   J6  GNDJ6 CONN76_H22707001_THMT1-CONN,H2A   I111 @BASEBOARD_FAB2_LIB.BASEBOARD_FAB2(SCH_1):PAGE181
  J1F1   J8  GNDJ8 CONN76_H22707001_THMT1-CONN,H2A   I111 @BASEBOARD_FAB2_LIB.BASEBOARD_FAB2(SCH_1):PAGE181
  Q9T1    2      E NPN_SM-MMBT3904,IC,C52245-001   I181 @BASEBOARD_FAB2_LIB.BASEBOARD_FAB2(SCH_1):PAGE181
  R9T3    2      B RES_0402-6.19K,1%,1/16W,CHIP,GA   I185 @BASEBOARD_FAB2_LIB.BASEBOARD_FAB2(SCH_1):PAGE181
  J1F3    8    IO8 CONN8_H62179001_PIP-CONN,H6217A   I189 @BASEBOARD_FAB2_LIB.BASEBOARD_FAB2(SCH_1):PAGE181
  C2R6    2      B CAP_0402LF-470PF,50V,10%,EMPTYA   I224 @BASEBOARD_FAB2_LIB.BASEBOARD_FAB2(SCH_1):PAGE181
  C8E1    2      B CAP_A_0402V-0.1UF,16V,10%,X7R,A   I253 @BASEBOARD_FAB2_LIB.BASEBOARD_FAB2(SCH_1):PAGE181
  J1C1   A2  GNDA2 CONN76_H22707001_THMT1-CONN,H2A    I18 @BASEBOARD_FAB2_LIB.BASEBOARD_FAB2(SCH_1):PAGE182
  J1C1   A4  GNDA4 CONN76_H22707001_THMT1-CONN,H2A    I18 @BASEBOARD_FAB2_LIB.BASEBOARD_FAB2(SCH_1):PAGE182
  J1C1   A6  GNDA6 CONN76_H22707001_THMT1-CONN,H2A    I18 @BASEBOARD_FAB2_LIB.BASEBOARD_FAB2(SCH_1):PAGE182
  J1C1   A8  GNDA8 CONN76_H22707001_THMT1-CONN,H2A    I18 @BASEBOARD_FAB2_LIB.BASEBOARD_FAB2(SCH_1):PAGE182
  J1C1   C1  GNDC1 CONN76_H22707001_THMT1-CONN,H2A    I18 @BASEBOARD_FAB2_LIB.BASEBOARD_FAB2(SCH_1):PAGE182
  J1C1   C3  GNDC3 CONN76_H22707001_THMT1-CONN,H2A    I18 @BASEBOARD_FAB2_LIB.BASEBOARD_FAB2(SCH_1):PAGE182
  J1C1   C5  GNDC5 CONN76_H22707001_THMT1-CONN,H2A    I18 @BASEBOARD_FAB2_LIB.BASEBOARD_FAB2(SCH_1):PAGE182
  J1C1   C7  GNDC7 CONN76_H22707001_THMT1-CONN,H2A    I18 @BASEBOARD_FAB2_LIB.BASEBOARD_FAB2(SCH_1):PAGE182
  J1C1   D2  GNDD2 CONN76_H22707001_THMT1-CONN,H2A    I18 @BASEBOARD_FAB2_LIB.BASEBOARD_FAB2(SCH_1):PAGE182
  J1C1   D4  GNDD4 CONN76_H22707001_THMT1-CONN,H2A    I18 @BASEBOARD_FAB2_LIB.BASEBOARD_FAB2(SCH_1):PAGE182
  J1C1   D6  GNDD6 CONN76_H22707001_THMT1-CONN,H2A    I18 @BASEBOARD_FAB2_LIB.BASEBOARD_FAB2(SCH_1):PAGE182
  J1C1   D8  GNDD8 CONN76_H22707001_THMT1-CONN,H2A    I18 @BASEBOARD_FAB2_LIB.BASEBOARD_FAB2(SCH_1):PAGE182
  J1C1   F1  GNDF1 CONN76_H22707001_THMT1-CONN,H2A    I18 @BASEBOARD_FAB2_LIB.BASEBOARD_FAB2(SCH_1):PAGE182
  J1C1   F3  GNDF3 CONN76_H22707001_THMT1-CONN,H2A    I18 @BASEBOARD_FAB2_LIB.BASEBOARD_FAB2(SCH_1):PAGE182
  J1C1   F5  GNDF5 CONN76_H22707001_THMT1-CONN,H2A    I18 @BASEBOARD_FAB2_LIB.BASEBOARD_FAB2(SCH_1):PAGE182
  J1C1   F7  GNDF7 CONN76_H22707001_THMT1-CONN,H2A    I18 @BASEBOARD_FAB2_LIB.BASEBOARD_FAB2(SCH_1):PAGE182
  J1C1   G2  GNDG2 CONN76_H22707001_THMT1-CONN,H2A    I18 @BASEBOARD_FAB2_LIB.BASEBOARD_FAB2(SCH_1):PAGE182
  J1C1   G4  GNDG4 CONN76_H22707001_THMT1-CONN,H2A    I18 @BASEBOARD_FAB2_LIB.BASEBOARD_FAB2(SCH_1):PAGE182
  J1C1   G6  GNDG6 CONN76_H22707001_THMT1-CONN,H2A    I18 @BASEBOARD_FAB2_LIB.BASEBOARD_FAB2(SCH_1):PAGE182
  J1C1   G8  GNDG8 CONN76_H22707001_THMT1-CONN,H2A    I18 @BASEBOARD_FAB2_LIB.BASEBOARD_FAB2(SCH_1):PAGE182
  J1C1   I1  GNDI1 CONN76_H22707001_THMT1-CONN,H2A    I18 @BASEBOARD_FAB2_LIB.BASEBOARD_FAB2(SCH_1):PAGE182
  J1C1   I3  GNDI3 CONN76_H22707001_THMT1-CONN,H2A    I18 @BASEBOARD_FAB2_LIB.BASEBOARD_FAB2(SCH_1):PAGE182
  J1C1   I5  GNDI5 CONN76_H22707001_THMT1-CONN,H2A    I18 @BASEBOARD_FAB2_LIB.BASEBOARD_FAB2(SCH_1):PAGE182
  J1C1   I7  GNDI7 CONN76_H22707001_THMT1-CONN,H2A    I18 @BASEBOARD_FAB2_LIB.BASEBOARD_FAB2(SCH_1):PAGE182
  J1C1   J2  GNDJ2 CONN76_H22707001_THMT1-CONN,H2A    I18 @BASEBOARD_FAB2_LIB.BASEBOARD_FAB2(SCH_1):PAGE182
  J1C1   J4  GNDJ4 CONN76_H22707001_THMT1-CONN,H2A    I18 @BASEBOARD_FAB2_LIB.BASEBOARD_FAB2(SCH_1):PAGE182
  J1C1   J6  GNDJ6 CONN76_H22707001_THMT1-CONN,H2A    I18 @BASEBOARD_FAB2_LIB.BASEBOARD_FAB2(SCH_1):PAGE182
  J1C1   J8  GNDJ8 CONN76_H22707001_THMT1-CONN,H2A    I18 @BASEBOARD_FAB2_LIB.BASEBOARD_FAB2(SCH_1):PAGE182
 EU9F3   25 CTSA_N PI7C9X1172_QFN-IC,H66899-001     I1 @BASEBOARD_FAB2_LIB.BASEBOARD_FAB2(SCH_1):PAGE183
 EU9F3   16 CTSB_N PI7C9X1172_QFN-IC,H66899-001     I1 @BASEBOARD_FAB2_LIB.BASEBOARD_FAB2(SCH_1):PAGE183
 EU9F3   12    GND PI7C9X1172_QFN-IC,H66899-001     I1 @BASEBOARD_FAB2_LIB.BASEBOARD_FAB2(SCH_1):PAGE183
 EU9F3   33  THPAD PI7C9X1172_QFN-IC,H66899-001     I1 @BASEBOARD_FAB2_LIB.BASEBOARD_FAB2(SCH_1):PAGE183
 C9F19    2      B CAP_A_0402V-0.1UF,16V,10%,X7R,A     I7 @BASEBOARD_FAB2_LIB.BASEBOARD_FAB2(SCH_1):PAGE183
 R9F50    2      B RES_0402-1.00K,1%,1/16W,CHIP,GA    I11 @BASEBOARD_FAB2_LIB.BASEBOARD_FAB2(SCH_1):PAGE183
 R9F51    2      B RES_0402-1.00K,1%,1/16W,CHIP,GA    I12 @BASEBOARD_FAB2_LIB.BASEBOARD_FAB2(SCH_1):PAGE183
 C9F20    2      B CAP_0402LF-12.0PF,50V,5%,COG,AA    I20 @BASEBOARD_FAB2_LIB.BASEBOARD_FAB2(SCH_1):PAGE183
 C9F21    2      B CAP_0402LF-12.0PF,50V,5%,COG,AA    I21 @BASEBOARD_FAB2_LIB.BASEBOARD_FAB2(SCH_1):PAGE183
  J8E1   11   IO11 SCONN11_H67026001_SM-CONN,H670A    I87 @BASEBOARD_FAB2_LIB.BASEBOARD_FAB2(SCH_1):PAGE184
  J8E1  MP1    MP1 SCONN11_H67026001_SM-CONN,H670A    I87 @BASEBOARD_FAB2_LIB.BASEBOARD_FAB2(SCH_1):PAGE184
  J8E1  MP2    MP2 SCONN11_H67026001_SM-CONN,H670A    I87 @BASEBOARD_FAB2_LIB.BASEBOARD_FAB2(SCH_1):PAGE184
 RM8D1    1    IO1 STANDOFF_TH1-SO,H72821-001   I104 @BASEBOARD_FAB2_LIB.BASEBOARD_FAB2(SCH_1):PAGE184
  J8F1    1 GND<0> SCONN75K_H17033002_SMT1-SCONN,A    I53 @BASEBOARD_FAB2_LIB.BASEBOARD_FAB2(SCH_1):PAGE185
  J8F1    3 GND<1> SCONN75K_H17033002_SMT1-SCONN,A    I53 @BASEBOARD_FAB2_LIB.BASEBOARD_FAB2(SCH_1):PAGE185
  J8F1    9 GND<2> SCONN75K_H17033002_SMT1-SCONN,A    I53 @BASEBOARD_FAB2_LIB.BASEBOARD_FAB2(SCH_1):PAGE185
  J8F1   15 GND<3> SCONN75K_H17033002_SMT1-SCONN,A    I53 @BASEBOARD_FAB2_LIB.BASEBOARD_FAB2(SCH_1):PAGE185
  J8F1   21 GND<4> SCONN75K_H17033002_SMT1-SCONN,A    I53 @BASEBOARD_FAB2_LIB.BASEBOARD_FAB2(SCH_1):PAGE185
  J8F1   27 GND<5> SCONN75K_H17033002_SMT1-SCONN,A    I53 @BASEBOARD_FAB2_LIB.BASEBOARD_FAB2(SCH_1):PAGE185
  J8F1   33 GND<6> SCONN75K_H17033002_SMT1-SCONN,A    I53 @BASEBOARD_FAB2_LIB.BASEBOARD_FAB2(SCH_1):PAGE185
  J8F1   39 GND<7> SCONN75K_H17033002_SMT1-SCONN,A    I53 @BASEBOARD_FAB2_LIB.BASEBOARD_FAB2(SCH_1):PAGE185
  J8F1   45 GND<8> SCONN75K_H17033002_SMT1-SCONN,A    I53 @BASEBOARD_FAB2_LIB.BASEBOARD_FAB2(SCH_1):PAGE185
  J8F1   51 GND<9> SCONN75K_H17033002_SMT1-SCONN,A    I53 @BASEBOARD_FAB2_LIB.BASEBOARD_FAB2(SCH_1):PAGE185
  J8F1   57 GND<10> SCONN75K_H17033002_SMT1-SCONN,A    I53 @BASEBOARD_FAB2_LIB.BASEBOARD_FAB2(SCH_1):PAGE185
  J8F1   71 GND<11> SCONN75K_H17033002_SMT1-SCONN,A    I53 @BASEBOARD_FAB2_LIB.BASEBOARD_FAB2(SCH_1):PAGE185
  J8F1   73 GND<12> SCONN75K_H17033002_SMT1-SCONN,A    I53 @BASEBOARD_FAB2_LIB.BASEBOARD_FAB2(SCH_1):PAGE185
  J8F1   75 GND<13> SCONN75K_H17033002_SMT1-SCONN,A    I53 @BASEBOARD_FAB2_LIB.BASEBOARD_FAB2(SCH_1):PAGE185
  J8F1  MP1    MP1 SCONN75K_H17033002_SMT1-SCONN,A    I53 @BASEBOARD_FAB2_LIB.BASEBOARD_FAB2(SCH_1):PAGE185
  J8F1  MP2    MP2 SCONN75K_H17033002_SMT1-SCONN,A    I53 @BASEBOARD_FAB2_LIB.BASEBOARD_FAB2(SCH_1):PAGE185
  C2P9    2      B CAP_A_0402V-0.1UF,16V,10%,X7R,A   I117 @BASEBOARD_FAB2_LIB.BASEBOARD_FAB2(SCH_1):PAGE185
 C2T29    2      B CAP_A_0402V-0.1UF,16V,10%,X7R,A   I120 @BASEBOARD_FAB2_LIB.BASEBOARD_FAB2(SCH_1):PAGE185
 C2T26    2      B CAP_A_0402V-0.1UF,16V,10%,X7R,A   I123 @BASEBOARD_FAB2_LIB.BASEBOARD_FAB2(SCH_1):PAGE185
 C2T21    2      B CAP_A_0402V-0.1UF,16V,10%,X7R,A   I124 @BASEBOARD_FAB2_LIB.BASEBOARD_FAB2(SCH_1):PAGE185
 C2T16    2      B CAP_A_0402V-0.1UF,16V,10%,X7R,A   I126 @BASEBOARD_FAB2_LIB.BASEBOARD_FAB2(SCH_1):PAGE185
 C2T15    2      B CAP_A_0402V-0.1UF,16V,10%,X7R,A   I127 @BASEBOARD_FAB2_LIB.BASEBOARD_FAB2(SCH_1):PAGE185
 C2T24    2      B CAP_A_0402V-0.1UF,16V,10%,X7R,A   I129 @BASEBOARD_FAB2_LIB.BASEBOARD_FAB2(SCH_1):PAGE185
  C2T2    2      B CAP_A_0402V-0.1UF,16V,10%,X7R,A   I131 @BASEBOARD_FAB2_LIB.BASEBOARD_FAB2(SCH_1):PAGE185
  C2T4    2      B CAP_A_0402V-0.1UF,16V,10%,X7R,A   I132 @BASEBOARD_FAB2_LIB.BASEBOARD_FAB2(SCH_1):PAGE185
  C2T5    2      B CAP_A_0402V-0.1UF,16V,10%,X7R,A   I135 @BASEBOARD_FAB2_LIB.BASEBOARD_FAB2(SCH_1):PAGE185
 C1M27    2      B CAP_0805-10UF,16V,10%,X6S,C953A     I3 @BASEBOARD_FAB2_LIB.BASEBOARD_FAB2(SCH_1):PAGE186
 C1M26    2      B CAP_0805-10UF,16V,10%,X6S,C953A     I6 @BASEBOARD_FAB2_LIB.BASEBOARD_FAB2(SCH_1):PAGE186
 C1M23    2      B CAP_A_0402V-0.1UF,16V,10%,X7R,A     I7 @BASEBOARD_FAB2_LIB.BASEBOARD_FAB2(SCH_1):PAGE186
 C1M22    2      B CAP_A_0402V-0.1UF,16V,10%,X7R,A     I8 @BASEBOARD_FAB2_LIB.BASEBOARD_FAB2(SCH_1):PAGE186
 C1M24    2      B CAP_A_0402V-0.1UF,16V,10%,X7R,A    I10 @BASEBOARD_FAB2_LIB.BASEBOARD_FAB2(SCH_1):PAGE186
  R9B7    1      A RES_0402-100.0,1%,1/16W,CHIP,GA   I222 @BASEBOARD_FAB2_LIB.BASEBOARD_FAB2(SCH_1):PAGE186
 C1M20    2      B CAP_A_0402V-0.1UF,16V,10%,X7R,A   I270 @BASEBOARD_FAB2_LIB.BASEBOARD_FAB2(SCH_1):PAGE186
 C1M21    2      B CAP_A_0402V-1.0UF,6.3V,10%,X6SA   I334 @BASEBOARD_FAB2_LIB.BASEBOARD_FAB2(SCH_1):PAGE186
 C1M25    2      B CAP_A_0402V-1.0UF,6.3V,10%,X6SA   I335 @BASEBOARD_FAB2_LIB.BASEBOARD_FAB2(SCH_1):PAGE186
  J9B3    8    IO8 SCONN120_A28699018_SM-SCONN,A2A   I336 @BASEBOARD_FAB2_LIB.BASEBOARD_FAB2(SCH_1):PAGE186
  J9B3    9    IO9 SCONN120_A28699018_SM-SCONN,A2A   I336 @BASEBOARD_FAB2_LIB.BASEBOARD_FAB2(SCH_1):PAGE186
  J9B3   10   IO10 SCONN120_A28699018_SM-SCONN,A2A   I336 @BASEBOARD_FAB2_LIB.BASEBOARD_FAB2(SCH_1):PAGE186
  J9B3   11   IO11 SCONN120_A28699018_SM-SCONN,A2A   I336 @BASEBOARD_FAB2_LIB.BASEBOARD_FAB2(SCH_1):PAGE186
  J9B3   14   IO14 SCONN120_A28699018_SM-SCONN,A2A   I336 @BASEBOARD_FAB2_LIB.BASEBOARD_FAB2(SCH_1):PAGE186
  J9B3   15   IO15 SCONN120_A28699018_SM-SCONN,A2A   I336 @BASEBOARD_FAB2_LIB.BASEBOARD_FAB2(SCH_1):PAGE186
  J9B3   16   IO16 SCONN120_A28699018_SM-SCONN,A2A   I336 @BASEBOARD_FAB2_LIB.BASEBOARD_FAB2(SCH_1):PAGE186
  J9B3   17   IO17 SCONN120_A28699018_SM-SCONN,A2A   I336 @BASEBOARD_FAB2_LIB.BASEBOARD_FAB2(SCH_1):PAGE186
  J9B3   26   IO26 SCONN120_A28699018_SM-SCONN,A2A   I336 @BASEBOARD_FAB2_LIB.BASEBOARD_FAB2(SCH_1):PAGE186
  J9B3   38   IO38 SCONN120_A28699018_SM-SCONN,A2A   I336 @BASEBOARD_FAB2_LIB.BASEBOARD_FAB2(SCH_1):PAGE186
  J9B3   39   IO39 SCONN120_A28699018_SM-SCONN,A2A   I336 @BASEBOARD_FAB2_LIB.BASEBOARD_FAB2(SCH_1):PAGE186
  J9B3   41   IO41 SCONN120_A28699018_SM-SCONN,A2A   I336 @BASEBOARD_FAB2_LIB.BASEBOARD_FAB2(SCH_1):PAGE186
  J9B3   44   IO44 SCONN120_A28699018_SM-SCONN,A2A   I336 @BASEBOARD_FAB2_LIB.BASEBOARD_FAB2(SCH_1):PAGE186
  J9B3   46   IO46 SCONN120_A28699018_SM-SCONN,A2A   I336 @BASEBOARD_FAB2_LIB.BASEBOARD_FAB2(SCH_1):PAGE186
  J9B3   47   IO47 SCONN120_A28699018_SM-SCONN,A2A   I336 @BASEBOARD_FAB2_LIB.BASEBOARD_FAB2(SCH_1):PAGE186
  J9B3   49   IO49 SCONN120_A28699018_SM-SCONN,A2A   I336 @BASEBOARD_FAB2_LIB.BASEBOARD_FAB2(SCH_1):PAGE186
  J9B3   52   IO52 SCONN120_A28699018_SM-SCONN,A2A   I336 @BASEBOARD_FAB2_LIB.BASEBOARD_FAB2(SCH_1):PAGE186
  J9B3   54   IO54 SCONN120_A28699018_SM-SCONN,A2A   I336 @BASEBOARD_FAB2_LIB.BASEBOARD_FAB2(SCH_1):PAGE186
  J9B3   55   IO55 SCONN120_A28699018_SM-SCONN,A2A   I336 @BASEBOARD_FAB2_LIB.BASEBOARD_FAB2(SCH_1):PAGE186
  J9B3   57   IO57 SCONN120_A28699018_SM-SCONN,A2A   I336 @BASEBOARD_FAB2_LIB.BASEBOARD_FAB2(SCH_1):PAGE186
  J9B3   60   IO60 SCONN120_A28699018_SM-SCONN,A2A   I336 @BASEBOARD_FAB2_LIB.BASEBOARD_FAB2(SCH_1):PAGE186
  J9B3   62   IO62 SCONN120_A28699018_SM-SCONN,A2A   I336 @BASEBOARD_FAB2_LIB.BASEBOARD_FAB2(SCH_1):PAGE186
  J9B3   63   IO63 SCONN120_A28699018_SM-SCONN,A2A   I336 @BASEBOARD_FAB2_LIB.BASEBOARD_FAB2(SCH_1):PAGE186
  J9B3   65   IO65 SCONN120_A28699018_SM-SCONN,A2A   I336 @BASEBOARD_FAB2_LIB.BASEBOARD_FAB2(SCH_1):PAGE186
  J9B3   68   IO68 SCONN120_A28699018_SM-SCONN,A2A   I336 @BASEBOARD_FAB2_LIB.BASEBOARD_FAB2(SCH_1):PAGE186
  J9B3   70   IO70 SCONN120_A28699018_SM-SCONN,A2A   I336 @BASEBOARD_FAB2_LIB.BASEBOARD_FAB2(SCH_1):PAGE186
  J9B3   71   IO71 SCONN120_A28699018_SM-SCONN,A2A   I336 @BASEBOARD_FAB2_LIB.BASEBOARD_FAB2(SCH_1):PAGE186
  J9B3   73   IO73 SCONN120_A28699018_SM-SCONN,A2A   I336 @BASEBOARD_FAB2_LIB.BASEBOARD_FAB2(SCH_1):PAGE186
  J9B3   76   IO76 SCONN120_A28699018_SM-SCONN,A2A   I336 @BASEBOARD_FAB2_LIB.BASEBOARD_FAB2(SCH_1):PAGE186
  J9B3   78   IO78 SCONN120_A28699018_SM-SCONN,A2A   I336 @BASEBOARD_FAB2_LIB.BASEBOARD_FAB2(SCH_1):PAGE186
  J9B3   79   IO79 SCONN120_A28699018_SM-SCONN,A2A   I336 @BASEBOARD_FAB2_LIB.BASEBOARD_FAB2(SCH_1):PAGE186
  J9B3   81   IO81 SCONN120_A28699018_SM-SCONN,A2A   I336 @BASEBOARD_FAB2_LIB.BASEBOARD_FAB2(SCH_1):PAGE186
  J9B3   84   IO84 SCONN120_A28699018_SM-SCONN,A2A   I336 @BASEBOARD_FAB2_LIB.BASEBOARD_FAB2(SCH_1):PAGE186
  J9B3   86   IO86 SCONN120_A28699018_SM-SCONN,A2A   I336 @BASEBOARD_FAB2_LIB.BASEBOARD_FAB2(SCH_1):PAGE186
  J9B3   87   IO87 SCONN120_A28699018_SM-SCONN,A2A   I336 @BASEBOARD_FAB2_LIB.BASEBOARD_FAB2(SCH_1):PAGE186
  J9B3   89   IO89 SCONN120_A28699018_SM-SCONN,A2A   I336 @BASEBOARD_FAB2_LIB.BASEBOARD_FAB2(SCH_1):PAGE186
  J9B3   92   IO92 SCONN120_A28699018_SM-SCONN,A2A   I336 @BASEBOARD_FAB2_LIB.BASEBOARD_FAB2(SCH_1):PAGE186
  J9B3   94   IO94 SCONN120_A28699018_SM-SCONN,A2A   I336 @BASEBOARD_FAB2_LIB.BASEBOARD_FAB2(SCH_1):PAGE186
  J9B3   95   IO95 SCONN120_A28699018_SM-SCONN,A2A   I336 @BASEBOARD_FAB2_LIB.BASEBOARD_FAB2(SCH_1):PAGE186
  J9B3   97   IO97 SCONN120_A28699018_SM-SCONN,A2A   I336 @BASEBOARD_FAB2_LIB.BASEBOARD_FAB2(SCH_1):PAGE186
  J9B3  100  IO100 SCONN120_A28699018_SM-SCONN,A2A   I336 @BASEBOARD_FAB2_LIB.BASEBOARD_FAB2(SCH_1):PAGE186
  J9B3  102  IO102 SCONN120_A28699018_SM-SCONN,A2A   I336 @BASEBOARD_FAB2_LIB.BASEBOARD_FAB2(SCH_1):PAGE186
  J9B3  103  IO103 SCONN120_A28699018_SM-SCONN,A2A   I336 @BASEBOARD_FAB2_LIB.BASEBOARD_FAB2(SCH_1):PAGE186
  J9B3  105  IO105 SCONN120_A28699018_SM-SCONN,A2A   I336 @BASEBOARD_FAB2_LIB.BASEBOARD_FAB2(SCH_1):PAGE186
  J9B3  108  IO108 SCONN120_A28699018_SM-SCONN,A2A   I336 @BASEBOARD_FAB2_LIB.BASEBOARD_FAB2(SCH_1):PAGE186
  J9B3  110  IO110 SCONN120_A28699018_SM-SCONN,A2A   I336 @BASEBOARD_FAB2_LIB.BASEBOARD_FAB2(SCH_1):PAGE186
  J9B3  111  IO111 SCONN120_A28699018_SM-SCONN,A2A   I336 @BASEBOARD_FAB2_LIB.BASEBOARD_FAB2(SCH_1):PAGE186
  J9B3  113  IO113 SCONN120_A28699018_SM-SCONN,A2A   I336 @BASEBOARD_FAB2_LIB.BASEBOARD_FAB2(SCH_1):PAGE186
  J9B3  116  IO116 SCONN120_A28699018_SM-SCONN,A2A   I336 @BASEBOARD_FAB2_LIB.BASEBOARD_FAB2(SCH_1):PAGE186
  J9B3  118  IO118 SCONN120_A28699018_SM-SCONN,A2A   I336 @BASEBOARD_FAB2_LIB.BASEBOARD_FAB2(SCH_1):PAGE186
  J9B3  119  IO119 SCONN120_A28699018_SM-SCONN,A2A   I336 @BASEBOARD_FAB2_LIB.BASEBOARD_FAB2(SCH_1):PAGE186
 C9B10    2      B CAP_A_0402V-0.1UF,16V,10%,X7R,A   I345 @BASEBOARD_FAB2_LIB.BASEBOARD_FAB2(SCH_1):PAGE186
  C9B9    2      B CAP_A_0402V-1.0UF,6.3V,10%,X6SA   I347 @BASEBOARD_FAB2_LIB.BASEBOARD_FAB2(SCH_1):PAGE186
  R2R8    2      B RES_0402-100.0,1%,1/16W,CHIP,GA    I18 @BASEBOARD_FAB2_LIB.BASEBOARD_FAB2(SCH_1):PAGE187
  J8E3    3    IO3 SCONN80_E67482007_SM-CONN,E674A   I119 @BASEBOARD_FAB2_LIB.BASEBOARD_FAB2(SCH_1):PAGE187
  J8E3    8    IO8 SCONN80_E67482007_SM-CONN,E674A   I119 @BASEBOARD_FAB2_LIB.BASEBOARD_FAB2(SCH_1):PAGE187
  J8E3    9    IO9 SCONN80_E67482007_SM-CONN,E674A   I119 @BASEBOARD_FAB2_LIB.BASEBOARD_FAB2(SCH_1):PAGE187
  J8E3   11   IO11 SCONN80_E67482007_SM-CONN,E674A   I119 @BASEBOARD_FAB2_LIB.BASEBOARD_FAB2(SCH_1):PAGE187
  J8E3   14   IO14 SCONN80_E67482007_SM-CONN,E674A   I119 @BASEBOARD_FAB2_LIB.BASEBOARD_FAB2(SCH_1):PAGE187
  J8E3   16   IO16 SCONN80_E67482007_SM-CONN,E674A   I119 @BASEBOARD_FAB2_LIB.BASEBOARD_FAB2(SCH_1):PAGE187
  J8E3   17   IO17 SCONN80_E67482007_SM-CONN,E674A   I119 @BASEBOARD_FAB2_LIB.BASEBOARD_FAB2(SCH_1):PAGE187
  J8E3   19   IO19 SCONN80_E67482007_SM-CONN,E674A   I119 @BASEBOARD_FAB2_LIB.BASEBOARD_FAB2(SCH_1):PAGE187
  J8E3   22   IO22 SCONN80_E67482007_SM-CONN,E674A   I119 @BASEBOARD_FAB2_LIB.BASEBOARD_FAB2(SCH_1):PAGE187
  J8E3   24   IO24 SCONN80_E67482007_SM-CONN,E674A   I119 @BASEBOARD_FAB2_LIB.BASEBOARD_FAB2(SCH_1):PAGE187
  J8E3   25   IO25 SCONN80_E67482007_SM-CONN,E674A   I119 @BASEBOARD_FAB2_LIB.BASEBOARD_FAB2(SCH_1):PAGE187
  J8E3   27   IO27 SCONN80_E67482007_SM-CONN,E674A   I119 @BASEBOARD_FAB2_LIB.BASEBOARD_FAB2(SCH_1):PAGE187
  J8E3   30   IO30 SCONN80_E67482007_SM-CONN,E674A   I119 @BASEBOARD_FAB2_LIB.BASEBOARD_FAB2(SCH_1):PAGE187
  J8E3   32   IO32 SCONN80_E67482007_SM-CONN,E674A   I119 @BASEBOARD_FAB2_LIB.BASEBOARD_FAB2(SCH_1):PAGE187
  J8E3   33   IO33 SCONN80_E67482007_SM-CONN,E674A   I119 @BASEBOARD_FAB2_LIB.BASEBOARD_FAB2(SCH_1):PAGE187
  J8E3   35   IO35 SCONN80_E67482007_SM-CONN,E674A   I119 @BASEBOARD_FAB2_LIB.BASEBOARD_FAB2(SCH_1):PAGE187
  J8E3   38   IO38 SCONN80_E67482007_SM-CONN,E674A   I119 @BASEBOARD_FAB2_LIB.BASEBOARD_FAB2(SCH_1):PAGE187
  J8E3   40   IO40 SCONN80_E67482007_SM-CONN,E674A   I119 @BASEBOARD_FAB2_LIB.BASEBOARD_FAB2(SCH_1):PAGE187
  J8E3   41   IO41 SCONN80_E67482007_SM-CONN,E674A   I119 @BASEBOARD_FAB2_LIB.BASEBOARD_FAB2(SCH_1):PAGE187
  J8E3   43   IO43 SCONN80_E67482007_SM-CONN,E674A   I119 @BASEBOARD_FAB2_LIB.BASEBOARD_FAB2(SCH_1):PAGE187
  J8E3   46   IO46 SCONN80_E67482007_SM-CONN,E674A   I119 @BASEBOARD_FAB2_LIB.BASEBOARD_FAB2(SCH_1):PAGE187
  J8E3   48   IO48 SCONN80_E67482007_SM-CONN,E674A   I119 @BASEBOARD_FAB2_LIB.BASEBOARD_FAB2(SCH_1):PAGE187
  J8E3   49   IO49 SCONN80_E67482007_SM-CONN,E674A   I119 @BASEBOARD_FAB2_LIB.BASEBOARD_FAB2(SCH_1):PAGE187
  J8E3   51   IO51 SCONN80_E67482007_SM-CONN,E674A   I119 @BASEBOARD_FAB2_LIB.BASEBOARD_FAB2(SCH_1):PAGE187
  J8E3   54   IO54 SCONN80_E67482007_SM-CONN,E674A   I119 @BASEBOARD_FAB2_LIB.BASEBOARD_FAB2(SCH_1):PAGE187
  J8E3   56   IO56 SCONN80_E67482007_SM-CONN,E674A   I119 @BASEBOARD_FAB2_LIB.BASEBOARD_FAB2(SCH_1):PAGE187
  J8E3   57   IO57 SCONN80_E67482007_SM-CONN,E674A   I119 @BASEBOARD_FAB2_LIB.BASEBOARD_FAB2(SCH_1):PAGE187
  J8E3   59   IO59 SCONN80_E67482007_SM-CONN,E674A   I119 @BASEBOARD_FAB2_LIB.BASEBOARD_FAB2(SCH_1):PAGE187
  J8E3   62   IO62 SCONN80_E67482007_SM-CONN,E674A   I119 @BASEBOARD_FAB2_LIB.BASEBOARD_FAB2(SCH_1):PAGE187
  J8E3   64   IO64 SCONN80_E67482007_SM-CONN,E674A   I119 @BASEBOARD_FAB2_LIB.BASEBOARD_FAB2(SCH_1):PAGE187
  J8E3   65   IO65 SCONN80_E67482007_SM-CONN,E674A   I119 @BASEBOARD_FAB2_LIB.BASEBOARD_FAB2(SCH_1):PAGE187
  J8E3   67   IO67 SCONN80_E67482007_SM-CONN,E674A   I119 @BASEBOARD_FAB2_LIB.BASEBOARD_FAB2(SCH_1):PAGE187
  J8E3   70   IO70 SCONN80_E67482007_SM-CONN,E674A   I119 @BASEBOARD_FAB2_LIB.BASEBOARD_FAB2(SCH_1):PAGE187
  J8E3   72   IO72 SCONN80_E67482007_SM-CONN,E674A   I119 @BASEBOARD_FAB2_LIB.BASEBOARD_FAB2(SCH_1):PAGE187
  J8E3   73   IO73 SCONN80_E67482007_SM-CONN,E674A   I119 @BASEBOARD_FAB2_LIB.BASEBOARD_FAB2(SCH_1):PAGE187
  J8E3   78   IO78 SCONN80_E67482007_SM-CONN,E674A   I119 @BASEBOARD_FAB2_LIB.BASEBOARD_FAB2(SCH_1):PAGE187
 C2R15    2      B CAP_A_0402V-0.1UF,16V,10%,X7R,A     I2 @BASEBOARD_FAB2_LIB.BASEBOARD_FAB2(SCH_1):PAGE188
 C2R18    2      B CAP_A_0402V-0.1UF,16V,10%,X7R,A     I3 @BASEBOARD_FAB2_LIB.BASEBOARD_FAB2(SCH_1):PAGE188
 C2P11    2      B CAP_A_0402V-0.1UF,16V,10%,X7R,A    I21 @BASEBOARD_FAB2_LIB.BASEBOARD_FAB2(SCH_1):PAGE188
 C2P12    2      B CAP_A_0402V-0.1UF,16V,10%,X7R,A    I23 @BASEBOARD_FAB2_LIB.BASEBOARD_FAB2(SCH_1):PAGE188
 C2R17    2      B CAP_A_0402V-0.1UF,16V,10%,X7R,A    I25 @BASEBOARD_FAB2_LIB.BASEBOARD_FAB2(SCH_1):PAGE188
  J8E4    4    IO4 SCONN64_H87568002_A_SMT-CONN,HA    I27 @BASEBOARD_FAB2_LIB.BASEBOARD_FAB2(SCH_1):PAGE188
  J8E4    7    IO7 SCONN64_H87568002_A_SMT-CONN,HA    I27 @BASEBOARD_FAB2_LIB.BASEBOARD_FAB2(SCH_1):PAGE188
  J8E4   10   IO10 SCONN64_H87568002_A_SMT-CONN,HA    I27 @BASEBOARD_FAB2_LIB.BASEBOARD_FAB2(SCH_1):PAGE188
  J8E4   13   IO13 SCONN64_H87568002_A_SMT-CONN,HA    I27 @BASEBOARD_FAB2_LIB.BASEBOARD_FAB2(SCH_1):PAGE188
  J8E4   16   IO16 SCONN64_H87568002_A_SMT-CONN,HA    I27 @BASEBOARD_FAB2_LIB.BASEBOARD_FAB2(SCH_1):PAGE188
  J8E4   19   IO19 SCONN64_H87568002_A_SMT-CONN,HA    I27 @BASEBOARD_FAB2_LIB.BASEBOARD_FAB2(SCH_1):PAGE188
  J8E4   22   IO22 SCONN64_H87568002_A_SMT-CONN,HA    I27 @BASEBOARD_FAB2_LIB.BASEBOARD_FAB2(SCH_1):PAGE188
  J8E4   25   IO25 SCONN64_H87568002_A_SMT-CONN,HA    I27 @BASEBOARD_FAB2_LIB.BASEBOARD_FAB2(SCH_1):PAGE188
  J8E4   28   IO28 SCONN64_H87568002_A_SMT-CONN,HA    I27 @BASEBOARD_FAB2_LIB.BASEBOARD_FAB2(SCH_1):PAGE188
  J8E4   39   IO39 SCONN64_H87568002_A_SMT-CONN,HA    I27 @BASEBOARD_FAB2_LIB.BASEBOARD_FAB2(SCH_1):PAGE188
  J8E4   42   IO42 SCONN64_H87568002_A_SMT-CONN,HA    I27 @BASEBOARD_FAB2_LIB.BASEBOARD_FAB2(SCH_1):PAGE188
  J8E4   45   IO45 SCONN64_H87568002_A_SMT-CONN,HA    I27 @BASEBOARD_FAB2_LIB.BASEBOARD_FAB2(SCH_1):PAGE188
  J8E4   48   IO48 SCONN64_H87568002_A_SMT-CONN,HA    I27 @BASEBOARD_FAB2_LIB.BASEBOARD_FAB2(SCH_1):PAGE188
  J8E4   51   IO51 SCONN64_H87568002_A_SMT-CONN,HA    I27 @BASEBOARD_FAB2_LIB.BASEBOARD_FAB2(SCH_1):PAGE188
  J8E4   54   IO54 SCONN64_H87568002_A_SMT-CONN,HA    I27 @BASEBOARD_FAB2_LIB.BASEBOARD_FAB2(SCH_1):PAGE188
  J8E4   57   IO57 SCONN64_H87568002_A_SMT-CONN,HA    I27 @BASEBOARD_FAB2_LIB.BASEBOARD_FAB2(SCH_1):PAGE188
  J8E4   60   IO60 SCONN64_H87568002_A_SMT-CONN,HA    I27 @BASEBOARD_FAB2_LIB.BASEBOARD_FAB2(SCH_1):PAGE188
  J8E4   63   IO63 SCONN64_H87568002_A_SMT-CONN,HA    I27 @BASEBOARD_FAB2_LIB.BASEBOARD_FAB2(SCH_1):PAGE188
 C2R16    2      B CAP_A_0402V-0.1UF,16V,10%,X7R,A    I40 @BASEBOARD_FAB2_LIB.BASEBOARD_FAB2(SCH_1):PAGE188
 C2P10    2      B CAP_1206LF-22UF,16V,10%,X6S,D3A    I41 @BASEBOARD_FAB2_LIB.BASEBOARD_FAB2(SCH_1):PAGE188
 C2P16    2      B CAP_A_0402V-0.1UF,16V,10%,X7R,A    I53 @BASEBOARD_FAB2_LIB.BASEBOARD_FAB2(SCH_1):PAGE188
 C2P15    2      B CAP_A_0402V-0.1UF,16V,10%,X7R,A    I55 @BASEBOARD_FAB2_LIB.BASEBOARD_FAB2(SCH_1):PAGE188
 C2P14    2      B CAP_A_0402V-0.1UF,16V,10%,X7R,A    I56 @BASEBOARD_FAB2_LIB.BASEBOARD_FAB2(SCH_1):PAGE188
 C2P13    2      B CAP_A_0402V-0.1UF,16V,10%,X7R,A    I57 @BASEBOARD_FAB2_LIB.BASEBOARD_FAB2(SCH_1):PAGE188
 R3R11    2      B RES_0402-10.0K,1%,1/16W,EMPTY,A    I45 @BASEBOARD_FAB2_LIB.BASEBOARD_FAB2(SCH_1):PAGE189
  J7G2    7    IO7 CONN8_C77962004_PIP-CONN,C7796A    I47 @BASEBOARD_FAB2_LIB.BASEBOARD_FAB2(SCH_1):PAGE189
 R8G23    2      B RES_0402-4.75K,1%,1/16W,CHIP,GA    I56 @BASEBOARD_FAB2_LIB.BASEBOARD_FAB2(SCH_1):PAGE189
  C2P8    2      B CAP_A_0402V-0.01UF,25V,10%,X7RA     I1 @BASEBOARD_FAB2_LIB.BASEBOARD_FAB2(SCH_1):PAGE192
  C2P5    2      B CAP_A_0402V-0.1UF,16V,10%,X7R,A     I3 @BASEBOARD_FAB2_LIB.BASEBOARD_FAB2(SCH_1):PAGE192
  C3R1    2      B CAP_A_0402V-0.1UF,16V,10%,X7R,A     I4 @BASEBOARD_FAB2_LIB.BASEBOARD_FAB2(SCH_1):PAGE192
 C3P43    2      B CAP_A_0402V-0.1UF,16V,10%,X7R,A     I6 @BASEBOARD_FAB2_LIB.BASEBOARD_FAB2(SCH_1):PAGE192
  C3R3    2      B CAP_A_0402V-0.1UF,16V,10%,X7R,A     I7 @BASEBOARD_FAB2_LIB.BASEBOARD_FAB2(SCH_1):PAGE192
  C2R1    2      B CAP_A_0402V-0.1UF,16V,10%,X7R,A     I8 @BASEBOARD_FAB2_LIB.BASEBOARD_FAB2(SCH_1):PAGE192
  C2P2    2      B CAP_A_0402V-0.1UF,16V,10%,X7R,A     I9 @BASEBOARD_FAB2_LIB.BASEBOARD_FAB2(SCH_1):PAGE192
  C3R2    2      B CAP_A_0402V-0.1UF,16V,10%,X7R,A    I10 @BASEBOARD_FAB2_LIB.BASEBOARD_FAB2(SCH_1):PAGE192
 C3P51    2      B CAP_A_0402V-0.1UF,16V,10%,X7R,A    I11 @BASEBOARD_FAB2_LIB.BASEBOARD_FAB2(SCH_1):PAGE192
 C3P47    2      B CAP_A_0402V-0.1UF,16V,10%,X7R,A    I12 @BASEBOARD_FAB2_LIB.BASEBOARD_FAB2(SCH_1):PAGE192
  U8D7   B2 GND<0> LCMXO2_A_256BGA-IC,H63395-001    I14 @BASEBOARD_FAB2_LIB.BASEBOARD_FAB2(SCH_1):PAGE192
  U8D7  B15 GND<1> LCMXO2_A_256BGA-IC,H63395-001    I14 @BASEBOARD_FAB2_LIB.BASEBOARD_FAB2(SCH_1):PAGE192
  U8D7   C3 GND<2> LCMXO2_A_256BGA-IC,H63395-001    I14 @BASEBOARD_FAB2_LIB.BASEBOARD_FAB2(SCH_1):PAGE192
  U8D7  C14 GND<3> LCMXO2_A_256BGA-IC,H63395-001    I14 @BASEBOARD_FAB2_LIB.BASEBOARD_FAB2(SCH_1):PAGE192
  U8D7   D4 GND<4> LCMXO2_A_256BGA-IC,H63395-001    I14 @BASEBOARD_FAB2_LIB.BASEBOARD_FAB2(SCH_1):PAGE192
  U8D7  D13 GND<5> LCMXO2_A_256BGA-IC,H63395-001    I14 @BASEBOARD_FAB2_LIB.BASEBOARD_FAB2(SCH_1):PAGE192
  U8D7   E5 GND<6> LCMXO2_A_256BGA-IC,H63395-001    I14 @BASEBOARD_FAB2_LIB.BASEBOARD_FAB2(SCH_1):PAGE192
  U8D7  E12 GND<7> LCMXO2_A_256BGA-IC,H63395-001    I14 @BASEBOARD_FAB2_LIB.BASEBOARD_FAB2(SCH_1):PAGE192
  U8D7   F6 GND<8> LCMXO2_A_256BGA-IC,H63395-001    I14 @BASEBOARD_FAB2_LIB.BASEBOARD_FAB2(SCH_1):PAGE192
  U8D7  F11 GND<9> LCMXO2_A_256BGA-IC,H63395-001    I14 @BASEBOARD_FAB2_LIB.BASEBOARD_FAB2(SCH_1):PAGE192
  U8D7   H8 GND<10> LCMXO2_A_256BGA-IC,H63395-001    I14 @BASEBOARD_FAB2_LIB.BASEBOARD_FAB2(SCH_1):PAGE192
  U8D7   H9 GND<11> LCMXO2_A_256BGA-IC,H63395-001    I14 @BASEBOARD_FAB2_LIB.BASEBOARD_FAB2(SCH_1):PAGE192
  U8D7   J8 GND<12> LCMXO2_A_256BGA-IC,H63395-001    I14 @BASEBOARD_FAB2_LIB.BASEBOARD_FAB2(SCH_1):PAGE192
  U8D7   J9 GND<13> LCMXO2_A_256BGA-IC,H63395-001    I14 @BASEBOARD_FAB2_LIB.BASEBOARD_FAB2(SCH_1):PAGE192
  U8D7   L6 GND<14> LCMXO2_A_256BGA-IC,H63395-001    I14 @BASEBOARD_FAB2_LIB.BASEBOARD_FAB2(SCH_1):PAGE192
  U8D7  L11 GND<15> LCMXO2_A_256BGA-IC,H63395-001    I14 @BASEBOARD_FAB2_LIB.BASEBOARD_FAB2(SCH_1):PAGE192
  U8D7   M5 GND<16> LCMXO2_A_256BGA-IC,H63395-001    I14 @BASEBOARD_FAB2_LIB.BASEBOARD_FAB2(SCH_1):PAGE192
  U8D7  M12 GND<17> LCMXO2_A_256BGA-IC,H63395-001    I14 @BASEBOARD_FAB2_LIB.BASEBOARD_FAB2(SCH_1):PAGE192
  U8D7   N4 GND<18> LCMXO2_A_256BGA-IC,H63395-001    I14 @BASEBOARD_FAB2_LIB.BASEBOARD_FAB2(SCH_1):PAGE192
  U8D7  N13 GND<19> LCMXO2_A_256BGA-IC,H63395-001    I14 @BASEBOARD_FAB2_LIB.BASEBOARD_FAB2(SCH_1):PAGE192
  U8D7   P3 GND<20> LCMXO2_A_256BGA-IC,H63395-001    I14 @BASEBOARD_FAB2_LIB.BASEBOARD_FAB2(SCH_1):PAGE192
  U8D7  P14 GND<21> LCMXO2_A_256BGA-IC,H63395-001    I14 @BASEBOARD_FAB2_LIB.BASEBOARD_FAB2(SCH_1):PAGE192
  U8D7   R2 GND<22> LCMXO2_A_256BGA-IC,H63395-001    I14 @BASEBOARD_FAB2_LIB.BASEBOARD_FAB2(SCH_1):PAGE192
  U8D7  R15 GND<23> LCMXO2_A_256BGA-IC,H63395-001    I14 @BASEBOARD_FAB2_LIB.BASEBOARD_FAB2(SCH_1):PAGE192
  C2R5    2      B CAP_A_0402V-0.1UF,16V,10%,X7R,A    I15 @BASEBOARD_FAB2_LIB.BASEBOARD_FAB2(SCH_1):PAGE192
  C2P4    2      B CAP_A_0402V-0.1UF,16V,10%,X7R,A    I16 @BASEBOARD_FAB2_LIB.BASEBOARD_FAB2(SCH_1):PAGE192
 C3P52    2      B CAP_A_0402V-0.1UF,16V,10%,X7R,A    I17 @BASEBOARD_FAB2_LIB.BASEBOARD_FAB2(SCH_1):PAGE192
  C2P6    2      B CAP_A_0402V-0.1UF,16V,10%,X7R,A    I18 @BASEBOARD_FAB2_LIB.BASEBOARD_FAB2(SCH_1):PAGE192
  C2R3    2      B CAP_A_0402V-0.1UF,16V,10%,X7R,A    I19 @BASEBOARD_FAB2_LIB.BASEBOARD_FAB2(SCH_1):PAGE192
  C2P7    2      B CAP_A_0402V-0.1UF,16V,10%,X7R,A    I20 @BASEBOARD_FAB2_LIB.BASEBOARD_FAB2(SCH_1):PAGE192
  C2R4    2      B CAP_A_0402V-0.1UF,16V,10%,X7R,A    I21 @BASEBOARD_FAB2_LIB.BASEBOARD_FAB2(SCH_1):PAGE192
  C2P3    2      B CAP_A_0402V-0.1UF,16V,10%,X7R,A    I22 @BASEBOARD_FAB2_LIB.BASEBOARD_FAB2(SCH_1):PAGE192
 C3P44    2      B CAP_A_0402V-0.1UF,16V,10%,X7R,A    I23 @BASEBOARD_FAB2_LIB.BASEBOARD_FAB2(SCH_1):PAGE192
 C3P48    2      B CAP_A_0402V-0.1UF,16V,10%,X7R,A    I25 @BASEBOARD_FAB2_LIB.BASEBOARD_FAB2(SCH_1):PAGE192
  C2R2    2      B CAP_A_0402V-0.1UF,16V,10%,X7R,A    I28 @BASEBOARD_FAB2_LIB.BASEBOARD_FAB2(SCH_1):PAGE192
 R7E20    2      B RES_0402-1.00K,1%,1/16W,CHIP,GA    I59 @BASEBOARD_FAB2_LIB.BASEBOARD_FAB2(SCH_1):PAGE192
  C4C1    2      B CAPP_3018-470UF,2.5V,20%,ALUM,A    I29 @BASEBOARD_FAB2_LIB.BASEBOARD_FAB2(SCH_1):PAGE193
  C3C2    2      B CAP_A_0402V-1.0UF,6.3V,10%,X6SA    I31 @BASEBOARD_FAB2_LIB.BASEBOARD_FAB2(SCH_1):PAGE193
  C3C1    2      B CAP_A_0402V-1.0UF,6.3V,10%,X6SA    I38 @BASEBOARD_FAB2_LIB.BASEBOARD_FAB2(SCH_1):PAGE193
  J4E1  A19  IOA19 SCONN120_H61426002_SM-CONN,H61A    I45 @BASEBOARD_FAB2_LIB.BASEBOARD_FAB2(SCH_1):PAGE193
  J4E1  A20  IOA20 SCONN120_H61426002_SM-CONN,H61A    I45 @BASEBOARD_FAB2_LIB.BASEBOARD_FAB2(SCH_1):PAGE193
  J4E1  B19  IOB19 SCONN120_H61426002_SM-CONN,H61A    I45 @BASEBOARD_FAB2_LIB.BASEBOARD_FAB2(SCH_1):PAGE193
  J4E1  B20  IOB20 SCONN120_H61426002_SM-CONN,H61A    I45 @BASEBOARD_FAB2_LIB.BASEBOARD_FAB2(SCH_1):PAGE193
  J4E1  C19  IOC19 SCONN120_H61426002_SM-CONN,H61A    I45 @BASEBOARD_FAB2_LIB.BASEBOARD_FAB2(SCH_1):PAGE193
  J4E1  C20  IOC20 SCONN120_H61426002_SM-CONN,H61A    I45 @BASEBOARD_FAB2_LIB.BASEBOARD_FAB2(SCH_1):PAGE193
  J4E1   D3   IOD3 SCONN120_H61426002_SM-CONN,H61A    I45 @BASEBOARD_FAB2_LIB.BASEBOARD_FAB2(SCH_1):PAGE193
  J4E1   D4   IOD4 SCONN120_H61426002_SM-CONN,H61A    I45 @BASEBOARD_FAB2_LIB.BASEBOARD_FAB2(SCH_1):PAGE193
  J4E1   D5   IOD5 SCONN120_H61426002_SM-CONN,H61A    I45 @BASEBOARD_FAB2_LIB.BASEBOARD_FAB2(SCH_1):PAGE193
  J4E1   D6   IOD6 SCONN120_H61426002_SM-CONN,H61A    I45 @BASEBOARD_FAB2_LIB.BASEBOARD_FAB2(SCH_1):PAGE193
  J4E1   D7   IOD7 SCONN120_H61426002_SM-CONN,H61A    I45 @BASEBOARD_FAB2_LIB.BASEBOARD_FAB2(SCH_1):PAGE193
  J4E1   D8   IOD8 SCONN120_H61426002_SM-CONN,H61A    I45 @BASEBOARD_FAB2_LIB.BASEBOARD_FAB2(SCH_1):PAGE193
  J4E1   D9   IOD9 SCONN120_H61426002_SM-CONN,H61A    I45 @BASEBOARD_FAB2_LIB.BASEBOARD_FAB2(SCH_1):PAGE193
  J4E1  D10  IOD10 SCONN120_H61426002_SM-CONN,H61A    I45 @BASEBOARD_FAB2_LIB.BASEBOARD_FAB2(SCH_1):PAGE193
  J4E1  D11  IOD11 SCONN120_H61426002_SM-CONN,H61A    I45 @BASEBOARD_FAB2_LIB.BASEBOARD_FAB2(SCH_1):PAGE193
  J4E1  D12  IOD12 SCONN120_H61426002_SM-CONN,H61A    I45 @BASEBOARD_FAB2_LIB.BASEBOARD_FAB2(SCH_1):PAGE193
  J4E1  D13  IOD13 SCONN120_H61426002_SM-CONN,H61A    I45 @BASEBOARD_FAB2_LIB.BASEBOARD_FAB2(SCH_1):PAGE193
  J4E1  D14  IOD14 SCONN120_H61426002_SM-CONN,H61A    I45 @BASEBOARD_FAB2_LIB.BASEBOARD_FAB2(SCH_1):PAGE193
  J4E1  D15  IOD15 SCONN120_H61426002_SM-CONN,H61A    I45 @BASEBOARD_FAB2_LIB.BASEBOARD_FAB2(SCH_1):PAGE193
  J4E1  D16  IOD16 SCONN120_H61426002_SM-CONN,H61A    I45 @BASEBOARD_FAB2_LIB.BASEBOARD_FAB2(SCH_1):PAGE193
  J4E1  D17  IOD17 SCONN120_H61426002_SM-CONN,H61A    I45 @BASEBOARD_FAB2_LIB.BASEBOARD_FAB2(SCH_1):PAGE193
  J4E1  D18  IOD18 SCONN120_H61426002_SM-CONN,H61A    I45 @BASEBOARD_FAB2_LIB.BASEBOARD_FAB2(SCH_1):PAGE193
  J4E1  D19  IOD19 SCONN120_H61426002_SM-CONN,H61A    I45 @BASEBOARD_FAB2_LIB.BASEBOARD_FAB2(SCH_1):PAGE193
  J4E1  D20  IOD20 SCONN120_H61426002_SM-CONN,H61A    I45 @BASEBOARD_FAB2_LIB.BASEBOARD_FAB2(SCH_1):PAGE193
  J4E1   E3   IOE3 SCONN120_H61426002_SM-CONN,H61A    I45 @BASEBOARD_FAB2_LIB.BASEBOARD_FAB2(SCH_1):PAGE193
  J4E1   E4   IOE4 SCONN120_H61426002_SM-CONN,H61A    I45 @BASEBOARD_FAB2_LIB.BASEBOARD_FAB2(SCH_1):PAGE193
  J4E1   E6   IOE6 SCONN120_H61426002_SM-CONN,H61A    I45 @BASEBOARD_FAB2_LIB.BASEBOARD_FAB2(SCH_1):PAGE193
  J4E1   E7   IOE7 SCONN120_H61426002_SM-CONN,H61A    I45 @BASEBOARD_FAB2_LIB.BASEBOARD_FAB2(SCH_1):PAGE193
  J4E1   E8   IOE8 SCONN120_H61426002_SM-CONN,H61A    I45 @BASEBOARD_FAB2_LIB.BASEBOARD_FAB2(SCH_1):PAGE193
  J4E1   E9   IOE9 SCONN120_H61426002_SM-CONN,H61A    I45 @BASEBOARD_FAB2_LIB.BASEBOARD_FAB2(SCH_1):PAGE193
  J4E1  E10  IOE10 SCONN120_H61426002_SM-CONN,H61A    I45 @BASEBOARD_FAB2_LIB.BASEBOARD_FAB2(SCH_1):PAGE193
  J4E1  E11  IOE11 SCONN120_H61426002_SM-CONN,H61A    I45 @BASEBOARD_FAB2_LIB.BASEBOARD_FAB2(SCH_1):PAGE193
  J4E1  E12  IOE12 SCONN120_H61426002_SM-CONN,H61A    I45 @BASEBOARD_FAB2_LIB.BASEBOARD_FAB2(SCH_1):PAGE193
  J4E1  E13  IOE13 SCONN120_H61426002_SM-CONN,H61A    I45 @BASEBOARD_FAB2_LIB.BASEBOARD_FAB2(SCH_1):PAGE193
  J4E1  E14  IOE14 SCONN120_H61426002_SM-CONN,H61A    I45 @BASEBOARD_FAB2_LIB.BASEBOARD_FAB2(SCH_1):PAGE193
  J4E1  E15  IOE15 SCONN120_H61426002_SM-CONN,H61A    I45 @BASEBOARD_FAB2_LIB.BASEBOARD_FAB2(SCH_1):PAGE193
  J4E1  E16  IOE16 SCONN120_H61426002_SM-CONN,H61A    I45 @BASEBOARD_FAB2_LIB.BASEBOARD_FAB2(SCH_1):PAGE193
  J4E1  E17  IOE17 SCONN120_H61426002_SM-CONN,H61A    I45 @BASEBOARD_FAB2_LIB.BASEBOARD_FAB2(SCH_1):PAGE193
  J4E1  E18  IOE18 SCONN120_H61426002_SM-CONN,H61A    I45 @BASEBOARD_FAB2_LIB.BASEBOARD_FAB2(SCH_1):PAGE193
  J4E1  E19  IOE19 SCONN120_H61426002_SM-CONN,H61A    I45 @BASEBOARD_FAB2_LIB.BASEBOARD_FAB2(SCH_1):PAGE193
  J4E1  E20  IOE20 SCONN120_H61426002_SM-CONN,H61A    I45 @BASEBOARD_FAB2_LIB.BASEBOARD_FAB2(SCH_1):PAGE193
  J4E1   F3   IOF3 SCONN120_H61426002_SM-CONN,H61A    I45 @BASEBOARD_FAB2_LIB.BASEBOARD_FAB2(SCH_1):PAGE193
  J4E1   F4   IOF4 SCONN120_H61426002_SM-CONN,H61A    I45 @BASEBOARD_FAB2_LIB.BASEBOARD_FAB2(SCH_1):PAGE193
  J4E1   F6   IOF6 SCONN120_H61426002_SM-CONN,H61A    I45 @BASEBOARD_FAB2_LIB.BASEBOARD_FAB2(SCH_1):PAGE193
  J4E1   F7   IOF7 SCONN120_H61426002_SM-CONN,H61A    I45 @BASEBOARD_FAB2_LIB.BASEBOARD_FAB2(SCH_1):PAGE193
  J4E1   F8   IOF8 SCONN120_H61426002_SM-CONN,H61A    I45 @BASEBOARD_FAB2_LIB.BASEBOARD_FAB2(SCH_1):PAGE193
  J4E1   F9   IOF9 SCONN120_H61426002_SM-CONN,H61A    I45 @BASEBOARD_FAB2_LIB.BASEBOARD_FAB2(SCH_1):PAGE193
  J4E1  F10  IOF10 SCONN120_H61426002_SM-CONN,H61A    I45 @BASEBOARD_FAB2_LIB.BASEBOARD_FAB2(SCH_1):PAGE193
  J4E1  F11  IOF11 SCONN120_H61426002_SM-CONN,H61A    I45 @BASEBOARD_FAB2_LIB.BASEBOARD_FAB2(SCH_1):PAGE193
  J4E1  F12  IOF12 SCONN120_H61426002_SM-CONN,H61A    I45 @BASEBOARD_FAB2_LIB.BASEBOARD_FAB2(SCH_1):PAGE193
  J4E1  F13  IOF13 SCONN120_H61426002_SM-CONN,H61A    I45 @BASEBOARD_FAB2_LIB.BASEBOARD_FAB2(SCH_1):PAGE193
  J4E1  F14  IOF14 SCONN120_H61426002_SM-CONN,H61A    I45 @BASEBOARD_FAB2_LIB.BASEBOARD_FAB2(SCH_1):PAGE193
  J4E1  F15  IOF15 SCONN120_H61426002_SM-CONN,H61A    I45 @BASEBOARD_FAB2_LIB.BASEBOARD_FAB2(SCH_1):PAGE193
  J4E1  F16  IOF16 SCONN120_H61426002_SM-CONN,H61A    I45 @BASEBOARD_FAB2_LIB.BASEBOARD_FAB2(SCH_1):PAGE193
  J4E1  F17  IOF17 SCONN120_H61426002_SM-CONN,H61A    I45 @BASEBOARD_FAB2_LIB.BASEBOARD_FAB2(SCH_1):PAGE193
  J4E1  F18  IOF18 SCONN120_H61426002_SM-CONN,H61A    I45 @BASEBOARD_FAB2_LIB.BASEBOARD_FAB2(SCH_1):PAGE193
  J4E1  F19  IOF19 SCONN120_H61426002_SM-CONN,H61A    I45 @BASEBOARD_FAB2_LIB.BASEBOARD_FAB2(SCH_1):PAGE193
  J4E1  F20  IOF20 SCONN120_H61426002_SM-CONN,H61A    I45 @BASEBOARD_FAB2_LIB.BASEBOARD_FAB2(SCH_1):PAGE193
  J4B2   A9   IOA9 SCONN120_H61426002_SM-CONN,H61A    I46 @BASEBOARD_FAB2_LIB.BASEBOARD_FAB2(SCH_1):PAGE193
  J4B2  A10  IOA10 SCONN120_H61426002_SM-CONN,H61A    I46 @BASEBOARD_FAB2_LIB.BASEBOARD_FAB2(SCH_1):PAGE193
  J4B2  A12  IOA12 SCONN120_H61426002_SM-CONN,H61A    I46 @BASEBOARD_FAB2_LIB.BASEBOARD_FAB2(SCH_1):PAGE193
  J4B2  A14  IOA14 SCONN120_H61426002_SM-CONN,H61A    I46 @BASEBOARD_FAB2_LIB.BASEBOARD_FAB2(SCH_1):PAGE193
  J4B2  A17  IOA17 SCONN120_H61426002_SM-CONN,H61A    I46 @BASEBOARD_FAB2_LIB.BASEBOARD_FAB2(SCH_1):PAGE193
  J4B2   B9   IOB9 SCONN120_H61426002_SM-CONN,H61A    I46 @BASEBOARD_FAB2_LIB.BASEBOARD_FAB2(SCH_1):PAGE193
  J4B2  B10  IOB10 SCONN120_H61426002_SM-CONN,H61A    I46 @BASEBOARD_FAB2_LIB.BASEBOARD_FAB2(SCH_1):PAGE193
  J4B2  B12  IOB12 SCONN120_H61426002_SM-CONN,H61A    I46 @BASEBOARD_FAB2_LIB.BASEBOARD_FAB2(SCH_1):PAGE193
  J4B2  B14  IOB14 SCONN120_H61426002_SM-CONN,H61A    I46 @BASEBOARD_FAB2_LIB.BASEBOARD_FAB2(SCH_1):PAGE193
  J4B2  B17  IOB17 SCONN120_H61426002_SM-CONN,H61A    I46 @BASEBOARD_FAB2_LIB.BASEBOARD_FAB2(SCH_1):PAGE193
  J4B2   C1   IOC1 SCONN120_H61426002_SM-CONN,H61A    I46 @BASEBOARD_FAB2_LIB.BASEBOARD_FAB2(SCH_1):PAGE193
  J4B2   C2   IOC2 SCONN120_H61426002_SM-CONN,H61A    I46 @BASEBOARD_FAB2_LIB.BASEBOARD_FAB2(SCH_1):PAGE193
  J4B2   C3   IOC3 SCONN120_H61426002_SM-CONN,H61A    I46 @BASEBOARD_FAB2_LIB.BASEBOARD_FAB2(SCH_1):PAGE193
  J4B2   C4   IOC4 SCONN120_H61426002_SM-CONN,H61A    I46 @BASEBOARD_FAB2_LIB.BASEBOARD_FAB2(SCH_1):PAGE193
  J4B2   C5   IOC5 SCONN120_H61426002_SM-CONN,H61A    I46 @BASEBOARD_FAB2_LIB.BASEBOARD_FAB2(SCH_1):PAGE193
  J4B2   C6   IOC6 SCONN120_H61426002_SM-CONN,H61A    I46 @BASEBOARD_FAB2_LIB.BASEBOARD_FAB2(SCH_1):PAGE193
  J4B2   C7   IOC7 SCONN120_H61426002_SM-CONN,H61A    I46 @BASEBOARD_FAB2_LIB.BASEBOARD_FAB2(SCH_1):PAGE193
  J4B2   C8   IOC8 SCONN120_H61426002_SM-CONN,H61A    I46 @BASEBOARD_FAB2_LIB.BASEBOARD_FAB2(SCH_1):PAGE193
  J4B2   C9   IOC9 SCONN120_H61426002_SM-CONN,H61A    I46 @BASEBOARD_FAB2_LIB.BASEBOARD_FAB2(SCH_1):PAGE193
  J4B2  C10  IOC10 SCONN120_H61426002_SM-CONN,H61A    I46 @BASEBOARD_FAB2_LIB.BASEBOARD_FAB2(SCH_1):PAGE193
  J4B2  C12  IOC12 SCONN120_H61426002_SM-CONN,H61A    I46 @BASEBOARD_FAB2_LIB.BASEBOARD_FAB2(SCH_1):PAGE193
  J4B2  C14  IOC14 SCONN120_H61426002_SM-CONN,H61A    I46 @BASEBOARD_FAB2_LIB.BASEBOARD_FAB2(SCH_1):PAGE193
  J4B2  C15  IOC15 SCONN120_H61426002_SM-CONN,H61A    I46 @BASEBOARD_FAB2_LIB.BASEBOARD_FAB2(SCH_1):PAGE193
  J4B2  C16  IOC16 SCONN120_H61426002_SM-CONN,H61A    I46 @BASEBOARD_FAB2_LIB.BASEBOARD_FAB2(SCH_1):PAGE193
  J4B2   D2   IOD2 SCONN120_H61426002_SM-CONN,H61A    I46 @BASEBOARD_FAB2_LIB.BASEBOARD_FAB2(SCH_1):PAGE193
  J4B2   D3   IOD3 SCONN120_H61426002_SM-CONN,H61A    I46 @BASEBOARD_FAB2_LIB.BASEBOARD_FAB2(SCH_1):PAGE193
  J4B2   D4   IOD4 SCONN120_H61426002_SM-CONN,H61A    I46 @BASEBOARD_FAB2_LIB.BASEBOARD_FAB2(SCH_1):PAGE193
  J4B2   D5   IOD5 SCONN120_H61426002_SM-CONN,H61A    I46 @BASEBOARD_FAB2_LIB.BASEBOARD_FAB2(SCH_1):PAGE193
  J4B2   D6   IOD6 SCONN120_H61426002_SM-CONN,H61A    I46 @BASEBOARD_FAB2_LIB.BASEBOARD_FAB2(SCH_1):PAGE193
  J4B2   D7   IOD7 SCONN120_H61426002_SM-CONN,H61A    I46 @BASEBOARD_FAB2_LIB.BASEBOARD_FAB2(SCH_1):PAGE193
  J4B2   D8   IOD8 SCONN120_H61426002_SM-CONN,H61A    I46 @BASEBOARD_FAB2_LIB.BASEBOARD_FAB2(SCH_1):PAGE193
  J4B2   D9   IOD9 SCONN120_H61426002_SM-CONN,H61A    I46 @BASEBOARD_FAB2_LIB.BASEBOARD_FAB2(SCH_1):PAGE193
  J4B2  D10  IOD10 SCONN120_H61426002_SM-CONN,H61A    I46 @BASEBOARD_FAB2_LIB.BASEBOARD_FAB2(SCH_1):PAGE193
  J4B2  D11  IOD11 SCONN120_H61426002_SM-CONN,H61A    I46 @BASEBOARD_FAB2_LIB.BASEBOARD_FAB2(SCH_1):PAGE193
  J4B2  D12  IOD12 SCONN120_H61426002_SM-CONN,H61A    I46 @BASEBOARD_FAB2_LIB.BASEBOARD_FAB2(SCH_1):PAGE193
  J4B2  D13  IOD13 SCONN120_H61426002_SM-CONN,H61A    I46 @BASEBOARD_FAB2_LIB.BASEBOARD_FAB2(SCH_1):PAGE193
  J4B2  D14  IOD14 SCONN120_H61426002_SM-CONN,H61A    I46 @BASEBOARD_FAB2_LIB.BASEBOARD_FAB2(SCH_1):PAGE193
  J4B2   E2   IOE2 SCONN120_H61426002_SM-CONN,H61A    I46 @BASEBOARD_FAB2_LIB.BASEBOARD_FAB2(SCH_1):PAGE193
  J4B2   E3   IOE3 SCONN120_H61426002_SM-CONN,H61A    I46 @BASEBOARD_FAB2_LIB.BASEBOARD_FAB2(SCH_1):PAGE193
  J4B2   E4   IOE4 SCONN120_H61426002_SM-CONN,H61A    I46 @BASEBOARD_FAB2_LIB.BASEBOARD_FAB2(SCH_1):PAGE193
  J4B2   E5   IOE5 SCONN120_H61426002_SM-CONN,H61A    I46 @BASEBOARD_FAB2_LIB.BASEBOARD_FAB2(SCH_1):PAGE193
  J4B2   E6   IOE6 SCONN120_H61426002_SM-CONN,H61A    I46 @BASEBOARD_FAB2_LIB.BASEBOARD_FAB2(SCH_1):PAGE193
  J4B2   E7   IOE7 SCONN120_H61426002_SM-CONN,H61A    I46 @BASEBOARD_FAB2_LIB.BASEBOARD_FAB2(SCH_1):PAGE193
  J4B2   E9   IOE9 SCONN120_H61426002_SM-CONN,H61A    I46 @BASEBOARD_FAB2_LIB.BASEBOARD_FAB2(SCH_1):PAGE193
  J4B2  E11  IOE11 SCONN120_H61426002_SM-CONN,H61A    I46 @BASEBOARD_FAB2_LIB.BASEBOARD_FAB2(SCH_1):PAGE193
  J4B2  E12  IOE12 SCONN120_H61426002_SM-CONN,H61A    I46 @BASEBOARD_FAB2_LIB.BASEBOARD_FAB2(SCH_1):PAGE193
  J4B2  E13  IOE13 SCONN120_H61426002_SM-CONN,H61A    I46 @BASEBOARD_FAB2_LIB.BASEBOARD_FAB2(SCH_1):PAGE193
  J4B2  E14  IOE14 SCONN120_H61426002_SM-CONN,H61A    I46 @BASEBOARD_FAB2_LIB.BASEBOARD_FAB2(SCH_1):PAGE193
  J4B2   F2   IOF2 SCONN120_H61426002_SM-CONN,H61A    I46 @BASEBOARD_FAB2_LIB.BASEBOARD_FAB2(SCH_1):PAGE193
  J4B2   F3   IOF3 SCONN120_H61426002_SM-CONN,H61A    I46 @BASEBOARD_FAB2_LIB.BASEBOARD_FAB2(SCH_1):PAGE193
  J4B2   F4   IOF4 SCONN120_H61426002_SM-CONN,H61A    I46 @BASEBOARD_FAB2_LIB.BASEBOARD_FAB2(SCH_1):PAGE193
  J4B2   F5   IOF5 SCONN120_H61426002_SM-CONN,H61A    I46 @BASEBOARD_FAB2_LIB.BASEBOARD_FAB2(SCH_1):PAGE193
  J4B2   F6   IOF6 SCONN120_H61426002_SM-CONN,H61A    I46 @BASEBOARD_FAB2_LIB.BASEBOARD_FAB2(SCH_1):PAGE193
  J4B2   F7   IOF7 SCONN120_H61426002_SM-CONN,H61A    I46 @BASEBOARD_FAB2_LIB.BASEBOARD_FAB2(SCH_1):PAGE193
  J4B2   F9   IOF9 SCONN120_H61426002_SM-CONN,H61A    I46 @BASEBOARD_FAB2_LIB.BASEBOARD_FAB2(SCH_1):PAGE193
  J4B2  F11  IOF11 SCONN120_H61426002_SM-CONN,H61A    I46 @BASEBOARD_FAB2_LIB.BASEBOARD_FAB2(SCH_1):PAGE193
  J4B2  F12  IOF12 SCONN120_H61426002_SM-CONN,H61A    I46 @BASEBOARD_FAB2_LIB.BASEBOARD_FAB2(SCH_1):PAGE193
  J4B2  F13  IOF13 SCONN120_H61426002_SM-CONN,H61A    I46 @BASEBOARD_FAB2_LIB.BASEBOARD_FAB2(SCH_1):PAGE193
  J4B2  F14  IOF14 SCONN120_H61426002_SM-CONN,H61A    I46 @BASEBOARD_FAB2_LIB.BASEBOARD_FAB2(SCH_1):PAGE193
 C4E24    2      B CAPP_3018-470UF,2.5V,20%,ALUM,A    I61 @BASEBOARD_FAB2_LIB.BASEBOARD_FAB2(SCH_1):PAGE193
 C6R16    2      B CAPP_3018-470UF,2.5V,20%,ALUM,A    I62 @BASEBOARD_FAB2_LIB.BASEBOARD_FAB2(SCH_1):PAGE193
  C4F1    2      B CAP_A_0402V-1.0UF,6.3V,10%,X6SA    I68 @BASEBOARD_FAB2_LIB.BASEBOARD_FAB2(SCH_1):PAGE193
  C4F3    2      B CAP_A_0402V-1.0UF,6.3V,10%,X6SA    I70 @BASEBOARD_FAB2_LIB.BASEBOARD_FAB2(SCH_1):PAGE193
  C3F1    2      B CAP_A_0603V-47UF,4V,20%,X5R,60A   I140 @BASEBOARD_FAB2_LIB.BASEBOARD_FAB2(SCH_1):PAGE193
  C4F2    2      B CAP_A_0603V-47UF,4V,20%,X5R,60A   I141 @BASEBOARD_FAB2_LIB.BASEBOARD_FAB2(SCH_1):PAGE193
 R4C12    2      B RES_0402-8.06K,1%,1/16W,CHIP,GA   I169 @BASEBOARD_FAB2_LIB.BASEBOARD_FAB2(SCH_1):PAGE193
 R4C11    2      B RES_0402-3.16K,1%,1/16W,CHIP,GA   I170 @BASEBOARD_FAB2_LIB.BASEBOARD_FAB2(SCH_1):PAGE193
  C4T2    2      B CAP_A_0402V-1.0UF,6.3V,10%,X6SA     I9 @BASEBOARD_FAB2_LIB.BASEBOARD_FAB2(SCH_1):PAGE194
  C4T1    2      B CAP_A_0402V-1.0UF,6.3V,10%,X6SA    I16 @BASEBOARD_FAB2_LIB.BASEBOARD_FAB2(SCH_1):PAGE194
  C4R1    2      B CAPP_3018-470UF,2.5V,20%,ALUM,A    I29 @BASEBOARD_FAB2_LIB.BASEBOARD_FAB2(SCH_1):PAGE194
  C3R4    2      B CAPP_3018-470UF,2.5V,20%,ALUM,A    I31 @BASEBOARD_FAB2_LIB.BASEBOARD_FAB2(SCH_1):PAGE194
  J6E1  A19  IOA19 SCONN120_H61426002_SM-CONN,H61A    I55 @BASEBOARD_FAB2_LIB.BASEBOARD_FAB2(SCH_1):PAGE194
  J6E1  A20  IOA20 SCONN120_H61426002_SM-CONN,H61A    I55 @BASEBOARD_FAB2_LIB.BASEBOARD_FAB2(SCH_1):PAGE194
  J6E1  B19  IOB19 SCONN120_H61426002_SM-CONN,H61A    I55 @BASEBOARD_FAB2_LIB.BASEBOARD_FAB2(SCH_1):PAGE194
  J6E1  B20  IOB20 SCONN120_H61426002_SM-CONN,H61A    I55 @BASEBOARD_FAB2_LIB.BASEBOARD_FAB2(SCH_1):PAGE194
  J6E1  C19  IOC19 SCONN120_H61426002_SM-CONN,H61A    I55 @BASEBOARD_FAB2_LIB.BASEBOARD_FAB2(SCH_1):PAGE194
  J6E1  C20  IOC20 SCONN120_H61426002_SM-CONN,H61A    I55 @BASEBOARD_FAB2_LIB.BASEBOARD_FAB2(SCH_1):PAGE194
  J6E1   D3   IOD3 SCONN120_H61426002_SM-CONN,H61A    I55 @BASEBOARD_FAB2_LIB.BASEBOARD_FAB2(SCH_1):PAGE194
  J6E1   D4   IOD4 SCONN120_H61426002_SM-CONN,H61A    I55 @BASEBOARD_FAB2_LIB.BASEBOARD_FAB2(SCH_1):PAGE194
  J6E1   D5   IOD5 SCONN120_H61426002_SM-CONN,H61A    I55 @BASEBOARD_FAB2_LIB.BASEBOARD_FAB2(SCH_1):PAGE194
  J6E1   D6   IOD6 SCONN120_H61426002_SM-CONN,H61A    I55 @BASEBOARD_FAB2_LIB.BASEBOARD_FAB2(SCH_1):PAGE194
  J6E1   D7   IOD7 SCONN120_H61426002_SM-CONN,H61A    I55 @BASEBOARD_FAB2_LIB.BASEBOARD_FAB2(SCH_1):PAGE194
  J6E1   D8   IOD8 SCONN120_H61426002_SM-CONN,H61A    I55 @BASEBOARD_FAB2_LIB.BASEBOARD_FAB2(SCH_1):PAGE194
  J6E1   D9   IOD9 SCONN120_H61426002_SM-CONN,H61A    I55 @BASEBOARD_FAB2_LIB.BASEBOARD_FAB2(SCH_1):PAGE194
  J6E1  D10  IOD10 SCONN120_H61426002_SM-CONN,H61A    I55 @BASEBOARD_FAB2_LIB.BASEBOARD_FAB2(SCH_1):PAGE194
  J6E1  D11  IOD11 SCONN120_H61426002_SM-CONN,H61A    I55 @BASEBOARD_FAB2_LIB.BASEBOARD_FAB2(SCH_1):PAGE194
  J6E1  D12  IOD12 SCONN120_H61426002_SM-CONN,H61A    I55 @BASEBOARD_FAB2_LIB.BASEBOARD_FAB2(SCH_1):PAGE194
  J6E1  D13  IOD13 SCONN120_H61426002_SM-CONN,H61A    I55 @BASEBOARD_FAB2_LIB.BASEBOARD_FAB2(SCH_1):PAGE194
  J6E1  D14  IOD14 SCONN120_H61426002_SM-CONN,H61A    I55 @BASEBOARD_FAB2_LIB.BASEBOARD_FAB2(SCH_1):PAGE194
  J6E1  D15  IOD15 SCONN120_H61426002_SM-CONN,H61A    I55 @BASEBOARD_FAB2_LIB.BASEBOARD_FAB2(SCH_1):PAGE194
  J6E1  D16  IOD16 SCONN120_H61426002_SM-CONN,H61A    I55 @BASEBOARD_FAB2_LIB.BASEBOARD_FAB2(SCH_1):PAGE194
  J6E1  D17  IOD17 SCONN120_H61426002_SM-CONN,H61A    I55 @BASEBOARD_FAB2_LIB.BASEBOARD_FAB2(SCH_1):PAGE194
  J6E1  D18  IOD18 SCONN120_H61426002_SM-CONN,H61A    I55 @BASEBOARD_FAB2_LIB.BASEBOARD_FAB2(SCH_1):PAGE194
  J6E1  D19  IOD19 SCONN120_H61426002_SM-CONN,H61A    I55 @BASEBOARD_FAB2_LIB.BASEBOARD_FAB2(SCH_1):PAGE194
  J6E1  D20  IOD20 SCONN120_H61426002_SM-CONN,H61A    I55 @BASEBOARD_FAB2_LIB.BASEBOARD_FAB2(SCH_1):PAGE194
  J6E1   E3   IOE3 SCONN120_H61426002_SM-CONN,H61A    I55 @BASEBOARD_FAB2_LIB.BASEBOARD_FAB2(SCH_1):PAGE194
  J6E1   E4   IOE4 SCONN120_H61426002_SM-CONN,H61A    I55 @BASEBOARD_FAB2_LIB.BASEBOARD_FAB2(SCH_1):PAGE194
  J6E1   E6   IOE6 SCONN120_H61426002_SM-CONN,H61A    I55 @BASEBOARD_FAB2_LIB.BASEBOARD_FAB2(SCH_1):PAGE194
  J6E1   E7   IOE7 SCONN120_H61426002_SM-CONN,H61A    I55 @BASEBOARD_FAB2_LIB.BASEBOARD_FAB2(SCH_1):PAGE194
  J6E1   E8   IOE8 SCONN120_H61426002_SM-CONN,H61A    I55 @BASEBOARD_FAB2_LIB.BASEBOARD_FAB2(SCH_1):PAGE194
  J6E1   E9   IOE9 SCONN120_H61426002_SM-CONN,H61A    I55 @BASEBOARD_FAB2_LIB.BASEBOARD_FAB2(SCH_1):PAGE194
  J6E1  E10  IOE10 SCONN120_H61426002_SM-CONN,H61A    I55 @BASEBOARD_FAB2_LIB.BASEBOARD_FAB2(SCH_1):PAGE194
  J6E1  E11  IOE11 SCONN120_H61426002_SM-CONN,H61A    I55 @BASEBOARD_FAB2_LIB.BASEBOARD_FAB2(SCH_1):PAGE194
  J6E1  E12  IOE12 SCONN120_H61426002_SM-CONN,H61A    I55 @BASEBOARD_FAB2_LIB.BASEBOARD_FAB2(SCH_1):PAGE194
  J6E1  E13  IOE13 SCONN120_H61426002_SM-CONN,H61A    I55 @BASEBOARD_FAB2_LIB.BASEBOARD_FAB2(SCH_1):PAGE194
  J6E1  E14  IOE14 SCONN120_H61426002_SM-CONN,H61A    I55 @BASEBOARD_FAB2_LIB.BASEBOARD_FAB2(SCH_1):PAGE194
  J6E1  E15  IOE15 SCONN120_H61426002_SM-CONN,H61A    I55 @BASEBOARD_FAB2_LIB.BASEBOARD_FAB2(SCH_1):PAGE194
  J6E1  E16  IOE16 SCONN120_H61426002_SM-CONN,H61A    I55 @BASEBOARD_FAB2_LIB.BASEBOARD_FAB2(SCH_1):PAGE194
  J6E1  E17  IOE17 SCONN120_H61426002_SM-CONN,H61A    I55 @BASEBOARD_FAB2_LIB.BASEBOARD_FAB2(SCH_1):PAGE194
  J6E1  E18  IOE18 SCONN120_H61426002_SM-CONN,H61A    I55 @BASEBOARD_FAB2_LIB.BASEBOARD_FAB2(SCH_1):PAGE194
  J6E1  E19  IOE19 SCONN120_H61426002_SM-CONN,H61A    I55 @BASEBOARD_FAB2_LIB.BASEBOARD_FAB2(SCH_1):PAGE194
  J6E1  E20  IOE20 SCONN120_H61426002_SM-CONN,H61A    I55 @BASEBOARD_FAB2_LIB.BASEBOARD_FAB2(SCH_1):PAGE194
  J6E1   F3   IOF3 SCONN120_H61426002_SM-CONN,H61A    I55 @BASEBOARD_FAB2_LIB.BASEBOARD_FAB2(SCH_1):PAGE194
  J6E1   F4   IOF4 SCONN120_H61426002_SM-CONN,H61A    I55 @BASEBOARD_FAB2_LIB.BASEBOARD_FAB2(SCH_1):PAGE194
  J6E1   F6   IOF6 SCONN120_H61426002_SM-CONN,H61A    I55 @BASEBOARD_FAB2_LIB.BASEBOARD_FAB2(SCH_1):PAGE194
  J6E1   F7   IOF7 SCONN120_H61426002_SM-CONN,H61A    I55 @BASEBOARD_FAB2_LIB.BASEBOARD_FAB2(SCH_1):PAGE194
  J6E1   F8   IOF8 SCONN120_H61426002_SM-CONN,H61A    I55 @BASEBOARD_FAB2_LIB.BASEBOARD_FAB2(SCH_1):PAGE194
  J6E1   F9   IOF9 SCONN120_H61426002_SM-CONN,H61A    I55 @BASEBOARD_FAB2_LIB.BASEBOARD_FAB2(SCH_1):PAGE194
  J6E1  F10  IOF10 SCONN120_H61426002_SM-CONN,H61A    I55 @BASEBOARD_FAB2_LIB.BASEBOARD_FAB2(SCH_1):PAGE194
  J6E1  F11  IOF11 SCONN120_H61426002_SM-CONN,H61A    I55 @BASEBOARD_FAB2_LIB.BASEBOARD_FAB2(SCH_1):PAGE194
  J6E1  F12  IOF12 SCONN120_H61426002_SM-CONN,H61A    I55 @BASEBOARD_FAB2_LIB.BASEBOARD_FAB2(SCH_1):PAGE194
  J6E1  F13  IOF13 SCONN120_H61426002_SM-CONN,H61A    I55 @BASEBOARD_FAB2_LIB.BASEBOARD_FAB2(SCH_1):PAGE194
  J6E1  F14  IOF14 SCONN120_H61426002_SM-CONN,H61A    I55 @BASEBOARD_FAB2_LIB.BASEBOARD_FAB2(SCH_1):PAGE194
  J6E1  F15  IOF15 SCONN120_H61426002_SM-CONN,H61A    I55 @BASEBOARD_FAB2_LIB.BASEBOARD_FAB2(SCH_1):PAGE194
  J6E1  F16  IOF16 SCONN120_H61426002_SM-CONN,H61A    I55 @BASEBOARD_FAB2_LIB.BASEBOARD_FAB2(SCH_1):PAGE194
  J6E1  F17  IOF17 SCONN120_H61426002_SM-CONN,H61A    I55 @BASEBOARD_FAB2_LIB.BASEBOARD_FAB2(SCH_1):PAGE194
  J6E1  F18  IOF18 SCONN120_H61426002_SM-CONN,H61A    I55 @BASEBOARD_FAB2_LIB.BASEBOARD_FAB2(SCH_1):PAGE194
  J6E1  F19  IOF19 SCONN120_H61426002_SM-CONN,H61A    I55 @BASEBOARD_FAB2_LIB.BASEBOARD_FAB2(SCH_1):PAGE194
  J6E1  F20  IOF20 SCONN120_H61426002_SM-CONN,H61A    I55 @BASEBOARD_FAB2_LIB.BASEBOARD_FAB2(SCH_1):PAGE194
  J6B1   A9   IOA9 SCONN120_H61426002_SM-CONN,H61A    I56 @BASEBOARD_FAB2_LIB.BASEBOARD_FAB2(SCH_1):PAGE194
  J6B1  A10  IOA10 SCONN120_H61426002_SM-CONN,H61A    I56 @BASEBOARD_FAB2_LIB.BASEBOARD_FAB2(SCH_1):PAGE194
  J6B1  A12  IOA12 SCONN120_H61426002_SM-CONN,H61A    I56 @BASEBOARD_FAB2_LIB.BASEBOARD_FAB2(SCH_1):PAGE194
  J6B1  A14  IOA14 SCONN120_H61426002_SM-CONN,H61A    I56 @BASEBOARD_FAB2_LIB.BASEBOARD_FAB2(SCH_1):PAGE194
  J6B1  A17  IOA17 SCONN120_H61426002_SM-CONN,H61A    I56 @BASEBOARD_FAB2_LIB.BASEBOARD_FAB2(SCH_1):PAGE194
  J6B1   B9   IOB9 SCONN120_H61426002_SM-CONN,H61A    I56 @BASEBOARD_FAB2_LIB.BASEBOARD_FAB2(SCH_1):PAGE194
  J6B1  B10  IOB10 SCONN120_H61426002_SM-CONN,H61A    I56 @BASEBOARD_FAB2_LIB.BASEBOARD_FAB2(SCH_1):PAGE194
  J6B1  B12  IOB12 SCONN120_H61426002_SM-CONN,H61A    I56 @BASEBOARD_FAB2_LIB.BASEBOARD_FAB2(SCH_1):PAGE194
  J6B1  B14  IOB14 SCONN120_H61426002_SM-CONN,H61A    I56 @BASEBOARD_FAB2_LIB.BASEBOARD_FAB2(SCH_1):PAGE194
  J6B1  B17  IOB17 SCONN120_H61426002_SM-CONN,H61A    I56 @BASEBOARD_FAB2_LIB.BASEBOARD_FAB2(SCH_1):PAGE194
  J6B1   C1   IOC1 SCONN120_H61426002_SM-CONN,H61A    I56 @BASEBOARD_FAB2_LIB.BASEBOARD_FAB2(SCH_1):PAGE194
  J6B1   C2   IOC2 SCONN120_H61426002_SM-CONN,H61A    I56 @BASEBOARD_FAB2_LIB.BASEBOARD_FAB2(SCH_1):PAGE194
  J6B1   C3   IOC3 SCONN120_H61426002_SM-CONN,H61A    I56 @BASEBOARD_FAB2_LIB.BASEBOARD_FAB2(SCH_1):PAGE194
  J6B1   C4   IOC4 SCONN120_H61426002_SM-CONN,H61A    I56 @BASEBOARD_FAB2_LIB.BASEBOARD_FAB2(SCH_1):PAGE194
  J6B1   C5   IOC5 SCONN120_H61426002_SM-CONN,H61A    I56 @BASEBOARD_FAB2_LIB.BASEBOARD_FAB2(SCH_1):PAGE194
  J6B1   C6   IOC6 SCONN120_H61426002_SM-CONN,H61A    I56 @BASEBOARD_FAB2_LIB.BASEBOARD_FAB2(SCH_1):PAGE194
  J6B1   C7   IOC7 SCONN120_H61426002_SM-CONN,H61A    I56 @BASEBOARD_FAB2_LIB.BASEBOARD_FAB2(SCH_1):PAGE194
  J6B1   C8   IOC8 SCONN120_H61426002_SM-CONN,H61A    I56 @BASEBOARD_FAB2_LIB.BASEBOARD_FAB2(SCH_1):PAGE194
  J6B1   C9   IOC9 SCONN120_H61426002_SM-CONN,H61A    I56 @BASEBOARD_FAB2_LIB.BASEBOARD_FAB2(SCH_1):PAGE194
  J6B1  C10  IOC10 SCONN120_H61426002_SM-CONN,H61A    I56 @BASEBOARD_FAB2_LIB.BASEBOARD_FAB2(SCH_1):PAGE194
  J6B1  C12  IOC12 SCONN120_H61426002_SM-CONN,H61A    I56 @BASEBOARD_FAB2_LIB.BASEBOARD_FAB2(SCH_1):PAGE194
  J6B1  C14  IOC14 SCONN120_H61426002_SM-CONN,H61A    I56 @BASEBOARD_FAB2_LIB.BASEBOARD_FAB2(SCH_1):PAGE194
  J6B1  C15  IOC15 SCONN120_H61426002_SM-CONN,H61A    I56 @BASEBOARD_FAB2_LIB.BASEBOARD_FAB2(SCH_1):PAGE194
  J6B1  C16  IOC16 SCONN120_H61426002_SM-CONN,H61A    I56 @BASEBOARD_FAB2_LIB.BASEBOARD_FAB2(SCH_1):PAGE194
  J6B1   D2   IOD2 SCONN120_H61426002_SM-CONN,H61A    I56 @BASEBOARD_FAB2_LIB.BASEBOARD_FAB2(SCH_1):PAGE194
  J6B1   D3   IOD3 SCONN120_H61426002_SM-CONN,H61A    I56 @BASEBOARD_FAB2_LIB.BASEBOARD_FAB2(SCH_1):PAGE194
  J6B1   D4   IOD4 SCONN120_H61426002_SM-CONN,H61A    I56 @BASEBOARD_FAB2_LIB.BASEBOARD_FAB2(SCH_1):PAGE194
  J6B1   D5   IOD5 SCONN120_H61426002_SM-CONN,H61A    I56 @BASEBOARD_FAB2_LIB.BASEBOARD_FAB2(SCH_1):PAGE194
  J6B1   D6   IOD6 SCONN120_H61426002_SM-CONN,H61A    I56 @BASEBOARD_FAB2_LIB.BASEBOARD_FAB2(SCH_1):PAGE194
  J6B1   D7   IOD7 SCONN120_H61426002_SM-CONN,H61A    I56 @BASEBOARD_FAB2_LIB.BASEBOARD_FAB2(SCH_1):PAGE194
  J6B1   D8   IOD8 SCONN120_H61426002_SM-CONN,H61A    I56 @BASEBOARD_FAB2_LIB.BASEBOARD_FAB2(SCH_1):PAGE194
  J6B1   D9   IOD9 SCONN120_H61426002_SM-CONN,H61A    I56 @BASEBOARD_FAB2_LIB.BASEBOARD_FAB2(SCH_1):PAGE194
  J6B1  D10  IOD10 SCONN120_H61426002_SM-CONN,H61A    I56 @BASEBOARD_FAB2_LIB.BASEBOARD_FAB2(SCH_1):PAGE194
  J6B1  D11  IOD11 SCONN120_H61426002_SM-CONN,H61A    I56 @BASEBOARD_FAB2_LIB.BASEBOARD_FAB2(SCH_1):PAGE194
  J6B1  D12  IOD12 SCONN120_H61426002_SM-CONN,H61A    I56 @BASEBOARD_FAB2_LIB.BASEBOARD_FAB2(SCH_1):PAGE194
  J6B1  D13  IOD13 SCONN120_H61426002_SM-CONN,H61A    I56 @BASEBOARD_FAB2_LIB.BASEBOARD_FAB2(SCH_1):PAGE194
  J6B1  D14  IOD14 SCONN120_H61426002_SM-CONN,H61A    I56 @BASEBOARD_FAB2_LIB.BASEBOARD_FAB2(SCH_1):PAGE194
  J6B1   E2   IOE2 SCONN120_H61426002_SM-CONN,H61A    I56 @BASEBOARD_FAB2_LIB.BASEBOARD_FAB2(SCH_1):PAGE194
  J6B1   E3   IOE3 SCONN120_H61426002_SM-CONN,H61A    I56 @BASEBOARD_FAB2_LIB.BASEBOARD_FAB2(SCH_1):PAGE194
  J6B1   E4   IOE4 SCONN120_H61426002_SM-CONN,H61A    I56 @BASEBOARD_FAB2_LIB.BASEBOARD_FAB2(SCH_1):PAGE194
  J6B1   E5   IOE5 SCONN120_H61426002_SM-CONN,H61A    I56 @BASEBOARD_FAB2_LIB.BASEBOARD_FAB2(SCH_1):PAGE194
  J6B1   E6   IOE6 SCONN120_H61426002_SM-CONN,H61A    I56 @BASEBOARD_FAB2_LIB.BASEBOARD_FAB2(SCH_1):PAGE194
  J6B1   E7   IOE7 SCONN120_H61426002_SM-CONN,H61A    I56 @BASEBOARD_FAB2_LIB.BASEBOARD_FAB2(SCH_1):PAGE194
  J6B1   E9   IOE9 SCONN120_H61426002_SM-CONN,H61A    I56 @BASEBOARD_FAB2_LIB.BASEBOARD_FAB2(SCH_1):PAGE194
  J6B1  E11  IOE11 SCONN120_H61426002_SM-CONN,H61A    I56 @BASEBOARD_FAB2_LIB.BASEBOARD_FAB2(SCH_1):PAGE194
  J6B1  E12  IOE12 SCONN120_H61426002_SM-CONN,H61A    I56 @BASEBOARD_FAB2_LIB.BASEBOARD_FAB2(SCH_1):PAGE194
  J6B1  E13  IOE13 SCONN120_H61426002_SM-CONN,H61A    I56 @BASEBOARD_FAB2_LIB.BASEBOARD_FAB2(SCH_1):PAGE194
  J6B1  E14  IOE14 SCONN120_H61426002_SM-CONN,H61A    I56 @BASEBOARD_FAB2_LIB.BASEBOARD_FAB2(SCH_1):PAGE194
  J6B1   F2   IOF2 SCONN120_H61426002_SM-CONN,H61A    I56 @BASEBOARD_FAB2_LIB.BASEBOARD_FAB2(SCH_1):PAGE194
  J6B1   F3   IOF3 SCONN120_H61426002_SM-CONN,H61A    I56 @BASEBOARD_FAB2_LIB.BASEBOARD_FAB2(SCH_1):PAGE194
  J6B1   F4   IOF4 SCONN120_H61426002_SM-CONN,H61A    I56 @BASEBOARD_FAB2_LIB.BASEBOARD_FAB2(SCH_1):PAGE194
  J6B1   F5   IOF5 SCONN120_H61426002_SM-CONN,H61A    I56 @BASEBOARD_FAB2_LIB.BASEBOARD_FAB2(SCH_1):PAGE194
  J6B1   F6   IOF6 SCONN120_H61426002_SM-CONN,H61A    I56 @BASEBOARD_FAB2_LIB.BASEBOARD_FAB2(SCH_1):PAGE194
  J6B1   F7   IOF7 SCONN120_H61426002_SM-CONN,H61A    I56 @BASEBOARD_FAB2_LIB.BASEBOARD_FAB2(SCH_1):PAGE194
  J6B1   F9   IOF9 SCONN120_H61426002_SM-CONN,H61A    I56 @BASEBOARD_FAB2_LIB.BASEBOARD_FAB2(SCH_1):PAGE194
  J6B1  F11  IOF11 SCONN120_H61426002_SM-CONN,H61A    I56 @BASEBOARD_FAB2_LIB.BASEBOARD_FAB2(SCH_1):PAGE194
  J6B1  F12  IOF12 SCONN120_H61426002_SM-CONN,H61A    I56 @BASEBOARD_FAB2_LIB.BASEBOARD_FAB2(SCH_1):PAGE194
  J6B1  F13  IOF13 SCONN120_H61426002_SM-CONN,H61A    I56 @BASEBOARD_FAB2_LIB.BASEBOARD_FAB2(SCH_1):PAGE194
  J6B1  F14  IOF14 SCONN120_H61426002_SM-CONN,H61A    I56 @BASEBOARD_FAB2_LIB.BASEBOARD_FAB2(SCH_1):PAGE194
 C3N40    2      B CAP_A_0402V-1.0UF,6.3V,10%,X6SA    I86 @BASEBOARD_FAB2_LIB.BASEBOARD_FAB2(SCH_1):PAGE194
 C3M46    2      B CAP_A_0402V-1.0UF,6.3V,10%,X6SA    I99 @BASEBOARD_FAB2_LIB.BASEBOARD_FAB2(SCH_1):PAGE194
 C3N14    2      B CAPP_3018-470UF,2.5V,20%,ALUM,A   I101 @BASEBOARD_FAB2_LIB.BASEBOARD_FAB2(SCH_1):PAGE194
  C3T1    2      B CAP_A_0603V-47UF,4V,20%,X5R,60A   I149 @BASEBOARD_FAB2_LIB.BASEBOARD_FAB2(SCH_1):PAGE194
  C3T2    2      B CAP_A_0603V-47UF,4V,20%,X5R,60A   I150 @BASEBOARD_FAB2_LIB.BASEBOARD_FAB2(SCH_1):PAGE194
 R7C24    2      B RES_0402-4.02K,1%,1/16W,CHIP,GA   I155 @BASEBOARD_FAB2_LIB.BASEBOARD_FAB2(SCH_1):PAGE194
 R3N29    2      B RES_0402-16K,1.0%,1/16W,CHIP,GA   I156 @BASEBOARD_FAB2_LIB.BASEBOARD_FAB2(SCH_1):PAGE194
 RM1E1    1    IO1 CONN3_G98259001_PIP-CONN,G9825A    I26 @BASEBOARD_FAB2_LIB.BASEBOARD_FAB2(SCH_1):PAGE195
 RM1E1    2    IO2 CONN3_G98259001_PIP-CONN,G9825A    I26 @BASEBOARD_FAB2_LIB.BASEBOARD_FAB2(SCH_1):PAGE195
 RM1E1    3    IO3 CONN3_G98259001_PIP-CONN,G9825A    I26 @BASEBOARD_FAB2_LIB.BASEBOARD_FAB2(SCH_1):PAGE195
  J1E1   C1     C1 CONN12_G98257001_THMT-CONN,G98A    I29 @BASEBOARD_FAB2_LIB.BASEBOARD_FAB2(SCH_1):PAGE195
  J1E1   C2     C2 CONN12_G98257001_THMT-CONN,G98A    I29 @BASEBOARD_FAB2_LIB.BASEBOARD_FAB2(SCH_1):PAGE195
  J1E1   C3     C3 CONN12_G98257001_THMT-CONN,G98A    I29 @BASEBOARD_FAB2_LIB.BASEBOARD_FAB2(SCH_1):PAGE195
  J1E1   D1     D1 CONN12_G98257001_THMT-CONN,G98A    I29 @BASEBOARD_FAB2_LIB.BASEBOARD_FAB2(SCH_1):PAGE195
  J1E1   D2     D2 CONN12_G98257001_THMT-CONN,G98A    I29 @BASEBOARD_FAB2_LIB.BASEBOARD_FAB2(SCH_1):PAGE195
  J1E1   D3     D3 CONN12_G98257001_THMT-CONN,G98A    I29 @BASEBOARD_FAB2_LIB.BASEBOARD_FAB2(SCH_1):PAGE195
  C9R5    2      B CAP_0805-10UF,16V,10%,X6S,C953A    I31 @BASEBOARD_FAB2_LIB.BASEBOARD_FAB2(SCH_1):PAGE195
 C1E12    2      B CAP_0805-10UF,16V,10%,X6S,C953A    I32 @BASEBOARD_FAB2_LIB.BASEBOARD_FAB2(SCH_1):PAGE195
 C1E15    2      B CAP_0805-10UF,16V,10%,X6S,C953A    I35 @BASEBOARD_FAB2_LIB.BASEBOARD_FAB2(SCH_1):PAGE195
 C9R12    2      B CAP_A_0402V-0.1UF,16V,10%,X7R,A    I36 @BASEBOARD_FAB2_LIB.BASEBOARD_FAB2(SCH_1):PAGE195
  C9R6    2      B CAP_A_0402V-0.1UF,16V,10%,X7R,A    I37 @BASEBOARD_FAB2_LIB.BASEBOARD_FAB2(SCH_1):PAGE195
 C1E17    2      B CAP_A_0402V-0.1UF,16V,10%,X7R,A    I38 @BASEBOARD_FAB2_LIB.BASEBOARD_FAB2(SCH_1):PAGE195
 C1E16    2      B CAP_A_0402V-0.1UF,16V,10%,X7R,A    I39 @BASEBOARD_FAB2_LIB.BASEBOARD_FAB2(SCH_1):PAGE195
 TH4G1    1      1 MTG_KEYHOLE_TH-EMPTY,NA    I49 @BASEBOARD_FAB2_LIB.BASEBOARD_FAB2(SCH_1):PAGE195
 TH9G1    1      1 MTG_KEYHOLE_TH-EMPTY,NA    I52 @BASEBOARD_FAB2_LIB.BASEBOARD_FAB2(SCH_1):PAGE195
 TH9A1    1      1 MTG_KEYHOLE_TH-EMPTY,NA    I54 @BASEBOARD_FAB2_LIB.BASEBOARD_FAB2(SCH_1):PAGE195
 TH1A1    1      1 MTG_KEYHOLE_TH-EMPTY,NA    I56 @BASEBOARD_FAB2_LIB.BASEBOARD_FAB2(SCH_1):PAGE195
 TH4A1    1      1 MTG_KEYHOLE_TH-EMPTY,NA    I62 @BASEBOARD_FAB2_LIB.BASEBOARD_FAB2(SCH_1):PAGE195
 TH7A1    1      1 MTG_KEYHOLE_TH-EMPTY,NA    I65 @BASEBOARD_FAB2_LIB.BASEBOARD_FAB2(SCH_1):PAGE195
 TH7G1    1      1 MTG_KEYHOLE_TH-EMPTY,NA    I67 @BASEBOARD_FAB2_LIB.BASEBOARD_FAB2(SCH_1):PAGE195
  J1D1   C1     C1 CONN12_G98257001_THMT-CONN,G98A    I78 @BASEBOARD_FAB2_LIB.BASEBOARD_FAB2(SCH_1):PAGE195
  J1D1   C2     C2 CONN12_G98257001_THMT-CONN,G98A    I78 @BASEBOARD_FAB2_LIB.BASEBOARD_FAB2(SCH_1):PAGE195
  J1D1   C3     C3 CONN12_G98257001_THMT-CONN,G98A    I78 @BASEBOARD_FAB2_LIB.BASEBOARD_FAB2(SCH_1):PAGE195
  J1D1   D1     D1 CONN12_G98257001_THMT-CONN,G98A    I78 @BASEBOARD_FAB2_LIB.BASEBOARD_FAB2(SCH_1):PAGE195
  J1D1   D2     D2 CONN12_G98257001_THMT-CONN,G98A    I78 @BASEBOARD_FAB2_LIB.BASEBOARD_FAB2(SCH_1):PAGE195
  J1D1   D3     D3 CONN12_G98257001_THMT-CONN,G98A    I78 @BASEBOARD_FAB2_LIB.BASEBOARD_FAB2(SCH_1):PAGE195
  C4F6    2      B CAPP_4040LF-470UF,16V,20%,ALUMA    I82 @BASEBOARD_FAB2_LIB.BASEBOARD_FAB2(SCH_1):PAGE195
 C4B13    2      B CAPP_4040LF-470UF,16V,20%,ALUMA    I83 @BASEBOARD_FAB2_LIB.BASEBOARD_FAB2(SCH_1):PAGE195
 C1B14    2      B CAPP_4040LF-470UF,16V,20%,ALUMA    I84 @BASEBOARD_FAB2_LIB.BASEBOARD_FAB2(SCH_1):PAGE195
  C1F7    2      B CAPP_4040LF-470UF,16V,20%,ALUMA    I85 @BASEBOARD_FAB2_LIB.BASEBOARD_FAB2(SCH_1):PAGE195
  C4F5    2      B CAPP_3018-68UF,16V,20%,TANT,72A    I96 @BASEBOARD_FAB2_LIB.BASEBOARD_FAB2(SCH_1):PAGE195
 C4B14    2      B CAPP_3018-68UF,16V,20%,TANT,72A    I97 @BASEBOARD_FAB2_LIB.BASEBOARD_FAB2(SCH_1):PAGE195
  C3T6    2      B CAPP_3018-68UF,16V,20%,TANT,72A    I98 @BASEBOARD_FAB2_LIB.BASEBOARD_FAB2(SCH_1):PAGE195
  C9M3    2      B CAPP_3018-68UF,16V,20%,TANT,72A    I99 @BASEBOARD_FAB2_LIB.BASEBOARD_FAB2(SCH_1):PAGE195
  C3B6    2      B CAPP_3018-68UF,16V,20%,TANT,72A   I100 @BASEBOARD_FAB2_LIB.BASEBOARD_FAB2(SCH_1):PAGE195
 C1R23    2      B CAPP_3018-68UF,16V,20%,TANT,72A   I101 @BASEBOARD_FAB2_LIB.BASEBOARD_FAB2(SCH_1):PAGE195
  C4M6    2      B CAPP_3018-68UF,16V,20%,TANT,72A   I102 @BASEBOARD_FAB2_LIB.BASEBOARD_FAB2(SCH_1):PAGE195
  C1M5    2      B CAPP_3018-68UF,16V,20%,TANT,72A   I103 @BASEBOARD_FAB2_LIB.BASEBOARD_FAB2(SCH_1):PAGE195
 C3T13    2      B CAPP_3018-68UF,16V,20%,TANT,72A   I104 @BASEBOARD_FAB2_LIB.BASEBOARD_FAB2(SCH_1):PAGE195
  C4M7    2      B CAPP_3018-68UF,16V,20%,TANT,72A   I105 @BASEBOARD_FAB2_LIB.BASEBOARD_FAB2(SCH_1):PAGE195
 C3T15    2      B CAPP_3018-68UF,16V,20%,TANT,72A   I106 @BASEBOARD_FAB2_LIB.BASEBOARD_FAB2(SCH_1):PAGE195
  C7M6    2      B CAPP_3018-68UF,16V,20%,TANT,72A   I108 @BASEBOARD_FAB2_LIB.BASEBOARD_FAB2(SCH_1):PAGE195
  C6N5    2      B CAPP_3018-68UF,16V,20%,TANT,72A   I109 @BASEBOARD_FAB2_LIB.BASEBOARD_FAB2(SCH_1):PAGE195
  C9T3    2      B CAPP_3018-68UF,16V,20%,TANT,72A   I111 @BASEBOARD_FAB2_LIB.BASEBOARD_FAB2(SCH_1):PAGE195
  C4F4    2      B CAPP_3018-68UF,16V,20%,TANT,72A   I112 @BASEBOARD_FAB2_LIB.BASEBOARD_FAB2(SCH_1):PAGE195
  C3T3    2      B CAPP_3018-68UF,16V,20%,TANT,72A   I113 @BASEBOARD_FAB2_LIB.BASEBOARD_FAB2(SCH_1):PAGE195
XBT8G1    3      N VERT_BATT_3PIN_PIP-3PVERT,C686A    I51 @BASEBOARD_FAB2_LIB.BASEBOARD_FAB2(SCH_1):PAGE196
 C3P45    2      B CAP_0402-0.047UF,25V,10%,X7R,AA    I60 @BASEBOARD_FAB2_LIB.BASEBOARD_FAB2(SCH_1):PAGE196
  U7D3    2    GND ADM1085_SMT-IC,H46130-001    I70 @BASEBOARD_FAB2_LIB.BASEBOARD_FAB2(SCH_1):PAGE196
 C3P46    2      B CAP_A_0402V-0.1UF,16V,10%,X7R,A    I72 @BASEBOARD_FAB2_LIB.BASEBOARD_FAB2(SCH_1):PAGE196
 R3P51    2      B RES_0402-6.34K,1%,1/16W,CHIP,GA    I75 @BASEBOARD_FAB2_LIB.BASEBOARD_FAB2(SCH_1):PAGE196
 C1L16    2      B CAP_A_0402V-0.1UF,16V,10%,X7R,A    I81 @BASEBOARD_FAB2_LIB.BASEBOARD_FAB2(SCH_1):PAGE196
  C8E3    2      B CAP_A_0402V-0.1UF,16V,10%,X7R,A    I94 @BASEBOARD_FAB2_LIB.BASEBOARD_FAB2(SCH_1):PAGE196
 C2U26    2      B CAP_A_0402V-1.0UF,6.3V,10%,X6SA   I102 @BASEBOARD_FAB2_LIB.BASEBOARD_FAB2(SCH_1):PAGE196
  U8D8    5    GND TPS3700_SM-IC,H69492-001   I104 @BASEBOARD_FAB2_LIB.BASEBOARD_FAB2(SCH_1):PAGE196
  C8D4    2      B CAP_A_0402V-0.1UF,16V,10%,X7R,A   I105 @BASEBOARD_FAB2_LIB.BASEBOARD_FAB2(SCH_1):PAGE196
 R8D40    2      B RES_0402-3.74K,1%,1/16W,CHIP,GA   I113 @BASEBOARD_FAB2_LIB.BASEBOARD_FAB2(SCH_1):PAGE196
 R8D37    2      B RES_0402-4.75K,1%,1/16W,CHIP,GA   I115 @BASEBOARD_FAB2_LIB.BASEBOARD_FAB2(SCH_1):PAGE196
  Q2P2    2    SRC FET_N_SOT23-2N7002,FET,C79254-A   I124 @BASEBOARD_FAB2_LIB.BASEBOARD_FAB2(SCH_1):PAGE196
 C6U18    2      B CAP_0805-10UF,16V,10%,X7R,G106A    I52 @BASEBOARD_FAB2_LIB.BASEBOARD_FAB2(SCH_1):PAGE197
  C6T2    2      B CAP_0805-10UF,16V,10%,X7R,G106A    I54 @BASEBOARD_FAB2_LIB.BASEBOARD_FAB2(SCH_1):PAGE197
 C4B11    2      B CAP_0805-10UF,16V,10%,X7R,G106A    I59 @BASEBOARD_FAB2_LIB.BASEBOARD_FAB2(SCH_1):PAGE197
  C4A4    2      B CAP_0805-10UF,16V,10%,X7R,G106A    I62 @BASEBOARD_FAB2_LIB.BASEBOARD_FAB2(SCH_1):PAGE197
 C6U10    2      B CAP_0805-10UF,16V,10%,X7R,G106A    I65 @BASEBOARD_FAB2_LIB.BASEBOARD_FAB2(SCH_1):PAGE197
 C4A17    2      B CAP_0805-10UF,16V,10%,X7R,G106A    I67 @BASEBOARD_FAB2_LIB.BASEBOARD_FAB2(SCH_1):PAGE197
  C9T8    2      B CAP_0805-10UF,16V,10%,X7R,G106A    I70 @BASEBOARD_FAB2_LIB.BASEBOARD_FAB2(SCH_1):PAGE197
 C9U11    2      B CAP_0805-10UF,16V,10%,X7R,G106A    I73 @BASEBOARD_FAB2_LIB.BASEBOARD_FAB2(SCH_1):PAGE197
  C9U8    2      B CAP_0805-10UF,16V,10%,X7R,G106A    I76 @BASEBOARD_FAB2_LIB.BASEBOARD_FAB2(SCH_1):PAGE197
  C1A4    2      B CAP_0805-10UF,16V,10%,X7R,G106A    I79 @BASEBOARD_FAB2_LIB.BASEBOARD_FAB2(SCH_1):PAGE197
  C1B7    2      B CAP_0805-10UF,16V,10%,X7R,G106A    I82 @BASEBOARD_FAB2_LIB.BASEBOARD_FAB2(SCH_1):PAGE197
 C1A16    2      B CAP_0805-10UF,16V,10%,X7R,G106A    I85 @BASEBOARD_FAB2_LIB.BASEBOARD_FAB2(SCH_1):PAGE197
  U4F1    2 GND<0> MAX9634_SOT-IC,H35789-001    I97 @BASEBOARD_FAB2_LIB.BASEBOARD_FAB2(SCH_1):PAGE197
  U4F1    1 GND<1> MAX9634_SOT-IC,H35789-001    I97 @BASEBOARD_FAB2_LIB.BASEBOARD_FAB2(SCH_1):PAGE197
  U4B1    2 GND<0> MAX9634_SOT-IC,H35789-001   I120 @BASEBOARD_FAB2_LIB.BASEBOARD_FAB2(SCH_1):PAGE197
  U4B1    1 GND<1> MAX9634_SOT-IC,H35789-001   I120 @BASEBOARD_FAB2_LIB.BASEBOARD_FAB2(SCH_1):PAGE197
  U1F1    2 GND<0> MAX9634_SOT-IC,H35789-001   I133 @BASEBOARD_FAB2_LIB.BASEBOARD_FAB2(SCH_1):PAGE197
  U1F1    1 GND<1> MAX9634_SOT-IC,H35789-001   I133 @BASEBOARD_FAB2_LIB.BASEBOARD_FAB2(SCH_1):PAGE197
  U1B1    2 GND<0> MAX9634_SOT-IC,H35789-001   I144 @BASEBOARD_FAB2_LIB.BASEBOARD_FAB2(SCH_1):PAGE197
  U1B1    1 GND<1> MAX9634_SOT-IC,H35789-001   I144 @BASEBOARD_FAB2_LIB.BASEBOARD_FAB2(SCH_1):PAGE197
 EU2T1    4    GND SLG55021_SM-IC,G56246-001     I1 @BASEBOARD_FAB2_LIB.BASEBOARD_FAB2(SCH_1):PAGE198
 EU2T1    9  THPAD SLG55021_SM-IC,G56246-001     I1 @BASEBOARD_FAB2_LIB.BASEBOARD_FAB2(SCH_1):PAGE198
 EU8B1    4    GND SLG55021_SM-IC,G56246-001    I13 @BASEBOARD_FAB2_LIB.BASEBOARD_FAB2(SCH_1):PAGE198
 EU8B1    9  THPAD SLG55021_SM-IC,G56246-001    I13 @BASEBOARD_FAB2_LIB.BASEBOARD_FAB2(SCH_1):PAGE198
 EU7E1    4    GND SLG55021_SM-IC,G56246-001    I19 @BASEBOARD_FAB2_LIB.BASEBOARD_FAB2(SCH_1):PAGE198
 EU7E1    9  THPAD SLG55021_SM-IC,G56246-001    I19 @BASEBOARD_FAB2_LIB.BASEBOARD_FAB2(SCH_1):PAGE198
 C8F17    2      B CAP_A_0402V-0.1UF,16V,10%,X7R,A    I24 @BASEBOARD_FAB2_LIB.BASEBOARD_FAB2(SCH_1):PAGE198
  C8B8    2      B CAP_A_0402V-0.1UF,16V,10%,X7R,A    I26 @BASEBOARD_FAB2_LIB.BASEBOARD_FAB2(SCH_1):PAGE198
 C8E19    2      B CAP_A_0402V-0.1UF,16V,10%,X7R,A    I28 @BASEBOARD_FAB2_LIB.BASEBOARD_FAB2(SCH_1):PAGE198
  C8B5    2      B CAP_A_0402V-0.1UF,16V,10%,X7R,A    I37 @BASEBOARD_FAB2_LIB.BASEBOARD_FAB2(SCH_1):PAGE198
 C8B12    2      B CAP_0805-10UF,16V,10%,X6S,C953A    I38 @BASEBOARD_FAB2_LIB.BASEBOARD_FAB2(SCH_1):PAGE198
  C8B6    2      B CAP_0805-10UF,16V,10%,X6S,C953A    I40 @BASEBOARD_FAB2_LIB.BASEBOARD_FAB2(SCH_1):PAGE198
  C8B7    2      B CAP_A_0402V-0.1UF,16V,10%,X7R,A    I41 @BASEBOARD_FAB2_LIB.BASEBOARD_FAB2(SCH_1):PAGE198
 C2T36    2      B CAP_A_0402V-0.1UF,16V,10%,X7R,A    I43 @BASEBOARD_FAB2_LIB.BASEBOARD_FAB2(SCH_1):PAGE198
  C2U1    2      B CAP_0805-10UF,16V,10%,X6S,C953A    I44 @BASEBOARD_FAB2_LIB.BASEBOARD_FAB2(SCH_1):PAGE198
 C2U19    2      B CAP_A_0402V-0.1UF,16V,10%,X7R,A    I46 @BASEBOARD_FAB2_LIB.BASEBOARD_FAB2(SCH_1):PAGE198
  C2U2    2      B CAP_0805-10UF,16V,10%,X6S,C953A    I47 @BASEBOARD_FAB2_LIB.BASEBOARD_FAB2(SCH_1):PAGE198
  C7E9    2      B CAP_A_0402V-0.1UF,16V,10%,X7R,A    I49 @BASEBOARD_FAB2_LIB.BASEBOARD_FAB2(SCH_1):PAGE198
  C7E8    2      B CAP_0805-10UF,16V,10%,X6S,C953A    I50 @BASEBOARD_FAB2_LIB.BASEBOARD_FAB2(SCH_1):PAGE198
  C7E5    2      B CAP_A_0402V-0.1UF,16V,10%,X7R,A    I52 @BASEBOARD_FAB2_LIB.BASEBOARD_FAB2(SCH_1):PAGE198
  C7E6    2      B CAP_0805-10UF,16V,10%,X6S,C953A    I53 @BASEBOARD_FAB2_LIB.BASEBOARD_FAB2(SCH_1):PAGE198
 C1B18    2      B CAP_0805-10UF,16V,10%,X6S,C953A    I61 @BASEBOARD_FAB2_LIB.BASEBOARD_FAB2(SCH_1):PAGE198
 C1B19    2      B CAP_A_0402V-0.1UF,16V,10%,X7R,A    I64 @BASEBOARD_FAB2_LIB.BASEBOARD_FAB2(SCH_1):PAGE198
  C9M6    2      B CAP_A_0402V-0.1UF,16V,10%,X7R,A    I67 @BASEBOARD_FAB2_LIB.BASEBOARD_FAB2(SCH_1):PAGE198
 EU9M1    4    GND SLG55021_SM-IC,G56246-001    I69 @BASEBOARD_FAB2_LIB.BASEBOARD_FAB2(SCH_1):PAGE198
 EU9M1    9  THPAD SLG55021_SM-IC,G56246-001    I69 @BASEBOARD_FAB2_LIB.BASEBOARD_FAB2(SCH_1):PAGE198
 C9M10    2      B CAP_0805-10UF,16V,10%,X6S,C953A    I74 @BASEBOARD_FAB2_LIB.BASEBOARD_FAB2(SCH_1):PAGE198
  C9M9    2      B CAP_A_0402V-0.1UF,16V,10%,X7R,A    I76 @BASEBOARD_FAB2_LIB.BASEBOARD_FAB2(SCH_1):PAGE198
  R8B4    2      B RES_0402-100.0K,1%,1/16W,CHIP,A    I83 @BASEBOARD_FAB2_LIB.BASEBOARD_FAB2(SCH_1):PAGE198
 EU1D2   23   PGND ADM1278_SM-IC,G99251-001    I10 @BASEBOARD_FAB2_LIB.BASEBOARD_FAB2(SCH_1):PAGE199
 R1D41    1      A RES_0805-0.0,5%,1/8W,CHIP,G221A    I19 @BASEBOARD_FAB2_LIB.BASEBOARD_FAB2(SCH_1):PAGE199
 R1D31    2      B RES_0402-6.19K,1%,1/16W,CHIP,GA    I43 @BASEBOARD_FAB2_LIB.BASEBOARD_FAB2(SCH_1):PAGE199
  Q1D3    2      E NPN_SM-MMBT3904,IC,C52245-001    I58 @BASEBOARD_FAB2_LIB.BASEBOARD_FAB2(SCH_1):PAGE199
 VR1D1    2      A ZENER_SM-13V,IC,H69095-001    I99 @BASEBOARD_FAB2_LIB.BASEBOARD_FAB2(SCH_1):PAGE199
  C1E2    2      B CAP_1206-0.068UF,50V,20%,X7R,1A   I155 @BASEBOARD_FAB2_LIB.BASEBOARD_FAB2(SCH_1):PAGE200
  U9P1    5    GND TPS3700_SM-IC,H69492-001   I163 @BASEBOARD_FAB2_LIB.BASEBOARD_FAB2(SCH_1):PAGE200
  U1D2    5    GND TPS3700_SM-IC,H69492-001   I170 @BASEBOARD_FAB2_LIB.BASEBOARD_FAB2(SCH_1):PAGE200
  Q9P1    1 SOURCE<0> FET_N_DUAL_SMLF-2N7002DW,FET,DA   I196 @BASEBOARD_FAB2_LIB.BASEBOARD_FAB2(SCH_1):PAGE200
  Q9P1    4 SOURCE<0> FET_N_DUAL_SMLF-2N7002DW,FET,DA   I199 @BASEBOARD_FAB2_LIB.BASEBOARD_FAB2(SCH_1):PAGE200
  U9P2    5    GND TPS3700_SM-IC,H69492-001   I200 @BASEBOARD_FAB2_LIB.BASEBOARD_FAB2(SCH_1):PAGE200
 C9P11    2      B CAP_A_0402V-0.1UF,16V,10%,X7R,A   I201 @BASEBOARD_FAB2_LIB.BASEBOARD_FAB2(SCH_1):PAGE200
  Q1D2    2    SRC FET_N_SOT23LF-2N7002,FET,C7925A   I203 @BASEBOARD_FAB2_LIB.BASEBOARD_FAB2(SCH_1):PAGE200
 CR1F5    2      A DIODE_SM-MBRS340T3G,EMPTY,C819A   I220 @BASEBOARD_FAB2_LIB.BASEBOARD_FAB2(SCH_1):PAGE200
 C4D25    2      B CAP_A_0402V-1.0UF,6.3V,10%,X6SA    I30 @BASEBOARD_FAB2_LIB.BASEBOARD_FAB2(SCH_1):PAGE201
 C4D26    2      B CAP_A_0402V-0.1UF,16V,10%,X7R,A    I32 @BASEBOARD_FAB2_LIB.BASEBOARD_FAB2(SCH_1):PAGE201
 C4D15    2      B CAP_A_0402V-1.0UF,6.3V,10%,X6SA    I37 @BASEBOARD_FAB2_LIB.BASEBOARD_FAB2(SCH_1):PAGE201
 C4D19    2      B CAP_A_0402V-0.1UF,16V,10%,X7R,A    I39 @BASEBOARD_FAB2_LIB.BASEBOARD_FAB2(SCH_1):PAGE201
 R4D32    2      B RES_0402-1.5K,1%,1/16W,CHIP,G2A    I55 @BASEBOARD_FAB2_LIB.BASEBOARD_FAB2(SCH_1):PAGE201
 C4D20    2      B CAP_0402LF-1000PF,50V,10%,X7R,A    I60 @BASEBOARD_FAB2_LIB.BASEBOARD_FAB2(SCH_1):PAGE201
 C4D17    2      B CAP_0402LF-220PF,50V,10%,X7R,AA    I66 @BASEBOARD_FAB2_LIB.BASEBOARD_FAB2(SCH_1):PAGE201
 C4D18    2      B CAP_0402LF-220PF,50V,10%,X7R,AA    I68 @BASEBOARD_FAB2_LIB.BASEBOARD_FAB2(SCH_1):PAGE201
 R6P27    2      B RES_0402-4.02K,1%,1/16W,CHIP,GA   I120 @BASEBOARD_FAB2_LIB.BASEBOARD_FAB2(SCH_1):PAGE201
 R6P28    2      B RES_0402-4.02K,1%,1/16W,CHIP,GA   I121 @BASEBOARD_FAB2_LIB.BASEBOARD_FAB2(SCH_1):PAGE201
  J8D4    2    IO2 CONN3_C95678002_PIP-CONN,C9567A   I122 @BASEBOARD_FAB2_LIB.BASEBOARD_FAB2(SCH_1):PAGE201
 C4D42    2      B CAP_0402LF-1000PF,50V,10%,X7R,A   I125 @BASEBOARD_FAB2_LIB.BASEBOARD_FAB2(SCH_1):PAGE201
 EU4D4   49  THPAD PXE1610B_QFN-IC,H79206-001   I155 @BASEBOARD_FAB2_LIB.BASEBOARD_FAB2(SCH_1):PAGE201
  C6R7    2      B CAP_A_0603V-22.0UF,4V,20%,X6S,A     I9 @BASEBOARD_FAB2_LIB.BASEBOARD_FAB2(SCH_1):PAGE202
  C4E5    2      B CAP_0402-0.22UF,16V,10%,X7R,A3A    I18 @BASEBOARD_FAB2_LIB.BASEBOARD_FAB2(SCH_1):PAGE202
  C4E6    2      B CAP_A_0402V-1.0UF,6.3V,10%,X6SA    I19 @BASEBOARD_FAB2_LIB.BASEBOARD_FAB2(SCH_1):PAGE202
 C4E27    2      B CAP_0402-0.22UF,16V,10%,X7R,A3A    I24 @BASEBOARD_FAB2_LIB.BASEBOARD_FAB2(SCH_1):PAGE202
 C4E25    2      B CAP_A_0402V-1.0UF,6.3V,10%,X6SA    I25 @BASEBOARD_FAB2_LIB.BASEBOARD_FAB2(SCH_1):PAGE202
 C4E11    2      B CAP_A_0603V-22.0UF,4V,20%,X6S,A    I27 @BASEBOARD_FAB2_LIB.BASEBOARD_FAB2(SCH_1):PAGE202
 C4E10    2      B CAP_0402-1.0UF,16V,10%,X6S,D97A    I34 @BASEBOARD_FAB2_LIB.BASEBOARD_FAB2(SCH_1):PAGE202
 C4E20    2      B CAP_A_0402V-0.1UF,16V,10%,X7R,A    I35 @BASEBOARD_FAB2_LIB.BASEBOARD_FAB2(SCH_1):PAGE202
 C4E19    2      B CAP_0402-1.0UF,16V,10%,X6S,D97A    I36 @BASEBOARD_FAB2_LIB.BASEBOARD_FAB2(SCH_1):PAGE202
 C6R11    2      B CAP_0805-10UF,16V,10%,X6S,C953A    I37 @BASEBOARD_FAB2_LIB.BASEBOARD_FAB2(SCH_1):PAGE202
 C6P13    2      B CAP_0805-10UF,16V,10%,X6S,C953A    I38 @BASEBOARD_FAB2_LIB.BASEBOARD_FAB2(SCH_1):PAGE202
 C6R13    2      B CAP_0805-10UF,16V,10%,X6S,C953A    I42 @BASEBOARD_FAB2_LIB.BASEBOARD_FAB2(SCH_1):PAGE202
 C4E26    2      B CAP_0402-1.0UF,16V,10%,X6S,D97A    I45 @BASEBOARD_FAB2_LIB.BASEBOARD_FAB2(SCH_1):PAGE202
 C4D49    2      B CAP_A_0402V-0.1UF,16V,10%,X7R,A    I46 @BASEBOARD_FAB2_LIB.BASEBOARD_FAB2(SCH_1):PAGE202
 C4D48    2      B CAP_0402-1.0UF,16V,10%,X6S,D97A    I47 @BASEBOARD_FAB2_LIB.BASEBOARD_FAB2(SCH_1):PAGE202
  C6R4    2      B CAP_0805-10UF,16V,10%,X6S,C953A    I48 @BASEBOARD_FAB2_LIB.BASEBOARD_FAB2(SCH_1):PAGE202
 C6P22    2      B CAP_0805-10UF,16V,10%,X6S,C953A    I49 @BASEBOARD_FAB2_LIB.BASEBOARD_FAB2(SCH_1):PAGE202
  C6N8    2      B CAP_0805-10UF,16V,10%,X6S,C953A    I51 @BASEBOARD_FAB2_LIB.BASEBOARD_FAB2(SCH_1):PAGE202
  C4E3    2      B CAP_A_0603V-22.0UF,4V,20%,X6S,A    I61 @BASEBOARD_FAB2_LIB.BASEBOARD_FAB2(SCH_1):PAGE202
 C6P16    2      B CAP_A_0603V-22.0UF,4V,20%,X6S,A    I62 @BASEBOARD_FAB2_LIB.BASEBOARD_FAB2(SCH_1):PAGE202
 EU4E1    2   LGND IR354XX_SM-IR35411,IC,H73688-0A    I63 @BASEBOARD_FAB2_LIB.BASEBOARD_FAB2(SCH_1):PAGE202
 EU4E1    5 PGND<0> IR354XX_SM-IR35411,IC,H73688-0A    I63 @BASEBOARD_FAB2_LIB.BASEBOARD_FAB2(SCH_1):PAGE202
 EU4E1    7 PGND<1> IR354XX_SM-IR35411,IC,H73688-0A    I63 @BASEBOARD_FAB2_LIB.BASEBOARD_FAB2(SCH_1):PAGE202
 EU4E1   40 PGND<2> IR354XX_SM-IR35411,IC,H73688-0A    I63 @BASEBOARD_FAB2_LIB.BASEBOARD_FAB2(SCH_1):PAGE202
 EU4D6    2   LGND IR354XX_SM-IR35411,IC,H73688-0A    I64 @BASEBOARD_FAB2_LIB.BASEBOARD_FAB2(SCH_1):PAGE202
 EU4D6    5 PGND<0> IR354XX_SM-IR35411,IC,H73688-0A    I64 @BASEBOARD_FAB2_LIB.BASEBOARD_FAB2(SCH_1):PAGE202
 EU4D6    7 PGND<1> IR354XX_SM-IR35411,IC,H73688-0A    I64 @BASEBOARD_FAB2_LIB.BASEBOARD_FAB2(SCH_1):PAGE202
 EU4D6   40 PGND<2> IR354XX_SM-IR35411,IC,H73688-0A    I64 @BASEBOARD_FAB2_LIB.BASEBOARD_FAB2(SCH_1):PAGE202
 R4E22    2      B RES_0402-68.1K,1%,1/16W,EMPTY,A    I65 @BASEBOARD_FAB2_LIB.BASEBOARD_FAB2(SCH_1):PAGE202
 R4E19    2      B RES_0402-68.1K,1%,1/16W,EMPTY,A    I67 @BASEBOARD_FAB2_LIB.BASEBOARD_FAB2(SCH_1):PAGE202
 C6P24    2      B CAP_0805-10UF,16V,10%,X6S,C953A     I1 @BASEBOARD_FAB2_LIB.BASEBOARD_FAB2(SCH_1):PAGE203
  C6R6    2      B CAP_0805-10UF,16V,10%,X6S,C953A     I2 @BASEBOARD_FAB2_LIB.BASEBOARD_FAB2(SCH_1):PAGE203
  C6R3    2      B CAPP_3018-470UF,2.5V,20%,ALUM,A    I16 @BASEBOARD_FAB2_LIB.BASEBOARD_FAB2(SCH_1):PAGE203
  C6R9    2      B CAPP_3018-470UF,2.5V,20%,ALUM,A    I18 @BASEBOARD_FAB2_LIB.BASEBOARD_FAB2(SCH_1):PAGE203
  C6P3    2      B CAP_A_0603V-22.0UF,4V,20%,X6S,A    I25 @BASEBOARD_FAB2_LIB.BASEBOARD_FAB2(SCH_1):PAGE203
 C6P23    2      B CAPP_3018-470UF,2.5V,20%,ALUM,A    I28 @BASEBOARD_FAB2_LIB.BASEBOARD_FAB2(SCH_1):PAGE203
 C6P14    2      B CAPP_3018-470UF,2.5V,20%,ALUM,A    I29 @BASEBOARD_FAB2_LIB.BASEBOARD_FAB2(SCH_1):PAGE203
 C6P18    2      B CAPP_3018-470UF,2.5V,20%,ALUM,A    I30 @BASEBOARD_FAB2_LIB.BASEBOARD_FAB2(SCH_1):PAGE203
  C6P8    2      B CAPP_3018-470UF,2.5V,20%,ALUM,A    I32 @BASEBOARD_FAB2_LIB.BASEBOARD_FAB2(SCH_1):PAGE203
  C6N9    2      B CAPP_3018-470UF,2.5V,20%,ALUM,A    I34 @BASEBOARD_FAB2_LIB.BASEBOARD_FAB2(SCH_1):PAGE203
 C4D13    2      B CAP_0402-0.22UF,16V,10%,X7R,A3A    I40 @BASEBOARD_FAB2_LIB.BASEBOARD_FAB2(SCH_1):PAGE203
 C4D14    2      B CAP_A_0402V-1.0UF,6.3V,10%,X6SA    I41 @BASEBOARD_FAB2_LIB.BASEBOARD_FAB2(SCH_1):PAGE203
 C4D16    2      B CAP_0402-1.0UF,16V,10%,X6S,D97A    I45 @BASEBOARD_FAB2_LIB.BASEBOARD_FAB2(SCH_1):PAGE203
 C4D35    2      B CAP_A_0402V-0.1UF,16V,10%,X7R,A    I46 @BASEBOARD_FAB2_LIB.BASEBOARD_FAB2(SCH_1):PAGE203
 C4D30    2      B CAP_0402-1.0UF,16V,10%,X6S,D97A    I47 @BASEBOARD_FAB2_LIB.BASEBOARD_FAB2(SCH_1):PAGE203
  C4D5    2      B CAP_0402-0.22UF,16V,10%,X7R,A3A    I48 @BASEBOARD_FAB2_LIB.BASEBOARD_FAB2(SCH_1):PAGE203
  C4D6    2      B CAP_A_0402V-1.0UF,6.3V,10%,X6SA    I49 @BASEBOARD_FAB2_LIB.BASEBOARD_FAB2(SCH_1):PAGE203
  C4D7    2      B CAP_0402-1.0UF,16V,10%,X6S,D97A    I51 @BASEBOARD_FAB2_LIB.BASEBOARD_FAB2(SCH_1):PAGE203
 C4D11    2      B CAP_A_0402V-0.1UF,16V,10%,X7R,A    I52 @BASEBOARD_FAB2_LIB.BASEBOARD_FAB2(SCH_1):PAGE203
 C4D10    2      B CAP_0402-1.0UF,16V,10%,X6S,D97A    I53 @BASEBOARD_FAB2_LIB.BASEBOARD_FAB2(SCH_1):PAGE203
 C6P19    2      B CAP_0805-10UF,16V,10%,X6S,C953A    I54 @BASEBOARD_FAB2_LIB.BASEBOARD_FAB2(SCH_1):PAGE203
 C6P20    2      B CAP_0805-10UF,16V,10%,X6S,C953A    I57 @BASEBOARD_FAB2_LIB.BASEBOARD_FAB2(SCH_1):PAGE203
 C6P15    2      B CAP_0805-10UF,16V,10%,X6S,C953A    I58 @BASEBOARD_FAB2_LIB.BASEBOARD_FAB2(SCH_1):PAGE203
  C6P7    2      B CAP_0805-10UF,16V,10%,X6S,C953A    I59 @BASEBOARD_FAB2_LIB.BASEBOARD_FAB2(SCH_1):PAGE203
 C6P21    2      B CAP_A_0603V-22.0UF,4V,20%,X6S,A    I66 @BASEBOARD_FAB2_LIB.BASEBOARD_FAB2(SCH_1):PAGE203
 R4E13    2      B RES_0603-100.0,1%,1/10W,CHIP,GA    I67 @BASEBOARD_FAB2_LIB.BASEBOARD_FAB2(SCH_1):PAGE203
 C4D34    2      B CAP_A_0603V-22.0UF,4V,20%,X6S,A    I68 @BASEBOARD_FAB2_LIB.BASEBOARD_FAB2(SCH_1):PAGE203
  C4D4    2      B CAP_A_0603V-22.0UF,4V,20%,X6S,A    I69 @BASEBOARD_FAB2_LIB.BASEBOARD_FAB2(SCH_1):PAGE203
 EU4D3    2   LGND IR354XX_SM-IR35411,IC,H73688-0A    I70 @BASEBOARD_FAB2_LIB.BASEBOARD_FAB2(SCH_1):PAGE203
 EU4D3    5 PGND<0> IR354XX_SM-IR35411,IC,H73688-0A    I70 @BASEBOARD_FAB2_LIB.BASEBOARD_FAB2(SCH_1):PAGE203
 EU4D3    7 PGND<1> IR354XX_SM-IR35411,IC,H73688-0A    I70 @BASEBOARD_FAB2_LIB.BASEBOARD_FAB2(SCH_1):PAGE203
 EU4D3   40 PGND<2> IR354XX_SM-IR35411,IC,H73688-0A    I70 @BASEBOARD_FAB2_LIB.BASEBOARD_FAB2(SCH_1):PAGE203
 EU4D1    2   LGND IR354XX_SM-IR35411,IC,H73688-0A    I71 @BASEBOARD_FAB2_LIB.BASEBOARD_FAB2(SCH_1):PAGE203
 EU4D1    5 PGND<0> IR354XX_SM-IR35411,IC,H73688-0A    I71 @BASEBOARD_FAB2_LIB.BASEBOARD_FAB2(SCH_1):PAGE203
 EU4D1    7 PGND<1> IR354XX_SM-IR35411,IC,H73688-0A    I71 @BASEBOARD_FAB2_LIB.BASEBOARD_FAB2(SCH_1):PAGE203
 EU4D1   40 PGND<2> IR354XX_SM-IR35411,IC,H73688-0A    I71 @BASEBOARD_FAB2_LIB.BASEBOARD_FAB2(SCH_1):PAGE203
 R4D72    2      B RES_0402-68.1K,1%,1/16W,EMPTY,A    I89 @BASEBOARD_FAB2_LIB.BASEBOARD_FAB2(SCH_1):PAGE203
 R4D71    2      B RES_0402-68.1K,1%,1/16W,EMPTY,A    I91 @BASEBOARD_FAB2_LIB.BASEBOARD_FAB2(SCH_1):PAGE203
 C4D12    2      B CAP_A_0603V-22.0UF,4V,20%,X6S,A     I9 @BASEBOARD_FAB2_LIB.BASEBOARD_FAB2(SCH_1):PAGE204
 C4D47    2      B CAP_0402-0.22UF,16V,10%,X7R,A3A    I18 @BASEBOARD_FAB2_LIB.BASEBOARD_FAB2(SCH_1):PAGE204
 C4C14    2      B CAP_A_0402V-1.0UF,6.3V,10%,X6SA    I19 @BASEBOARD_FAB2_LIB.BASEBOARD_FAB2(SCH_1):PAGE204
 C4D46    2      B CAP_0402-1.0UF,16V,10%,X6S,D97A    I34 @BASEBOARD_FAB2_LIB.BASEBOARD_FAB2(SCH_1):PAGE204
 C4C19    2      B CAP_A_0402V-0.1UF,16V,10%,X7R,A    I35 @BASEBOARD_FAB2_LIB.BASEBOARD_FAB2(SCH_1):PAGE204
 C4C18    2      B CAP_0402-1.0UF,16V,10%,X6S,D97A    I36 @BASEBOARD_FAB2_LIB.BASEBOARD_FAB2(SCH_1):PAGE204
 C6N10    2      B CAP_0805-10UF,16V,10%,X6S,C953A    I37 @BASEBOARD_FAB2_LIB.BASEBOARD_FAB2(SCH_1):PAGE204
 C6P17    2      B CAP_0805-10UF,16V,10%,X6S,C953A    I38 @BASEBOARD_FAB2_LIB.BASEBOARD_FAB2(SCH_1):PAGE204
 C6N11    2      B CAP_0805-10UF,16V,10%,X6S,C953A    I42 @BASEBOARD_FAB2_LIB.BASEBOARD_FAB2(SCH_1):PAGE204
  C4D2    2      B CAPP_2626-270UF,16V,20%,OSCON,A    I48 @BASEBOARD_FAB2_LIB.BASEBOARD_FAB2(SCH_1):PAGE204
 C4E16    2      B CAPP_2626-270UF,16V,20%,OSCON,A    I50 @BASEBOARD_FAB2_LIB.BASEBOARD_FAB2(SCH_1):PAGE204
  C4C2    2      B CAP_A_0402V-0.1UF,16V,10%,EMPTA    I51 @BASEBOARD_FAB2_LIB.BASEBOARD_FAB2(SCH_1):PAGE204
  U4C1    1 GND<0> ADM4073_SM-EMPTY,G12194-001    I53 @BASEBOARD_FAB2_LIB.BASEBOARD_FAB2(SCH_1):PAGE204
  U4C1    2 GND<1> ADM4073_SM-EMPTY,G12194-001    I53 @BASEBOARD_FAB2_LIB.BASEBOARD_FAB2(SCH_1):PAGE204
 R4E18    2      B RES_0402-100.0,1%,1/16W,CHIP,GA    I64 @BASEBOARD_FAB2_LIB.BASEBOARD_FAB2(SCH_1):PAGE204
 C4C12    2      B CAPP_2626-270UF,16V,20%,OSCON,A    I67 @BASEBOARD_FAB2_LIB.BASEBOARD_FAB2(SCH_1):PAGE204
  C6R2    2      B CAP_A_0603V-22.0UF,4V,20%,X6S,A    I70 @BASEBOARD_FAB2_LIB.BASEBOARD_FAB2(SCH_1):PAGE204
 EU4C2    2   LGND IR354XX_SM-IR35411,IC,H73688-0A    I71 @BASEBOARD_FAB2_LIB.BASEBOARD_FAB2(SCH_1):PAGE204
 EU4C2    5 PGND<0> IR354XX_SM-IR35411,IC,H73688-0A    I71 @BASEBOARD_FAB2_LIB.BASEBOARD_FAB2(SCH_1):PAGE204
 EU4C2    7 PGND<1> IR354XX_SM-IR35411,IC,H73688-0A    I71 @BASEBOARD_FAB2_LIB.BASEBOARD_FAB2(SCH_1):PAGE204
 EU4C2   40 PGND<2> IR354XX_SM-IR35411,IC,H73688-0A    I71 @BASEBOARD_FAB2_LIB.BASEBOARD_FAB2(SCH_1):PAGE204
 R4D68    2      B RES_0402-68.1K,1%,1/16W,EMPTY,A    I83 @BASEBOARD_FAB2_LIB.BASEBOARD_FAB2(SCH_1):PAGE204
  C6N7    2      B CAP_A_0603V-22.0UF,4V,20%,X6S,A     I5 @BASEBOARD_FAB2_LIB.BASEBOARD_FAB2(SCH_1):PAGE205
  C6N1    2      B CAPP_3018-470UF,2.5V,20%,ALUM,A    I12 @BASEBOARD_FAB2_LIB.BASEBOARD_FAB2(SCH_1):PAGE205
  C6N4    2      B CAPP_3018-470UF,2.5V,20%,ALUM,A    I14 @BASEBOARD_FAB2_LIB.BASEBOARD_FAB2(SCH_1):PAGE205
  C4C5    2      B CAP_0402-0.22UF,16V,10%,X7R,A3A    I16 @BASEBOARD_FAB2_LIB.BASEBOARD_FAB2(SCH_1):PAGE205
  C4C4    2      B CAP_A_0402V-1.0UF,6.3V,10%,X6SA    I18 @BASEBOARD_FAB2_LIB.BASEBOARD_FAB2(SCH_1):PAGE205
  C4C6    2      B CAP_0402-1.0UF,16V,10%,X6S,D97A    I20 @BASEBOARD_FAB2_LIB.BASEBOARD_FAB2(SCH_1):PAGE205
  R4C1    2      B RES_0402-100.0,1%,1/16W,CHIP,GA    I29 @BASEBOARD_FAB2_LIB.BASEBOARD_FAB2(SCH_1):PAGE205
 C4C10    2      B CAP_A_0402V-0.1UF,16V,10%,X7R,A    I31 @BASEBOARD_FAB2_LIB.BASEBOARD_FAB2(SCH_1):PAGE205
  C4C9    2      B CAP_0402-1.0UF,16V,10%,X6S,D97A    I32 @BASEBOARD_FAB2_LIB.BASEBOARD_FAB2(SCH_1):PAGE205
  C6N2    2      B CAP_0805-10UF,16V,10%,X6S,C953A    I33 @BASEBOARD_FAB2_LIB.BASEBOARD_FAB2(SCH_1):PAGE205
  C6N3    2      B CAP_0805-10UF,16V,10%,X6S,C953A    I34 @BASEBOARD_FAB2_LIB.BASEBOARD_FAB2(SCH_1):PAGE205
  C6N6    2      B CAP_0805-10UF,16V,10%,X6S,C953A    I35 @BASEBOARD_FAB2_LIB.BASEBOARD_FAB2(SCH_1):PAGE205
 C4C11    2      B CAP_A_0603V-22.0UF,4V,20%,X6S,A    I43 @BASEBOARD_FAB2_LIB.BASEBOARD_FAB2(SCH_1):PAGE205
  R6N4    2      B RES_0402-51.1,1.0%,1/16W,CHIP,A    I45 @BASEBOARD_FAB2_LIB.BASEBOARD_FAB2(SCH_1):PAGE205
 EU4C1    2   LGND IR354XX_SM-IR35412,IC,H73684-0A    I46 @BASEBOARD_FAB2_LIB.BASEBOARD_FAB2(SCH_1):PAGE205
 EU4C1    5 PGND<0> IR354XX_SM-IR35412,IC,H73684-0A    I46 @BASEBOARD_FAB2_LIB.BASEBOARD_FAB2(SCH_1):PAGE205
 EU4C1    7 PGND<1> IR354XX_SM-IR35412,IC,H73684-0A    I46 @BASEBOARD_FAB2_LIB.BASEBOARD_FAB2(SCH_1):PAGE205
 EU4C1   40 PGND<2> IR354XX_SM-IR35412,IC,H73684-0A    I46 @BASEBOARD_FAB2_LIB.BASEBOARD_FAB2(SCH_1):PAGE205
 R4C13    2      B RES_0402-68.1K,1%,1/16W,EMPTY,A    I62 @BASEBOARD_FAB2_LIB.BASEBOARD_FAB2(SCH_1):PAGE205
 C1C13    2      B CAP_A_0402V-1.0UF,6.3V,10%,X6SA    I29 @BASEBOARD_FAB2_LIB.BASEBOARD_FAB2(SCH_1):PAGE206
 C1C14    2      B CAP_A_0402V-0.1UF,16V,10%,X7R,A    I31 @BASEBOARD_FAB2_LIB.BASEBOARD_FAB2(SCH_1):PAGE206
  C1C7    2      B CAP_A_0402V-1.0UF,6.3V,10%,X6SA    I41 @BASEBOARD_FAB2_LIB.BASEBOARD_FAB2(SCH_1):PAGE206
  C1C9    2      B CAP_A_0402V-0.1UF,16V,10%,X7R,A    I42 @BASEBOARD_FAB2_LIB.BASEBOARD_FAB2(SCH_1):PAGE206
 R1C16    2      B RES_0402-1.5K,1%,1/16W,CHIP,G2A    I56 @BASEBOARD_FAB2_LIB.BASEBOARD_FAB2(SCH_1):PAGE206
 C1C10    2      B CAP_0402LF-220PF,50V,10%,X7R,AA    I69 @BASEBOARD_FAB2_LIB.BASEBOARD_FAB2(SCH_1):PAGE206
 C1C11    2      B CAP_0402LF-220PF,50V,10%,X7R,AA    I71 @BASEBOARD_FAB2_LIB.BASEBOARD_FAB2(SCH_1):PAGE206
  C1C8    2      B CAP_0402LF-1000PF,50V,10%,X7R,A    I73 @BASEBOARD_FAB2_LIB.BASEBOARD_FAB2(SCH_1):PAGE206
  R9N7    2      B RES_0402-3.16K,1%,1/16W,CHIP,GA   I111 @BASEBOARD_FAB2_LIB.BASEBOARD_FAB2(SCH_1):PAGE206
  R9N8    2      B RES_0402-4.02K,1%,1/16W,CHIP,GA   I112 @BASEBOARD_FAB2_LIB.BASEBOARD_FAB2(SCH_1):PAGE206
 C1C23    2      B CAP_0402LF-1000PF,50V,10%,X7R,A   I114 @BASEBOARD_FAB2_LIB.BASEBOARD_FAB2(SCH_1):PAGE206
 EU1C2   49  THPAD PXE1610B_QFN-IC,H79206-001   I130 @BASEBOARD_FAB2_LIB.BASEBOARD_FAB2(SCH_1):PAGE206
  C9R8    2      B CAP_A_0603V-22.0UF,4V,20%,X6S,A     I8 @BASEBOARD_FAB2_LIB.BASEBOARD_FAB2(SCH_1):PAGE207
  C1E3    2      B CAP_A_0603V-22.0UF,4V,20%,X6S,A    I18 @BASEBOARD_FAB2_LIB.BASEBOARD_FAB2(SCH_1):PAGE207
 EU1E2    2   LGND IR354XX_SM-IR35411,IC,H73688-0A    I20 @BASEBOARD_FAB2_LIB.BASEBOARD_FAB2(SCH_1):PAGE207
 EU1E2    5 PGND<0> IR354XX_SM-IR35411,IC,H73688-0A    I20 @BASEBOARD_FAB2_LIB.BASEBOARD_FAB2(SCH_1):PAGE207
 EU1E2    7 PGND<1> IR354XX_SM-IR35411,IC,H73688-0A    I20 @BASEBOARD_FAB2_LIB.BASEBOARD_FAB2(SCH_1):PAGE207
 EU1E2   40 PGND<2> IR354XX_SM-IR35411,IC,H73688-0A    I20 @BASEBOARD_FAB2_LIB.BASEBOARD_FAB2(SCH_1):PAGE207
 EU1D4    2   LGND IR354XX_SM-IR35411,IC,H73688-0A    I24 @BASEBOARD_FAB2_LIB.BASEBOARD_FAB2(SCH_1):PAGE207
 EU1D4    5 PGND<0> IR354XX_SM-IR35411,IC,H73688-0A    I24 @BASEBOARD_FAB2_LIB.BASEBOARD_FAB2(SCH_1):PAGE207
 EU1D4    7 PGND<1> IR354XX_SM-IR35411,IC,H73688-0A    I24 @BASEBOARD_FAB2_LIB.BASEBOARD_FAB2(SCH_1):PAGE207
 EU1D4   40 PGND<2> IR354XX_SM-IR35411,IC,H73688-0A    I24 @BASEBOARD_FAB2_LIB.BASEBOARD_FAB2(SCH_1):PAGE207
  C1E7    2      B CAP_0402-0.22UF,16V,10%,X7R,A3A    I28 @BASEBOARD_FAB2_LIB.BASEBOARD_FAB2(SCH_1):PAGE207
  C1E6    2      B CAP_A_0402V-1.0UF,6.3V,10%,X6SA    I29 @BASEBOARD_FAB2_LIB.BASEBOARD_FAB2(SCH_1):PAGE207
  C1E8    2      B CAP_0402-1.0UF,16V,10%,X6S,D97A    I32 @BASEBOARD_FAB2_LIB.BASEBOARD_FAB2(SCH_1):PAGE207
 C1E14    2      B CAP_A_0402V-0.1UF,16V,10%,X7R,A    I33 @BASEBOARD_FAB2_LIB.BASEBOARD_FAB2(SCH_1):PAGE207
 C1E13    2      B CAP_0402-1.0UF,16V,10%,X6S,D97A    I34 @BASEBOARD_FAB2_LIB.BASEBOARD_FAB2(SCH_1):PAGE207
 C1E25    2      B CAP_0402-0.22UF,16V,10%,X7R,A3A    I36 @BASEBOARD_FAB2_LIB.BASEBOARD_FAB2(SCH_1):PAGE207
 C1E23    2      B CAP_A_0402V-1.0UF,6.3V,10%,X6SA    I37 @BASEBOARD_FAB2_LIB.BASEBOARD_FAB2(SCH_1):PAGE207
 C1E24    2      B CAP_0402-1.0UF,16V,10%,X6S,D97A    I40 @BASEBOARD_FAB2_LIB.BASEBOARD_FAB2(SCH_1):PAGE207
 C1D34    2      B CAP_A_0402V-0.1UF,16V,10%,X7R,A    I41 @BASEBOARD_FAB2_LIB.BASEBOARD_FAB2(SCH_1):PAGE207
 C1D35    2      B CAP_0402-1.0UF,16V,10%,X6S,D97A    I42 @BASEBOARD_FAB2_LIB.BASEBOARD_FAB2(SCH_1):PAGE207
  C9R7    2      B CAP_0805-10UF,16V,10%,X6S,C953A    I43 @BASEBOARD_FAB2_LIB.BASEBOARD_FAB2(SCH_1):PAGE207
 C9R10    2      B CAP_0805-10UF,16V,10%,X6S,C953A    I44 @BASEBOARD_FAB2_LIB.BASEBOARD_FAB2(SCH_1):PAGE207
 C9R11    2      B CAP_0805-10UF,16V,10%,X6S,C953A    I48 @BASEBOARD_FAB2_LIB.BASEBOARD_FAB2(SCH_1):PAGE207
 C9P22    2      B CAP_0805-10UF,16V,10%,X6S,C953A    I50 @BASEBOARD_FAB2_LIB.BASEBOARD_FAB2(SCH_1):PAGE207
 C9P25    2      B CAP_0805-10UF,16V,10%,X6S,C953A    I51 @BASEBOARD_FAB2_LIB.BASEBOARD_FAB2(SCH_1):PAGE207
 C9P26    2      B CAP_0805-10UF,16V,10%,X6S,C953A    I54 @BASEBOARD_FAB2_LIB.BASEBOARD_FAB2(SCH_1):PAGE207
  C1E9    2      B CAP_A_0603V-22.0UF,4V,20%,X6S,A    I58 @BASEBOARD_FAB2_LIB.BASEBOARD_FAB2(SCH_1):PAGE207
  C9P3    2      B CAP_A_0603V-22.0UF,4V,20%,X6S,A    I59 @BASEBOARD_FAB2_LIB.BASEBOARD_FAB2(SCH_1):PAGE207
 R1E13    2      B RES_0402-68.1K,1%,1/16W,EMPTY,A    I67 @BASEBOARD_FAB2_LIB.BASEBOARD_FAB2(SCH_1):PAGE207
 R1E14    2      B RES_0402-68.1K,1%,1/16W,EMPTY,A    I68 @BASEBOARD_FAB2_LIB.BASEBOARD_FAB2(SCH_1):PAGE207
  R1E3    2      B RES_0603-100.0,1%,1/10W,CHIP,GA     I7 @BASEBOARD_FAB2_LIB.BASEBOARD_FAB2(SCH_1):PAGE208
 C1D14    2      B CAP_A_0603V-22.0UF,4V,20%,X6S,A     I9 @BASEBOARD_FAB2_LIB.BASEBOARD_FAB2(SCH_1):PAGE208
  C9P8    2      B CAPP_3018-470UF,2.5V,20%,ALUM,A    I12 @BASEBOARD_FAB2_LIB.BASEBOARD_FAB2(SCH_1):PAGE208
  C9P5    2      B CAPP_3018-470UF,2.5V,20%,ALUM,A    I14 @BASEBOARD_FAB2_LIB.BASEBOARD_FAB2(SCH_1):PAGE208
  C1D3    2      B CAP_A_0603V-22.0UF,4V,20%,X6S,A    I22 @BASEBOARD_FAB2_LIB.BASEBOARD_FAB2(SCH_1):PAGE208
 C9N24    2      B CAPP_3018-470UF,2.5V,20%,ALUM,A    I24 @BASEBOARD_FAB2_LIB.BASEBOARD_FAB2(SCH_1):PAGE208
  C9R9    2      B CAPP_3018-470UF,2.5V,20%,ALUM,A    I25 @BASEBOARD_FAB2_LIB.BASEBOARD_FAB2(SCH_1):PAGE208
  C9R3    2      B CAPP_3018-470UF,2.5V,20%,ALUM,A    I26 @BASEBOARD_FAB2_LIB.BASEBOARD_FAB2(SCH_1):PAGE208
 EU1D3    2   LGND IR354XX_SM-IR35411,IC,H73688-0A    I27 @BASEBOARD_FAB2_LIB.BASEBOARD_FAB2(SCH_1):PAGE208
 EU1D3    5 PGND<0> IR354XX_SM-IR35411,IC,H73688-0A    I27 @BASEBOARD_FAB2_LIB.BASEBOARD_FAB2(SCH_1):PAGE208
 EU1D3    7 PGND<1> IR354XX_SM-IR35411,IC,H73688-0A    I27 @BASEBOARD_FAB2_LIB.BASEBOARD_FAB2(SCH_1):PAGE208
 EU1D3   40 PGND<2> IR354XX_SM-IR35411,IC,H73688-0A    I27 @BASEBOARD_FAB2_LIB.BASEBOARD_FAB2(SCH_1):PAGE208
 C9P23    2      B CAPP_3018-470UF,2.5V,20%,ALUM,A    I28 @BASEBOARD_FAB2_LIB.BASEBOARD_FAB2(SCH_1):PAGE208
 C9P18    2      B CAPP_3018-470UF,2.5V,20%,ALUM,A    I30 @BASEBOARD_FAB2_LIB.BASEBOARD_FAB2(SCH_1):PAGE208
 C1D16    2      B CAP_0402-0.22UF,16V,10%,X7R,A3A    I38 @BASEBOARD_FAB2_LIB.BASEBOARD_FAB2(SCH_1):PAGE208
 C1D15    2      B CAP_A_0402V-1.0UF,6.3V,10%,X6SA    I39 @BASEBOARD_FAB2_LIB.BASEBOARD_FAB2(SCH_1):PAGE208
 C1D17    2      B CAP_0402-1.0UF,16V,10%,X6S,D97A    I43 @BASEBOARD_FAB2_LIB.BASEBOARD_FAB2(SCH_1):PAGE208
 C1D28    2      B CAP_A_0402V-0.1UF,16V,10%,X7R,A    I44 @BASEBOARD_FAB2_LIB.BASEBOARD_FAB2(SCH_1):PAGE208
 C1D23    2      B CAP_0402-1.0UF,16V,10%,X6S,D97A    I45 @BASEBOARD_FAB2_LIB.BASEBOARD_FAB2(SCH_1):PAGE208
  C1D6    2      B CAP_0402-0.22UF,16V,10%,X7R,A3A    I46 @BASEBOARD_FAB2_LIB.BASEBOARD_FAB2(SCH_1):PAGE208
  C1D5    2      B CAP_A_0402V-1.0UF,6.3V,10%,X6SA    I47 @BASEBOARD_FAB2_LIB.BASEBOARD_FAB2(SCH_1):PAGE208
  C1D7    2      B CAP_0402-1.0UF,16V,10%,X6S,D97A    I50 @BASEBOARD_FAB2_LIB.BASEBOARD_FAB2(SCH_1):PAGE208
 C1D13    2      B CAP_A_0402V-0.1UF,16V,10%,X7R,A    I51 @BASEBOARD_FAB2_LIB.BASEBOARD_FAB2(SCH_1):PAGE208
 C1D12    2      B CAP_0402-1.0UF,16V,10%,X6S,D97A    I52 @BASEBOARD_FAB2_LIB.BASEBOARD_FAB2(SCH_1):PAGE208
  C9P4    2      B CAP_0805-10UF,16V,10%,X6S,C953A    I53 @BASEBOARD_FAB2_LIB.BASEBOARD_FAB2(SCH_1):PAGE208
  C9P7    2      B CAP_0805-10UF,16V,10%,X6S,C953A    I54 @BASEBOARD_FAB2_LIB.BASEBOARD_FAB2(SCH_1):PAGE208
  C9P9    2      B CAP_0805-10UF,16V,10%,X6S,C953A    I55 @BASEBOARD_FAB2_LIB.BASEBOARD_FAB2(SCH_1):PAGE208
 C9P24    2      B CAP_0805-10UF,16V,10%,X6S,C953A    I58 @BASEBOARD_FAB2_LIB.BASEBOARD_FAB2(SCH_1):PAGE208
  C9P1    2      B CAP_0805-10UF,16V,10%,X6S,C953A    I59 @BASEBOARD_FAB2_LIB.BASEBOARD_FAB2(SCH_1):PAGE208
  C9P2    2      B CAP_0805-10UF,16V,10%,X6S,C953A    I60 @BASEBOARD_FAB2_LIB.BASEBOARD_FAB2(SCH_1):PAGE208
 C9P10    2      B CAP_A_0603V-22.0UF,4V,20%,X6S,A    I66 @BASEBOARD_FAB2_LIB.BASEBOARD_FAB2(SCH_1):PAGE208
  C9R2    2      B CAP_A_0603V-22.0UF,4V,20%,X6S,A    I67 @BASEBOARD_FAB2_LIB.BASEBOARD_FAB2(SCH_1):PAGE208
 EU1D1    2   LGND IR354XX_SM-IR35411,IC,H73688-0A    I71 @BASEBOARD_FAB2_LIB.BASEBOARD_FAB2(SCH_1):PAGE208
 EU1D1    5 PGND<0> IR354XX_SM-IR35411,IC,H73688-0A    I71 @BASEBOARD_FAB2_LIB.BASEBOARD_FAB2(SCH_1):PAGE208
 EU1D1    7 PGND<1> IR354XX_SM-IR35411,IC,H73688-0A    I71 @BASEBOARD_FAB2_LIB.BASEBOARD_FAB2(SCH_1):PAGE208
 EU1D1   40 PGND<2> IR354XX_SM-IR35411,IC,H73688-0A    I71 @BASEBOARD_FAB2_LIB.BASEBOARD_FAB2(SCH_1):PAGE208
 R1D54    2      B RES_0402-68.1K,1%,1/16W,EMPTY,A    I75 @BASEBOARD_FAB2_LIB.BASEBOARD_FAB2(SCH_1):PAGE208
 R1D55    2      B RES_0402-68.1K,1%,1/16W,EMPTY,A    I76 @BASEBOARD_FAB2_LIB.BASEBOARD_FAB2(SCH_1):PAGE208
 C9N27    2      B CAP_0805-10UF,16V,10%,X6S,C953A     I5 @BASEBOARD_FAB2_LIB.BASEBOARD_FAB2(SCH_1):PAGE209
 C9N26    2      B CAP_0805-10UF,16V,10%,X6S,C953A     I7 @BASEBOARD_FAB2_LIB.BASEBOARD_FAB2(SCH_1):PAGE209
 C9N25    2      B CAP_0805-10UF,16V,10%,X6S,C953A     I8 @BASEBOARD_FAB2_LIB.BASEBOARD_FAB2(SCH_1):PAGE209
  R1E8    2      B RES_0402-100.0,1%,1/16W,CHIP,GA     I9 @BASEBOARD_FAB2_LIB.BASEBOARD_FAB2(SCH_1):PAGE209
 C1C26    2      B CAP_0402-1.0UF,16V,10%,X6S,D97A    I16 @BASEBOARD_FAB2_LIB.BASEBOARD_FAB2(SCH_1):PAGE209
 C1C25    2      B CAP_A_0402V-0.1UF,16V,10%,X7R,A    I17 @BASEBOARD_FAB2_LIB.BASEBOARD_FAB2(SCH_1):PAGE209
 C1D32    2      B CAP_0402-1.0UF,16V,10%,X6S,D97A    I18 @BASEBOARD_FAB2_LIB.BASEBOARD_FAB2(SCH_1):PAGE209
 C1C18    2      B CAP_A_0402V-1.0UF,6.3V,10%,X6SA    I21 @BASEBOARD_FAB2_LIB.BASEBOARD_FAB2(SCH_1):PAGE209
 C1D33    2      B CAP_0402-0.22UF,16V,10%,X7R,A3A    I22 @BASEBOARD_FAB2_LIB.BASEBOARD_FAB2(SCH_1):PAGE209
 C1B16    2      B CAP_A_0402V-0.1UF,16V,10%,EMPTA    I30 @BASEBOARD_FAB2_LIB.BASEBOARD_FAB2(SCH_1):PAGE209
  C1C1    2      B CAPP_2626-270UF,16V,20%,OSCON,A    I35 @BASEBOARD_FAB2_LIB.BASEBOARD_FAB2(SCH_1):PAGE209
 C1E18    2      B CAPP_2626-270UF,16V,20%,OSCON,A    I37 @BASEBOARD_FAB2_LIB.BASEBOARD_FAB2(SCH_1):PAGE209
  C1C2    2      B CAPP_2626-270UF,16V,20%,OSCON,A    I38 @BASEBOARD_FAB2_LIB.BASEBOARD_FAB2(SCH_1):PAGE209
 C1D24    2      B CAP_A_0603V-22.0UF,4V,20%,X6S,A    I42 @BASEBOARD_FAB2_LIB.BASEBOARD_FAB2(SCH_1):PAGE209
  U1B3    1 GND<0> ADM4073_SM-EMPTY,G12194-001    I52 @BASEBOARD_FAB2_LIB.BASEBOARD_FAB2(SCH_1):PAGE209
  U1B3    2 GND<1> ADM4073_SM-EMPTY,G12194-001    I52 @BASEBOARD_FAB2_LIB.BASEBOARD_FAB2(SCH_1):PAGE209
 C9P20    2      B CAP_A_0603V-22.0UF,4V,20%,X6S,A    I55 @BASEBOARD_FAB2_LIB.BASEBOARD_FAB2(SCH_1):PAGE209
 EU1C3    2   LGND IR354XX_SM-IR35411,IC,H73688-0A    I56 @BASEBOARD_FAB2_LIB.BASEBOARD_FAB2(SCH_1):PAGE209
 EU1C3    5 PGND<0> IR354XX_SM-IR35411,IC,H73688-0A    I56 @BASEBOARD_FAB2_LIB.BASEBOARD_FAB2(SCH_1):PAGE209
 EU1C3    7 PGND<1> IR354XX_SM-IR35411,IC,H73688-0A    I56 @BASEBOARD_FAB2_LIB.BASEBOARD_FAB2(SCH_1):PAGE209
 EU1C3   40 PGND<2> IR354XX_SM-IR35411,IC,H73688-0A    I56 @BASEBOARD_FAB2_LIB.BASEBOARD_FAB2(SCH_1):PAGE209
 R1D52    2      B RES_0402-68.1K,1%,1/16W,EMPTY,A    I59 @BASEBOARD_FAB2_LIB.BASEBOARD_FAB2(SCH_1):PAGE209
 C1C19    2      B CAP_A_0603V-22.0UF,4V,20%,X6S,A     I8 @BASEBOARD_FAB2_LIB.BASEBOARD_FAB2(SCH_1):PAGE210
 C9N11    2      B CAPP_3018-470UF,2.5V,20%,ALUM,A    I12 @BASEBOARD_FAB2_LIB.BASEBOARD_FAB2(SCH_1):PAGE210
 C9N20    2      B CAPP_3018-470UF,2.5V,20%,ALUM,A    I14 @BASEBOARD_FAB2_LIB.BASEBOARD_FAB2(SCH_1):PAGE210
  C1C4    2      B CAP_0402-0.22UF,16V,10%,X7R,A3A    I22 @BASEBOARD_FAB2_LIB.BASEBOARD_FAB2(SCH_1):PAGE210
  C1C3    2      B CAP_A_0402V-1.0UF,6.3V,10%,X6SA    I23 @BASEBOARD_FAB2_LIB.BASEBOARD_FAB2(SCH_1):PAGE210
  C1C5    2      B CAP_0402-1.0UF,16V,10%,X6S,D97A    I26 @BASEBOARD_FAB2_LIB.BASEBOARD_FAB2(SCH_1):PAGE210
 C1C17    2      B CAP_A_0402V-0.1UF,16V,10%,X7R,A    I27 @BASEBOARD_FAB2_LIB.BASEBOARD_FAB2(SCH_1):PAGE210
 C1C15    2      B CAP_0402-1.0UF,16V,10%,X6S,D97A    I28 @BASEBOARD_FAB2_LIB.BASEBOARD_FAB2(SCH_1):PAGE210
  R1C4    2      B RES_0402-100.0,1%,1/16W,CHIP,GA    I33 @BASEBOARD_FAB2_LIB.BASEBOARD_FAB2(SCH_1):PAGE210
 C9N13    2      B CAP_0805-10UF,16V,10%,X6S,C953A    I35 @BASEBOARD_FAB2_LIB.BASEBOARD_FAB2(SCH_1):PAGE210
 C9N19    2      B CAP_0805-10UF,16V,10%,X6S,C953A    I36 @BASEBOARD_FAB2_LIB.BASEBOARD_FAB2(SCH_1):PAGE210
 C9N21    2      B CAP_0805-10UF,16V,10%,X6S,C953A    I38 @BASEBOARD_FAB2_LIB.BASEBOARD_FAB2(SCH_1):PAGE210
 C9N22    2      B CAP_A_0603V-22.0UF,4V,20%,X6S,A    I44 @BASEBOARD_FAB2_LIB.BASEBOARD_FAB2(SCH_1):PAGE210
  R9N4    2      B RES_0402-51.1,1.0%,1/16W,CHIP,A    I45 @BASEBOARD_FAB2_LIB.BASEBOARD_FAB2(SCH_1):PAGE210
 EU1C1    2   LGND IR354XX_SM-IR35412,IC,H73684-0A    I51 @BASEBOARD_FAB2_LIB.BASEBOARD_FAB2(SCH_1):PAGE210
 EU1C1    5 PGND<0> IR354XX_SM-IR35412,IC,H73684-0A    I51 @BASEBOARD_FAB2_LIB.BASEBOARD_FAB2(SCH_1):PAGE210
 EU1C1    7 PGND<1> IR354XX_SM-IR35412,IC,H73684-0A    I51 @BASEBOARD_FAB2_LIB.BASEBOARD_FAB2(SCH_1):PAGE210
 EU1C1   40 PGND<2> IR354XX_SM-IR35412,IC,H73684-0A    I51 @BASEBOARD_FAB2_LIB.BASEBOARD_FAB2(SCH_1):PAGE210
 R1C37    2      B RES_0402-68.1K,1%,1/16W,EMPTY,A    I52 @BASEBOARD_FAB2_LIB.BASEBOARD_FAB2(SCH_1):PAGE210
  C3P4    2      B CAP_A_0402V-1.0UF,6.3V,10%,X6SA    I11 @BASEBOARD_FAB2_LIB.BASEBOARD_FAB2(SCH_1):PAGE211
  C3P5    2      B CAP_A_0402V-0.1UF,16V,10%,X7R,A    I13 @BASEBOARD_FAB2_LIB.BASEBOARD_FAB2(SCH_1):PAGE211
  C3P3    2      B CAP_A_0402V-1.0UF,6.3V,10%,X6SA    I20 @BASEBOARD_FAB2_LIB.BASEBOARD_FAB2(SCH_1):PAGE211
  C3P7    2      B CAP_A_0402V-0.1UF,16V,10%,X7R,A    I22 @BASEBOARD_FAB2_LIB.BASEBOARD_FAB2(SCH_1):PAGE211
 R3P16    2      B RES_0402-1.5K,1%,1/16W,CHIP,G2A    I32 @BASEBOARD_FAB2_LIB.BASEBOARD_FAB2(SCH_1):PAGE211
  C3P2    2      B CAP_0402LF-1000PF,50V,10%,X7R,A    I33 @BASEBOARD_FAB2_LIB.BASEBOARD_FAB2(SCH_1):PAGE211
 R3N31    2      B RES_0402-3.16K,1%,1/16W,CHIP,GA    I52 @BASEBOARD_FAB2_LIB.BASEBOARD_FAB2(SCH_1):PAGE211
 R3N22    2      B RES_0402-4.02K,1%,1/16W,CHIP,GA    I65 @BASEBOARD_FAB2_LIB.BASEBOARD_FAB2(SCH_1):PAGE211
  C3P6    2      B CAP_0402LF-1000PF,50V,10%,X7R,A    I71 @BASEBOARD_FAB2_LIB.BASEBOARD_FAB2(SCH_1):PAGE211
 EU3P1   26 BISEN1 PXE1110B_QFN-IC,H89187-001    I93 @BASEBOARD_FAB2_LIB.BASEBOARD_FAB2(SCH_1):PAGE211
 EU3P1   27 GND<0> PXE1110B_QFN-IC,H89187-001    I93 @BASEBOARD_FAB2_LIB.BASEBOARD_FAB2(SCH_1):PAGE211
 EU3P1   23 GND<1> PXE1110B_QFN-IC,H89187-001    I93 @BASEBOARD_FAB2_LIB.BASEBOARD_FAB2(SCH_1):PAGE211
 EU3P1   41  THPAD PXE1110B_QFN-IC,H89187-001    I93 @BASEBOARD_FAB2_LIB.BASEBOARD_FAB2(SCH_1):PAGE211
 C3N38    2      B CAPP_3018-470UF,2.5V,20%,ALUM,A    I16 @BASEBOARD_FAB2_LIB.BASEBOARD_FAB2(SCH_1):PAGE212
 C3N26    2      B CAPP_3018-470UF,2.5V,20%,ALUM,A    I17 @BASEBOARD_FAB2_LIB.BASEBOARD_FAB2(SCH_1):PAGE212
 C3N35    2      B CAPP_3018-470UF,2.5V,20%,ALUM,A    I18 @BASEBOARD_FAB2_LIB.BASEBOARD_FAB2(SCH_1):PAGE212
  C7C6    2      B CAP_A_0603V-22.0UF,4V,20%,X6S,A    I23 @BASEBOARD_FAB2_LIB.BASEBOARD_FAB2(SCH_1):PAGE212
 C7C18    2      B CAP_0402-0.22UF,16V,10%,X7R,A3A    I33 @BASEBOARD_FAB2_LIB.BASEBOARD_FAB2(SCH_1):PAGE212
 C7C20    2      B CAP_A_0402V-1.0UF,6.3V,10%,X6SA    I34 @BASEBOARD_FAB2_LIB.BASEBOARD_FAB2(SCH_1):PAGE212
 C7C17    2      B CAP_0402-1.0UF,16V,10%,X6S,D97A    I36 @BASEBOARD_FAB2_LIB.BASEBOARD_FAB2(SCH_1):PAGE212
 C7C11    2      B CAP_A_0402V-0.1UF,16V,10%,X7R,A    I38 @BASEBOARD_FAB2_LIB.BASEBOARD_FAB2(SCH_1):PAGE212
 C7C12    2      B CAP_0402-1.0UF,16V,10%,X6S,D97A    I39 @BASEBOARD_FAB2_LIB.BASEBOARD_FAB2(SCH_1):PAGE212
 C3N36    2      B CAP_0805-10UF,16V,10%,X6S,C953A    I40 @BASEBOARD_FAB2_LIB.BASEBOARD_FAB2(SCH_1):PAGE212
 C3N33    2      B CAP_0805-10UF,16V,10%,X6S,C953A    I41 @BASEBOARD_FAB2_LIB.BASEBOARD_FAB2(SCH_1):PAGE212
 C3N34    2      B CAP_0805-10UF,16V,10%,X6S,C953A    I43 @BASEBOARD_FAB2_LIB.BASEBOARD_FAB2(SCH_1):PAGE212
  C7C8    2      B CAP_1210-100UF,16V,20%,X5R,644A    I51 @BASEBOARD_FAB2_LIB.BASEBOARD_FAB2(SCH_1):PAGE212
  C7C7    2      B CAP_1210-100UF,16V,20%,X5R,644A    I54 @BASEBOARD_FAB2_LIB.BASEBOARD_FAB2(SCH_1):PAGE212
 R3N20    2      B RES_0402-100.0,1%,1/16W,CHIP,GA    I68 @BASEBOARD_FAB2_LIB.BASEBOARD_FAB2(SCH_1):PAGE212
 C7C10    2      B CAP_A_0603V-22.0UF,4V,20%,X6S,A    I77 @BASEBOARD_FAB2_LIB.BASEBOARD_FAB2(SCH_1):PAGE212
  R7C3    2      B RES_0402-51.1,1.0%,1/16W,CHIP,A    I78 @BASEBOARD_FAB2_LIB.BASEBOARD_FAB2(SCH_1):PAGE212
 EU7C1    2   LGND IR354XX_SM-IR35412,IC,H73684-0A   I101 @BASEBOARD_FAB2_LIB.BASEBOARD_FAB2(SCH_1):PAGE212
 EU7C1    5 PGND<0> IR354XX_SM-IR35412,IC,H73684-0A   I101 @BASEBOARD_FAB2_LIB.BASEBOARD_FAB2(SCH_1):PAGE212
 EU7C1    7 PGND<1> IR354XX_SM-IR35412,IC,H73684-0A   I101 @BASEBOARD_FAB2_LIB.BASEBOARD_FAB2(SCH_1):PAGE212
 EU7C1   40 PGND<2> IR354XX_SM-IR35412,IC,H73684-0A   I101 @BASEBOARD_FAB2_LIB.BASEBOARD_FAB2(SCH_1):PAGE212
 R7C25    2      B RES_0402-68.1K,1%,1/16W,EMPTY,A   I103 @BASEBOARD_FAB2_LIB.BASEBOARD_FAB2(SCH_1):PAGE212
 C4D31    2      B CAP_A_0402V-1.0UF,6.3V,10%,X6SA     I9 @BASEBOARD_FAB2_LIB.BASEBOARD_FAB2(SCH_1):PAGE213
 C4D32    2      B CAP_A_0402V-0.1UF,16V,10%,X7R,A    I11 @BASEBOARD_FAB2_LIB.BASEBOARD_FAB2(SCH_1):PAGE213
 C4D36    2      B CAP_A_0402V-1.0UF,6.3V,10%,X6SA    I17 @BASEBOARD_FAB2_LIB.BASEBOARD_FAB2(SCH_1):PAGE213
 R4D57    2      B RES_0402-1.5K,1%,1/16W,CHIP,G2A    I32 @BASEBOARD_FAB2_LIB.BASEBOARD_FAB2(SCH_1):PAGE213
 C4D40    2      B CAP_0402LF-1000PF,50V,10%,X7R,A    I33 @BASEBOARD_FAB2_LIB.BASEBOARD_FAB2(SCH_1):PAGE213
 C4D38    2      B CAP_A_0402V-0.1UF,16V,10%,X7R,A    I35 @BASEBOARD_FAB2_LIB.BASEBOARD_FAB2(SCH_1):PAGE213
 R4D64    2      B RES_0402-3.16K,1%,1/16W,CHIP,GA    I42 @BASEBOARD_FAB2_LIB.BASEBOARD_FAB2(SCH_1):PAGE213
  R4E2    2      B RES_0402-3.16K,1%,1/16W,CHIP,GA    I65 @BASEBOARD_FAB2_LIB.BASEBOARD_FAB2(SCH_1):PAGE213
 C4D33    2      B CAP_0402LF-1000PF,50V,10%,X7R,A    I73 @BASEBOARD_FAB2_LIB.BASEBOARD_FAB2(SCH_1):PAGE213
 EU4D5   26 BISEN1 PXE1110B_QFN-IC,H89187-001    I96 @BASEBOARD_FAB2_LIB.BASEBOARD_FAB2(SCH_1):PAGE213
 EU4D5   27 GND<0> PXE1110B_QFN-IC,H89187-001    I96 @BASEBOARD_FAB2_LIB.BASEBOARD_FAB2(SCH_1):PAGE213
 EU4D5   23 GND<1> PXE1110B_QFN-IC,H89187-001    I96 @BASEBOARD_FAB2_LIB.BASEBOARD_FAB2(SCH_1):PAGE213
 EU4D5   41  THPAD PXE1110B_QFN-IC,H89187-001    I96 @BASEBOARD_FAB2_LIB.BASEBOARD_FAB2(SCH_1):PAGE213
  C4E9    2      B CAP_1210-100UF,16V,20%,X5R,644A     I8 @BASEBOARD_FAB2_LIB.BASEBOARD_FAB2(SCH_1):PAGE214
  C4E7    2      B CAPP_3018-470UF,2.5V,20%,ALUM,A    I20 @BASEBOARD_FAB2_LIB.BASEBOARD_FAB2(SCH_1):PAGE214
 C6R12    2      B CAPP_3018-470UF,2.5V,20%,ALUM,A    I21 @BASEBOARD_FAB2_LIB.BASEBOARD_FAB2(SCH_1):PAGE214
  C6R5    2      B CAPP_3018-470UF,2.5V,20%,ALUM,A    I24 @BASEBOARD_FAB2_LIB.BASEBOARD_FAB2(SCH_1):PAGE214
  C4E8    2      B CAP_1210-100UF,16V,20%,X5R,644A    I29 @BASEBOARD_FAB2_LIB.BASEBOARD_FAB2(SCH_1):PAGE214
 C4E14    2      B CAP_1210-100UF,16V,20%,X5R,644A    I31 @BASEBOARD_FAB2_LIB.BASEBOARD_FAB2(SCH_1):PAGE214
  C7R1    2      B CAP_A_0603V-22.0UF,4V,20%,X6S,A    I65 @BASEBOARD_FAB2_LIB.BASEBOARD_FAB2(SCH_1):PAGE214
 C4E23    2      B CAP_0402-0.22UF,16V,10%,X7R,A3A    I73 @BASEBOARD_FAB2_LIB.BASEBOARD_FAB2(SCH_1):PAGE214
 C4E28    2      B CAP_A_0402V-1.0UF,6.3V,10%,X6SA    I74 @BASEBOARD_FAB2_LIB.BASEBOARD_FAB2(SCH_1):PAGE214
 C4E22    2      B CAP_0402-1.0UF,16V,10%,X6S,D97A    I76 @BASEBOARD_FAB2_LIB.BASEBOARD_FAB2(SCH_1):PAGE214
 C4E13    2      B CAP_A_0402V-0.1UF,16V,10%,X7R,A    I77 @BASEBOARD_FAB2_LIB.BASEBOARD_FAB2(SCH_1):PAGE214
 C4E15    2      B CAP_0402-1.0UF,16V,10%,X6S,D97A    I79 @BASEBOARD_FAB2_LIB.BASEBOARD_FAB2(SCH_1):PAGE214
 C6R14    2      B CAP_0805-10UF,16V,10%,X6S,C953A    I80 @BASEBOARD_FAB2_LIB.BASEBOARD_FAB2(SCH_1):PAGE214
 C6R10    2      B CAP_0805-10UF,16V,10%,X6S,C953A    I81 @BASEBOARD_FAB2_LIB.BASEBOARD_FAB2(SCH_1):PAGE214
  C6R8    2      B CAP_0805-10UF,16V,10%,X6S,C953A    I83 @BASEBOARD_FAB2_LIB.BASEBOARD_FAB2(SCH_1):PAGE214
 R3D28    2      B RES_0402-100.0,1%,1/16W,CHIP,GA   I101 @BASEBOARD_FAB2_LIB.BASEBOARD_FAB2(SCH_1):PAGE214
  C3E1    2      B CAP_A_0603V-22.0UF,4V,20%,X6S,A   I108 @BASEBOARD_FAB2_LIB.BASEBOARD_FAB2(SCH_1):PAGE214
  R7R1    2      B RES_0402-51.1,1.0%,1/16W,CHIP,A   I109 @BASEBOARD_FAB2_LIB.BASEBOARD_FAB2(SCH_1):PAGE214
 EU4E2    2   LGND IR354XX_SM-IR35412,IC,H73684-0A   I126 @BASEBOARD_FAB2_LIB.BASEBOARD_FAB2(SCH_1):PAGE214
 EU4E2    5 PGND<0> IR354XX_SM-IR35412,IC,H73684-0A   I126 @BASEBOARD_FAB2_LIB.BASEBOARD_FAB2(SCH_1):PAGE214
 EU4E2    7 PGND<1> IR354XX_SM-IR35412,IC,H73684-0A   I126 @BASEBOARD_FAB2_LIB.BASEBOARD_FAB2(SCH_1):PAGE214
 EU4E2   40 PGND<2> IR354XX_SM-IR35412,IC,H73684-0A   I126 @BASEBOARD_FAB2_LIB.BASEBOARD_FAB2(SCH_1):PAGE214
 R4E21    2      B RES_0402-68.1K,1%,1/16W,EMPTY,A   I127 @BASEBOARD_FAB2_LIB.BASEBOARD_FAB2(SCH_1):PAGE214
 C7F14    2      B CAP_0402LF-1000PF,50V,10%,X7R,A   I305 @BASEBOARD_FAB2_LIB.BASEBOARD_FAB2(SCH_1):PAGE215
 C7F18    2      B CAP_A_0402V-1.0UF,6.3V,10%,X6SA   I309 @BASEBOARD_FAB2_LIB.BASEBOARD_FAB2(SCH_1):PAGE215
 C7F17    2      B CAP_A_0402V-0.1UF,16V,10%,X7R,A   I311 @BASEBOARD_FAB2_LIB.BASEBOARD_FAB2(SCH_1):PAGE215
 R7G10    2      B RES_0402-8.06K,1%,1/16W,CHIP,GA   I317 @BASEBOARD_FAB2_LIB.BASEBOARD_FAB2(SCH_1):PAGE215
  C7G3    2      B CAP_0402LF-220PF,50V,10%,X7R,AA   I320 @BASEBOARD_FAB2_LIB.BASEBOARD_FAB2(SCH_1):PAGE215
  R7G8    2      B RES_0402-4.02K,1%,1/16W,CHIP,GA   I321 @BASEBOARD_FAB2_LIB.BASEBOARD_FAB2(SCH_1):PAGE215
 C7F16    2      B CAP_A_0402V-1.0UF,6.3V,10%,X6SA   I325 @BASEBOARD_FAB2_LIB.BASEBOARD_FAB2(SCH_1):PAGE215
 C7F15    2      B CAP_A_0402V-0.1UF,16V,10%,X7R,A   I327 @BASEBOARD_FAB2_LIB.BASEBOARD_FAB2(SCH_1):PAGE215
  R7G3    2      B RES_0402-1.5K,1%,1/16W,CHIP,G2A   I337 @BASEBOARD_FAB2_LIB.BASEBOARD_FAB2(SCH_1):PAGE215
  C7G1    2      B CAP_0402LF-1000PF,50V,10%,X7R,A   I339 @BASEBOARD_FAB2_LIB.BASEBOARD_FAB2(SCH_1):PAGE215
 EU7G1   32 BISEN1 PXM1310B_QFN-IC,H89186-001   I358 @BASEBOARD_FAB2_LIB.BASEBOARD_FAB2(SCH_1):PAGE215
 EU7G1   27    GND PXM1310B_QFN-IC,H89186-001   I358 @BASEBOARD_FAB2_LIB.BASEBOARD_FAB2(SCH_1):PAGE215
 EU7G1   41  THPAD PXM1310B_QFN-IC,H89186-001   I358 @BASEBOARD_FAB2_LIB.BASEBOARD_FAB2(SCH_1):PAGE215
 C3U10    2      B CAP_A_0402V-0.1UF,16V,10%,X7R,A   I360 @BASEBOARD_FAB2_LIB.BASEBOARD_FAB2(SCH_1):PAGE215
  C6G3    2      B CAP_0805LF-22UF,4V,20%,X6S,C95A     I6 @BASEBOARD_FAB2_LIB.BASEBOARD_FAB2(SCH_1):PAGE216
  C3U2    2      B CAP_0805-10UF,16V,10%,X6S,C953A    I45 @BASEBOARD_FAB2_LIB.BASEBOARD_FAB2(SCH_1):PAGE216
  C3U3    2      B CAP_0805-10UF,16V,10%,X6S,C953A    I46 @BASEBOARD_FAB2_LIB.BASEBOARD_FAB2(SCH_1):PAGE216
  C3U4    2      B CAP_0805-10UF,16V,10%,X6S,C953A    I47 @BASEBOARD_FAB2_LIB.BASEBOARD_FAB2(SCH_1):PAGE216
 C7G37    2      B CAP_0402-1.0UF,16V,10%,X6S,D97A    I48 @BASEBOARD_FAB2_LIB.BASEBOARD_FAB2(SCH_1):PAGE216
 C7G33    2      B CAP_0402-1.0UF,16V,10%,X6S,D97A    I50 @BASEBOARD_FAB2_LIB.BASEBOARD_FAB2(SCH_1):PAGE216
 C7G29    2      B CAP_A_0402V-0.1UF,16V,10%,X7R,A    I51 @BASEBOARD_FAB2_LIB.BASEBOARD_FAB2(SCH_1):PAGE216
 C7G35    2      B CAP_A_0402V-1.0UF,6.3V,10%,X6SA    I53 @BASEBOARD_FAB2_LIB.BASEBOARD_FAB2(SCH_1):PAGE216
 C7G34    2      B CAP_0402-0.22UF,16V,10%,X7R,A3A    I54 @BASEBOARD_FAB2_LIB.BASEBOARD_FAB2(SCH_1):PAGE216
 C7G27    2      B CAP_0805LF-22UF,4V,20%,X6S,C95A    I68 @BASEBOARD_FAB2_LIB.BASEBOARD_FAB2(SCH_1):PAGE216
 C7G41    2      B CAP_0402-0.22UF,16V,10%,X7R,A3A    I72 @BASEBOARD_FAB2_LIB.BASEBOARD_FAB2(SCH_1):PAGE216
 C7G42    2      B CAP_A_0402V-1.0UF,6.3V,10%,X6SA    I73 @BASEBOARD_FAB2_LIB.BASEBOARD_FAB2(SCH_1):PAGE216
 C7G40    2      B CAP_0402-1.0UF,16V,10%,X6S,D97A    I77 @BASEBOARD_FAB2_LIB.BASEBOARD_FAB2(SCH_1):PAGE216
 C7G36    2      B CAP_A_0402V-0.1UF,16V,10%,X7R,A    I78 @BASEBOARD_FAB2_LIB.BASEBOARD_FAB2(SCH_1):PAGE216
 C7G30    2      B CAP_0402-1.0UF,16V,10%,X6S,D97A    I79 @BASEBOARD_FAB2_LIB.BASEBOARD_FAB2(SCH_1):PAGE216
  C3U9    2      B CAP_0805-10UF,16V,10%,X6S,C953A    I80 @BASEBOARD_FAB2_LIB.BASEBOARD_FAB2(SCH_1):PAGE216
  C3U7    2      B CAP_0805-10UF,16V,10%,X6S,C953A    I81 @BASEBOARD_FAB2_LIB.BASEBOARD_FAB2(SCH_1):PAGE216
  C3U6    2      B CAP_0805-10UF,16V,10%,X6S,C953A    I84 @BASEBOARD_FAB2_LIB.BASEBOARD_FAB2(SCH_1):PAGE216
 EU7G2    2   LGND IR354XX_SM-IR35411,IC,H73688-0A   I102 @BASEBOARD_FAB2_LIB.BASEBOARD_FAB2(SCH_1):PAGE216
 EU7G2    5 PGND<0> IR354XX_SM-IR35411,IC,H73688-0A   I102 @BASEBOARD_FAB2_LIB.BASEBOARD_FAB2(SCH_1):PAGE216
 EU7G2    7 PGND<1> IR354XX_SM-IR35411,IC,H73688-0A   I102 @BASEBOARD_FAB2_LIB.BASEBOARD_FAB2(SCH_1):PAGE216
 EU7G2   40 PGND<2> IR354XX_SM-IR35411,IC,H73688-0A   I102 @BASEBOARD_FAB2_LIB.BASEBOARD_FAB2(SCH_1):PAGE216
 EU7G3    2   LGND IR354XX_SM-IR35411,IC,H73688-0A   I103 @BASEBOARD_FAB2_LIB.BASEBOARD_FAB2(SCH_1):PAGE216
 EU7G3    5 PGND<0> IR354XX_SM-IR35411,IC,H73688-0A   I103 @BASEBOARD_FAB2_LIB.BASEBOARD_FAB2(SCH_1):PAGE216
 EU7G3    7 PGND<1> IR354XX_SM-IR35411,IC,H73688-0A   I103 @BASEBOARD_FAB2_LIB.BASEBOARD_FAB2(SCH_1):PAGE216
 EU7G3   40 PGND<2> IR354XX_SM-IR35411,IC,H73688-0A   I103 @BASEBOARD_FAB2_LIB.BASEBOARD_FAB2(SCH_1):PAGE216
 R7G25    2      B RES_0402-68.1K,1%,1/16W,EMPTY,A   I104 @BASEBOARD_FAB2_LIB.BASEBOARD_FAB2(SCH_1):PAGE216
 R7G30    2      B RES_0402-68.1K,1%,1/16W,EMPTY,A   I106 @BASEBOARD_FAB2_LIB.BASEBOARD_FAB2(SCH_1):PAGE216
  R3U4    2      B RES_0603-120.0,1%,1/10W,CHIP,GA    I58 @BASEBOARD_FAB2_LIB.BASEBOARD_FAB2(SCH_1):PAGE217
 C7G28    2      B CAPP_3018-470UF,2.5V,20%,ALUM,A    I75 @BASEBOARD_FAB2_LIB.BASEBOARD_FAB2(SCH_1):PAGE217
  C3U1    2      B CAPP_3018-470UF,2.5V,20%,ALUM,A    I76 @BASEBOARD_FAB2_LIB.BASEBOARD_FAB2(SCH_1):PAGE217
  C3U5    2      B CAPP_3018-470UF,2.5V,20%,ALUM,A    I77 @BASEBOARD_FAB2_LIB.BASEBOARD_FAB2(SCH_1):PAGE217
  C3U8    2      B CAPP_3018-470UF,2.5V,20%,ALUM,A    I78 @BASEBOARD_FAB2_LIB.BASEBOARD_FAB2(SCH_1):PAGE217
 C5U13    2      B CAP_0805-100UF,4V,20%,X5R,6024A    I82 @BASEBOARD_FAB2_LIB.BASEBOARD_FAB2(SCH_1):PAGE217
 C5U10    2      B CAP_0805-100UF,4V,20%,X5R,6024A    I83 @BASEBOARD_FAB2_LIB.BASEBOARD_FAB2(SCH_1):PAGE217
  C5U1    2      B CAP_0805-100UF,4V,20%,X5R,6024A    I88 @BASEBOARD_FAB2_LIB.BASEBOARD_FAB2(SCH_1):PAGE217
 C5U14    2      B CAP_0805-100UF,4V,20%,X5R,6024A    I89 @BASEBOARD_FAB2_LIB.BASEBOARD_FAB2(SCH_1):PAGE217
 C5U15    2      B CAP_0805-100UF,4V,20%,X5R,6024A    I90 @BASEBOARD_FAB2_LIB.BASEBOARD_FAB2(SCH_1):PAGE217
  C4T4    2      B CAP_0805-100UF,4V,20%,X5R,6024A    I91 @BASEBOARD_FAB2_LIB.BASEBOARD_FAB2(SCH_1):PAGE217
  C5G9    2      B CAP_0805-100UF,4V,20%,X5R,6024A    I92 @BASEBOARD_FAB2_LIB.BASEBOARD_FAB2(SCH_1):PAGE217
 C5G20    2      B CAP_0805-100UF,4V,20%,X5R,6024A   I110 @BASEBOARD_FAB2_LIB.BASEBOARD_FAB2(SCH_1):PAGE217
  C7G2    2      B CAPP_2626-270UF,16V,20%,OSCON,A   I175 @BASEBOARD_FAB2_LIB.BASEBOARD_FAB2(SCH_1):PAGE217
 C5P39    2      B CAP_0805LF-22UF,4V,20%,X6S,C95A   I184 @BASEBOARD_FAB2_LIB.BASEBOARD_FAB2(SCH_1):PAGE217
 C5D57    2      B CAP_0603LF-10UF,4V,20%,X6S,E15A   I186 @BASEBOARD_FAB2_LIB.BASEBOARD_FAB2(SCH_1):PAGE217
 C5D56    2      B CAP_0603LF-10UF,4V,20%,X6S,E15A   I188 @BASEBOARD_FAB2_LIB.BASEBOARD_FAB2(SCH_1):PAGE217
 C5D55    2      B CAP_0603LF-10UF,4V,20%,X6S,E15A   I189 @BASEBOARD_FAB2_LIB.BASEBOARD_FAB2(SCH_1):PAGE217
 C5D54    2      B CAP_0603LF-10UF,4V,20%,X6S,E15A   I190 @BASEBOARD_FAB2_LIB.BASEBOARD_FAB2(SCH_1):PAGE217
 C5P38    2      B CAP_0805LF-22UF,4V,20%,X6S,C95A   I193 @BASEBOARD_FAB2_LIB.BASEBOARD_FAB2(SCH_1):PAGE217
  C5F2    2      B CAP_A_0603V-47UF,4V,20%,X5R,60A   I205 @BASEBOARD_FAB2_LIB.BASEBOARD_FAB2(SCH_1):PAGE217
  C5F1    2      B CAP_A_0603V-47UF,4V,20%,X5R,60A   I206 @BASEBOARD_FAB2_LIB.BASEBOARD_FAB2(SCH_1):PAGE217
 C5G10    2      B CAP_A_0603V-47UF,4V,20%,X5R,60A   I207 @BASEBOARD_FAB2_LIB.BASEBOARD_FAB2(SCH_1):PAGE217
  C5T2    2      B CAP_A_0603V-47UF,4V,20%,X5R,60A   I208 @BASEBOARD_FAB2_LIB.BASEBOARD_FAB2(SCH_1):PAGE217
 C5U11    2      B CAP_A_0603V-47UF,4V,20%,X5R,60A   I209 @BASEBOARD_FAB2_LIB.BASEBOARD_FAB2(SCH_1):PAGE217
 C5T13    2      B CAP_A_0603V-47UF,4V,20%,X5R,60A   I210 @BASEBOARD_FAB2_LIB.BASEBOARD_FAB2(SCH_1):PAGE217
  C5T4    2      B CAP_A_0603V-47UF,4V,20%,X5R,60A   I211 @BASEBOARD_FAB2_LIB.BASEBOARD_FAB2(SCH_1):PAGE217
  C5T1    2      B CAP_A_0603V-47UF,4V,20%,X5R,60A   I212 @BASEBOARD_FAB2_LIB.BASEBOARD_FAB2(SCH_1):PAGE217
 C5G19    2      B CAP_A_0603V-47UF,4V,20%,X5R,60A   I213 @BASEBOARD_FAB2_LIB.BASEBOARD_FAB2(SCH_1):PAGE217
  C5T5    2      B CAP_A_0603V-22.0UF,4V,20%,X6S,A   I216 @BASEBOARD_FAB2_LIB.BASEBOARD_FAB2(SCH_1):PAGE217
  C5G3    2      B CAP_A_0603V-22.0UF,4V,20%,X6S,A   I217 @BASEBOARD_FAB2_LIB.BASEBOARD_FAB2(SCH_1):PAGE217
  C5T6    2      B CAP_A_0603V-22.0UF,4V,20%,X6S,A   I218 @BASEBOARD_FAB2_LIB.BASEBOARD_FAB2(SCH_1):PAGE217
  C5T7    2      B CAP_A_0603V-22.0UF,4V,20%,X6S,A   I219 @BASEBOARD_FAB2_LIB.BASEBOARD_FAB2(SCH_1):PAGE217
 C5G15    2      B CAP_A_0603V-22.0UF,4V,20%,X6S,A   I220 @BASEBOARD_FAB2_LIB.BASEBOARD_FAB2(SCH_1):PAGE217
 C5G16    2      B CAP_A_0603V-22.0UF,4V,20%,X6S,A   I221 @BASEBOARD_FAB2_LIB.BASEBOARD_FAB2(SCH_1):PAGE217
  C5T8    2      B CAP_A_0603V-22.0UF,4V,20%,X6S,A   I222 @BASEBOARD_FAB2_LIB.BASEBOARD_FAB2(SCH_1):PAGE217
 C5G14    2      B CAP_A_0603V-22.0UF,4V,20%,X6S,A   I223 @BASEBOARD_FAB2_LIB.BASEBOARD_FAB2(SCH_1):PAGE217
  C5T9    2      B CAP_A_0603V-22.0UF,4V,20%,X6S,A   I224 @BASEBOARD_FAB2_LIB.BASEBOARD_FAB2(SCH_1):PAGE217
 C5T10    2      B CAP_A_0603V-22.0UF,4V,20%,X6S,A   I225 @BASEBOARD_FAB2_LIB.BASEBOARD_FAB2(SCH_1):PAGE217
 C5G17    2      B CAP_A_0603V-22.0UF,4V,20%,X6S,A   I226 @BASEBOARD_FAB2_LIB.BASEBOARD_FAB2(SCH_1):PAGE217
 C5G18    2      B CAP_A_0603V-22.0UF,4V,20%,X6S,A   I227 @BASEBOARD_FAB2_LIB.BASEBOARD_FAB2(SCH_1):PAGE217
 C5T11    2      B CAP_A_0603V-22.0UF,4V,20%,X6S,A   I228 @BASEBOARD_FAB2_LIB.BASEBOARD_FAB2(SCH_1):PAGE217
 C5T12    2      B CAP_A_0603V-22.0UF,4V,20%,X6S,A   I229 @BASEBOARD_FAB2_LIB.BASEBOARD_FAB2(SCH_1):PAGE217
  C5G8    2      B CAP_A_0603V-22.0UF,4V,20%,X6S,A   I230 @BASEBOARD_FAB2_LIB.BASEBOARD_FAB2(SCH_1):PAGE217
  C5G1    2      B CAP_A_0603V-22.0UF,4V,20%,X6S,A   I231 @BASEBOARD_FAB2_LIB.BASEBOARD_FAB2(SCH_1):PAGE217
  C5U9    2      B CAP_A_0603V-22.0UF,4V,20%,X6S,A   I232 @BASEBOARD_FAB2_LIB.BASEBOARD_FAB2(SCH_1):PAGE217
  C5U8    2      B CAP_A_0603V-22.0UF,4V,20%,X6S,A   I233 @BASEBOARD_FAB2_LIB.BASEBOARD_FAB2(SCH_1):PAGE217
  C5G7    2      B CAP_A_0603V-22.0UF,4V,20%,X6S,A   I234 @BASEBOARD_FAB2_LIB.BASEBOARD_FAB2(SCH_1):PAGE217
  C5G5    2      B CAP_A_0603V-22.0UF,4V,20%,X6S,A   I235 @BASEBOARD_FAB2_LIB.BASEBOARD_FAB2(SCH_1):PAGE217
  C5U7    2      B CAP_A_0603V-22.0UF,4V,20%,X6S,A   I236 @BASEBOARD_FAB2_LIB.BASEBOARD_FAB2(SCH_1):PAGE217
  C5G6    2      B CAP_A_0603V-22.0UF,4V,20%,X6S,A   I237 @BASEBOARD_FAB2_LIB.BASEBOARD_FAB2(SCH_1):PAGE217
  C5U6    2      B CAP_A_0603V-22.0UF,4V,20%,X6S,A   I238 @BASEBOARD_FAB2_LIB.BASEBOARD_FAB2(SCH_1):PAGE217
  C5U5    2      B CAP_A_0603V-22.0UF,4V,20%,X6S,A   I239 @BASEBOARD_FAB2_LIB.BASEBOARD_FAB2(SCH_1):PAGE217
 C5G13    2      B CAP_A_0603V-22.0UF,4V,20%,X6S,A   I240 @BASEBOARD_FAB2_LIB.BASEBOARD_FAB2(SCH_1):PAGE217
  C5G4    2      B CAP_A_0603V-22.0UF,4V,20%,X6S,A   I241 @BASEBOARD_FAB2_LIB.BASEBOARD_FAB2(SCH_1):PAGE217
  C5U4    2      B CAP_A_0603V-22.0UF,4V,20%,X6S,A   I243 @BASEBOARD_FAB2_LIB.BASEBOARD_FAB2(SCH_1):PAGE217
  C5U3    2      B CAP_A_0603V-22.0UF,4V,20%,X6S,A   I244 @BASEBOARD_FAB2_LIB.BASEBOARD_FAB2(SCH_1):PAGE217
  C5G2    2      B CAP_A_0603V-22.0UF,4V,20%,X6S,A   I245 @BASEBOARD_FAB2_LIB.BASEBOARD_FAB2(SCH_1):PAGE217
 C5G12    2      B CAP_A_0603V-22.0UF,4V,20%,X6S,A   I246 @BASEBOARD_FAB2_LIB.BASEBOARD_FAB2(SCH_1):PAGE217
  C5U2    2      B CAP_A_0603V-22.0UF,4V,20%,X6S,A   I247 @BASEBOARD_FAB2_LIB.BASEBOARD_FAB2(SCH_1):PAGE217
 C5G11    2      B CAP_A_0603V-22.0UF,4V,20%,X6S,A   I250 @BASEBOARD_FAB2_LIB.BASEBOARD_FAB2(SCH_1):PAGE217
 SH4U1    2      B SHUNT_SH0201-EMPTY,N_A   I259 @BASEBOARD_FAB2_LIB.BASEBOARD_FAB2(SCH_1):PAGE217
  C7B1    2      B CAP_A_0402V-1.0UF,6.3V,10%,X6SA    I22 @BASEBOARD_FAB2_LIB.BASEBOARD_FAB2(SCH_1):PAGE218
  C7B2    2      B CAP_A_0402V-0.1UF,16V,10%,X7R,A    I23 @BASEBOARD_FAB2_LIB.BASEBOARD_FAB2(SCH_1):PAGE218
  C7B3    2      B CAP_0402LF-1000PF,50V,10%,X7R,A    I26 @BASEBOARD_FAB2_LIB.BASEBOARD_FAB2(SCH_1):PAGE218
 C7A37    2      B CAP_A_0402V-1.0UF,6.3V,10%,X6SA    I29 @BASEBOARD_FAB2_LIB.BASEBOARD_FAB2(SCH_1):PAGE218
 C7A38    2      B CAP_A_0402V-0.1UF,16V,10%,X7R,A    I31 @BASEBOARD_FAB2_LIB.BASEBOARD_FAB2(SCH_1):PAGE218
  R7A8    2      B RES_0402-8.06K,1%,1/16W,CHIP,GA    I37 @BASEBOARD_FAB2_LIB.BASEBOARD_FAB2(SCH_1):PAGE218
 C7A29    2      B CAP_0402LF-220PF,50V,10%,X7R,AA    I39 @BASEBOARD_FAB2_LIB.BASEBOARD_FAB2(SCH_1):PAGE218
 R7A10    2      B RES_0402-3.16K,1%,1/16W,CHIP,GA    I40 @BASEBOARD_FAB2_LIB.BASEBOARD_FAB2(SCH_1):PAGE218
 R7A16    2      B RES_0402-1.5K,1%,1/16W,CHIP,G2A    I54 @BASEBOARD_FAB2_LIB.BASEBOARD_FAB2(SCH_1):PAGE218
 C7A35    2      B CAP_0402LF-1000PF,50V,10%,X7R,A    I55 @BASEBOARD_FAB2_LIB.BASEBOARD_FAB2(SCH_1):PAGE218
 EU7A5   32 BISEN1 PXM1310B_QFN-IC,H89186-001    I75 @BASEBOARD_FAB2_LIB.BASEBOARD_FAB2(SCH_1):PAGE218
 EU7A5   27    GND PXM1310B_QFN-IC,H89186-001    I75 @BASEBOARD_FAB2_LIB.BASEBOARD_FAB2(SCH_1):PAGE218
 EU7A5   41  THPAD PXM1310B_QFN-IC,H89186-001    I75 @BASEBOARD_FAB2_LIB.BASEBOARD_FAB2(SCH_1):PAGE218
 C3L31    2      B CAP_A_0402V-0.1UF,16V,10%,X7R,A    I77 @BASEBOARD_FAB2_LIB.BASEBOARD_FAB2(SCH_1):PAGE218
  C3L2    2      B CAP_0805-10UF,16V,10%,X6S,C953A    I45 @BASEBOARD_FAB2_LIB.BASEBOARD_FAB2(SCH_1):PAGE219
  C3L4    2      B CAP_0805-10UF,16V,10%,X6S,C953A    I46 @BASEBOARD_FAB2_LIB.BASEBOARD_FAB2(SCH_1):PAGE219
 C3L13    2      B CAP_0805-10UF,16V,10%,X6S,C953A    I47 @BASEBOARD_FAB2_LIB.BASEBOARD_FAB2(SCH_1):PAGE219
 C7A11    2      B CAP_0402-1.0UF,16V,10%,X6S,D97A    I48 @BASEBOARD_FAB2_LIB.BASEBOARD_FAB2(SCH_1):PAGE219
 C7A16    2      B CAP_0402-1.0UF,16V,10%,X6S,D97A    I50 @BASEBOARD_FAB2_LIB.BASEBOARD_FAB2(SCH_1):PAGE219
  C7A5    2      B CAP_A_0402V-0.1UF,16V,10%,X7R,A    I51 @BASEBOARD_FAB2_LIB.BASEBOARD_FAB2(SCH_1):PAGE219
 C7A18    2      B CAP_A_0402V-1.0UF,6.3V,10%,X6SA    I53 @BASEBOARD_FAB2_LIB.BASEBOARD_FAB2(SCH_1):PAGE219
 C7A17    2      B CAP_0402-0.22UF,16V,10%,X7R,A3A    I54 @BASEBOARD_FAB2_LIB.BASEBOARD_FAB2(SCH_1):PAGE219
  C6A4    2      B CAP_0805LF-22UF,4V,20%,X6S,C95A    I68 @BASEBOARD_FAB2_LIB.BASEBOARD_FAB2(SCH_1):PAGE219
 C7A25    2      B CAP_0402-0.22UF,16V,10%,X7R,A3A    I72 @BASEBOARD_FAB2_LIB.BASEBOARD_FAB2(SCH_1):PAGE219
 C7A26    2      B CAP_A_0402V-1.0UF,6.3V,10%,X6SA    I73 @BASEBOARD_FAB2_LIB.BASEBOARD_FAB2(SCH_1):PAGE219
 C7A24    2      B CAP_0402-1.0UF,16V,10%,X6S,D97A    I77 @BASEBOARD_FAB2_LIB.BASEBOARD_FAB2(SCH_1):PAGE219
 C7A20    2      B CAP_A_0402V-0.1UF,16V,10%,X7R,A    I78 @BASEBOARD_FAB2_LIB.BASEBOARD_FAB2(SCH_1):PAGE219
 C7A21    2      B CAP_0402-1.0UF,16V,10%,X6S,D97A    I79 @BASEBOARD_FAB2_LIB.BASEBOARD_FAB2(SCH_1):PAGE219
 C3L17    2      B CAP_0805-10UF,16V,10%,X6S,C953A    I80 @BASEBOARD_FAB2_LIB.BASEBOARD_FAB2(SCH_1):PAGE219
 C3L16    2      B CAP_0805-10UF,16V,10%,X6S,C953A    I81 @BASEBOARD_FAB2_LIB.BASEBOARD_FAB2(SCH_1):PAGE219
 C3L15    2      B CAP_0805-10UF,16V,10%,X6S,C953A    I84 @BASEBOARD_FAB2_LIB.BASEBOARD_FAB2(SCH_1):PAGE219
  C6A1    2      B CAP_0805LF-22UF,4V,20%,X6S,C95A    I87 @BASEBOARD_FAB2_LIB.BASEBOARD_FAB2(SCH_1):PAGE219
 EU7A1    2   LGND IR354XX_SM-IR35411,IC,H73688-0A   I106 @BASEBOARD_FAB2_LIB.BASEBOARD_FAB2(SCH_1):PAGE219
 EU7A1    5 PGND<0> IR354XX_SM-IR35411,IC,H73688-0A   I106 @BASEBOARD_FAB2_LIB.BASEBOARD_FAB2(SCH_1):PAGE219
 EU7A1    7 PGND<1> IR354XX_SM-IR35411,IC,H73688-0A   I106 @BASEBOARD_FAB2_LIB.BASEBOARD_FAB2(SCH_1):PAGE219
 EU7A1   40 PGND<2> IR354XX_SM-IR35411,IC,H73688-0A   I106 @BASEBOARD_FAB2_LIB.BASEBOARD_FAB2(SCH_1):PAGE219
 EU7A4    2   LGND IR354XX_SM-IR35411,IC,H73688-0A   I107 @BASEBOARD_FAB2_LIB.BASEBOARD_FAB2(SCH_1):PAGE219
 EU7A4    5 PGND<0> IR354XX_SM-IR35411,IC,H73688-0A   I107 @BASEBOARD_FAB2_LIB.BASEBOARD_FAB2(SCH_1):PAGE219
 EU7A4    7 PGND<1> IR354XX_SM-IR35411,IC,H73688-0A   I107 @BASEBOARD_FAB2_LIB.BASEBOARD_FAB2(SCH_1):PAGE219
 EU7A4   40 PGND<2> IR354XX_SM-IR35411,IC,H73688-0A   I107 @BASEBOARD_FAB2_LIB.BASEBOARD_FAB2(SCH_1):PAGE219
 R7A20    2      B RES_0402-68.1K,1%,1/16W,EMPTY,A   I108 @BASEBOARD_FAB2_LIB.BASEBOARD_FAB2(SCH_1):PAGE219
 R7A21    2      B RES_0402-68.1K,1%,1/16W,EMPTY,A   I110 @BASEBOARD_FAB2_LIB.BASEBOARD_FAB2(SCH_1):PAGE219
  R4L4    2      B RES_0603-120.0,1%,1/10W,CHIP,GA    I58 @BASEBOARD_FAB2_LIB.BASEBOARD_FAB2(SCH_1):PAGE220
  C3L6    2      B CAPP_3018-470UF,2.5V,20%,ALUM,A    I75 @BASEBOARD_FAB2_LIB.BASEBOARD_FAB2(SCH_1):PAGE220
 C3L14    2      B CAPP_3018-470UF,2.5V,20%,ALUM,A    I76 @BASEBOARD_FAB2_LIB.BASEBOARD_FAB2(SCH_1):PAGE220
  C6A5    2      B CAPP_3018-470UF,2.5V,20%,ALUM,A    I77 @BASEBOARD_FAB2_LIB.BASEBOARD_FAB2(SCH_1):PAGE220
  C4L5    2      B CAPP_3018-470UF,2.5V,20%,ALUM,A    I78 @BASEBOARD_FAB2_LIB.BASEBOARD_FAB2(SCH_1):PAGE220
  C5M8    2      B CAP_0805-100UF,4V,20%,X5R,6024A    I82 @BASEBOARD_FAB2_LIB.BASEBOARD_FAB2(SCH_1):PAGE220
 C5L14    2      B CAP_0805-100UF,4V,20%,X5R,6024A    I83 @BASEBOARD_FAB2_LIB.BASEBOARD_FAB2(SCH_1):PAGE220
 C5M12    2      B CAP_0805-100UF,4V,20%,X5R,6024A    I88 @BASEBOARD_FAB2_LIB.BASEBOARD_FAB2(SCH_1):PAGE220
  C5L3    2      B CAP_0805-100UF,4V,20%,X5R,6024A    I89 @BASEBOARD_FAB2_LIB.BASEBOARD_FAB2(SCH_1):PAGE220
  C5L2    2      B CAP_0805-100UF,4V,20%,X5R,6024A    I90 @BASEBOARD_FAB2_LIB.BASEBOARD_FAB2(SCH_1):PAGE220
  C5L1    2      B CAP_0805-100UF,4V,20%,X5R,6024A    I91 @BASEBOARD_FAB2_LIB.BASEBOARD_FAB2(SCH_1):PAGE220
 C5A20    2      B CAP_0805-100UF,4V,20%,X5R,6024A    I92 @BASEBOARD_FAB2_LIB.BASEBOARD_FAB2(SCH_1):PAGE220
 C5A10    2      B CAP_0805-100UF,4V,20%,X5R,6024A   I110 @BASEBOARD_FAB2_LIB.BASEBOARD_FAB2(SCH_1):PAGE220
 C7A19    2      B CAPP_2626-270UF,16V,20%,OSCON,A   I175 @BASEBOARD_FAB2_LIB.BASEBOARD_FAB2(SCH_1):PAGE220
  C5P2    2      B CAP_0805LF-22UF,4V,20%,X6S,C95A   I177 @BASEBOARD_FAB2_LIB.BASEBOARD_FAB2(SCH_1):PAGE220
  C5P1    2      B CAP_0805LF-22UF,4V,20%,X6S,C95A   I179 @BASEBOARD_FAB2_LIB.BASEBOARD_FAB2(SCH_1):PAGE220
  C5D9    2      B CAP_0603LF-10UF,4V,20%,X6S,E15A   I180 @BASEBOARD_FAB2_LIB.BASEBOARD_FAB2(SCH_1):PAGE220
  C5D6    2      B CAP_0603LF-10UF,4V,20%,X6S,E15A   I182 @BASEBOARD_FAB2_LIB.BASEBOARD_FAB2(SCH_1):PAGE220
  C5D7    2      B CAP_0603LF-10UF,4V,20%,X6S,E15A   I183 @BASEBOARD_FAB2_LIB.BASEBOARD_FAB2(SCH_1):PAGE220
  C5D8    2      B CAP_0603LF-10UF,4V,20%,X6S,E15A   I184 @BASEBOARD_FAB2_LIB.BASEBOARD_FAB2(SCH_1):PAGE220
 C5L15    2      B CAP_A_0603V-47UF,4V,20%,X5R,60A   I192 @BASEBOARD_FAB2_LIB.BASEBOARD_FAB2(SCH_1):PAGE220
  C5A5    2      B CAP_A_0603V-47UF,4V,20%,X5R,60A   I193 @BASEBOARD_FAB2_LIB.BASEBOARD_FAB2(SCH_1):PAGE220
  C5B1    2      B CAP_A_0603V-47UF,4V,20%,X5R,60A   I194 @BASEBOARD_FAB2_LIB.BASEBOARD_FAB2(SCH_1):PAGE220
  C5M9    2      B CAP_A_0603V-47UF,4V,20%,X5R,60A   I195 @BASEBOARD_FAB2_LIB.BASEBOARD_FAB2(SCH_1):PAGE220
  C4M5    2      B CAP_A_0603V-47UF,4V,20%,X5R,60A   I196 @BASEBOARD_FAB2_LIB.BASEBOARD_FAB2(SCH_1):PAGE220
  C5B2    2      B CAP_A_0603V-47UF,4V,20%,X5R,60A   I197 @BASEBOARD_FAB2_LIB.BASEBOARD_FAB2(SCH_1):PAGE220
 C5M10    2      B CAP_A_0603V-47UF,4V,20%,X5R,60A   I198 @BASEBOARD_FAB2_LIB.BASEBOARD_FAB2(SCH_1):PAGE220
  C5M3    2      B CAP_A_0603V-47UF,4V,20%,X5R,60A   I199 @BASEBOARD_FAB2_LIB.BASEBOARD_FAB2(SCH_1):PAGE220
 C5M11    2      B CAP_A_0603V-47UF,4V,20%,X5R,60A   I200 @BASEBOARD_FAB2_LIB.BASEBOARD_FAB2(SCH_1):PAGE220
 C5A19    2      B CAP_A_0603V-22.0UF,4V,20%,X6S,A   I203 @BASEBOARD_FAB2_LIB.BASEBOARD_FAB2(SCH_1):PAGE220
 C5A18    2      B CAP_A_0603V-22.0UF,4V,20%,X6S,A   I204 @BASEBOARD_FAB2_LIB.BASEBOARD_FAB2(SCH_1):PAGE220
 C5A17    2      B CAP_A_0603V-22.0UF,4V,20%,X6S,A   I205 @BASEBOARD_FAB2_LIB.BASEBOARD_FAB2(SCH_1):PAGE220
  C5A4    2      B CAP_A_0603V-22.0UF,4V,20%,X6S,A   I206 @BASEBOARD_FAB2_LIB.BASEBOARD_FAB2(SCH_1):PAGE220
 C5A16    2      B CAP_A_0603V-22.0UF,4V,20%,X6S,A   I207 @BASEBOARD_FAB2_LIB.BASEBOARD_FAB2(SCH_1):PAGE220
  C5A9    2      B CAP_A_0603V-22.0UF,4V,20%,X6S,A   I208 @BASEBOARD_FAB2_LIB.BASEBOARD_FAB2(SCH_1):PAGE220
  C5A8    2      B CAP_A_0603V-22.0UF,4V,20%,X6S,A   I209 @BASEBOARD_FAB2_LIB.BASEBOARD_FAB2(SCH_1):PAGE220
  C5A3    2      B CAP_A_0603V-22.0UF,4V,20%,X6S,A   I210 @BASEBOARD_FAB2_LIB.BASEBOARD_FAB2(SCH_1):PAGE220
  C5A7    2      B CAP_A_0603V-22.0UF,4V,20%,X6S,A   I211 @BASEBOARD_FAB2_LIB.BASEBOARD_FAB2(SCH_1):PAGE220
  C5A6    2      B CAP_A_0603V-22.0UF,4V,20%,X6S,A   I212 @BASEBOARD_FAB2_LIB.BASEBOARD_FAB2(SCH_1):PAGE220
 C5A14    2      B CAP_A_0603V-22.0UF,4V,20%,X6S,A   I213 @BASEBOARD_FAB2_LIB.BASEBOARD_FAB2(SCH_1):PAGE220
  C5A2    2      B CAP_A_0603V-22.0UF,4V,20%,X6S,A   I214 @BASEBOARD_FAB2_LIB.BASEBOARD_FAB2(SCH_1):PAGE220
 C5A13    2      B CAP_A_0603V-22.0UF,4V,20%,X6S,A   I215 @BASEBOARD_FAB2_LIB.BASEBOARD_FAB2(SCH_1):PAGE220
 C5A12    2      B CAP_A_0603V-22.0UF,4V,20%,X6S,A   I216 @BASEBOARD_FAB2_LIB.BASEBOARD_FAB2(SCH_1):PAGE220
 C5A15    2      B CAP_A_0603V-22.0UF,4V,20%,X6S,A   I217 @BASEBOARD_FAB2_LIB.BASEBOARD_FAB2(SCH_1):PAGE220
  C5A1    2      B CAP_A_0603V-22.0UF,4V,20%,X6S,A   I219 @BASEBOARD_FAB2_LIB.BASEBOARD_FAB2(SCH_1):PAGE220
 C5A11    2      B CAP_A_0603V-22.0UF,4V,20%,X6S,A   I221 @BASEBOARD_FAB2_LIB.BASEBOARD_FAB2(SCH_1):PAGE220
  C4M2    2      B CAP_A_0603V-22.0UF,4V,20%,X6S,A   I222 @BASEBOARD_FAB2_LIB.BASEBOARD_FAB2(SCH_1):PAGE220
  C5M1    2      B CAP_A_0603V-22.0UF,4V,20%,X6S,A   I223 @BASEBOARD_FAB2_LIB.BASEBOARD_FAB2(SCH_1):PAGE220
  C5M2    2      B CAP_A_0603V-22.0UF,4V,20%,X6S,A   I224 @BASEBOARD_FAB2_LIB.BASEBOARD_FAB2(SCH_1):PAGE220
  C5M4    2      B CAP_A_0603V-22.0UF,4V,20%,X6S,A   I225 @BASEBOARD_FAB2_LIB.BASEBOARD_FAB2(SCH_1):PAGE220
  C5M5    2      B CAP_A_0603V-22.0UF,4V,20%,X6S,A   I226 @BASEBOARD_FAB2_LIB.BASEBOARD_FAB2(SCH_1):PAGE220
  C5M6    2      B CAP_A_0603V-22.0UF,4V,20%,X6S,A   I227 @BASEBOARD_FAB2_LIB.BASEBOARD_FAB2(SCH_1):PAGE220
  C5M7    2      B CAP_A_0603V-22.0UF,4V,20%,X6S,A   I228 @BASEBOARD_FAB2_LIB.BASEBOARD_FAB2(SCH_1):PAGE220
 C5L13    2      B CAP_A_0603V-22.0UF,4V,20%,X6S,A   I229 @BASEBOARD_FAB2_LIB.BASEBOARD_FAB2(SCH_1):PAGE220
 C5L12    2      B CAP_A_0603V-22.0UF,4V,20%,X6S,A   I230 @BASEBOARD_FAB2_LIB.BASEBOARD_FAB2(SCH_1):PAGE220
 C5L11    2      B CAP_A_0603V-22.0UF,4V,20%,X6S,A   I231 @BASEBOARD_FAB2_LIB.BASEBOARD_FAB2(SCH_1):PAGE220
 C5L10    2      B CAP_A_0603V-22.0UF,4V,20%,X6S,A   I232 @BASEBOARD_FAB2_LIB.BASEBOARD_FAB2(SCH_1):PAGE220
  C5L9    2      B CAP_A_0603V-22.0UF,4V,20%,X6S,A   I233 @BASEBOARD_FAB2_LIB.BASEBOARD_FAB2(SCH_1):PAGE220
  C5L8    2      B CAP_A_0603V-22.0UF,4V,20%,X6S,A   I234 @BASEBOARD_FAB2_LIB.BASEBOARD_FAB2(SCH_1):PAGE220
  C5L7    2      B CAP_A_0603V-22.0UF,4V,20%,X6S,A   I236 @BASEBOARD_FAB2_LIB.BASEBOARD_FAB2(SCH_1):PAGE220
  C5L6    2      B CAP_A_0603V-22.0UF,4V,20%,X6S,A   I237 @BASEBOARD_FAB2_LIB.BASEBOARD_FAB2(SCH_1):PAGE220
 SH4L1    2      B SHUNT_SH0201-EMPTY,N_A   I240 @BASEBOARD_FAB2_LIB.BASEBOARD_FAB2(SCH_1):PAGE220
 EU4G3    3   AGND MIC5166_DFN-IC,H55101-001     I1 @BASEBOARD_FAB2_LIB.BASEBOARD_FAB2(SCH_1):PAGE221
 EU4G3    8   PGND MIC5166_DFN-IC,H55101-001     I1 @BASEBOARD_FAB2_LIB.BASEBOARD_FAB2(SCH_1):PAGE221
 EU4G3   11  THPAD MIC5166_DFN-IC,H55101-001     I1 @BASEBOARD_FAB2_LIB.BASEBOARD_FAB2(SCH_1):PAGE221
 C4G14    2      B CAP_0402LF-1000PF,50V,10%,X7R,A    I15 @BASEBOARD_FAB2_LIB.BASEBOARD_FAB2(SCH_1):PAGE221
 C4G24    2      B CAP_0805LF-22UF,4V,20%,X6S,C95A    I20 @BASEBOARD_FAB2_LIB.BASEBOARD_FAB2(SCH_1):PAGE221
 C6U16    2      B CAP_0603LF-10UF,4V,20%,X6S,E15A    I22 @BASEBOARD_FAB2_LIB.BASEBOARD_FAB2(SCH_1):PAGE221
 C4G15    2      B CAP_0402-1.0UF,16V,10%,X6S,D97A    I24 @BASEBOARD_FAB2_LIB.BASEBOARD_FAB2(SCH_1):PAGE221
 C6U15    2      B CAP_0603LF-10UF,4V,20%,X6S,E15A    I26 @BASEBOARD_FAB2_LIB.BASEBOARD_FAB2(SCH_1):PAGE221
 C4G16    2      B CAP_0402-1.0UF,16V,10%,X6S,D97A    I34 @BASEBOARD_FAB2_LIB.BASEBOARD_FAB2(SCH_1):PAGE221
 C4G23    2      B CAP_0402LF-1000PF,50V,10%,EMPTA    I39 @BASEBOARD_FAB2_LIB.BASEBOARD_FAB2(SCH_1):PAGE221
 C6U12    2      B CAP_0603-4.7UF,6.3V,10%,X6S,E1A    I49 @BASEBOARD_FAB2_LIB.BASEBOARD_FAB2(SCH_1):PAGE221
 C5U12    2      B CAP_A_0603V-47UF,4V,20%,X5R,60A    I50 @BASEBOARD_FAB2_LIB.BASEBOARD_FAB2(SCH_1):PAGE221
  C5T3    2      B CAP_A_0603V-47UF,4V,20%,X5R,60A    I51 @BASEBOARD_FAB2_LIB.BASEBOARD_FAB2(SCH_1):PAGE221
 C5U16    2      B CAP_A_0603V-47UF,4V,20%,X5R,60A    I52 @BASEBOARD_FAB2_LIB.BASEBOARD_FAB2(SCH_1):PAGE221
 R6U16    1      A RES_0402-51.1,1.0%,1/16W,CHIP,A    I55 @BASEBOARD_FAB2_LIB.BASEBOARD_FAB2(SCH_1):PAGE221
 C4A12    2      B CAP_0402LF-1000PF,50V,10%,X7R,A    I12 @BASEBOARD_FAB2_LIB.BASEBOARD_FAB2(SCH_1):PAGE222
  C4A1    2      B CAP_0805LF-22UF,4V,20%,X6S,C95A    I16 @BASEBOARD_FAB2_LIB.BASEBOARD_FAB2(SCH_1):PAGE222
  C4A9    2      B CAP_0402-1.0UF,16V,10%,X6S,D97A    I21 @BASEBOARD_FAB2_LIB.BASEBOARD_FAB2(SCH_1):PAGE222
  C6L3    2      B CAP_0603LF-10UF,4V,20%,X6S,E15A    I24 @BASEBOARD_FAB2_LIB.BASEBOARD_FAB2(SCH_1):PAGE222
  C6L4    2      B CAP_0603LF-10UF,4V,20%,X6S,E15A    I26 @BASEBOARD_FAB2_LIB.BASEBOARD_FAB2(SCH_1):PAGE222
 C4A10    2      B CAP_0402-1.0UF,16V,10%,X6S,D97A    I28 @BASEBOARD_FAB2_LIB.BASEBOARD_FAB2(SCH_1):PAGE222
 EU4A1    3   AGND MIC5166_DFN-IC,H55101-001    I31 @BASEBOARD_FAB2_LIB.BASEBOARD_FAB2(SCH_1):PAGE222
 EU4A1    8   PGND MIC5166_DFN-IC,H55101-001    I31 @BASEBOARD_FAB2_LIB.BASEBOARD_FAB2(SCH_1):PAGE222
 EU4A1   11  THPAD MIC5166_DFN-IC,H55101-001    I31 @BASEBOARD_FAB2_LIB.BASEBOARD_FAB2(SCH_1):PAGE222
  C4A2    2      B CAP_0402LF-1000PF,50V,10%,EMPTA    I40 @BASEBOARD_FAB2_LIB.BASEBOARD_FAB2(SCH_1):PAGE222
 C4A11    2      B CAP_0603-4.7UF,6.3V,10%,X6S,E1A    I46 @BASEBOARD_FAB2_LIB.BASEBOARD_FAB2(SCH_1):PAGE222
  C5L4    2      B CAP_A_0603V-47UF,4V,20%,X5R,60A    I47 @BASEBOARD_FAB2_LIB.BASEBOARD_FAB2(SCH_1):PAGE222
 C5M13    2      B CAP_A_0603V-47UF,4V,20%,X5R,60A    I48 @BASEBOARD_FAB2_LIB.BASEBOARD_FAB2(SCH_1):PAGE222
  C5L5    2      B CAP_A_0603V-47UF,4V,20%,X5R,60A    I49 @BASEBOARD_FAB2_LIB.BASEBOARD_FAB2(SCH_1):PAGE222
  R4A1    1      A RES_0402-51.1,1.0%,1/16W,CHIP,A    I52 @BASEBOARD_FAB2_LIB.BASEBOARD_FAB2(SCH_1):PAGE222
 C1G27    2      B CAP_A_0402V-1.0UF,6.3V,10%,X6SA    I25 @BASEBOARD_FAB2_LIB.BASEBOARD_FAB2(SCH_1):PAGE223
 C1G25    2      B CAP_A_0402V-0.1UF,16V,10%,X7R,A    I27 @BASEBOARD_FAB2_LIB.BASEBOARD_FAB2(SCH_1):PAGE223
 C1G24    2      B CAP_0402LF-220PF,50V,10%,X7R,AA    I36 @BASEBOARD_FAB2_LIB.BASEBOARD_FAB2(SCH_1):PAGE223
 C1G23    2      B CAP_A_0402V-1.0UF,6.3V,10%,X6SA    I41 @BASEBOARD_FAB2_LIB.BASEBOARD_FAB2(SCH_1):PAGE223
 C1G22    2      B CAP_A_0402V-0.1UF,16V,10%,X7R,A    I44 @BASEBOARD_FAB2_LIB.BASEBOARD_FAB2(SCH_1):PAGE223
 R1G24    2      B RES_0402-1.5K,1%,1/16W,CHIP,G2A    I58 @BASEBOARD_FAB2_LIB.BASEBOARD_FAB2(SCH_1):PAGE223
 C1G26    2      B CAP_0402LF-1000PF,50V,10%,X7R,A    I59 @BASEBOARD_FAB2_LIB.BASEBOARD_FAB2(SCH_1):PAGE223
 R1G23    2      B RES_0402-4.02K,1%,1/16W,CHIP,GA    I77 @BASEBOARD_FAB2_LIB.BASEBOARD_FAB2(SCH_1):PAGE223
 R1G22    2      B RES_0402-5.36K,1.0%,1/16W,CHIPA    I78 @BASEBOARD_FAB2_LIB.BASEBOARD_FAB2(SCH_1):PAGE223
 C1G21    2      B CAP_0402LF-1000PF,50V,10%,X7R,A    I80 @BASEBOARD_FAB2_LIB.BASEBOARD_FAB2(SCH_1):PAGE223
 EU1G2   32 BISEN1 PXM1310B_QFN-IC,H89186-001    I90 @BASEBOARD_FAB2_LIB.BASEBOARD_FAB2(SCH_1):PAGE223
 EU1G2   27    GND PXM1310B_QFN-IC,H89186-001    I90 @BASEBOARD_FAB2_LIB.BASEBOARD_FAB2(SCH_1):PAGE223
 EU1G2   41  THPAD PXM1310B_QFN-IC,H89186-001    I90 @BASEBOARD_FAB2_LIB.BASEBOARD_FAB2(SCH_1):PAGE223
 C9U12    2      B CAP_A_0402V-0.1UF,16V,10%,X7R,A    I92 @BASEBOARD_FAB2_LIB.BASEBOARD_FAB2(SCH_1):PAGE223
 C1G17    2      B CAP_0805LF-22UF,4V,20%,X6S,C95A     I6 @BASEBOARD_FAB2_LIB.BASEBOARD_FAB2(SCH_1):PAGE224
  C9U6    2      B CAP_0805-10UF,16V,10%,X6S,C953A    I45 @BASEBOARD_FAB2_LIB.BASEBOARD_FAB2(SCH_1):PAGE224
  C9U4    2      B CAP_0805-10UF,16V,10%,X6S,C953A    I46 @BASEBOARD_FAB2_LIB.BASEBOARD_FAB2(SCH_1):PAGE224
  C9T4    2      B CAP_0805-10UF,16V,10%,X6S,C953A    I47 @BASEBOARD_FAB2_LIB.BASEBOARD_FAB2(SCH_1):PAGE224
 C1F27    2      B CAP_0402-1.0UF,16V,10%,X6S,D97A    I48 @BASEBOARD_FAB2_LIB.BASEBOARD_FAB2(SCH_1):PAGE224
  C1G6    2      B CAP_0402-1.0UF,16V,10%,X6S,D97A    I50 @BASEBOARD_FAB2_LIB.BASEBOARD_FAB2(SCH_1):PAGE224
 C1G14    2      B CAP_A_0402V-0.1UF,16V,10%,X7R,A    I51 @BASEBOARD_FAB2_LIB.BASEBOARD_FAB2(SCH_1):PAGE224
  C1G4    2      B CAP_A_0402V-1.0UF,6.3V,10%,X6SA    I53 @BASEBOARD_FAB2_LIB.BASEBOARD_FAB2(SCH_1):PAGE224
  C1G5    2      B CAP_0402-0.22UF,16V,10%,X7R,A3A    I54 @BASEBOARD_FAB2_LIB.BASEBOARD_FAB2(SCH_1):PAGE224
 C1G20    2      B CAP_0805LF-22UF,4V,20%,X6S,C95A    I68 @BASEBOARD_FAB2_LIB.BASEBOARD_FAB2(SCH_1):PAGE224
 C1G29    2      B CAP_0402-0.22UF,16V,10%,X7R,A3A    I72 @BASEBOARD_FAB2_LIB.BASEBOARD_FAB2(SCH_1):PAGE224
 C1F21    2      B CAP_A_0402V-1.0UF,6.3V,10%,X6SA    I73 @BASEBOARD_FAB2_LIB.BASEBOARD_FAB2(SCH_1):PAGE224
 C1G28    2      B CAP_0402-1.0UF,16V,10%,X6S,D97A    I77 @BASEBOARD_FAB2_LIB.BASEBOARD_FAB2(SCH_1):PAGE224
 C1F28    2      B CAP_A_0402V-0.1UF,16V,10%,X7R,A    I78 @BASEBOARD_FAB2_LIB.BASEBOARD_FAB2(SCH_1):PAGE224
 C1G13    2      B CAP_0402-1.0UF,16V,10%,X6S,D97A    I79 @BASEBOARD_FAB2_LIB.BASEBOARD_FAB2(SCH_1):PAGE224
  C9U3    2      B CAP_0805-10UF,16V,10%,X6S,C953A    I80 @BASEBOARD_FAB2_LIB.BASEBOARD_FAB2(SCH_1):PAGE224
  C9T6    2      B CAP_0805-10UF,16V,10%,X6S,C953A    I81 @BASEBOARD_FAB2_LIB.BASEBOARD_FAB2(SCH_1):PAGE224
  C9T9    2      B CAP_0805-10UF,16V,10%,X6S,C953A    I84 @BASEBOARD_FAB2_LIB.BASEBOARD_FAB2(SCH_1):PAGE224
 EU1G1    2   LGND IR354XX_SM-IR35411,IC,H73688-0A   I110 @BASEBOARD_FAB2_LIB.BASEBOARD_FAB2(SCH_1):PAGE224
 EU1G1    5 PGND<0> IR354XX_SM-IR35411,IC,H73688-0A   I110 @BASEBOARD_FAB2_LIB.BASEBOARD_FAB2(SCH_1):PAGE224
 EU1G1    7 PGND<1> IR354XX_SM-IR35411,IC,H73688-0A   I110 @BASEBOARD_FAB2_LIB.BASEBOARD_FAB2(SCH_1):PAGE224
 EU1G1   40 PGND<2> IR354XX_SM-IR35411,IC,H73688-0A   I110 @BASEBOARD_FAB2_LIB.BASEBOARD_FAB2(SCH_1):PAGE224
 EU1F1    2   LGND IR354XX_SM-IR35411,IC,H73688-0A   I111 @BASEBOARD_FAB2_LIB.BASEBOARD_FAB2(SCH_1):PAGE224
 EU1F1    5 PGND<0> IR354XX_SM-IR35411,IC,H73688-0A   I111 @BASEBOARD_FAB2_LIB.BASEBOARD_FAB2(SCH_1):PAGE224
 EU1F1    7 PGND<1> IR354XX_SM-IR35411,IC,H73688-0A   I111 @BASEBOARD_FAB2_LIB.BASEBOARD_FAB2(SCH_1):PAGE224
 EU1F1   40 PGND<2> IR354XX_SM-IR35411,IC,H73688-0A   I111 @BASEBOARD_FAB2_LIB.BASEBOARD_FAB2(SCH_1):PAGE224
 R1G26    2      B RES_0402-68.1K,1%,1/16W,EMPTY,A   I112 @BASEBOARD_FAB2_LIB.BASEBOARD_FAB2(SCH_1):PAGE224
 R1G25    2      B RES_0402-68.1K,1%,1/16W,EMPTY,A   I114 @BASEBOARD_FAB2_LIB.BASEBOARD_FAB2(SCH_1):PAGE224
 R1G20    2      B RES_0603-120.0,1%,1/10W,CHIP,GA    I58 @BASEBOARD_FAB2_LIB.BASEBOARD_FAB2(SCH_1):PAGE225
  C9T5    2      B CAPP_3018-470UF,2.5V,20%,ALUM,A    I75 @BASEBOARD_FAB2_LIB.BASEBOARD_FAB2(SCH_1):PAGE225
  C9U2    2      B CAPP_3018-470UF,2.5V,20%,ALUM,A    I76 @BASEBOARD_FAB2_LIB.BASEBOARD_FAB2(SCH_1):PAGE225
  C9U9    2      B CAPP_3018-470UF,2.5V,20%,ALUM,A    I77 @BASEBOARD_FAB2_LIB.BASEBOARD_FAB2(SCH_1):PAGE225
  C9U5    2      B CAPP_3018-470UF,2.5V,20%,ALUM,A    I78 @BASEBOARD_FAB2_LIB.BASEBOARD_FAB2(SCH_1):PAGE225
  C8U1    2      B CAP_0805-100UF,4V,20%,X5R,6024A    I82 @BASEBOARD_FAB2_LIB.BASEBOARD_FAB2(SCH_1):PAGE225
  C8U8    2      B CAP_0805-100UF,4V,20%,X5R,6024A    I83 @BASEBOARD_FAB2_LIB.BASEBOARD_FAB2(SCH_1):PAGE225
 C8U12    2      B CAP_0805-100UF,4V,20%,X5R,6024A    I88 @BASEBOARD_FAB2_LIB.BASEBOARD_FAB2(SCH_1):PAGE225
 C8U11    2      B CAP_0805-100UF,4V,20%,X5R,6024A    I89 @BASEBOARD_FAB2_LIB.BASEBOARD_FAB2(SCH_1):PAGE225
  C7T1    2      B CAP_0805-100UF,4V,20%,X5R,6024A    I90 @BASEBOARD_FAB2_LIB.BASEBOARD_FAB2(SCH_1):PAGE225
  C7U7    2      B CAP_0805-100UF,4V,20%,X5R,6024A    I91 @BASEBOARD_FAB2_LIB.BASEBOARD_FAB2(SCH_1):PAGE225
  C2G7    2      B CAP_0805-100UF,4V,20%,X5R,6024A    I92 @BASEBOARD_FAB2_LIB.BASEBOARD_FAB2(SCH_1):PAGE225
 C2G16    2      B CAP_0805-100UF,4V,20%,X5R,6024A   I110 @BASEBOARD_FAB2_LIB.BASEBOARD_FAB2(SCH_1):PAGE225
 C8P31    2      B CAP_0805LF-22UF,4V,20%,X6S,C95A   I178 @BASEBOARD_FAB2_LIB.BASEBOARD_FAB2(SCH_1):PAGE225
 C2D43    2      B CAP_0603LF-10UF,4V,20%,X6S,E15A   I179 @BASEBOARD_FAB2_LIB.BASEBOARD_FAB2(SCH_1):PAGE225
 C2D41    2      B CAP_0603LF-10UF,4V,20%,X6S,E15A   I180 @BASEBOARD_FAB2_LIB.BASEBOARD_FAB2(SCH_1):PAGE225
 C2D44    2      B CAP_0603LF-10UF,4V,20%,X6S,E15A   I181 @BASEBOARD_FAB2_LIB.BASEBOARD_FAB2(SCH_1):PAGE225
 C2D42    2      B CAP_0603LF-10UF,4V,20%,X6S,E15A   I183 @BASEBOARD_FAB2_LIB.BASEBOARD_FAB2(SCH_1):PAGE225
 C8P30    2      B CAP_0805LF-22UF,4V,20%,X6S,C95A   I184 @BASEBOARD_FAB2_LIB.BASEBOARD_FAB2(SCH_1):PAGE225
 C1G15    2      B CAP_1210-47UF,16V,20%,X6S,D384A   I192 @BASEBOARD_FAB2_LIB.BASEBOARD_FAB2(SCH_1):PAGE225
 C1G12    2      B CAP_1210-47UF,16V,20%,X6S,D384A   I193 @BASEBOARD_FAB2_LIB.BASEBOARD_FAB2(SCH_1):PAGE225
  C1G2    2      B CAP_1210-47UF,16V,20%,X6S,D384A   I194 @BASEBOARD_FAB2_LIB.BASEBOARD_FAB2(SCH_1):PAGE225
  C1G7    2      B CAP_1210-47UF,16V,20%,X6S,D384A   I195 @BASEBOARD_FAB2_LIB.BASEBOARD_FAB2(SCH_1):PAGE225
  C8T4    2      B CAP_A_0603V-47UF,4V,20%,X5R,60A   I196 @BASEBOARD_FAB2_LIB.BASEBOARD_FAB2(SCH_1):PAGE225
  C2G8    2      B CAP_A_0603V-47UF,4V,20%,X5R,60A   I197 @BASEBOARD_FAB2_LIB.BASEBOARD_FAB2(SCH_1):PAGE225
  C8T2    2      B CAP_A_0603V-47UF,4V,20%,X5R,60A   I198 @BASEBOARD_FAB2_LIB.BASEBOARD_FAB2(SCH_1):PAGE225
 C8U13    2      B CAP_A_0603V-47UF,4V,20%,X5R,60A   I199 @BASEBOARD_FAB2_LIB.BASEBOARD_FAB2(SCH_1):PAGE225
 C2G15    2      B CAP_A_0603V-47UF,4V,20%,X5R,60A   I200 @BASEBOARD_FAB2_LIB.BASEBOARD_FAB2(SCH_1):PAGE225
  C2F1    2      B CAP_A_0603V-47UF,4V,20%,X5R,60A   I201 @BASEBOARD_FAB2_LIB.BASEBOARD_FAB2(SCH_1):PAGE225
  C8T1    2      B CAP_A_0603V-47UF,4V,20%,X5R,60A   I202 @BASEBOARD_FAB2_LIB.BASEBOARD_FAB2(SCH_1):PAGE225
  C8U9    2      B CAP_A_0603V-47UF,4V,20%,X5R,60A   I203 @BASEBOARD_FAB2_LIB.BASEBOARD_FAB2(SCH_1):PAGE225
 C8T11    2      B CAP_A_0603V-47UF,4V,20%,X5R,60A   I204 @BASEBOARD_FAB2_LIB.BASEBOARD_FAB2(SCH_1):PAGE225
  C3G6    2      B CAP_A_0603V-22.0UF,4V,20%,X6S,A   I207 @BASEBOARD_FAB2_LIB.BASEBOARD_FAB2(SCH_1):PAGE225
  C3G5    2      B CAP_A_0603V-22.0UF,4V,20%,X6S,A   I208 @BASEBOARD_FAB2_LIB.BASEBOARD_FAB2(SCH_1):PAGE225
 C2G14    2      B CAP_A_0603V-22.0UF,4V,20%,X6S,A   I209 @BASEBOARD_FAB2_LIB.BASEBOARD_FAB2(SCH_1):PAGE225
 C2G13    2      B CAP_A_0603V-22.0UF,4V,20%,X6S,A   I210 @BASEBOARD_FAB2_LIB.BASEBOARD_FAB2(SCH_1):PAGE225
  C3G2    2      B CAP_A_0603V-22.0UF,4V,20%,X6S,A   I211 @BASEBOARD_FAB2_LIB.BASEBOARD_FAB2(SCH_1):PAGE225
  C3G1    2      B CAP_A_0603V-22.0UF,4V,20%,X6S,A   I212 @BASEBOARD_FAB2_LIB.BASEBOARD_FAB2(SCH_1):PAGE225
  C2G6    2      B CAP_A_0603V-22.0UF,4V,20%,X6S,A   I213 @BASEBOARD_FAB2_LIB.BASEBOARD_FAB2(SCH_1):PAGE225
  C2G5    2      B CAP_A_0603V-22.0UF,4V,20%,X6S,A   I214 @BASEBOARD_FAB2_LIB.BASEBOARD_FAB2(SCH_1):PAGE225
  C2G4    2      B CAP_A_0603V-22.0UF,4V,20%,X6S,A   I215 @BASEBOARD_FAB2_LIB.BASEBOARD_FAB2(SCH_1):PAGE225
  C2G3    2      B CAP_A_0603V-22.0UF,4V,20%,X6S,A   I216 @BASEBOARD_FAB2_LIB.BASEBOARD_FAB2(SCH_1):PAGE225
  C2G2    2      B CAP_A_0603V-22.0UF,4V,20%,X6S,A   I217 @BASEBOARD_FAB2_LIB.BASEBOARD_FAB2(SCH_1):PAGE225
  C2G9    2      B CAP_A_0603V-22.0UF,4V,20%,X6S,A   I218 @BASEBOARD_FAB2_LIB.BASEBOARD_FAB2(SCH_1):PAGE225
  C2G1    2      B CAP_A_0603V-22.0UF,4V,20%,X6S,A   I219 @BASEBOARD_FAB2_LIB.BASEBOARD_FAB2(SCH_1):PAGE225
 C2G12    2      B CAP_A_0603V-22.0UF,4V,20%,X6S,A   I220 @BASEBOARD_FAB2_LIB.BASEBOARD_FAB2(SCH_1):PAGE225
 C2G11    2      B CAP_A_0603V-22.0UF,4V,20%,X6S,A   I221 @BASEBOARD_FAB2_LIB.BASEBOARD_FAB2(SCH_1):PAGE225
 C2G10    2      B CAP_A_0603V-22.0UF,4V,20%,X6S,A   I223 @BASEBOARD_FAB2_LIB.BASEBOARD_FAB2(SCH_1):PAGE225
  C8U4    2      B CAP_A_0603V-22.0UF,4V,20%,X6S,A   I225 @BASEBOARD_FAB2_LIB.BASEBOARD_FAB2(SCH_1):PAGE225
 C8T10    2      B CAP_A_0603V-22.0UF,4V,20%,X6S,A   I226 @BASEBOARD_FAB2_LIB.BASEBOARD_FAB2(SCH_1):PAGE225
  C8T9    2      B CAP_A_0603V-22.0UF,4V,20%,X6S,A   I227 @BASEBOARD_FAB2_LIB.BASEBOARD_FAB2(SCH_1):PAGE225
  C8U5    2      B CAP_A_0603V-22.0UF,4V,20%,X6S,A   I228 @BASEBOARD_FAB2_LIB.BASEBOARD_FAB2(SCH_1):PAGE225
  C8T8    2      B CAP_A_0603V-22.0UF,4V,20%,X6S,A   I229 @BASEBOARD_FAB2_LIB.BASEBOARD_FAB2(SCH_1):PAGE225
  C8T7    2      B CAP_A_0603V-22.0UF,4V,20%,X6S,A   I230 @BASEBOARD_FAB2_LIB.BASEBOARD_FAB2(SCH_1):PAGE225
  C8T6    2      B CAP_A_0603V-22.0UF,4V,20%,X6S,A   I231 @BASEBOARD_FAB2_LIB.BASEBOARD_FAB2(SCH_1):PAGE225
  C8U6    2      B CAP_A_0603V-22.0UF,4V,20%,X6S,A   I232 @BASEBOARD_FAB2_LIB.BASEBOARD_FAB2(SCH_1):PAGE225
  C8T5    2      B CAP_A_0603V-22.0UF,4V,20%,X6S,A   I233 @BASEBOARD_FAB2_LIB.BASEBOARD_FAB2(SCH_1):PAGE225
  C7T5    2      B CAP_A_0603V-22.0UF,4V,20%,X6S,A   I234 @BASEBOARD_FAB2_LIB.BASEBOARD_FAB2(SCH_1):PAGE225
  C7T4    2      B CAP_A_0603V-22.0UF,4V,20%,X6S,A   I235 @BASEBOARD_FAB2_LIB.BASEBOARD_FAB2(SCH_1):PAGE225
  C8U3    2      B CAP_A_0603V-22.0UF,4V,20%,X6S,A   I236 @BASEBOARD_FAB2_LIB.BASEBOARD_FAB2(SCH_1):PAGE225
  C7U1    2      B CAP_A_0603V-22.0UF,4V,20%,X6S,A   I237 @BASEBOARD_FAB2_LIB.BASEBOARD_FAB2(SCH_1):PAGE225
  C7U2    2      B CAP_A_0603V-22.0UF,4V,20%,X6S,A   I238 @BASEBOARD_FAB2_LIB.BASEBOARD_FAB2(SCH_1):PAGE225
  C8U2    2      B CAP_A_0603V-22.0UF,4V,20%,X6S,A   I239 @BASEBOARD_FAB2_LIB.BASEBOARD_FAB2(SCH_1):PAGE225
  C8U7    2      B CAP_A_0603V-22.0UF,4V,20%,X6S,A   I241 @BASEBOARD_FAB2_LIB.BASEBOARD_FAB2(SCH_1):PAGE225
 SH7U2    2      B SHUNT_SH0201-EMPTY,N_A   I244 @BASEBOARD_FAB2_LIB.BASEBOARD_FAB2(SCH_1):PAGE225
  C1B6    2      B CAP_A_0402V-1.0UF,6.3V,10%,X6SA    I25 @BASEBOARD_FAB2_LIB.BASEBOARD_FAB2(SCH_1):PAGE226
  C1B5    2      B CAP_A_0402V-0.1UF,16V,10%,X7R,A    I27 @BASEBOARD_FAB2_LIB.BASEBOARD_FAB2(SCH_1):PAGE226
 C1B11    2      B CAP_0402LF-220PF,50V,10%,X7R,AA    I36 @BASEBOARD_FAB2_LIB.BASEBOARD_FAB2(SCH_1):PAGE226
  C1B3    2      B CAP_A_0402V-1.0UF,6.3V,10%,X6SA    I41 @BASEBOARD_FAB2_LIB.BASEBOARD_FAB2(SCH_1):PAGE226
  C1B2    2      B CAP_A_0402V-0.1UF,16V,10%,X7R,A    I44 @BASEBOARD_FAB2_LIB.BASEBOARD_FAB2(SCH_1):PAGE226
  R1B9    2      B RES_0402-1.5K,1%,1/16W,CHIP,G2A    I58 @BASEBOARD_FAB2_LIB.BASEBOARD_FAB2(SCH_1):PAGE226
  C1B8    2      B CAP_0402LF-1000PF,50V,10%,X7R,A    I59 @BASEBOARD_FAB2_LIB.BASEBOARD_FAB2(SCH_1):PAGE226
 R1B15    2      B RES_0402-5.36K,1.0%,1/16W,CHIPA    I77 @BASEBOARD_FAB2_LIB.BASEBOARD_FAB2(SCH_1):PAGE226
 R1B12    2      B RES_0402-3.16K,1%,1/16W,CHIP,GA    I78 @BASEBOARD_FAB2_LIB.BASEBOARD_FAB2(SCH_1):PAGE226
  C1B4    2      B CAP_0402LF-1000PF,50V,10%,X7R,A    I80 @BASEBOARD_FAB2_LIB.BASEBOARD_FAB2(SCH_1):PAGE226
 EU1B1   32 BISEN1 PXM1310B_QFN-IC,H89186-001    I90 @BASEBOARD_FAB2_LIB.BASEBOARD_FAB2(SCH_1):PAGE226
 EU1B1   27    GND PXM1310B_QFN-IC,H89186-001    I90 @BASEBOARD_FAB2_LIB.BASEBOARD_FAB2(SCH_1):PAGE226
 EU1B1   41  THPAD PXM1310B_QFN-IC,H89186-001    I90 @BASEBOARD_FAB2_LIB.BASEBOARD_FAB2(SCH_1):PAGE226
 C9M11    2      B CAP_A_0402V-0.1UF,16V,10%,X7R,A    I92 @BASEBOARD_FAB2_LIB.BASEBOARD_FAB2(SCH_1):PAGE226
 C1A12    2      B CAP_0805LF-22UF,4V,20%,X6S,C95A     I6 @BASEBOARD_FAB2_LIB.BASEBOARD_FAB2(SCH_1):PAGE227
 C9L11    2      B CAP_0805-10UF,16V,10%,X6S,C953A    I45 @BASEBOARD_FAB2_LIB.BASEBOARD_FAB2(SCH_1):PAGE227
 C9L10    2      B CAP_0805-10UF,16V,10%,X6S,C953A    I46 @BASEBOARD_FAB2_LIB.BASEBOARD_FAB2(SCH_1):PAGE227
  C9L6    2      B CAP_0805-10UF,16V,10%,X6S,C953A    I47 @BASEBOARD_FAB2_LIB.BASEBOARD_FAB2(SCH_1):PAGE227
 C1A19    2      B CAP_0402-1.0UF,16V,10%,X6S,D97A    I48 @BASEBOARD_FAB2_LIB.BASEBOARD_FAB2(SCH_1):PAGE227
 C1B20    2      B CAP_0402-1.0UF,16V,10%,X6S,D97A    I50 @BASEBOARD_FAB2_LIB.BASEBOARD_FAB2(SCH_1):PAGE227
 C1A10    2      B CAP_A_0402V-0.1UF,16V,10%,X7R,A    I51 @BASEBOARD_FAB2_LIB.BASEBOARD_FAB2(SCH_1):PAGE227
  C1A2    2      B CAP_A_0402V-1.0UF,6.3V,10%,X6SA    I53 @BASEBOARD_FAB2_LIB.BASEBOARD_FAB2(SCH_1):PAGE227
 C1B21    2      B CAP_0402-0.22UF,16V,10%,X7R,A3A    I54 @BASEBOARD_FAB2_LIB.BASEBOARD_FAB2(SCH_1):PAGE227
  C1A1    2      B CAP_0805LF-22UF,4V,20%,X6S,C95A    I68 @BASEBOARD_FAB2_LIB.BASEBOARD_FAB2(SCH_1):PAGE227
 C1A13    2      B CAP_0402-0.22UF,16V,10%,X7R,A3A    I72 @BASEBOARD_FAB2_LIB.BASEBOARD_FAB2(SCH_1):PAGE227
 C1A11    2      B CAP_A_0402V-1.0UF,6.3V,10%,X6SA    I73 @BASEBOARD_FAB2_LIB.BASEBOARD_FAB2(SCH_1):PAGE227
  C1A6    2      B CAP_0402-1.0UF,16V,10%,X6S,D97A    I77 @BASEBOARD_FAB2_LIB.BASEBOARD_FAB2(SCH_1):PAGE227
 C1A20    2      B CAP_A_0402V-0.1UF,16V,10%,X7R,A    I78 @BASEBOARD_FAB2_LIB.BASEBOARD_FAB2(SCH_1):PAGE227
  C1A9    2      B CAP_0402-1.0UF,16V,10%,X6S,D97A    I79 @BASEBOARD_FAB2_LIB.BASEBOARD_FAB2(SCH_1):PAGE227
  C9L5    2      B CAP_0805-10UF,16V,10%,X6S,C953A    I80 @BASEBOARD_FAB2_LIB.BASEBOARD_FAB2(SCH_1):PAGE227
 C9L13    2      B CAP_0805-10UF,16V,10%,X6S,C953A    I81 @BASEBOARD_FAB2_LIB.BASEBOARD_FAB2(SCH_1):PAGE227
 C9L14    2      B CAP_0805-10UF,16V,10%,X6S,C953A    I84 @BASEBOARD_FAB2_LIB.BASEBOARD_FAB2(SCH_1):PAGE227
 EU1A2    2   LGND IR354XX_SM-IR35411,IC,H73688-0A   I101 @BASEBOARD_FAB2_LIB.BASEBOARD_FAB2(SCH_1):PAGE227
 EU1A2    5 PGND<0> IR354XX_SM-IR35411,IC,H73688-0A   I101 @BASEBOARD_FAB2_LIB.BASEBOARD_FAB2(SCH_1):PAGE227
 EU1A2    7 PGND<1> IR354XX_SM-IR35411,IC,H73688-0A   I101 @BASEBOARD_FAB2_LIB.BASEBOARD_FAB2(SCH_1):PAGE227
 EU1A2   40 PGND<2> IR354XX_SM-IR35411,IC,H73688-0A   I101 @BASEBOARD_FAB2_LIB.BASEBOARD_FAB2(SCH_1):PAGE227
 EU1A1    2   LGND IR354XX_SM-IR35411,IC,H73688-0A   I102 @BASEBOARD_FAB2_LIB.BASEBOARD_FAB2(SCH_1):PAGE227
 EU1A1    5 PGND<0> IR354XX_SM-IR35411,IC,H73688-0A   I102 @BASEBOARD_FAB2_LIB.BASEBOARD_FAB2(SCH_1):PAGE227
 EU1A1    7 PGND<1> IR354XX_SM-IR35411,IC,H73688-0A   I102 @BASEBOARD_FAB2_LIB.BASEBOARD_FAB2(SCH_1):PAGE227
 EU1A1   40 PGND<2> IR354XX_SM-IR35411,IC,H73688-0A   I102 @BASEBOARD_FAB2_LIB.BASEBOARD_FAB2(SCH_1):PAGE227
  R1A3    2      B RES_0402-68.1K,1%,1/16W,EMPTY,A   I103 @BASEBOARD_FAB2_LIB.BASEBOARD_FAB2(SCH_1):PAGE227
  R1A2    2      B RES_0402-68.1K,1%,1/16W,EMPTY,A   I105 @BASEBOARD_FAB2_LIB.BASEBOARD_FAB2(SCH_1):PAGE227
  R1A1    2      B RES_0603-120.0,1%,1/10W,CHIP,GA    I58 @BASEBOARD_FAB2_LIB.BASEBOARD_FAB2(SCH_1):PAGE228
  C9L9    2      B CAPP_3018-470UF,2.5V,20%,ALUM,A    I75 @BASEBOARD_FAB2_LIB.BASEBOARD_FAB2(SCH_1):PAGE228
 C9L12    2      B CAPP_3018-470UF,2.5V,20%,ALUM,A    I76 @BASEBOARD_FAB2_LIB.BASEBOARD_FAB2(SCH_1):PAGE228
  C9L4    2      B CAPP_3018-470UF,2.5V,20%,ALUM,A    I77 @BASEBOARD_FAB2_LIB.BASEBOARD_FAB2(SCH_1):PAGE228
  C9L2    2      B CAPP_3018-470UF,2.5V,20%,ALUM,A    I78 @BASEBOARD_FAB2_LIB.BASEBOARD_FAB2(SCH_1):PAGE228
  C2A8    2      B CAP_0805-100UF,4V,20%,X5R,6024A    I82 @BASEBOARD_FAB2_LIB.BASEBOARD_FAB2(SCH_1):PAGE228
  C8L2    2      B CAP_0805-100UF,4V,20%,X5R,6024A    I83 @BASEBOARD_FAB2_LIB.BASEBOARD_FAB2(SCH_1):PAGE228
 C8L11    2      B CAP_0805-100UF,4V,20%,X5R,6024A    I88 @BASEBOARD_FAB2_LIB.BASEBOARD_FAB2(SCH_1):PAGE228
 C2A16    2      B CAP_0805-100UF,4V,20%,X5R,6024A    I89 @BASEBOARD_FAB2_LIB.BASEBOARD_FAB2(SCH_1):PAGE228
  C8M7    2      B CAP_0805-100UF,4V,20%,X5R,6024A    I90 @BASEBOARD_FAB2_LIB.BASEBOARD_FAB2(SCH_1):PAGE228
 C8M11    2      B CAP_0805-100UF,4V,20%,X5R,6024A    I91 @BASEBOARD_FAB2_LIB.BASEBOARD_FAB2(SCH_1):PAGE228
  C7L1    2      B CAP_0805-100UF,4V,20%,X5R,6024A    I92 @BASEBOARD_FAB2_LIB.BASEBOARD_FAB2(SCH_1):PAGE228
  C8L1    2      B CAP_0805-100UF,4V,20%,X5R,6024A   I110 @BASEBOARD_FAB2_LIB.BASEBOARD_FAB2(SCH_1):PAGE228
 C1B10    2      B CAPP_2626-270UF,16V,20%,OSCON,A   I175 @BASEBOARD_FAB2_LIB.BASEBOARD_FAB2(SCH_1):PAGE228
  C8P2    2      B CAP_0805LF-22UF,4V,20%,X6S,C95A   I183 @BASEBOARD_FAB2_LIB.BASEBOARD_FAB2(SCH_1):PAGE228
  C8P1    2      B CAP_0805LF-22UF,4V,20%,X6S,C95A   I185 @BASEBOARD_FAB2_LIB.BASEBOARD_FAB2(SCH_1):PAGE228
  C2D7    2      B CAP_0603LF-10UF,4V,20%,X6S,E15A   I186 @BASEBOARD_FAB2_LIB.BASEBOARD_FAB2(SCH_1):PAGE228
  C2D4    2      B CAP_0603LF-10UF,4V,20%,X6S,E15A   I187 @BASEBOARD_FAB2_LIB.BASEBOARD_FAB2(SCH_1):PAGE228
  C2D5    2      B CAP_0603LF-10UF,4V,20%,X6S,E15A   I188 @BASEBOARD_FAB2_LIB.BASEBOARD_FAB2(SCH_1):PAGE228
  C2D6    2      B CAP_0603LF-10UF,4V,20%,X6S,E15A   I190 @BASEBOARD_FAB2_LIB.BASEBOARD_FAB2(SCH_1):PAGE228
  C8M8    2      B CAP_A_0603V-47UF,4V,20%,X5R,60A   I198 @BASEBOARD_FAB2_LIB.BASEBOARD_FAB2(SCH_1):PAGE228
  C2A5    2      B CAP_A_0603V-47UF,4V,20%,X5R,60A   I199 @BASEBOARD_FAB2_LIB.BASEBOARD_FAB2(SCH_1):PAGE228
  C2B1    2      B CAP_A_0603V-47UF,4V,20%,X5R,60A   I200 @BASEBOARD_FAB2_LIB.BASEBOARD_FAB2(SCH_1):PAGE228
 C8L12    2      B CAP_A_0603V-47UF,4V,20%,X5R,60A   I201 @BASEBOARD_FAB2_LIB.BASEBOARD_FAB2(SCH_1):PAGE228
  C7M5    2      B CAP_A_0603V-47UF,4V,20%,X5R,60A   I202 @BASEBOARD_FAB2_LIB.BASEBOARD_FAB2(SCH_1):PAGE228
 C8M10    2      B CAP_A_0603V-47UF,4V,20%,X5R,60A   I203 @BASEBOARD_FAB2_LIB.BASEBOARD_FAB2(SCH_1):PAGE228
  C2B2    2      B CAP_A_0603V-47UF,4V,20%,X5R,60A   I204 @BASEBOARD_FAB2_LIB.BASEBOARD_FAB2(SCH_1):PAGE228
  C8M9    2      B CAP_A_0603V-47UF,4V,20%,X5R,60A   I205 @BASEBOARD_FAB2_LIB.BASEBOARD_FAB2(SCH_1):PAGE228
  C8M2    2      B CAP_A_0603V-47UF,4V,20%,X5R,60A   I206 @BASEBOARD_FAB2_LIB.BASEBOARD_FAB2(SCH_1):PAGE228
  C2A2    2      B CAP_A_0603V-22.0UF,4V,20%,X6S,A   I209 @BASEBOARD_FAB2_LIB.BASEBOARD_FAB2(SCH_1):PAGE228
  C2A1    2      B CAP_A_0603V-22.0UF,4V,20%,X6S,A   I210 @BASEBOARD_FAB2_LIB.BASEBOARD_FAB2(SCH_1):PAGE228
 C2A12    2      B CAP_A_0603V-22.0UF,4V,20%,X6S,A   I211 @BASEBOARD_FAB2_LIB.BASEBOARD_FAB2(SCH_1):PAGE228
 C2A13    2      B CAP_A_0603V-22.0UF,4V,20%,X6S,A   I212 @BASEBOARD_FAB2_LIB.BASEBOARD_FAB2(SCH_1):PAGE228
 C2A11    2      B CAP_A_0603V-22.0UF,4V,20%,X6S,A   I213 @BASEBOARD_FAB2_LIB.BASEBOARD_FAB2(SCH_1):PAGE228
 C2A10    2      B CAP_A_0603V-22.0UF,4V,20%,X6S,A   I214 @BASEBOARD_FAB2_LIB.BASEBOARD_FAB2(SCH_1):PAGE228
  C2A9    2      B CAP_A_0603V-22.0UF,4V,20%,X6S,A   I215 @BASEBOARD_FAB2_LIB.BASEBOARD_FAB2(SCH_1):PAGE228
  C3A2    2      B CAP_A_0603V-22.0UF,4V,20%,X6S,A   I216 @BASEBOARD_FAB2_LIB.BASEBOARD_FAB2(SCH_1):PAGE228
  C3A1    2      B CAP_A_0603V-22.0UF,4V,20%,X6S,A   I217 @BASEBOARD_FAB2_LIB.BASEBOARD_FAB2(SCH_1):PAGE228
  C2A7    2      B CAP_A_0603V-22.0UF,4V,20%,X6S,A   I218 @BASEBOARD_FAB2_LIB.BASEBOARD_FAB2(SCH_1):PAGE228
  C2A6    2      B CAP_A_0603V-22.0UF,4V,20%,X6S,A   I219 @BASEBOARD_FAB2_LIB.BASEBOARD_FAB2(SCH_1):PAGE228
 C2A14    2      B CAP_A_0603V-22.0UF,4V,20%,X6S,A   I220 @BASEBOARD_FAB2_LIB.BASEBOARD_FAB2(SCH_1):PAGE228
 C2A15    2      B CAP_A_0603V-22.0UF,4V,20%,X6S,A   I221 @BASEBOARD_FAB2_LIB.BASEBOARD_FAB2(SCH_1):PAGE228
  C3A5    2      B CAP_A_0603V-22.0UF,4V,20%,X6S,A   I222 @BASEBOARD_FAB2_LIB.BASEBOARD_FAB2(SCH_1):PAGE228
  C3A6    2      B CAP_A_0603V-22.0UF,4V,20%,X6S,A   I223 @BASEBOARD_FAB2_LIB.BASEBOARD_FAB2(SCH_1):PAGE228
  C7L5    2      B CAP_A_0603V-22.0UF,4V,20%,X6S,A   I225 @BASEBOARD_FAB2_LIB.BASEBOARD_FAB2(SCH_1):PAGE228
  C8M3    2      B CAP_A_0603V-22.0UF,4V,20%,X6S,A   I227 @BASEBOARD_FAB2_LIB.BASEBOARD_FAB2(SCH_1):PAGE228
  C8M5    2      B CAP_A_0603V-22.0UF,4V,20%,X6S,A   I228 @BASEBOARD_FAB2_LIB.BASEBOARD_FAB2(SCH_1):PAGE228
 C8L10    2      B CAP_A_0603V-22.0UF,4V,20%,X6S,A   I229 @BASEBOARD_FAB2_LIB.BASEBOARD_FAB2(SCH_1):PAGE228
  C2A3    2      B CAP_A_0603V-22.0UF,4V,20%,X6S,A   I230 @BASEBOARD_FAB2_LIB.BASEBOARD_FAB2(SCH_1):PAGE228
  C7M1    2      B CAP_A_0603V-22.0UF,4V,20%,X6S,A   I231 @BASEBOARD_FAB2_LIB.BASEBOARD_FAB2(SCH_1):PAGE228
  C7M2    2      B CAP_A_0603V-22.0UF,4V,20%,X6S,A   I232 @BASEBOARD_FAB2_LIB.BASEBOARD_FAB2(SCH_1):PAGE228
  C8M4    2      B CAP_A_0603V-22.0UF,4V,20%,X6S,A   I233 @BASEBOARD_FAB2_LIB.BASEBOARD_FAB2(SCH_1):PAGE228
  C2A4    2      B CAP_A_0603V-22.0UF,4V,20%,X6S,A   I234 @BASEBOARD_FAB2_LIB.BASEBOARD_FAB2(SCH_1):PAGE228
  C8M6    2      B CAP_A_0603V-22.0UF,4V,20%,X6S,A   I235 @BASEBOARD_FAB2_LIB.BASEBOARD_FAB2(SCH_1):PAGE228
  C8L9    2      B CAP_A_0603V-22.0UF,4V,20%,X6S,A   I236 @BASEBOARD_FAB2_LIB.BASEBOARD_FAB2(SCH_1):PAGE228
  C8L8    2      B CAP_A_0603V-22.0UF,4V,20%,X6S,A   I237 @BASEBOARD_FAB2_LIB.BASEBOARD_FAB2(SCH_1):PAGE228
  C7L4    2      B CAP_A_0603V-22.0UF,4V,20%,X6S,A   I238 @BASEBOARD_FAB2_LIB.BASEBOARD_FAB2(SCH_1):PAGE228
  C8L7    2      B CAP_A_0603V-22.0UF,4V,20%,X6S,A   I239 @BASEBOARD_FAB2_LIB.BASEBOARD_FAB2(SCH_1):PAGE228
  C8L6    2      B CAP_A_0603V-22.0UF,4V,20%,X6S,A   I240 @BASEBOARD_FAB2_LIB.BASEBOARD_FAB2(SCH_1):PAGE228
  C8L5    2      B CAP_A_0603V-22.0UF,4V,20%,X6S,A   I241 @BASEBOARD_FAB2_LIB.BASEBOARD_FAB2(SCH_1):PAGE228
  C8M1    2      B CAP_A_0603V-22.0UF,4V,20%,X6S,A   I243 @BASEBOARD_FAB2_LIB.BASEBOARD_FAB2(SCH_1):PAGE228
 SH7L1    2      B SHUNT_SH0201-EMPTY,N_A   I246 @BASEBOARD_FAB2_LIB.BASEBOARD_FAB2(SCH_1):PAGE228
 C4G13    2      B CAP_0402LF-1000PF,50V,10%,X7R,A    I15 @BASEBOARD_FAB2_LIB.BASEBOARD_FAB2(SCH_1):PAGE229
 C4G20    2      B CAP_0805LF-22UF,4V,20%,X6S,C95A    I17 @BASEBOARD_FAB2_LIB.BASEBOARD_FAB2(SCH_1):PAGE229
 C4G21    2      B CAP_0402-1.0UF,16V,10%,X6S,D97A    I21 @BASEBOARD_FAB2_LIB.BASEBOARD_FAB2(SCH_1):PAGE229
 EU4G2    3   AGND MIC5166_DFN-IC,H55101-001    I24 @BASEBOARD_FAB2_LIB.BASEBOARD_FAB2(SCH_1):PAGE229
 EU4G2    8   PGND MIC5166_DFN-IC,H55101-001    I24 @BASEBOARD_FAB2_LIB.BASEBOARD_FAB2(SCH_1):PAGE229
 EU4G2   11  THPAD MIC5166_DFN-IC,H55101-001    I24 @BASEBOARD_FAB2_LIB.BASEBOARD_FAB2(SCH_1):PAGE229
 C6U14    2      B CAP_0603LF-10UF,4V,20%,X6S,E15A    I25 @BASEBOARD_FAB2_LIB.BASEBOARD_FAB2(SCH_1):PAGE229
 C4G18    2      B CAP_0402-1.0UF,16V,10%,X6S,D97A    I27 @BASEBOARD_FAB2_LIB.BASEBOARD_FAB2(SCH_1):PAGE229
 C6U13    2      B CAP_0603LF-10UF,4V,20%,X6S,E15A    I29 @BASEBOARD_FAB2_LIB.BASEBOARD_FAB2(SCH_1):PAGE229
 C4G12    2      B CAP_0402LF-1000PF,50V,10%,EMPTA    I36 @BASEBOARD_FAB2_LIB.BASEBOARD_FAB2(SCH_1):PAGE229
 C6U11    2      B CAP_0603-4.7UF,6.3V,10%,X6S,E1A    I46 @BASEBOARD_FAB2_LIB.BASEBOARD_FAB2(SCH_1):PAGE229
  C2F2    2      B CAP_A_0603V-47UF,4V,20%,X5R,60A    I47 @BASEBOARD_FAB2_LIB.BASEBOARD_FAB2(SCH_1):PAGE229
  C8T3    2      B CAP_A_0603V-47UF,4V,20%,X5R,60A    I48 @BASEBOARD_FAB2_LIB.BASEBOARD_FAB2(SCH_1):PAGE229
 C8U10    2      B CAP_A_0603V-47UF,4V,20%,X5R,60A    I49 @BASEBOARD_FAB2_LIB.BASEBOARD_FAB2(SCH_1):PAGE229
  R6U8    1      A RES_0402-51.1,1.0%,1/16W,CHIP,A    I52 @BASEBOARD_FAB2_LIB.BASEBOARD_FAB2(SCH_1):PAGE229
  C4A3    2      B CAP_0402LF-1000PF,50V,10%,X7R,A    I16 @BASEBOARD_FAB2_LIB.BASEBOARD_FAB2(SCH_1):PAGE230
 C4A13    2      B CAP_0805LF-22UF,4V,20%,X6S,C95A    I18 @BASEBOARD_FAB2_LIB.BASEBOARD_FAB2(SCH_1):PAGE230
 C4A14    2      B CAP_0402-1.0UF,16V,10%,X6S,D97A    I21 @BASEBOARD_FAB2_LIB.BASEBOARD_FAB2(SCH_1):PAGE230
 C4A15    2      B CAP_0603LF-10UF,4V,20%,X6S,E15A    I25 @BASEBOARD_FAB2_LIB.BASEBOARD_FAB2(SCH_1):PAGE230
  C6L5    2      B CAP_0603LF-10UF,4V,20%,X6S,E15A    I26 @BASEBOARD_FAB2_LIB.BASEBOARD_FAB2(SCH_1):PAGE230
  C4A8    2      B CAP_0402-1.0UF,16V,10%,X6S,D97A    I28 @BASEBOARD_FAB2_LIB.BASEBOARD_FAB2(SCH_1):PAGE230
 EU4A2    3   AGND MIC5166_DFN-IC,H55101-001    I31 @BASEBOARD_FAB2_LIB.BASEBOARD_FAB2(SCH_1):PAGE230
 EU4A2    8   PGND MIC5166_DFN-IC,H55101-001    I31 @BASEBOARD_FAB2_LIB.BASEBOARD_FAB2(SCH_1):PAGE230
 EU4A2   11  THPAD MIC5166_DFN-IC,H55101-001    I31 @BASEBOARD_FAB2_LIB.BASEBOARD_FAB2(SCH_1):PAGE230
  C4A6    2      B CAP_0402LF-1000PF,50V,10%,EMPTA    I39 @BASEBOARD_FAB2_LIB.BASEBOARD_FAB2(SCH_1):PAGE230
  C4A7    2      B CAP_0603-4.7UF,6.3V,10%,X6S,E1A    I46 @BASEBOARD_FAB2_LIB.BASEBOARD_FAB2(SCH_1):PAGE230
 C8M12    2      B CAP_A_0603V-47UF,4V,20%,X5R,60A    I47 @BASEBOARD_FAB2_LIB.BASEBOARD_FAB2(SCH_1):PAGE230
  C8L3    2      B CAP_A_0603V-47UF,4V,20%,X5R,60A    I48 @BASEBOARD_FAB2_LIB.BASEBOARD_FAB2(SCH_1):PAGE230
  C8L4    2      B CAP_A_0603V-47UF,4V,20%,X5R,60A    I49 @BASEBOARD_FAB2_LIB.BASEBOARD_FAB2(SCH_1):PAGE230
  R6L7    1      A RES_0402-51.1,1.0%,1/16W,CHIP,A    I52 @BASEBOARD_FAB2_LIB.BASEBOARD_FAB2(SCH_1):PAGE230
  C6F6    2      B CAP_0603LF-10UF,4V,20%,X6S,E15A   I122 @BASEBOARD_FAB2_LIB.BASEBOARD_FAB2(SCH_1):PAGE231
  C4T6    2      B CAP_0603LF-10UF,4V,20%,X6S,E15A   I124 @BASEBOARD_FAB2_LIB.BASEBOARD_FAB2(SCH_1):PAGE231
  C4T5    2      B CAP_0603LF-10UF,4V,20%,X6S,E15A   I125 @BASEBOARD_FAB2_LIB.BASEBOARD_FAB2(SCH_1):PAGE231
  C6G1    2      B CAP_0603LF-10UF,4V,20%,X6S,E15A   I126 @BASEBOARD_FAB2_LIB.BASEBOARD_FAB2(SCH_1):PAGE231
  C6G2    2      B CAP_0603LF-10UF,4V,20%,X6S,E15A   I128 @BASEBOARD_FAB2_LIB.BASEBOARD_FAB2(SCH_1):PAGE231
  C4U2    2      B CAP_0603LF-10UF,4V,20%,X6S,E15A   I129 @BASEBOARD_FAB2_LIB.BASEBOARD_FAB2(SCH_1):PAGE231
  C4U1    2      B CAP_0603LF-10UF,4V,20%,X6S,E15A   I130 @BASEBOARD_FAB2_LIB.BASEBOARD_FAB2(SCH_1):PAGE231
  C6G4    2      B CAP_0603LF-10UF,4V,20%,X6S,E15A   I131 @BASEBOARD_FAB2_LIB.BASEBOARD_FAB2(SCH_1):PAGE231
 R7F14    2      B RES_0402-10.0K,1%,1/16W,CHIP,GA   I136 @BASEBOARD_FAB2_LIB.BASEBOARD_FAB2(SCH_1):PAGE231
 C7F11    2      B CAP_0402LF-1000PF,50V,10%,X7R,A   I142 @BASEBOARD_FAB2_LIB.BASEBOARD_FAB2(SCH_1):PAGE231
  C6G5    2      B CAP_0603LF-10UF,4V,20%,X6S,E15A   I145 @BASEBOARD_FAB2_LIB.BASEBOARD_FAB2(SCH_1):PAGE231
  C4U4    2      B CAP_0603LF-10UF,4V,20%,X6S,E15A   I146 @BASEBOARD_FAB2_LIB.BASEBOARD_FAB2(SCH_1):PAGE231
  C4U3    2      B CAP_0603LF-10UF,4V,20%,X6S,E15A   I148 @BASEBOARD_FAB2_LIB.BASEBOARD_FAB2(SCH_1):PAGE231
  C6F5    2      B CAP_0603LF-10UF,4V,20%,X6S,E15A   I149 @BASEBOARD_FAB2_LIB.BASEBOARD_FAB2(SCH_1):PAGE231
  C7F7    2      B CAP_1210-47UF,16V,20%,X6S,D384A   I151 @BASEBOARD_FAB2_LIB.BASEBOARD_FAB2(SCH_1):PAGE231
 C3T10    2      B CAP_0402-1.0UF,16V,10%,X6S,D97A   I161 @BASEBOARD_FAB2_LIB.BASEBOARD_FAB2(SCH_1):PAGE231
 R7F35    1      A RES_0402-0.0,5%,1/16W,CHIP,G21A   I170 @BASEBOARD_FAB2_LIB.BASEBOARD_FAB2(SCH_1):PAGE231
  R7F7    2      B RES_0402-2.2,5%,1/16W,EMPTY,G2A   I174 @BASEBOARD_FAB2_LIB.BASEBOARD_FAB2(SCH_1):PAGE231
 R7F10    2      B RES_0603-120.0,1%,1/10W,CHIP,GA   I177 @BASEBOARD_FAB2_LIB.BASEBOARD_FAB2(SCH_1):PAGE231
  C6F4    2      B CAPP_7343LF-330UF,6.3V,20%,POSA   I180 @BASEBOARD_FAB2_LIB.BASEBOARD_FAB2(SCH_1):PAGE231
  C3T7    2      B CAP_0805-47UF,4V,20%,X6S,C9533A   I184 @BASEBOARD_FAB2_LIB.BASEBOARD_FAB2(SCH_1):PAGE231
  C3T9    2      B CAP_0805-47UF,4V,20%,X6S,C9533A   I186 @BASEBOARD_FAB2_LIB.BASEBOARD_FAB2(SCH_1):PAGE231
 EU7F1   41    GND NCP3232L_SM-IC,H86355-001   I193 @BASEBOARD_FAB2_LIB.BASEBOARD_FAB2(SCH_1):PAGE231
 EU7F1   16 PGND<0> NCP3232L_SM-IC,H86355-001   I193 @BASEBOARD_FAB2_LIB.BASEBOARD_FAB2(SCH_1):PAGE231
 EU7F1   17 PGND<1> NCP3232L_SM-IC,H86355-001   I193 @BASEBOARD_FAB2_LIB.BASEBOARD_FAB2(SCH_1):PAGE231
 EU7F1   18 PGND<2> NCP3232L_SM-IC,H86355-001   I193 @BASEBOARD_FAB2_LIB.BASEBOARD_FAB2(SCH_1):PAGE231
 EU7F1   19 PGND<3> NCP3232L_SM-IC,H86355-001   I193 @BASEBOARD_FAB2_LIB.BASEBOARD_FAB2(SCH_1):PAGE231
 EU7F1   20 PGND<4> NCP3232L_SM-IC,H86355-001   I193 @BASEBOARD_FAB2_LIB.BASEBOARD_FAB2(SCH_1):PAGE231
 EU7F1   21 PGND<5> NCP3232L_SM-IC,H86355-001   I193 @BASEBOARD_FAB2_LIB.BASEBOARD_FAB2(SCH_1):PAGE231
 EU7F1   22 PGND<6> NCP3232L_SM-IC,H86355-001   I193 @BASEBOARD_FAB2_LIB.BASEBOARD_FAB2(SCH_1):PAGE231
 EU7F1   23 PGND<7> NCP3232L_SM-IC,H86355-001   I193 @BASEBOARD_FAB2_LIB.BASEBOARD_FAB2(SCH_1):PAGE231
 EU7F1   24 PGND<8> NCP3232L_SM-IC,H86355-001   I193 @BASEBOARD_FAB2_LIB.BASEBOARD_FAB2(SCH_1):PAGE231
 EU7F1   25 PGND<9> NCP3232L_SM-IC,H86355-001   I193 @BASEBOARD_FAB2_LIB.BASEBOARD_FAB2(SCH_1):PAGE231
 EU7F1   26 PGND<10> NCP3232L_SM-IC,H86355-001   I193 @BASEBOARD_FAB2_LIB.BASEBOARD_FAB2(SCH_1):PAGE231
 EU7F1   27 PGND<11> NCP3232L_SM-IC,H86355-001   I193 @BASEBOARD_FAB2_LIB.BASEBOARD_FAB2(SCH_1):PAGE231
 EU7F1   28 PGND<12> NCP3232L_SM-IC,H86355-001   I193 @BASEBOARD_FAB2_LIB.BASEBOARD_FAB2(SCH_1):PAGE231
 EU7F1   37 PGND<13> NCP3232L_SM-IC,H86355-001   I193 @BASEBOARD_FAB2_LIB.BASEBOARD_FAB2(SCH_1):PAGE231
  C7F6    2      B CAP_A_0402V-0.1UF,16V,10%,X7R,A   I205 @BASEBOARD_FAB2_LIB.BASEBOARD_FAB2(SCH_1):PAGE231
  C7F5    2      B CAP_0805-10UF,16V,10%,X6S,C953A   I209 @BASEBOARD_FAB2_LIB.BASEBOARD_FAB2(SCH_1):PAGE231
  C3T8    2      B CAP_0805-10UF,16V,10%,X6S,C953A   I210 @BASEBOARD_FAB2_LIB.BASEBOARD_FAB2(SCH_1):PAGE231
 C3T14    2      B CAP_0805-10UF,16V,10%,X6S,C953A   I211 @BASEBOARD_FAB2_LIB.BASEBOARD_FAB2(SCH_1):PAGE231
 C3T12    2      B CAP_0805-10UF,16V,10%,X6S,C953A   I215 @BASEBOARD_FAB2_LIB.BASEBOARD_FAB2(SCH_1):PAGE231
  C4T3    2      B CAPP_7343-220UF,4V,20%,POSCAP,A   I217 @BASEBOARD_FAB2_LIB.BASEBOARD_FAB2(SCH_1):PAGE231
  C4L2    2      B CAP_0603LF-10UF,4V,20%,X6S,E15A   I102 @BASEBOARD_FAB2_LIB.BASEBOARD_FAB2(SCH_1):PAGE232
  C6A3    2      B CAP_0603LF-10UF,4V,20%,X6S,E15A   I104 @BASEBOARD_FAB2_LIB.BASEBOARD_FAB2(SCH_1):PAGE232
  C6A2    2      B CAP_0603LF-10UF,4V,20%,X6S,E15A   I105 @BASEBOARD_FAB2_LIB.BASEBOARD_FAB2(SCH_1):PAGE232
  C4L3    2      B CAP_0603LF-10UF,4V,20%,X6S,E15A   I106 @BASEBOARD_FAB2_LIB.BASEBOARD_FAB2(SCH_1):PAGE232
  C4L4    2      B CAP_0603LF-10UF,4V,20%,X6S,E15A   I108 @BASEBOARD_FAB2_LIB.BASEBOARD_FAB2(SCH_1):PAGE232
  C6A7    2      B CAP_0603LF-10UF,4V,20%,X6S,E15A   I109 @BASEBOARD_FAB2_LIB.BASEBOARD_FAB2(SCH_1):PAGE232
  C6A6    2      B CAP_0603LF-10UF,4V,20%,X6S,E15A   I110 @BASEBOARD_FAB2_LIB.BASEBOARD_FAB2(SCH_1):PAGE232
  C4M3    2      B CAP_0603LF-10UF,4V,20%,X6S,E15A   I111 @BASEBOARD_FAB2_LIB.BASEBOARD_FAB2(SCH_1):PAGE232
  C4M4    2      B CAP_0603LF-10UF,4V,20%,X6S,E15A   I125 @BASEBOARD_FAB2_LIB.BASEBOARD_FAB2(SCH_1):PAGE232
  C6B2    2      B CAP_0603LF-10UF,4V,20%,X6S,E15A   I126 @BASEBOARD_FAB2_LIB.BASEBOARD_FAB2(SCH_1):PAGE232
  C6B1    2      B CAP_0603LF-10UF,4V,20%,X6S,E15A   I128 @BASEBOARD_FAB2_LIB.BASEBOARD_FAB2(SCH_1):PAGE232
  C4L1    2      B CAP_0603LF-10UF,4V,20%,X6S,E15A   I129 @BASEBOARD_FAB2_LIB.BASEBOARD_FAB2(SCH_1):PAGE232
 R7B20    1      A RES_0402-0.0,5%,1/16W,CHIP,G21A   I150 @BASEBOARD_FAB2_LIB.BASEBOARD_FAB2(SCH_1):PAGE232
  C7B8    2      B CAP_1210-47UF,16V,20%,X6S,D384A   I202 @BASEBOARD_FAB2_LIB.BASEBOARD_FAB2(SCH_1):PAGE232
  C3M9    2      B CAP_0402-1.0UF,16V,10%,X6S,D97A   I207 @BASEBOARD_FAB2_LIB.BASEBOARD_FAB2(SCH_1):PAGE232
 C7B12    2      B CAP_0402LF-1000PF,50V,10%,X7R,A   I209 @BASEBOARD_FAB2_LIB.BASEBOARD_FAB2(SCH_1):PAGE232
 EU7B1   41    GND NCP3232L_SM-IC,H86355-001   I214 @BASEBOARD_FAB2_LIB.BASEBOARD_FAB2(SCH_1):PAGE232
 EU7B1   16 PGND<0> NCP3232L_SM-IC,H86355-001   I214 @BASEBOARD_FAB2_LIB.BASEBOARD_FAB2(SCH_1):PAGE232
 EU7B1   17 PGND<1> NCP3232L_SM-IC,H86355-001   I214 @BASEBOARD_FAB2_LIB.BASEBOARD_FAB2(SCH_1):PAGE232
 EU7B1   18 PGND<2> NCP3232L_SM-IC,H86355-001   I214 @BASEBOARD_FAB2_LIB.BASEBOARD_FAB2(SCH_1):PAGE232
 EU7B1   19 PGND<3> NCP3232L_SM-IC,H86355-001   I214 @BASEBOARD_FAB2_LIB.BASEBOARD_FAB2(SCH_1):PAGE232
 EU7B1   20 PGND<4> NCP3232L_SM-IC,H86355-001   I214 @BASEBOARD_FAB2_LIB.BASEBOARD_FAB2(SCH_1):PAGE232
 EU7B1   21 PGND<5> NCP3232L_SM-IC,H86355-001   I214 @BASEBOARD_FAB2_LIB.BASEBOARD_FAB2(SCH_1):PAGE232
 EU7B1   22 PGND<6> NCP3232L_SM-IC,H86355-001   I214 @BASEBOARD_FAB2_LIB.BASEBOARD_FAB2(SCH_1):PAGE232
 EU7B1   23 PGND<7> NCP3232L_SM-IC,H86355-001   I214 @BASEBOARD_FAB2_LIB.BASEBOARD_FAB2(SCH_1):PAGE232
 EU7B1   24 PGND<8> NCP3232L_SM-IC,H86355-001   I214 @BASEBOARD_FAB2_LIB.BASEBOARD_FAB2(SCH_1):PAGE232
 EU7B1   25 PGND<9> NCP3232L_SM-IC,H86355-001   I214 @BASEBOARD_FAB2_LIB.BASEBOARD_FAB2(SCH_1):PAGE232
 EU7B1   26 PGND<10> NCP3232L_SM-IC,H86355-001   I214 @BASEBOARD_FAB2_LIB.BASEBOARD_FAB2(SCH_1):PAGE232
 EU7B1   27 PGND<11> NCP3232L_SM-IC,H86355-001   I214 @BASEBOARD_FAB2_LIB.BASEBOARD_FAB2(SCH_1):PAGE232
 EU7B1   28 PGND<12> NCP3232L_SM-IC,H86355-001   I214 @BASEBOARD_FAB2_LIB.BASEBOARD_FAB2(SCH_1):PAGE232
 EU7B1   37 PGND<13> NCP3232L_SM-IC,H86355-001   I214 @BASEBOARD_FAB2_LIB.BASEBOARD_FAB2(SCH_1):PAGE232
 R7A15    2      B RES_0402-2.2,5%,1/16W,EMPTY,G2A   I218 @BASEBOARD_FAB2_LIB.BASEBOARD_FAB2(SCH_1):PAGE232
 R7B10    2      B RES_0603-120.0,1%,1/10W,CHIP,GA   I227 @BASEBOARD_FAB2_LIB.BASEBOARD_FAB2(SCH_1):PAGE232
  C6B7    2      B CAPP_7343LF-330UF,6.3V,20%,POSA   I229 @BASEBOARD_FAB2_LIB.BASEBOARD_FAB2(SCH_1):PAGE232
  C6B3    2      B CAP_0805-47UF,4V,20%,X6S,C9533A   I236 @BASEBOARD_FAB2_LIB.BASEBOARD_FAB2(SCH_1):PAGE232
  C7B7    2      B CAP_0805-47UF,4V,20%,X6S,C9533A   I238 @BASEBOARD_FAB2_LIB.BASEBOARD_FAB2(SCH_1):PAGE232
  C7B6    2      B CAP_A_0402V-0.1UF,16V,10%,X7R,A   I252 @BASEBOARD_FAB2_LIB.BASEBOARD_FAB2(SCH_1):PAGE232
  C3M8    2      B CAP_0805-10UF,16V,10%,X6S,C953A   I259 @BASEBOARD_FAB2_LIB.BASEBOARD_FAB2(SCH_1):PAGE232
 C3M15    2      B CAP_0805-10UF,16V,10%,X6S,C953A   I260 @BASEBOARD_FAB2_LIB.BASEBOARD_FAB2(SCH_1):PAGE232
 C3M16    2      B CAP_0805-10UF,16V,10%,X6S,C953A   I261 @BASEBOARD_FAB2_LIB.BASEBOARD_FAB2(SCH_1):PAGE232
  C7B5    2      B CAP_0805-10UF,16V,10%,X6S,C953A   I262 @BASEBOARD_FAB2_LIB.BASEBOARD_FAB2(SCH_1):PAGE232
  C4M1    2      B CAPP_7343-220UF,4V,20%,POSCAP,A   I267 @BASEBOARD_FAB2_LIB.BASEBOARD_FAB2(SCH_1):PAGE232
  C7U4    2      B CAP_0603LF-10UF,4V,20%,X6S,E15A   I109 @BASEBOARD_FAB2_LIB.BASEBOARD_FAB2(SCH_1):PAGE233
  C7U5    2      B CAP_0603LF-10UF,4V,20%,X6S,E15A   I111 @BASEBOARD_FAB2_LIB.BASEBOARD_FAB2(SCH_1):PAGE233
  C7T2    2      B CAP_0603LF-10UF,4V,20%,X6S,E15A   I112 @BASEBOARD_FAB2_LIB.BASEBOARD_FAB2(SCH_1):PAGE233
  C7T3    2      B CAP_0603LF-10UF,4V,20%,X6S,E15A   I113 @BASEBOARD_FAB2_LIB.BASEBOARD_FAB2(SCH_1):PAGE233
  C7U6    2      B CAP_0603LF-10UF,4V,20%,X6S,E15A   I115 @BASEBOARD_FAB2_LIB.BASEBOARD_FAB2(SCH_1):PAGE233
  C3F3    2      B CAP_0603LF-10UF,4V,20%,X6S,E15A   I116 @BASEBOARD_FAB2_LIB.BASEBOARD_FAB2(SCH_1):PAGE233
  C3F4    2      B CAP_0603LF-10UF,4V,20%,X6S,E15A   I117 @BASEBOARD_FAB2_LIB.BASEBOARD_FAB2(SCH_1):PAGE233
  C3G3    2      B CAP_0603LF-10UF,4V,20%,X6S,E15A   I118 @BASEBOARD_FAB2_LIB.BASEBOARD_FAB2(SCH_1):PAGE233
  C3G7    2      B CAP_0603LF-10UF,4V,20%,X6S,E15A   I132 @BASEBOARD_FAB2_LIB.BASEBOARD_FAB2(SCH_1):PAGE233
  C3G4    2      B CAP_0603LF-10UF,4V,20%,X6S,E15A   I133 @BASEBOARD_FAB2_LIB.BASEBOARD_FAB2(SCH_1):PAGE233
  C3G8    2      B CAP_0603LF-10UF,4V,20%,X6S,E15A   I135 @BASEBOARD_FAB2_LIB.BASEBOARD_FAB2(SCH_1):PAGE233
  C7U3    2      B CAP_0603LF-10UF,4V,20%,X6S,E15A   I136 @BASEBOARD_FAB2_LIB.BASEBOARD_FAB2(SCH_1):PAGE233
 R4G25    1      A RES_0402-0.0,5%,1/16W,CHIP,G21A   I157 @BASEBOARD_FAB2_LIB.BASEBOARD_FAB2(SCH_1):PAGE233
  R4G5    2      B RES_0402-10.0K,1%,1/16W,CHIP,GA   I182 @BASEBOARD_FAB2_LIB.BASEBOARD_FAB2(SCH_1):PAGE233
  C4G5    2      B CAP_1210-47UF,16V,20%,X6S,D384A   I189 @BASEBOARD_FAB2_LIB.BASEBOARD_FAB2(SCH_1):PAGE233
  C4G4    2      B CAP_0402-1.0UF,16V,10%,X6S,D97A   I196 @BASEBOARD_FAB2_LIB.BASEBOARD_FAB2(SCH_1):PAGE233
  C4G9    2      B CAP_0402LF-1000PF,50V,10%,X7R,A   I201 @BASEBOARD_FAB2_LIB.BASEBOARD_FAB2(SCH_1):PAGE233
  R4F6    2      B RES_0402-2.2,5%,1/16W,EMPTY,G2A   I208 @BASEBOARD_FAB2_LIB.BASEBOARD_FAB2(SCH_1):PAGE233
  R4G6    2      B RES_0603-120.0,1%,1/10W,CHIP,GA   I211 @BASEBOARD_FAB2_LIB.BASEBOARD_FAB2(SCH_1):PAGE233
  C4F7    2      B CAPP_7343LF-330UF,6.3V,20%,POSA   I217 @BASEBOARD_FAB2_LIB.BASEBOARD_FAB2(SCH_1):PAGE233
  C6U3    2      B CAP_0805-47UF,4V,20%,X6S,C9533A   I221 @BASEBOARD_FAB2_LIB.BASEBOARD_FAB2(SCH_1):PAGE233
  C6U2    2      B CAP_0805-47UF,4V,20%,X6S,C9533A   I223 @BASEBOARD_FAB2_LIB.BASEBOARD_FAB2(SCH_1):PAGE233
 EU4G1   41    GND NCP3232L_SM-IC,H86355-001   I225 @BASEBOARD_FAB2_LIB.BASEBOARD_FAB2(SCH_1):PAGE233
 EU4G1   16 PGND<0> NCP3232L_SM-IC,H86355-001   I225 @BASEBOARD_FAB2_LIB.BASEBOARD_FAB2(SCH_1):PAGE233
 EU4G1   17 PGND<1> NCP3232L_SM-IC,H86355-001   I225 @BASEBOARD_FAB2_LIB.BASEBOARD_FAB2(SCH_1):PAGE233
 EU4G1   18 PGND<2> NCP3232L_SM-IC,H86355-001   I225 @BASEBOARD_FAB2_LIB.BASEBOARD_FAB2(SCH_1):PAGE233
 EU4G1   19 PGND<3> NCP3232L_SM-IC,H86355-001   I225 @BASEBOARD_FAB2_LIB.BASEBOARD_FAB2(SCH_1):PAGE233
 EU4G1   20 PGND<4> NCP3232L_SM-IC,H86355-001   I225 @BASEBOARD_FAB2_LIB.BASEBOARD_FAB2(SCH_1):PAGE233
 EU4G1   21 PGND<5> NCP3232L_SM-IC,H86355-001   I225 @BASEBOARD_FAB2_LIB.BASEBOARD_FAB2(SCH_1):PAGE233
 EU4G1   22 PGND<6> NCP3232L_SM-IC,H86355-001   I225 @BASEBOARD_FAB2_LIB.BASEBOARD_FAB2(SCH_1):PAGE233
 EU4G1   23 PGND<7> NCP3232L_SM-IC,H86355-001   I225 @BASEBOARD_FAB2_LIB.BASEBOARD_FAB2(SCH_1):PAGE233
 EU4G1   24 PGND<8> NCP3232L_SM-IC,H86355-001   I225 @BASEBOARD_FAB2_LIB.BASEBOARD_FAB2(SCH_1):PAGE233
 EU4G1   25 PGND<9> NCP3232L_SM-IC,H86355-001   I225 @BASEBOARD_FAB2_LIB.BASEBOARD_FAB2(SCH_1):PAGE233
 EU4G1   26 PGND<10> NCP3232L_SM-IC,H86355-001   I225 @BASEBOARD_FAB2_LIB.BASEBOARD_FAB2(SCH_1):PAGE233
 EU4G1   27 PGND<11> NCP3232L_SM-IC,H86355-001   I225 @BASEBOARD_FAB2_LIB.BASEBOARD_FAB2(SCH_1):PAGE233
 EU4G1   28 PGND<12> NCP3232L_SM-IC,H86355-001   I225 @BASEBOARD_FAB2_LIB.BASEBOARD_FAB2(SCH_1):PAGE233
 EU4G1   37 PGND<13> NCP3232L_SM-IC,H86355-001   I225 @BASEBOARD_FAB2_LIB.BASEBOARD_FAB2(SCH_1):PAGE233
  C6U5    2      B CAP_A_0402V-0.1UF,16V,10%,X7R,A   I242 @BASEBOARD_FAB2_LIB.BASEBOARD_FAB2(SCH_1):PAGE233
  C6U4    2      B CAP_0805-10UF,16V,10%,X6S,C953A   I248 @BASEBOARD_FAB2_LIB.BASEBOARD_FAB2(SCH_1):PAGE233
  C4G2    2      B CAP_0805-10UF,16V,10%,X6S,C953A   I253 @BASEBOARD_FAB2_LIB.BASEBOARD_FAB2(SCH_1):PAGE233
  C6U7    2      B CAP_0805-10UF,16V,10%,X6S,C953A   I254 @BASEBOARD_FAB2_LIB.BASEBOARD_FAB2(SCH_1):PAGE233
  C6U8    2      B CAP_0805-10UF,16V,10%,X6S,C953A   I255 @BASEBOARD_FAB2_LIB.BASEBOARD_FAB2(SCH_1):PAGE233
 C4F11    2      B CAPP_7343-220UF,4V,20%,POSCAP,A   I256 @BASEBOARD_FAB2_LIB.BASEBOARD_FAB2(SCH_1):PAGE233
 R4B14    1      A RES_0402-0.0,5%,1/16W,CHIP,G21A    I29 @BASEBOARD_FAB2_LIB.BASEBOARD_FAB2(SCH_1):PAGE234
  C3B2    2      B CAP_0603LF-10UF,4V,20%,X6S,E15A    I84 @BASEBOARD_FAB2_LIB.BASEBOARD_FAB2(SCH_1):PAGE234
  C3A8    2      B CAP_0603LF-10UF,4V,20%,X6S,E15A    I86 @BASEBOARD_FAB2_LIB.BASEBOARD_FAB2(SCH_1):PAGE234
  C7L3    2      B CAP_0603LF-10UF,4V,20%,X6S,E15A    I87 @BASEBOARD_FAB2_LIB.BASEBOARD_FAB2(SCH_1):PAGE234
  C7L2    2      B CAP_0603LF-10UF,4V,20%,X6S,E15A    I88 @BASEBOARD_FAB2_LIB.BASEBOARD_FAB2(SCH_1):PAGE234
  C7L7    2      B CAP_0603LF-10UF,4V,20%,X6S,E15A    I89 @BASEBOARD_FAB2_LIB.BASEBOARD_FAB2(SCH_1):PAGE234
  C7L6    2      B CAP_0603LF-10UF,4V,20%,X6S,E15A    I90 @BASEBOARD_FAB2_LIB.BASEBOARD_FAB2(SCH_1):PAGE234
  C7M4    2      B CAP_0603LF-10UF,4V,20%,X6S,E15A    I91 @BASEBOARD_FAB2_LIB.BASEBOARD_FAB2(SCH_1):PAGE234
  C7M3    2      B CAP_0603LF-10UF,4V,20%,X6S,E15A    I92 @BASEBOARD_FAB2_LIB.BASEBOARD_FAB2(SCH_1):PAGE234
  C3A4    2      B CAP_0603LF-10UF,4V,20%,X6S,E15A    I93 @BASEBOARD_FAB2_LIB.BASEBOARD_FAB2(SCH_1):PAGE234
  C3B1    2      B CAP_0603LF-10UF,4V,20%,X6S,E15A    I94 @BASEBOARD_FAB2_LIB.BASEBOARD_FAB2(SCH_1):PAGE234
  C3A7    2      B CAP_0603LF-10UF,4V,20%,X6S,E15A    I95 @BASEBOARD_FAB2_LIB.BASEBOARD_FAB2(SCH_1):PAGE234
  C3A3    2      B CAP_0603LF-10UF,4V,20%,X6S,E15A    I97 @BASEBOARD_FAB2_LIB.BASEBOARD_FAB2(SCH_1):PAGE234
  C4B1    2      B CAP_1210-47UF,16V,20%,X6S,D384A   I130 @BASEBOARD_FAB2_LIB.BASEBOARD_FAB2(SCH_1):PAGE234
  C4B8    2      B CAP_0402LF-1000PF,50V,10%,X7R,A   I139 @BASEBOARD_FAB2_LIB.BASEBOARD_FAB2(SCH_1):PAGE234
 C6L11    2      B CAP_0402-1.0UF,16V,10%,X6S,D97A   I152 @BASEBOARD_FAB2_LIB.BASEBOARD_FAB2(SCH_1):PAGE234
  R4A7    2      B RES_0402-2.2,5%,1/16W,EMPTY,G2A   I162 @BASEBOARD_FAB2_LIB.BASEBOARD_FAB2(SCH_1):PAGE234
  C3B3    2      B CAPP_7343LF-330UF,6.3V,20%,POSA   I167 @BASEBOARD_FAB2_LIB.BASEBOARD_FAB2(SCH_1):PAGE234
  C4B3    2      B CAP_0805-47UF,4V,20%,X6S,C9533A   I177 @BASEBOARD_FAB2_LIB.BASEBOARD_FAB2(SCH_1):PAGE234
  C4B2    2      B CAP_0805-47UF,4V,20%,X6S,C9533A   I180 @BASEBOARD_FAB2_LIB.BASEBOARD_FAB2(SCH_1):PAGE234
  R4B2    2      B RES_0603-120.0,1%,1/10W,CHIP,GA   I183 @BASEBOARD_FAB2_LIB.BASEBOARD_FAB2(SCH_1):PAGE234
 EU4A3   41    GND NCP3232L_SM-IC,H86355-001   I184 @BASEBOARD_FAB2_LIB.BASEBOARD_FAB2(SCH_1):PAGE234
 EU4A3   16 PGND<0> NCP3232L_SM-IC,H86355-001   I184 @BASEBOARD_FAB2_LIB.BASEBOARD_FAB2(SCH_1):PAGE234
 EU4A3   17 PGND<1> NCP3232L_SM-IC,H86355-001   I184 @BASEBOARD_FAB2_LIB.BASEBOARD_FAB2(SCH_1):PAGE234
 EU4A3   18 PGND<2> NCP3232L_SM-IC,H86355-001   I184 @BASEBOARD_FAB2_LIB.BASEBOARD_FAB2(SCH_1):PAGE234
 EU4A3   19 PGND<3> NCP3232L_SM-IC,H86355-001   I184 @BASEBOARD_FAB2_LIB.BASEBOARD_FAB2(SCH_1):PAGE234
 EU4A3   20 PGND<4> NCP3232L_SM-IC,H86355-001   I184 @BASEBOARD_FAB2_LIB.BASEBOARD_FAB2(SCH_1):PAGE234
 EU4A3   21 PGND<5> NCP3232L_SM-IC,H86355-001   I184 @BASEBOARD_FAB2_LIB.BASEBOARD_FAB2(SCH_1):PAGE234
 EU4A3   22 PGND<6> NCP3232L_SM-IC,H86355-001   I184 @BASEBOARD_FAB2_LIB.BASEBOARD_FAB2(SCH_1):PAGE234
 EU4A3   23 PGND<7> NCP3232L_SM-IC,H86355-001   I184 @BASEBOARD_FAB2_LIB.BASEBOARD_FAB2(SCH_1):PAGE234
 EU4A3   24 PGND<8> NCP3232L_SM-IC,H86355-001   I184 @BASEBOARD_FAB2_LIB.BASEBOARD_FAB2(SCH_1):PAGE234
 EU4A3   25 PGND<9> NCP3232L_SM-IC,H86355-001   I184 @BASEBOARD_FAB2_LIB.BASEBOARD_FAB2(SCH_1):PAGE234
 EU4A3   26 PGND<10> NCP3232L_SM-IC,H86355-001   I184 @BASEBOARD_FAB2_LIB.BASEBOARD_FAB2(SCH_1):PAGE234
 EU4A3   27 PGND<11> NCP3232L_SM-IC,H86355-001   I184 @BASEBOARD_FAB2_LIB.BASEBOARD_FAB2(SCH_1):PAGE234
 EU4A3   28 PGND<12> NCP3232L_SM-IC,H86355-001   I184 @BASEBOARD_FAB2_LIB.BASEBOARD_FAB2(SCH_1):PAGE234
 EU4A3   37 PGND<13> NCP3232L_SM-IC,H86355-001   I184 @BASEBOARD_FAB2_LIB.BASEBOARD_FAB2(SCH_1):PAGE234
 C4A20    2      B CAP_A_0402V-0.1UF,16V,10%,X7R,A   I199 @BASEBOARD_FAB2_LIB.BASEBOARD_FAB2(SCH_1):PAGE234
 C6L10    2      B CAP_0805-10UF,16V,10%,X6S,C953A   I202 @BASEBOARD_FAB2_LIB.BASEBOARD_FAB2(SCH_1):PAGE234
  C6M3    2      B CAP_0805-10UF,16V,10%,X6S,C953A   I203 @BASEBOARD_FAB2_LIB.BASEBOARD_FAB2(SCH_1):PAGE234
  C6M5    2      B CAP_0805-10UF,16V,10%,X6S,C953A   I204 @BASEBOARD_FAB2_LIB.BASEBOARD_FAB2(SCH_1):PAGE234
 C4A19    2      B CAP_0805-10UF,16V,10%,X6S,C953A   I205 @BASEBOARD_FAB2_LIB.BASEBOARD_FAB2(SCH_1):PAGE234
  C6L8    2      B CAPP_7343-220UF,4V,20%,POSCAP,A   I210 @BASEBOARD_FAB2_LIB.BASEBOARD_FAB2(SCH_1):PAGE234
  C8A7    2      B CAP_A_0402V-1.0UF,6.3V,10%,X6SA   I143 @BASEBOARD_FAB2_LIB.BASEBOARD_FAB2(SCH_1):PAGE235
  C8A8    2      B CAP_A_0402V-0.1UF,16V,10%,X7R,A   I145 @BASEBOARD_FAB2_LIB.BASEBOARD_FAB2(SCH_1):PAGE235
  C2L8    2      B CAP_A_0402V-1.0UF,6.3V,10%,X6SA   I151 @BASEBOARD_FAB2_LIB.BASEBOARD_FAB2(SCH_1):PAGE235
 R2L10    2      B RES_0402-1.5K,1%,1/16W,CHIP,G2A   I166 @BASEBOARD_FAB2_LIB.BASEBOARD_FAB2(SCH_1):PAGE235
  C8A3    2      B CAP_0402LF-1000PF,50V,10%,X7R,A   I167 @BASEBOARD_FAB2_LIB.BASEBOARD_FAB2(SCH_1):PAGE235
 C2L11    2      B CAP_A_0402V-0.1UF,16V,10%,X7R,A   I169 @BASEBOARD_FAB2_LIB.BASEBOARD_FAB2(SCH_1):PAGE235
  R2L9    2      B RES_0402-4.02K,1%,1/16W,CHIP,GA   I176 @BASEBOARD_FAB2_LIB.BASEBOARD_FAB2(SCH_1):PAGE235
  R8A2    2      B RES_0402-2.67K,1%,1/16W,CHIP,GA   I217 @BASEBOARD_FAB2_LIB.BASEBOARD_FAB2(SCH_1):PAGE235
  C8A9    2      B CAP_0402LF-1000PF,50V,10%,X7R,A   I218 @BASEBOARD_FAB2_LIB.BASEBOARD_FAB2(SCH_1):PAGE235
 EU8A1   27 GND<0> PXE1110B_QFN-IC,H89187-001   I229 @BASEBOARD_FAB2_LIB.BASEBOARD_FAB2(SCH_1):PAGE235
 EU8A1   23 GND<1> PXE1110B_QFN-IC,H89187-001   I229 @BASEBOARD_FAB2_LIB.BASEBOARD_FAB2(SCH_1):PAGE235
 EU8A1   41  THPAD PXE1110B_QFN-IC,H89187-001   I229 @BASEBOARD_FAB2_LIB.BASEBOARD_FAB2(SCH_1):PAGE235
 C7A30    2      B CAP_0805LF-22UF,4V,20%,X6S,C95A     I9 @BASEBOARD_FAB2_LIB.BASEBOARD_FAB2(SCH_1):PAGE236
  C7A8    2      B CAP_0402-0.22UF,16V,10%,X7R,A3A    I16 @BASEBOARD_FAB2_LIB.BASEBOARD_FAB2(SCH_1):PAGE236
  C3L1    2      B CAP_A_0402V-1.0UF,6.3V,10%,X6SA    I17 @BASEBOARD_FAB2_LIB.BASEBOARD_FAB2(SCH_1):PAGE236
  C7A6    2      B CAP_0402-1.0UF,16V,10%,X6S,D97A    I19 @BASEBOARD_FAB2_LIB.BASEBOARD_FAB2(SCH_1):PAGE236
 C7A39    2      B CAP_A_0402V-0.1UF,16V,10%,X7R,A    I20 @BASEBOARD_FAB2_LIB.BASEBOARD_FAB2(SCH_1):PAGE236
  C7A7    2      B CAP_0402-1.0UF,16V,10%,X6S,D97A    I22 @BASEBOARD_FAB2_LIB.BASEBOARD_FAB2(SCH_1):PAGE236
 C3L12    2      B CAP_0805-10UF,16V,10%,X6S,C953A    I23 @BASEBOARD_FAB2_LIB.BASEBOARD_FAB2(SCH_1):PAGE236
 C3L11    2      B CAP_0805-10UF,16V,10%,X6S,C953A    I24 @BASEBOARD_FAB2_LIB.BASEBOARD_FAB2(SCH_1):PAGE236
  C3L8    2      B CAP_0805-10UF,16V,10%,X6S,C953A    I26 @BASEBOARD_FAB2_LIB.BASEBOARD_FAB2(SCH_1):PAGE236
  C3L9    2      B CAP_0805-10UF,16V,10%,X6S,C953A    I29 @BASEBOARD_FAB2_LIB.BASEBOARD_FAB2(SCH_1):PAGE236
  C3L7    2      B CAP_0805-10UF,16V,10%,X6S,C953A    I31 @BASEBOARD_FAB2_LIB.BASEBOARD_FAB2(SCH_1):PAGE236
 C3L10    2      B CAP_0805-10UF,16V,10%,X6S,C953A    I32 @BASEBOARD_FAB2_LIB.BASEBOARD_FAB2(SCH_1):PAGE236
  C7A9    2      B CAP_0402-1.0UF,16V,10%,X6S,D97A    I33 @BASEBOARD_FAB2_LIB.BASEBOARD_FAB2(SCH_1):PAGE236
 C7A40    2      B CAP_A_0402V-0.1UF,16V,10%,X7R,A    I35 @BASEBOARD_FAB2_LIB.BASEBOARD_FAB2(SCH_1):PAGE236
 C7A10    2      B CAP_0402-1.0UF,16V,10%,X6S,D97A    I36 @BASEBOARD_FAB2_LIB.BASEBOARD_FAB2(SCH_1):PAGE236
 C3L29    2      B CAP_A_0402V-1.0UF,6.3V,10%,X6SA    I38 @BASEBOARD_FAB2_LIB.BASEBOARD_FAB2(SCH_1):PAGE236
 C7A41    2      B CAP_0402-0.22UF,16V,10%,X7R,A3A    I39 @BASEBOARD_FAB2_LIB.BASEBOARD_FAB2(SCH_1):PAGE236
 C7A42    2      B CAP_0805LF-22UF,4V,20%,X6S,C95A    I46 @BASEBOARD_FAB2_LIB.BASEBOARD_FAB2(SCH_1):PAGE236
 R8B12    2      B RES_0402-0.0,5%,1/16W,CHIP,G21A    I59 @BASEBOARD_FAB2_LIB.BASEBOARD_FAB2(SCH_1):PAGE236
 C7A13    2      B CAP_1210-100UF,16V,20%,X5R,644A    I63 @BASEBOARD_FAB2_LIB.BASEBOARD_FAB2(SCH_1):PAGE236
 C7A14    2      B CAP_1210-100UF,16V,20%,X5R,644A    I65 @BASEBOARD_FAB2_LIB.BASEBOARD_FAB2(SCH_1):PAGE236
 C3L18    2      B CAPP_SM-470UF,2V,20%,ALUM,6990A    I71 @BASEBOARD_FAB2_LIB.BASEBOARD_FAB2(SCH_1):PAGE236
 C3L20    2      B CAPP_SM-470UF,2V,20%,ALUM,6990A    I73 @BASEBOARD_FAB2_LIB.BASEBOARD_FAB2(SCH_1):PAGE236
 C3L21    2      B CAPP_SM-470UF,2V,20%,ALUM,6990A    I74 @BASEBOARD_FAB2_LIB.BASEBOARD_FAB2(SCH_1):PAGE236
 C7A27    2      B CAPP_SM-470UF,2V,20%,ALUM,6990A    I75 @BASEBOARD_FAB2_LIB.BASEBOARD_FAB2(SCH_1):PAGE236
 C3L19    2      B CAPP_SM-470UF,2V,20%,ALUM,6990A    I76 @BASEBOARD_FAB2_LIB.BASEBOARD_FAB2(SCH_1):PAGE236
 C2L46    2      B CAPP_SM-470UF,2V,20%,ALUM,6990A    I77 @BASEBOARD_FAB2_LIB.BASEBOARD_FAB2(SCH_1):PAGE236
 C8A15    2      B CAPP_SM-470UF,2V,20%,ALUM,6990A    I78 @BASEBOARD_FAB2_LIB.BASEBOARD_FAB2(SCH_1):PAGE236
 C2L25    2      B CAPP_SM-470UF,2V,20%,ALUM,6990A    I79 @BASEBOARD_FAB2_LIB.BASEBOARD_FAB2(SCH_1):PAGE236
 R7A18    1      A RES_0402-0.0,5%,1/16W,CHIP,G21A    I92 @BASEBOARD_FAB2_LIB.BASEBOARD_FAB2(SCH_1):PAGE236
 EU7A3    2   LGND IR354XX_SM-IR35412,IC,H73684-0A   I116 @BASEBOARD_FAB2_LIB.BASEBOARD_FAB2(SCH_1):PAGE236
 EU7A3    5 PGND<0> IR354XX_SM-IR35412,IC,H73684-0A   I116 @BASEBOARD_FAB2_LIB.BASEBOARD_FAB2(SCH_1):PAGE236
 EU7A3    7 PGND<1> IR354XX_SM-IR35412,IC,H73684-0A   I116 @BASEBOARD_FAB2_LIB.BASEBOARD_FAB2(SCH_1):PAGE236
 EU7A3   40 PGND<2> IR354XX_SM-IR35412,IC,H73684-0A   I116 @BASEBOARD_FAB2_LIB.BASEBOARD_FAB2(SCH_1):PAGE236
 EU7A2    2   LGND IR354XX_SM-IR35412,IC,H73684-0A   I117 @BASEBOARD_FAB2_LIB.BASEBOARD_FAB2(SCH_1):PAGE236
 EU7A2    5 PGND<0> IR354XX_SM-IR35412,IC,H73684-0A   I117 @BASEBOARD_FAB2_LIB.BASEBOARD_FAB2(SCH_1):PAGE236
 EU7A2    7 PGND<1> IR354XX_SM-IR35412,IC,H73684-0A   I117 @BASEBOARD_FAB2_LIB.BASEBOARD_FAB2(SCH_1):PAGE236
 EU7A2   40 PGND<2> IR354XX_SM-IR35412,IC,H73684-0A   I117 @BASEBOARD_FAB2_LIB.BASEBOARD_FAB2(SCH_1):PAGE236
 R3L15    2      B RES_0402-68.1K,1%,1/16W,EMPTY,A   I118 @BASEBOARD_FAB2_LIB.BASEBOARD_FAB2(SCH_1):PAGE236
 R3L14    2      B RES_0402-68.1K,1%,1/16W,EMPTY,A   I120 @BASEBOARD_FAB2_LIB.BASEBOARD_FAB2(SCH_1):PAGE236
 C8A11    2      B CAP_0402LF-1000PF,50V,10%,X7R,A     I5 @BASEBOARD_FAB2_LIB.BASEBOARD_FAB2(SCH_1):PAGE237
 C2L45    2      B CAP_0805-22UF,6.3V,20%,X6S,C95A    I12 @BASEBOARD_FAB2_LIB.BASEBOARD_FAB2(SCH_1):PAGE237
 C8A14    2      B CAP_0805-22UF,6.3V,20%,X6S,C95A    I13 @BASEBOARD_FAB2_LIB.BASEBOARD_FAB2(SCH_1):PAGE237
 R8A12    2      B RES_0603-475.0,1%,1/10W,CHIP,GA    I15 @BASEBOARD_FAB2_LIB.BASEBOARD_FAB2(SCH_1):PAGE237
  C8A6    2      B CAP_0603-10UF,6.3V,20%,X6S,E15A    I29 @BASEBOARD_FAB2_LIB.BASEBOARD_FAB2(SCH_1):PAGE237
  C8A4    2      B CAP_0603LF-0.1UF,25V,10%,X7R,6A    I31 @BASEBOARD_FAB2_LIB.BASEBOARD_FAB2(SCH_1):PAGE237
 C8A10    2      B CAP_0402LF-1000PF,50V,10%,EMPTA    I55 @BASEBOARD_FAB2_LIB.BASEBOARD_FAB2(SCH_1):PAGE237
 C8A12    2      B CAP_0805-47UF,4V,20%,X6S,C9533A    I77 @BASEBOARD_FAB2_LIB.BASEBOARD_FAB2(SCH_1):PAGE237
 C2L32    2      B CAP_0805-47UF,4V,20%,X6S,C9533A    I79 @BASEBOARD_FAB2_LIB.BASEBOARD_FAB2(SCH_1):PAGE237
 R2L19    2      B RES_0402-49.9K,1%,1/16W,CHIP,GA    I80 @BASEBOARD_FAB2_LIB.BASEBOARD_FAB2(SCH_1):PAGE237
 EU8A2   11    GND RT9059_DFN-IC,H65765-001    I86 @BASEBOARD_FAB2_LIB.BASEBOARD_FAB2(SCH_1):PAGE237
  C9F9    2      B CAP_0402LF-1000PF,50V,10%,EMPTA     I5 @BASEBOARD_FAB2_LIB.BASEBOARD_FAB2(SCH_1):PAGE238
  C9F3    2      B CAP_0603-10UF,6.3V,20%,X6S,E15A     I7 @BASEBOARD_FAB2_LIB.BASEBOARD_FAB2(SCH_1):PAGE238
  R9F8    1      A RES_0402-10.0K,1%,1/16W,CHIP,GA    I14 @BASEBOARD_FAB2_LIB.BASEBOARD_FAB2(SCH_1):PAGE238
  C9F8    2      B CAP_0402LF-1000PF,50V,10%,X7R,A    I19 @BASEBOARD_FAB2_LIB.BASEBOARD_FAB2(SCH_1):PAGE238
 C9E10    2      B CAP_0603-10UF,6.3V,20%,X6S,E15A    I23 @BASEBOARD_FAB2_LIB.BASEBOARD_FAB2(SCH_1):PAGE238
  C9F4    2      B CAP_0805LF-22UF,4V,20%,X6S,C95A    I30 @BASEBOARD_FAB2_LIB.BASEBOARD_FAB2(SCH_1):PAGE238
 C9E11    2      B CAP_0402-1.0UF,16V,10%,X6S,D97A    I39 @BASEBOARD_FAB2_LIB.BASEBOARD_FAB2(SCH_1):PAGE238
 EU9F1   11    GND RT9059_DFN-IC,H65765-001    I40 @BASEBOARD_FAB2_LIB.BASEBOARD_FAB2(SCH_1):PAGE238
 C9F10    2      B CAP_0402LF-1000PF,50V,10%,X7R,A     I4 @BASEBOARD_FAB2_LIB.BASEBOARD_FAB2(SCH_1):PAGE239
 C9F13    2      B CAP_0805LF-22UF,4V,20%,X6S,C95A     I7 @BASEBOARD_FAB2_LIB.BASEBOARD_FAB2(SCH_1):PAGE239
 C1T15    2      B CAP_0603-10UF,6.3V,20%,X6S,E15A    I12 @BASEBOARD_FAB2_LIB.BASEBOARD_FAB2(SCH_1):PAGE239
 R9F32    1      A RES_0402-13K,1.0%,1/16W,CHIP,GA    I15 @BASEBOARD_FAB2_LIB.BASEBOARD_FAB2(SCH_1):PAGE239
  C1T7    2      B CAP_0603-10UF,6.3V,20%,X6S,E15A    I22 @BASEBOARD_FAB2_LIB.BASEBOARD_FAB2(SCH_1):PAGE239
  C9F6    2      B CAP_0402LF-1000PF,50V,10%,EMPTA    I30 @BASEBOARD_FAB2_LIB.BASEBOARD_FAB2(SCH_1):PAGE239
 EU9F2   11    GND RT9059_DFN-IC,H65765-001    I70 @BASEBOARD_FAB2_LIB.BASEBOARD_FAB2(SCH_1):PAGE239
  C9F5    2      B CAP_A_0402V-0.1UF,16V,10%,X7R,A    I71 @BASEBOARD_FAB2_LIB.BASEBOARD_FAB2(SCH_1):PAGE239
  R8F1    2      B RES_0402-10.0K,1%,1/16W,EMPTY,A   I111 @BASEBOARD_FAB2_LIB.BASEBOARD_FAB2(SCH_1):PAGE240
  C8F2    2      B CAP_0402LF-1000PF,50V,10%,X7R,A   I116 @BASEBOARD_FAB2_LIB.BASEBOARD_FAB2(SCH_1):PAGE240
  C9F1    2      B CAP_1210-47UF,16V,20%,X6S,D384A   I134 @BASEBOARD_FAB2_LIB.BASEBOARD_FAB2(SCH_1):PAGE240
 C8E11    2      B CAP_1210-47UF,16V,20%,X6S,D384A   I135 @BASEBOARD_FAB2_LIB.BASEBOARD_FAB2(SCH_1):PAGE240
 C8E10    2      B CAP_1206LF-22UF,16V,10%,X6S,D3A   I137 @BASEBOARD_FAB2_LIB.BASEBOARD_FAB2(SCH_1):PAGE240
 C8E14    2      B CAP_0402-1.0UF,16V,10%,X6S,D97A   I139 @BASEBOARD_FAB2_LIB.BASEBOARD_FAB2(SCH_1):PAGE240
 R8F11    1      A RES_0402-0.0,5%,1/16W,CHIP,G21A   I146 @BASEBOARD_FAB2_LIB.BASEBOARD_FAB2(SCH_1):PAGE240
  R8F3    2      B RES_0402-2.2,5%,1/16W,EMPTY,G2A   I148 @BASEBOARD_FAB2_LIB.BASEBOARD_FAB2(SCH_1):PAGE240
  R2T4    2      B RES_0402-1.0K,0.1%,1/16W,CHIP,A   I152 @BASEBOARD_FAB2_LIB.BASEBOARD_FAB2(SCH_1):PAGE240
 C8F14    2      B CAPP_3018-470UF,6.3V,20%,POSCAA   I154 @BASEBOARD_FAB2_LIB.BASEBOARD_FAB2(SCH_1):PAGE240
  C8F8    2      B CAPP_3018-470UF,6.3V,20%,POSCAA   I155 @BASEBOARD_FAB2_LIB.BASEBOARD_FAB2(SCH_1):PAGE240
  C2T7    2      B CAP_0805-22UF,6.3V,20%,X6S,C95A   I158 @BASEBOARD_FAB2_LIB.BASEBOARD_FAB2(SCH_1):PAGE240
  C2T6    2      B CAP_0805-22UF,6.3V,20%,X6S,C95A   I160 @BASEBOARD_FAB2_LIB.BASEBOARD_FAB2(SCH_1):PAGE240
 EU8E1    3   PGND CSD87384M_SM-IC,H66258-001   I170 @BASEBOARD_FAB2_LIB.BASEBOARD_FAB2(SCH_1):PAGE240
  C2T9    2      B CAP_0805-22UF,6.3V,20%,X6S,C95A   I174 @BASEBOARD_FAB2_LIB.BASEBOARD_FAB2(SCH_1):PAGE240
  C8E9    2      B CAP_0805-22UF,6.3V,20%,X6S,C95A     I2 @BASEBOARD_FAB2_LIB.BASEBOARD_FAB2(SCH_1):PAGE241
  C8E7    2      B CAP_0805-22UF,6.3V,20%,X6S,C95A     I3 @BASEBOARD_FAB2_LIB.BASEBOARD_FAB2(SCH_1):PAGE241
  C8E4    2      B CAPP_3018-470UF,6.3V,20%,POSCAA     I8 @BASEBOARD_FAB2_LIB.BASEBOARD_FAB2(SCH_1):PAGE241
 R8E18    2      B RES_0402-1.0K,0.1%,1/16W,CHIP,A     I9 @BASEBOARD_FAB2_LIB.BASEBOARD_FAB2(SCH_1):PAGE241
 C7E10    2      B CAP_0402LF-1000PF,50V,10%,X7R,A    I14 @BASEBOARD_FAB2_LIB.BASEBOARD_FAB2(SCH_1):PAGE241
 C7E14    2      B CAP_0402-1.0UF,16V,10%,X6S,D97A    I30 @BASEBOARD_FAB2_LIB.BASEBOARD_FAB2(SCH_1):PAGE241
 C7E11    2      B CAP_1206LF-22UF,16V,10%,X6S,D3A    I39 @BASEBOARD_FAB2_LIB.BASEBOARD_FAB2(SCH_1):PAGE241
 C7E13    2      B CAP_1210-47UF,16V,20%,X6S,D384A    I45 @BASEBOARD_FAB2_LIB.BASEBOARD_FAB2(SCH_1):PAGE241
 C7E12    2      B CAP_1210-47UF,16V,20%,X6S,D384A    I47 @BASEBOARD_FAB2_LIB.BASEBOARD_FAB2(SCH_1):PAGE241
 R7E13    1      A RES_0402-0.0,5%,1/16W,CHIP,G21A    I58 @BASEBOARD_FAB2_LIB.BASEBOARD_FAB2(SCH_1):PAGE241
 EU7E2    2 GND<0> TPS54821_LCC-IC,H63269-001    I83 @BASEBOARD_FAB2_LIB.BASEBOARD_FAB2(SCH_1):PAGE241
 EU7E2    3 GND<1> TPS54821_LCC-IC,H63269-001    I83 @BASEBOARD_FAB2_LIB.BASEBOARD_FAB2(SCH_1):PAGE241
 EU7E2   15  THPAD TPS54821_LCC-IC,H63269-001    I83 @BASEBOARD_FAB2_LIB.BASEBOARD_FAB2(SCH_1):PAGE241
 C5G21    2      B CAP_0805-100UF,4V,20%,X5R,6024A    I11 @BASEBOARD_FAB2_LIB.BASEBOARD_FAB2(SCH_1):PAGE242
 C5G22    2      B CAP_0805-100UF,4V,20%,X5R,6024A    I15 @BASEBOARD_FAB2_LIB.BASEBOARD_FAB2(SCH_1):PAGE242
 C5G77    2      B CAP_0805-100UF,4V,20%,X5R,6024A    I37 @BASEBOARD_FAB2_LIB.BASEBOARD_FAB2(SCH_1):PAGE242
 C5G78    2      B CAP_0805-100UF,4V,20%,X5R,6024A    I41 @BASEBOARD_FAB2_LIB.BASEBOARD_FAB2(SCH_1):PAGE242
C5G117    2      B CAP_0805-100UF,4V,20%,X5R,6024A    I12 @BASEBOARD_FAB2_LIB.BASEBOARD_FAB2(SCH_1):PAGE243
C5G118    2      B CAP_0805-100UF,4V,20%,X5R,6024A    I13 @BASEBOARD_FAB2_LIB.BASEBOARD_FAB2(SCH_1):PAGE243
C5G115    2      B CAP_0805-100UF,4V,20%,X5R,6024A    I39 @BASEBOARD_FAB2_LIB.BASEBOARD_FAB2(SCH_1):PAGE243
C5G116    2      B CAP_0805-100UF,4V,20%,X5R,6024A    I43 @BASEBOARD_FAB2_LIB.BASEBOARD_FAB2(SCH_1):PAGE243
 C5G41    2      B CAP_A_0603V-22.0UF,4V,20%,X6S,A    I53 @BASEBOARD_FAB2_LIB.BASEBOARD_FAB2(SCH_1):PAGE242
 C5G42    2      B CAP_A_0603V-22.0UF,4V,20%,X6S,A    I54 @BASEBOARD_FAB2_LIB.BASEBOARD_FAB2(SCH_1):PAGE242
 C5G44    2      B CAP_A_0603V-22.0UF,4V,20%,X6S,A    I55 @BASEBOARD_FAB2_LIB.BASEBOARD_FAB2(SCH_1):PAGE242
 C5G43    2      B CAP_A_0603V-22.0UF,4V,20%,X6S,A    I56 @BASEBOARD_FAB2_LIB.BASEBOARD_FAB2(SCH_1):PAGE242
 C5G48    2      B CAP_A_0603V-22.0UF,4V,20%,X6S,A    I57 @BASEBOARD_FAB2_LIB.BASEBOARD_FAB2(SCH_1):PAGE242
 C5G47    2      B CAP_A_0603V-22.0UF,4V,20%,X6S,A    I58 @BASEBOARD_FAB2_LIB.BASEBOARD_FAB2(SCH_1):PAGE242
 C5G46    2      B CAP_A_0603V-22.0UF,4V,20%,X6S,A    I59 @BASEBOARD_FAB2_LIB.BASEBOARD_FAB2(SCH_1):PAGE242
 C5G45    2      B CAP_A_0603V-22.0UF,4V,20%,X6S,A    I60 @BASEBOARD_FAB2_LIB.BASEBOARD_FAB2(SCH_1):PAGE242
 C5G49    2      B CAP_A_0603V-22.0UF,4V,20%,X6S,A    I61 @BASEBOARD_FAB2_LIB.BASEBOARD_FAB2(SCH_1):PAGE242
 C5G54    2      B CAP_A_0603V-22.0UF,4V,20%,X6S,A    I62 @BASEBOARD_FAB2_LIB.BASEBOARD_FAB2(SCH_1):PAGE242
 C5G58    2      B CAP_A_0603V-22.0UF,4V,20%,X6S,A    I63 @BASEBOARD_FAB2_LIB.BASEBOARD_FAB2(SCH_1):PAGE242
 C5G57    2      B CAP_A_0603V-22.0UF,4V,20%,X6S,A    I64 @BASEBOARD_FAB2_LIB.BASEBOARD_FAB2(SCH_1):PAGE242
 C5G56    2      B CAP_A_0603V-22.0UF,4V,20%,X6S,A    I65 @BASEBOARD_FAB2_LIB.BASEBOARD_FAB2(SCH_1):PAGE242
 C5G55    2      B CAP_A_0603V-22.0UF,4V,20%,X6S,A    I66 @BASEBOARD_FAB2_LIB.BASEBOARD_FAB2(SCH_1):PAGE242
 C5G53    2      B CAP_A_0603V-22.0UF,4V,20%,X6S,A    I67 @BASEBOARD_FAB2_LIB.BASEBOARD_FAB2(SCH_1):PAGE242
 C5G52    2      B CAP_A_0603V-22.0UF,4V,20%,X6S,A    I68 @BASEBOARD_FAB2_LIB.BASEBOARD_FAB2(SCH_1):PAGE242
 C5G51    2      B CAP_A_0603V-22.0UF,4V,20%,X6S,A    I69 @BASEBOARD_FAB2_LIB.BASEBOARD_FAB2(SCH_1):PAGE242
 C5G50    2      B CAP_A_0603V-22.0UF,4V,20%,X6S,A    I70 @BASEBOARD_FAB2_LIB.BASEBOARD_FAB2(SCH_1):PAGE242
 C5G67    2      B CAP_A_0603V-22.0UF,4V,20%,X6S,A    I71 @BASEBOARD_FAB2_LIB.BASEBOARD_FAB2(SCH_1):PAGE242
 C5G66    2      B CAP_A_0603V-22.0UF,4V,20%,X6S,A    I72 @BASEBOARD_FAB2_LIB.BASEBOARD_FAB2(SCH_1):PAGE242
 C5G65    2      B CAP_A_0603V-22.0UF,4V,20%,X6S,A    I73 @BASEBOARD_FAB2_LIB.BASEBOARD_FAB2(SCH_1):PAGE242
 C5G64    2      B CAP_A_0603V-22.0UF,4V,20%,X6S,A    I74 @BASEBOARD_FAB2_LIB.BASEBOARD_FAB2(SCH_1):PAGE242
 C5G63    2      B CAP_A_0603V-22.0UF,4V,20%,X6S,A    I75 @BASEBOARD_FAB2_LIB.BASEBOARD_FAB2(SCH_1):PAGE242
 C5G62    2      B CAP_A_0603V-22.0UF,4V,20%,X6S,A    I76 @BASEBOARD_FAB2_LIB.BASEBOARD_FAB2(SCH_1):PAGE242
 C5G61    2      B CAP_A_0603V-22.0UF,4V,20%,X6S,A    I77 @BASEBOARD_FAB2_LIB.BASEBOARD_FAB2(SCH_1):PAGE242
 C5G60    2      B CAP_A_0603V-22.0UF,4V,20%,X6S,A    I78 @BASEBOARD_FAB2_LIB.BASEBOARD_FAB2(SCH_1):PAGE242
 C5G59    2      B CAP_A_0603V-22.0UF,4V,20%,X6S,A    I79 @BASEBOARD_FAB2_LIB.BASEBOARD_FAB2(SCH_1):PAGE242
 C5G76    2      B CAP_A_0603V-22.0UF,4V,20%,X6S,A    I80 @BASEBOARD_FAB2_LIB.BASEBOARD_FAB2(SCH_1):PAGE242
 C5G75    2      B CAP_A_0603V-22.0UF,4V,20%,X6S,A    I81 @BASEBOARD_FAB2_LIB.BASEBOARD_FAB2(SCH_1):PAGE242
 C5G74    2      B CAP_A_0603V-22.0UF,4V,20%,X6S,A    I82 @BASEBOARD_FAB2_LIB.BASEBOARD_FAB2(SCH_1):PAGE242
 C5G73    2      B CAP_A_0603V-22.0UF,4V,20%,X6S,A    I83 @BASEBOARD_FAB2_LIB.BASEBOARD_FAB2(SCH_1):PAGE242
 C5G72    2      B CAP_A_0603V-22.0UF,4V,20%,X6S,A    I84 @BASEBOARD_FAB2_LIB.BASEBOARD_FAB2(SCH_1):PAGE242
 C5G71    2      B CAP_A_0603V-22.0UF,4V,20%,X6S,A    I85 @BASEBOARD_FAB2_LIB.BASEBOARD_FAB2(SCH_1):PAGE242
 C5G70    2      B CAP_A_0603V-22.0UF,4V,20%,X6S,A    I86 @BASEBOARD_FAB2_LIB.BASEBOARD_FAB2(SCH_1):PAGE242
 C5G69    2      B CAP_A_0603V-22.0UF,4V,20%,X6S,A    I87 @BASEBOARD_FAB2_LIB.BASEBOARD_FAB2(SCH_1):PAGE242
 C5G68    2      B CAP_A_0603V-22.0UF,4V,20%,X6S,A    I88 @BASEBOARD_FAB2_LIB.BASEBOARD_FAB2(SCH_1):PAGE242
 C5G79    2      B CAP_A_0603V-22.0UF,4V,20%,X6S,A    I53 @BASEBOARD_FAB2_LIB.BASEBOARD_FAB2(SCH_1):PAGE243
 C5G87    2      B CAP_A_0603V-22.0UF,4V,20%,X6S,A    I54 @BASEBOARD_FAB2_LIB.BASEBOARD_FAB2(SCH_1):PAGE243
 C5G86    2      B CAP_A_0603V-22.0UF,4V,20%,X6S,A    I55 @BASEBOARD_FAB2_LIB.BASEBOARD_FAB2(SCH_1):PAGE243
 C5G85    2      B CAP_A_0603V-22.0UF,4V,20%,X6S,A    I56 @BASEBOARD_FAB2_LIB.BASEBOARD_FAB2(SCH_1):PAGE243
 C5G84    2      B CAP_A_0603V-22.0UF,4V,20%,X6S,A    I57 @BASEBOARD_FAB2_LIB.BASEBOARD_FAB2(SCH_1):PAGE243
 C5G83    2      B CAP_A_0603V-22.0UF,4V,20%,X6S,A    I58 @BASEBOARD_FAB2_LIB.BASEBOARD_FAB2(SCH_1):PAGE243
 C5G82    2      B CAP_A_0603V-22.0UF,4V,20%,X6S,A    I59 @BASEBOARD_FAB2_LIB.BASEBOARD_FAB2(SCH_1):PAGE243
 C5G81    2      B CAP_A_0603V-22.0UF,4V,20%,X6S,A    I60 @BASEBOARD_FAB2_LIB.BASEBOARD_FAB2(SCH_1):PAGE243
 C5G80    2      B CAP_A_0603V-22.0UF,4V,20%,X6S,A    I61 @BASEBOARD_FAB2_LIB.BASEBOARD_FAB2(SCH_1):PAGE243
 C5G96    2      B CAP_A_0603V-22.0UF,4V,20%,X6S,A    I62 @BASEBOARD_FAB2_LIB.BASEBOARD_FAB2(SCH_1):PAGE243
 C5G95    2      B CAP_A_0603V-22.0UF,4V,20%,X6S,A    I63 @BASEBOARD_FAB2_LIB.BASEBOARD_FAB2(SCH_1):PAGE243
 C5G94    2      B CAP_A_0603V-22.0UF,4V,20%,X6S,A    I64 @BASEBOARD_FAB2_LIB.BASEBOARD_FAB2(SCH_1):PAGE243
 C5G93    2      B CAP_A_0603V-22.0UF,4V,20%,X6S,A    I65 @BASEBOARD_FAB2_LIB.BASEBOARD_FAB2(SCH_1):PAGE243
 C5G92    2      B CAP_A_0603V-22.0UF,4V,20%,X6S,A    I66 @BASEBOARD_FAB2_LIB.BASEBOARD_FAB2(SCH_1):PAGE243
 C5G91    2      B CAP_A_0603V-22.0UF,4V,20%,X6S,A    I67 @BASEBOARD_FAB2_LIB.BASEBOARD_FAB2(SCH_1):PAGE243
 C5G90    2      B CAP_A_0603V-22.0UF,4V,20%,X6S,A    I68 @BASEBOARD_FAB2_LIB.BASEBOARD_FAB2(SCH_1):PAGE243
 C5G89    2      B CAP_A_0603V-22.0UF,4V,20%,X6S,A    I69 @BASEBOARD_FAB2_LIB.BASEBOARD_FAB2(SCH_1):PAGE243
 C5G88    2      B CAP_A_0603V-22.0UF,4V,20%,X6S,A    I70 @BASEBOARD_FAB2_LIB.BASEBOARD_FAB2(SCH_1):PAGE243
C5G103    2      B CAP_A_0603V-22.0UF,4V,20%,X6S,A    I71 @BASEBOARD_FAB2_LIB.BASEBOARD_FAB2(SCH_1):PAGE243
C5G104    2      B CAP_A_0603V-22.0UF,4V,20%,X6S,A    I72 @BASEBOARD_FAB2_LIB.BASEBOARD_FAB2(SCH_1):PAGE243
C5G105    2      B CAP_A_0603V-22.0UF,4V,20%,X6S,A    I73 @BASEBOARD_FAB2_LIB.BASEBOARD_FAB2(SCH_1):PAGE243
C5G102    2      B CAP_A_0603V-22.0UF,4V,20%,X6S,A    I74 @BASEBOARD_FAB2_LIB.BASEBOARD_FAB2(SCH_1):PAGE243
C5G101    2      B CAP_A_0603V-22.0UF,4V,20%,X6S,A    I75 @BASEBOARD_FAB2_LIB.BASEBOARD_FAB2(SCH_1):PAGE243
C5G100    2      B CAP_A_0603V-22.0UF,4V,20%,X6S,A    I76 @BASEBOARD_FAB2_LIB.BASEBOARD_FAB2(SCH_1):PAGE243
 C5G99    2      B CAP_A_0603V-22.0UF,4V,20%,X6S,A    I77 @BASEBOARD_FAB2_LIB.BASEBOARD_FAB2(SCH_1):PAGE243
 C5G98    2      B CAP_A_0603V-22.0UF,4V,20%,X6S,A    I78 @BASEBOARD_FAB2_LIB.BASEBOARD_FAB2(SCH_1):PAGE243
 C5G97    2      B CAP_A_0603V-22.0UF,4V,20%,X6S,A    I79 @BASEBOARD_FAB2_LIB.BASEBOARD_FAB2(SCH_1):PAGE243
C5G114    2      B CAP_A_0603V-22.0UF,4V,20%,X6S,A    I80 @BASEBOARD_FAB2_LIB.BASEBOARD_FAB2(SCH_1):PAGE243
C5G113    2      B CAP_A_0603V-22.0UF,4V,20%,X6S,A    I81 @BASEBOARD_FAB2_LIB.BASEBOARD_FAB2(SCH_1):PAGE243
C5G112    2      B CAP_A_0603V-22.0UF,4V,20%,X6S,A    I82 @BASEBOARD_FAB2_LIB.BASEBOARD_FAB2(SCH_1):PAGE243
C5G111    2      B CAP_A_0603V-22.0UF,4V,20%,X6S,A    I83 @BASEBOARD_FAB2_LIB.BASEBOARD_FAB2(SCH_1):PAGE243
C5G110    2      B CAP_A_0603V-22.0UF,4V,20%,X6S,A    I84 @BASEBOARD_FAB2_LIB.BASEBOARD_FAB2(SCH_1):PAGE243
C5G109    2      B CAP_A_0603V-22.0UF,4V,20%,X6S,A    I85 @BASEBOARD_FAB2_LIB.BASEBOARD_FAB2(SCH_1):PAGE243
C5G108    2      B CAP_A_0603V-22.0UF,4V,20%,X6S,A    I86 @BASEBOARD_FAB2_LIB.BASEBOARD_FAB2(SCH_1):PAGE243
C5G107    2      B CAP_A_0603V-22.0UF,4V,20%,X6S,A    I87 @BASEBOARD_FAB2_LIB.BASEBOARD_FAB2(SCH_1):PAGE243
C5G106    2      B CAP_A_0603V-22.0UF,4V,20%,X6S,A    I88 @BASEBOARD_FAB2_LIB.BASEBOARD_FAB2(SCH_1):PAGE243
   CT1    2      B CAP_A_0402V-0.1UF,16V,10%,X7R,A    I70 @BASEBOARD_FAB2_LIB.BASEBOARD_FAB2(SCH_1):PAGE202
   CT2    2      B CAP_0402LF-1000PF,50V,10%,X7R,A    I78 @BASEBOARD_FAB2_LIB.BASEBOARD_FAB2(SCH_1):PAGE202
   CT6    2      B CAP_A_0402V-0.1UF,16V,10%,X7R,A    I81 @BASEBOARD_FAB2_LIB.BASEBOARD_FAB2(SCH_1):PAGE202
   CT7    2      B CAP_A_0402V-0.1UF,16V,10%,X7R,A   I109 @BASEBOARD_FAB2_LIB.BASEBOARD_FAB2(SCH_1):PAGE227
   CT8    2      B CAP_0402LF-1000PF,50V,10%,X7R,A   I114 @BASEBOARD_FAB2_LIB.BASEBOARD_FAB2(SCH_1):PAGE227
  CT10    2      B CAP_0402LF-1000PF,50V,10%,X7R,A   I119 @BASEBOARD_FAB2_LIB.BASEBOARD_FAB2(SCH_1):PAGE227
  CT12    2      B CAP_A_0402V-0.1UF,16V,10%,X7R,A   I122 @BASEBOARD_FAB2_LIB.BASEBOARD_FAB2(SCH_1):PAGE227
  CT13    2      B CAP_A_0402V-0.1UF,16V,10%,X7R,A    I62 @BASEBOARD_FAB2_LIB.BASEBOARD_FAB2(SCH_1):PAGE209
  CT15    2      B CAP_0402LF-1000PF,50V,10%,X7R,A    I67 @BASEBOARD_FAB2_LIB.BASEBOARD_FAB2(SCH_1):PAGE209
  CT16    2      B CAP_A_0402V-0.1UF,16V,10%,X7R,A    I80 @BASEBOARD_FAB2_LIB.BASEBOARD_FAB2(SCH_1):PAGE208
  CTI7    2      B CAP_0402LF-1000PF,50V,10%,X7R,A    I82 @BASEBOARD_FAB2_LIB.BASEBOARD_FAB2(SCH_1):PAGE208
  CT21    2      B CAP_A_0402V-0.1UF,16V,10%,X7R,A    I87 @BASEBOARD_FAB2_LIB.BASEBOARD_FAB2(SCH_1):PAGE208
  CT19    2      B CAP_0402LF-1000PF,50V,10%,X7R,A    I90 @BASEBOARD_FAB2_LIB.BASEBOARD_FAB2(SCH_1):PAGE208
  CT24    2      B CAP_A_0402V-0.1UF,16V,10%,X7R,A    I71 @BASEBOARD_FAB2_LIB.BASEBOARD_FAB2(SCH_1):PAGE207
  CT22    2      B CAP_0402LF-1000PF,50V,10%,X7R,A    I74 @BASEBOARD_FAB2_LIB.BASEBOARD_FAB2(SCH_1):PAGE207
  CT30    2      B CAP_A_0402V-0.1UF,16V,10%,X7R,A   I117 @BASEBOARD_FAB2_LIB.BASEBOARD_FAB2(SCH_1):PAGE224
  CT28    2      B CAP_0402LF-1000PF,50V,10%,X7R,A   I122 @BASEBOARD_FAB2_LIB.BASEBOARD_FAB2(SCH_1):PAGE224
  CT31    2      B CAP_A_0402V-0.1UF,16V,10%,X7R,A   I124 @BASEBOARD_FAB2_LIB.BASEBOARD_FAB2(SCH_1):PAGE224
  CT32    2      B CAP_0402LF-1000PF,50V,10%,X7R,A   I130 @BASEBOARD_FAB2_LIB.BASEBOARD_FAB2(SCH_1):PAGE224
  CT36    2      B CAP_A_0402V-0.1UF,16V,10%,X7R,A    I85 @BASEBOARD_FAB2_LIB.BASEBOARD_FAB2(SCH_1):PAGE204
  CT34    2      B CAP_0402LF-1000PF,50V,10%,X7R,A    I88 @BASEBOARD_FAB2_LIB.BASEBOARD_FAB2(SCH_1):PAGE204
  CT40    2      B CAP_A_0402V-0.1UF,16V,10%,X7R,A    I93 @BASEBOARD_FAB2_LIB.BASEBOARD_FAB2(SCH_1):PAGE203
  CT39    2      B CAP_A_0402V-0.1UF,16V,10%,X7R,A    I96 @BASEBOARD_FAB2_LIB.BASEBOARD_FAB2(SCH_1):PAGE203
  CT37    2      B CAP_0402LF-1000PF,50V,10%,X7R,A    I99 @BASEBOARD_FAB2_LIB.BASEBOARD_FAB2(SCH_1):PAGE203
  CT42    2      B CAP_0402LF-1000PF,50V,10%,X7R,A   I108 @BASEBOARD_FAB2_LIB.BASEBOARD_FAB2(SCH_1):PAGE203
  CT46    2      B CAP_A_0402V-0.1UF,16V,10%,X7R,A   I113 @BASEBOARD_FAB2_LIB.BASEBOARD_FAB2(SCH_1):PAGE219
  CT45    2      B CAP_A_0402V-0.1UF,16V,10%,X7R,A   I116 @BASEBOARD_FAB2_LIB.BASEBOARD_FAB2(SCH_1):PAGE219
  CT48    2      B CAP_0402LF-1000PF,50V,10%,X7R,A   I119 @BASEBOARD_FAB2_LIB.BASEBOARD_FAB2(SCH_1):PAGE219
  CT43    2      B CAP_0402LF-1000PF,50V,10%,X7R,A   I124 @BASEBOARD_FAB2_LIB.BASEBOARD_FAB2(SCH_1):PAGE219
  CT51    2      B CAP_A_0402V-0.1UF,16V,10%,X7R,A   I108 @BASEBOARD_FAB2_LIB.BASEBOARD_FAB2(SCH_1):PAGE216
  CT52    2      B CAP_A_0402V-0.1UF,16V,10%,X7R,A   I111 @BASEBOARD_FAB2_LIB.BASEBOARD_FAB2(SCH_1):PAGE216
  CT49    2      B CAP_0402LF-1000PF,50V,10%,X7R,A   I118 @BASEBOARD_FAB2_LIB.BASEBOARD_FAB2(SCH_1):PAGE216
  CT54    2      B CAP_0402LF-1000PF,50V,10%,X7R,A   I121 @BASEBOARD_FAB2_LIB.BASEBOARD_FAB2(SCH_1):PAGE216
  CT57    2      B CAP_A_0402V-0.1UF,16V,10%,X7R,A    I55 @BASEBOARD_FAB2_LIB.BASEBOARD_FAB2(SCH_1):PAGE210
  CT55    2      B CAP_0402LF-1000PF,50V,10%,X7R,A    I60 @BASEBOARD_FAB2_LIB.BASEBOARD_FAB2(SCH_1):PAGE210
  CT58    2      B CAP_0402LF-1000PF,50V,10%,X7R,A    I65 @BASEBOARD_FAB2_LIB.BASEBOARD_FAB2(SCH_1):PAGE205
  CT60    2      B CAP_A_0402V-0.1UF,16V,10%,X7R,A    I69 @BASEBOARD_FAB2_LIB.BASEBOARD_FAB2(SCH_1):PAGE205
  CT61    2      B CAP_0402LF-1000PF,50V,10%,X7R,A   I134 @BASEBOARD_FAB2_LIB.BASEBOARD_FAB2(SCH_1):PAGE214
  CT63    2      B CAP_A_0402V-0.1UF,16V,10%,X7R,A   I137 @BASEBOARD_FAB2_LIB.BASEBOARD_FAB2(SCH_1):PAGE214
  CT67    2      B CAP_A_0402V-0.1UF,16V,10%,X7R,A   I124 @BASEBOARD_FAB2_LIB.BASEBOARD_FAB2(SCH_1):PAGE236
  CT66    2      B CAP_A_0402V-0.1UF,16V,10%,X7R,A   I127 @BASEBOARD_FAB2_LIB.BASEBOARD_FAB2(SCH_1):PAGE236
  CT69    2      B CAP_0402LF-1000PF,50V,10%,X7R,A   I134 @BASEBOARD_FAB2_LIB.BASEBOARD_FAB2(SCH_1):PAGE236
  CT64    2      B CAP_0402LF-1000PF,50V,10%,X7R,A   I136 @BASEBOARD_FAB2_LIB.BASEBOARD_FAB2(SCH_1):PAGE236
  CT70    2      B CAP_A_0402V-0.1UF,16V,10%,X7R,A   I106 @BASEBOARD_FAB2_LIB.BASEBOARD_FAB2(SCH_1):PAGE212
  CT71    2      B CAP_0402LF-1000PF,50V,10%,X7R,A   I109 @BASEBOARD_FAB2_LIB.BASEBOARD_FAB2(SCH_1):PAGE212
  CT25    2      B CAP_A_0402V-0.1UF,16V,10%,X7R,A    I81 @BASEBOARD_FAB2_LIB.BASEBOARD_FAB2(SCH_1):PAGE207
  CT26    2      B CAP_0402LF-1000PF,50V,10%,X7R,A    I82 @BASEBOARD_FAB2_LIB.BASEBOARD_FAB2(SCH_1):PAGE207
  RT10    1      1 3D01R5F-GP_SMD-RG5-3D01R5F-GP,A    I66 @BASEBOARD_FAB2_LIB.BASEBOARD_FAB2(SCH_1):PAGE209
   RT7    2      2 3D01R5F-GP_SMD-RG5-3D01R5F-GP,A   I124 @BASEBOARD_FAB2_LIB.BASEBOARD_FAB2(SCH_1):PAGE227
   RT6    2      2 3D01R5F-GP_SMD-RG5-3D01R5F-GP,A   I125 @BASEBOARD_FAB2_LIB.BASEBOARD_FAB2(SCH_1):PAGE227
  RT13    1      1 3D01R5F-GP_SMD-RG5-3D01R5F-GP,A    I94 @BASEBOARD_FAB2_LIB.BASEBOARD_FAB2(SCH_1):PAGE208
  RT12    1      1 3D01R5F-GP_SMD-RG5-3D01R5F-GP,A    I86 @BASEBOARD_FAB2_LIB.BASEBOARD_FAB2(SCH_1):PAGE208
  RT18    1      1 3D01R5F-GP_SMD-RG5-3D01R5F-GP,A    I85 @BASEBOARD_FAB2_LIB.BASEBOARD_FAB2(SCH_1):PAGE207
  RT16    1      1 3D01R5F-GP_SMD-RG5-3D01R5F-GP,A    I76 @BASEBOARD_FAB2_LIB.BASEBOARD_FAB2(SCH_1):PAGE207
  RT22    1      1 3D01R5F-GP_SMD-RG5-3D01R5F-GP,A   I129 @BASEBOARD_FAB2_LIB.BASEBOARD_FAB2(SCH_1):PAGE224
  RT20    1      1 3D01R5F-GP_SMD-RG5-3D01R5F-GP,A   I119 @BASEBOARD_FAB2_LIB.BASEBOARD_FAB2(SCH_1):PAGE224
  RT24    1      1 3D01R5F-GP_SMD-RG5-3D01R5F-GP,A    I91 @BASEBOARD_FAB2_LIB.BASEBOARD_FAB2(SCH_1):PAGE204
  RT27    1      1 3D01R5F-GP_SMD-RG5-3D01R5F-GP,A   I105 @BASEBOARD_FAB2_LIB.BASEBOARD_FAB2(SCH_1):PAGE203
  RT26    1      1 3D01R5F-GP_SMD-RG5-3D01R5F-GP,A   I102 @BASEBOARD_FAB2_LIB.BASEBOARD_FAB2(SCH_1):PAGE203
   RT4    1      1 3D01R5F-GP_SMD-RG5-3D01R5F-GP,A    I83 @BASEBOARD_FAB2_LIB.BASEBOARD_FAB2(SCH_1):PAGE202
   RT2    1      1 3D01R5F-GP_SMD-RG5-3D01R5F-GP,A    I75 @BASEBOARD_FAB2_LIB.BASEBOARD_FAB2(SCH_1):PAGE202
  RT29    1      1 3D01R5F-GP_SMD-RG5-3D01R5F-GP,A   I126 @BASEBOARD_FAB2_LIB.BASEBOARD_FAB2(SCH_1):PAGE219
  RT32    1      1 3D01R5F-GP_SMD-RG5-3D01R5F-GP,A   I123 @BASEBOARD_FAB2_LIB.BASEBOARD_FAB2(SCH_1):PAGE219
  RT34    1      1 3D01R5F-GP_SMD-RG5-3D01R5F-GP,A   I114 @BASEBOARD_FAB2_LIB.BASEBOARD_FAB2(SCH_1):PAGE216
  RT35    1      1 3D01R5F-GP_SMD-RG5-3D01R5F-GP,A   I123 @BASEBOARD_FAB2_LIB.BASEBOARD_FAB2(SCH_1):PAGE216
  RT38    1      1 3D01R5F-GP_SMD-RG5-3D01R5F-GP,A    I59 @BASEBOARD_FAB2_LIB.BASEBOARD_FAB2(SCH_1):PAGE210
  RT39    1      1 3D01R5F-GP_SMD-RG5-3D01R5F-GP,A    I68 @BASEBOARD_FAB2_LIB.BASEBOARD_FAB2(SCH_1):PAGE205
  RT42    1      1 3D01R5F-GP_SMD-RG5-3D01R5F-GP,A   I132 @BASEBOARD_FAB2_LIB.BASEBOARD_FAB2(SCH_1):PAGE214
  RT45    1      1 3D01R5F-GP_SMD-RG5-3D01R5F-GP,A   I137 @BASEBOARD_FAB2_LIB.BASEBOARD_FAB2(SCH_1):PAGE236
  RT43    1      1 3D01R5F-GP_SMD-RG5-3D01R5F-GP,A   I132 @BASEBOARD_FAB2_LIB.BASEBOARD_FAB2(SCH_1):PAGE236
  RT48    1      1 3D01R5F-GP_SMD-RG5-3D01R5F-GP,A   I112 @BASEBOARD_FAB2_LIB.BASEBOARD_FAB2(SCH_1):PAGE212
   CT4    2      B CAP_0402LF-1000PF,50V,10%,X7R,A    I87 @BASEBOARD_FAB2_LIB.BASEBOARD_FAB2(SCH_1):PAGE202
 CONX8    1      1 SMC-CONN60A-22-GP_CONN-G7-SMC-A    I48 @BASEBOARD_FAB2_LIB.BASEBOARD_FAB2(SCH_1):PAGE245
 CONX8    4      4 SMC-CONN60A-22-GP_CONN-G7-SMC-A    I48 @BASEBOARD_FAB2_LIB.BASEBOARD_FAB2(SCH_1):PAGE245
 CONX8    7      7 SMC-CONN60A-22-GP_CONN-G7-SMC-A    I48 @BASEBOARD_FAB2_LIB.BASEBOARD_FAB2(SCH_1):PAGE245
 CONX8   10     10 SMC-CONN60A-22-GP_CONN-G7-SMC-A    I48 @BASEBOARD_FAB2_LIB.BASEBOARD_FAB2(SCH_1):PAGE245
 CONX8   13     13 SMC-CONN60A-22-GP_CONN-G7-SMC-A    I48 @BASEBOARD_FAB2_LIB.BASEBOARD_FAB2(SCH_1):PAGE245
 CONX8   16     16 SMC-CONN60A-22-GP_CONN-G7-SMC-A    I48 @BASEBOARD_FAB2_LIB.BASEBOARD_FAB2(SCH_1):PAGE245
 CONX8   19     19 SMC-CONN60A-22-GP_CONN-G7-SMC-A    I48 @BASEBOARD_FAB2_LIB.BASEBOARD_FAB2(SCH_1):PAGE245
 CONX8   22     22 SMC-CONN60A-22-GP_CONN-G7-SMC-A    I48 @BASEBOARD_FAB2_LIB.BASEBOARD_FAB2(SCH_1):PAGE245
 CONX8   25     25 SMC-CONN60A-22-GP_CONN-G7-SMC-A    I48 @BASEBOARD_FAB2_LIB.BASEBOARD_FAB2(SCH_1):PAGE245
 CONX8   28     28 SMC-CONN60A-22-GP_CONN-G7-SMC-A    I48 @BASEBOARD_FAB2_LIB.BASEBOARD_FAB2(SCH_1):PAGE245
 CONX8   31     31 SMC-CONN60A-22-GP_CONN-G7-SMC-A    I48 @BASEBOARD_FAB2_LIB.BASEBOARD_FAB2(SCH_1):PAGE245
 CONX8   34     34 SMC-CONN60A-22-GP_CONN-G7-SMC-A    I48 @BASEBOARD_FAB2_LIB.BASEBOARD_FAB2(SCH_1):PAGE245
 CONX8   37     37 SMC-CONN60A-22-GP_CONN-G7-SMC-A    I48 @BASEBOARD_FAB2_LIB.BASEBOARD_FAB2(SCH_1):PAGE245
 CONX8   40     40 SMC-CONN60A-22-GP_CONN-G7-SMC-A    I48 @BASEBOARD_FAB2_LIB.BASEBOARD_FAB2(SCH_1):PAGE245
 CONX8   43     43 SMC-CONN60A-22-GP_CONN-G7-SMC-A    I48 @BASEBOARD_FAB2_LIB.BASEBOARD_FAB2(SCH_1):PAGE245
 CONX8   46     46 SMC-CONN60A-22-GP_CONN-G7-SMC-A    I48 @BASEBOARD_FAB2_LIB.BASEBOARD_FAB2(SCH_1):PAGE245
 CONX8   49     49 SMC-CONN60A-22-GP_CONN-G7-SMC-A    I48 @BASEBOARD_FAB2_LIB.BASEBOARD_FAB2(SCH_1):PAGE245
 CONX8   52     52 SMC-CONN60A-22-GP_CONN-G7-SMC-A    I48 @BASEBOARD_FAB2_LIB.BASEBOARD_FAB2(SCH_1):PAGE245
 CONX8   55     55 SMC-CONN60A-22-GP_CONN-G7-SMC-A    I48 @BASEBOARD_FAB2_LIB.BASEBOARD_FAB2(SCH_1):PAGE245
 CONX8   58     58 SMC-CONN60A-22-GP_CONN-G7-SMC-A    I48 @BASEBOARD_FAB2_LIB.BASEBOARD_FAB2(SCH_1):PAGE245
 CONX8  NP1    NP1 SMC-CONN60A-22-GP_CONN-G7-SMC-A    I48 @BASEBOARD_FAB2_LIB.BASEBOARD_FAB2(SCH_1):PAGE245
 CONX8  NP2    NP2 SMC-CONN60A-22-GP_CONN-G7-SMC-A    I48 @BASEBOARD_FAB2_LIB.BASEBOARD_FAB2(SCH_1):PAGE245
 CONX8 PTH1   PTH1 SMC-CONN60A-22-GP_CONN-G7-SMC-A    I48 @BASEBOARD_FAB2_LIB.BASEBOARD_FAB2(SCH_1):PAGE245
 CONX8 PTH2   PTH2 SMC-CONN60A-22-GP_CONN-G7-SMC-A    I48 @BASEBOARD_FAB2_LIB.BASEBOARD_FAB2(SCH_1):PAGE245
  J8G1  101  IO101 SCONN200_H68296001_SM-CONN,H68A    I78 @BASEBOARD_FAB2_LIB.BASEBOARD_FAB2(SCH_1):PAGE109
  J8G1  104  IO104 SCONN200_H68296001_SM-CONN,H68A    I78 @BASEBOARD_FAB2_LIB.BASEBOARD_FAB2(SCH_1):PAGE109
  J8G1  107  IO107 SCONN200_H68296001_SM-CONN,H68A    I78 @BASEBOARD_FAB2_LIB.BASEBOARD_FAB2(SCH_1):PAGE109
  J8G1  110  IO110 SCONN200_H68296001_SM-CONN,H68A    I78 @BASEBOARD_FAB2_LIB.BASEBOARD_FAB2(SCH_1):PAGE109
  J8G1  113  IO113 SCONN200_H68296001_SM-CONN,H68A    I78 @BASEBOARD_FAB2_LIB.BASEBOARD_FAB2(SCH_1):PAGE109
  J8G1  116  IO116 SCONN200_H68296001_SM-CONN,H68A    I78 @BASEBOARD_FAB2_LIB.BASEBOARD_FAB2(SCH_1):PAGE109
  J8G1  119  IO119 SCONN200_H68296001_SM-CONN,H68A    I78 @BASEBOARD_FAB2_LIB.BASEBOARD_FAB2(SCH_1):PAGE109
  J8G1  122  IO122 SCONN200_H68296001_SM-CONN,H68A    I78 @BASEBOARD_FAB2_LIB.BASEBOARD_FAB2(SCH_1):PAGE109
  J8G1  125  IO125 SCONN200_H68296001_SM-CONN,H68A    I78 @BASEBOARD_FAB2_LIB.BASEBOARD_FAB2(SCH_1):PAGE109
  J8G1  128  IO128 SCONN200_H68296001_SM-CONN,H68A    I78 @BASEBOARD_FAB2_LIB.BASEBOARD_FAB2(SCH_1):PAGE109
  J8G1  131  IO131 SCONN200_H68296001_SM-CONN,H68A    I78 @BASEBOARD_FAB2_LIB.BASEBOARD_FAB2(SCH_1):PAGE109
  J8G1  134  IO134 SCONN200_H68296001_SM-CONN,H68A    I78 @BASEBOARD_FAB2_LIB.BASEBOARD_FAB2(SCH_1):PAGE109
  J8G1  137  IO137 SCONN200_H68296001_SM-CONN,H68A    I78 @BASEBOARD_FAB2_LIB.BASEBOARD_FAB2(SCH_1):PAGE109
  J8G1  140  IO140 SCONN200_H68296001_SM-CONN,H68A    I78 @BASEBOARD_FAB2_LIB.BASEBOARD_FAB2(SCH_1):PAGE109
  J8G1  143  IO143 SCONN200_H68296001_SM-CONN,H68A    I78 @BASEBOARD_FAB2_LIB.BASEBOARD_FAB2(SCH_1):PAGE109
  J8G1  146  IO146 SCONN200_H68296001_SM-CONN,H68A    I78 @BASEBOARD_FAB2_LIB.BASEBOARD_FAB2(SCH_1):PAGE109
  J8G1  149  IO149 SCONN200_H68296001_SM-CONN,H68A    I78 @BASEBOARD_FAB2_LIB.BASEBOARD_FAB2(SCH_1):PAGE109
  J8G1  152  IO152 SCONN200_H68296001_SM-CONN,H68A    I78 @BASEBOARD_FAB2_LIB.BASEBOARD_FAB2(SCH_1):PAGE109
  J8G1  155  IO155 SCONN200_H68296001_SM-CONN,H68A    I78 @BASEBOARD_FAB2_LIB.BASEBOARD_FAB2(SCH_1):PAGE109
  J8G1  158  IO158 SCONN200_H68296001_SM-CONN,H68A    I78 @BASEBOARD_FAB2_LIB.BASEBOARD_FAB2(SCH_1):PAGE109
  J8G1  161  IO161 SCONN200_H68296001_SM-CONN,H68A    I78 @BASEBOARD_FAB2_LIB.BASEBOARD_FAB2(SCH_1):PAGE109
  J8G1  164  IO164 SCONN200_H68296001_SM-CONN,H68A    I78 @BASEBOARD_FAB2_LIB.BASEBOARD_FAB2(SCH_1):PAGE109
  J8G1  167  IO167 SCONN200_H68296001_SM-CONN,H68A    I78 @BASEBOARD_FAB2_LIB.BASEBOARD_FAB2(SCH_1):PAGE109
  J8G1  170  IO170 SCONN200_H68296001_SM-CONN,H68A    I78 @BASEBOARD_FAB2_LIB.BASEBOARD_FAB2(SCH_1):PAGE109
  J8G1  173  IO173 SCONN200_H68296001_SM-CONN,H68A    I78 @BASEBOARD_FAB2_LIB.BASEBOARD_FAB2(SCH_1):PAGE109
  J8G1  176  IO176 SCONN200_H68296001_SM-CONN,H68A    I78 @BASEBOARD_FAB2_LIB.BASEBOARD_FAB2(SCH_1):PAGE109
  J8G1  179  IO179 SCONN200_H68296001_SM-CONN,H68A    I78 @BASEBOARD_FAB2_LIB.BASEBOARD_FAB2(SCH_1):PAGE109
  J8G1  182  IO182 SCONN200_H68296001_SM-CONN,H68A    I78 @BASEBOARD_FAB2_LIB.BASEBOARD_FAB2(SCH_1):PAGE109
  J8G1  185  IO185 SCONN200_H68296001_SM-CONN,H68A    I78 @BASEBOARD_FAB2_LIB.BASEBOARD_FAB2(SCH_1):PAGE109
  J8G1  188  IO188 SCONN200_H68296001_SM-CONN,H68A    I78 @BASEBOARD_FAB2_LIB.BASEBOARD_FAB2(SCH_1):PAGE109
  J8G1  191  IO191 SCONN200_H68296001_SM-CONN,H68A    I78 @BASEBOARD_FAB2_LIB.BASEBOARD_FAB2(SCH_1):PAGE109
  J8G1  194  IO194 SCONN200_H68296001_SM-CONN,H68A    I78 @BASEBOARD_FAB2_LIB.BASEBOARD_FAB2(SCH_1):PAGE109
  J8G1  197  IO197 SCONN200_H68296001_SM-CONN,H68A    I78 @BASEBOARD_FAB2_LIB.BASEBOARD_FAB2(SCH_1):PAGE109
  J8G1  200  IO200 SCONN200_H68296001_SM-CONN,H68A    I78 @BASEBOARD_FAB2_LIB.BASEBOARD_FAB2(SCH_1):PAGE109
 RN8F6    2      B RES_0402-1.00K,1%,1/16W,EMPTY,A     I8 @BASEBOARD_FAB2_LIB.BASEBOARD_FAB2(SCH_1):PAGE246
 CN8F1    2      B CAP_0402-1.0UF,6.3V,10%,X6S,D9A    I15 @BASEBOARD_FAB2_LIB.BASEBOARD_FAB2(SCH_1):PAGE246
 CN8F2    2      B CAP_0402LF-0.01UF,25V,10%,X7R,A    I16 @BASEBOARD_FAB2_LIB.BASEBOARD_FAB2(SCH_1):PAGE246
 UN8F2   10    GND W25Q256_XSOI-IC,H25002-001    I17 @BASEBOARD_FAB2_LIB.BASEBOARD_FAB2(SCH_1):PAGE246
  Q6W1    2    SRC FET_N_SOT23LF-2N7002,FET,C7925A   I225 @BASEBOARD_FAB2_LIB.BASEBOARD_FAB2(SCH_1):PAGE200
  R6W2    2      B RES_0402-10.0K,1%,1/16W,CHIP,GA   I230 @BASEBOARD_FAB2_LIB.BASEBOARD_FAB2(SCH_1):PAGE200
  R6W7    2      B RES_0402-4.75K,1%,1/16W,CHIP,GA     I3 @BASEBOARD_FAB2_LIB.BASEBOARD_FAB2(SCH_1):PAGE247
  R6W8    2      B RES_0402-4.75K,1%,1/16W,CHIP,GA     I8 @BASEBOARD_FAB2_LIB.BASEBOARD_FAB2(SCH_1):PAGE247
  R6W9    2      B RES_0402-4.75K,1%,1/16W,CHIP,GA     I9 @BASEBOARD_FAB2_LIB.BASEBOARD_FAB2(SCH_1):PAGE247
  C6W1    2      B CAP_0402LF-0.1UF,16V,10%,X7R,AA    I18 @BASEBOARD_FAB2_LIB.BASEBOARD_FAB2(SCH_1):PAGE247
  Q6W2    1 SOURCE<0> FET_N_DUAL_SMLF-2N7002DW,FET,DA    I30 @BASEBOARD_FAB2_LIB.BASEBOARD_FAB2(SCH_1):PAGE168
 R6W14    2      B RES_0402-5.11K,1%,1/16W,CHIP,GA    I33 @BASEBOARD_FAB2_LIB.BASEBOARD_FAB2(SCH_1):PAGE168
  R3W1    2      B RES_0402-1.00K,1%,1/16W,CHIP,GA     I2 @BASEBOARD_FAB2_LIB.BASEBOARD_FAB2(SCH_1):PAGE249
  R3W9    2      B RES_0402-10.0K,1%,1/16W,CHIP,GA     I7 @BASEBOARD_FAB2_LIB.BASEBOARD_FAB2(SCH_1):PAGE249
  R3W2    2      B RES_0402-1.00K,1%,1/16W,CHIP,GA    I12 @BASEBOARD_FAB2_LIB.BASEBOARD_FAB2(SCH_1):PAGE249
  Q9W4    2    GND LMV331IDCKRG4-GP_DISCRET-G-LMVA    I15 @BASEBOARD_FAB2_LIB.BASEBOARD_FAB2(SCH_1):PAGE249
  C8W2    2      B CAP_0402LF-0.1UF,16V,10%,X7R,AA    I21 @BASEBOARD_FAB2_LIB.BASEBOARD_FAB2(SCH_1):PAGE249
  Q9W3    2      E NPN_SM-MMBT3904,IC,C52245-001    I26 @BASEBOARD_FAB2_LIB.BASEBOARD_FAB2(SCH_1):PAGE249
  Q9W2    2      E NPN_SM-MMBT3904,IC,C52245-001    I29 @BASEBOARD_FAB2_LIB.BASEBOARD_FAB2(SCH_1):PAGE249
 C6W10    2      B CAP_0402LF-0.1UF,16V,10%,X7R,AA   I124 @BASEBOARD_FAB2_LIB.BASEBOARD_FAB2(SCH_1):PAGE176
EU25F2   11    GND RT9059_DFN-IC,H65765-001    I73 @BASEBOARD_FAB2_LIB.BASEBOARD_FAB2(SCH_1):PAGE239
 C9W13    2      B CAP_0805LF-22UF,4V,20%,X6S,C95A    I81 @BASEBOARD_FAB2_LIB.BASEBOARD_FAB2(SCH_1):PAGE239
 C1W15    2      B CAP_0603-10UF,6.3V,20%,X6S,E15A    I83 @BASEBOARD_FAB2_LIB.BASEBOARD_FAB2(SCH_1):PAGE239
 C9W10    2      B CAP_0402LF-1000PF,50V,10%,X7R,A    I84 @BASEBOARD_FAB2_LIB.BASEBOARD_FAB2(SCH_1):PAGE239
 R9W32    1      A RES_0402-13K,1.0%,1/16W,CHIP,GA    I87 @BASEBOARD_FAB2_LIB.BASEBOARD_FAB2(SCH_1):PAGE239
  C9W5    2      B CAP_A_0402V-0.1UF,16V,10%,X7R,A    I90 @BASEBOARD_FAB2_LIB.BASEBOARD_FAB2(SCH_1):PAGE239
  C9W6    2      B CAP_0402LF-1000PF,50V,10%,EMPTA    I91 @BASEBOARD_FAB2_LIB.BASEBOARD_FAB2(SCH_1):PAGE239
  C1W7    2      B CAP_0603-10UF,6.3V,20%,X6S,E15A    I92 @BASEBOARD_FAB2_LIB.BASEBOARD_FAB2(SCH_1):PAGE239
  Q9W1    2    SRC FET_N_SOT23LF-2N7002,FET,C7925A    I30 @BASEBOARD_FAB2_LIB.BASEBOARD_FAB2(SCH_1):PAGE249
  R9T8    1      A RES_0402-0.0,5%,1/16W,CHIP,G21A   I278 @BASEBOARD_FAB2_LIB.BASEBOARD_FAB2(SCH_1):PAGE181
C25W22    2      B CAP_0402LF-0.1UF,16V,10%,X7R,AA    I55 @BASEBOARD_FAB2_LIB.BASEBOARD_FAB2(SCH_1):PAGE143
 R1T27    1      A RES_0402-240,1.0%,1/16W,CHIP,GA    I58 @BASEBOARD_FAB2_LIB.BASEBOARD_FAB2(SCH_1):PAGE143
R25W58    2      B RES_0402-2.7K,1%,1/16W,CHIP,G2A    I73 @BASEBOARD_FAB2_LIB.BASEBOARD_FAB2(SCH_1):PAGE144
  Y9F2    2    GND OSC_C_SM4-24MHZ,OSC,D34520-021     I8 @BASEBOARD_FAB2_LIB.BASEBOARD_FAB2(SCH_1):PAGE145
 C9F23    2      B CAP_A_0402V-0.1UF,16V,10%,X7R,A    I15 @BASEBOARD_FAB2_LIB.BASEBOARD_FAB2(SCH_1):PAGE145
 R9F20    2      B RES_0402-348,1%,1/16W,EMPTY,G2A    I22 @BASEBOARD_FAB2_LIB.BASEBOARD_FAB2(SCH_1):PAGE145
R25W61    2      B RES_0402-100.0K,1%,1/16W,CHIP,A    I30 @BASEBOARD_FAB2_LIB.BASEBOARD_FAB2(SCH_1):PAGE145
R25W62    2      B RES_0402-100.0K,1%,1/16W,CHIP,A    I31 @BASEBOARD_FAB2_LIB.BASEBOARD_FAB2(SCH_1):PAGE145
R25W60    2      B RES_0402-100.0K,1%,1/16W,CHIP,A    I34 @BASEBOARD_FAB2_LIB.BASEBOARD_FAB2(SCH_1):PAGE145
R25W64    2      B RES_0402-100.0K,1%,1/16W,CHIP,A    I36 @BASEBOARD_FAB2_LIB.BASEBOARD_FAB2(SCH_1):PAGE145
R25W65    2      B RES_0402-100.0K,1%,1/16W,CHIP,A    I38 @BASEBOARD_FAB2_LIB.BASEBOARD_FAB2(SCH_1):PAGE145
R25W67    2      B RES_0402-10.0K,1%,1/16W,EMPTY,A    I46 @BASEBOARD_FAB2_LIB.BASEBOARD_FAB2(SCH_1):PAGE145
 R1T25    2      B RES_0402-8.2K,1%,1/16W,CHIP,G2A    I35 @BASEBOARD_FAB2_LIB.BASEBOARD_FAB2(SCH_1):PAGE146
 R1T26    2      B RES_0402-8.2K,1%,1/16W,CHIP,G2A    I37 @BASEBOARD_FAB2_LIB.BASEBOARD_FAB2(SCH_1):PAGE146
  R1U2    2      B RES_0402-100.0K,1%,1/16W,CHIP,A    I62 @BASEBOARD_FAB2_LIB.BASEBOARD_FAB2(SCH_1):PAGE147
R25W116    1      A RES_0402-3.32K,1%,1/16W,CHIP,GA    I48 @BASEBOARD_FAB2_LIB.BASEBOARD_FAB2(SCH_1):PAGE151
C25W60    2      B CAP_0402-1.0UF,6.3V,10%,X6S,D9A     I1 @BASEBOARD_FAB2_LIB.BASEBOARD_FAB2(SCH_1):PAGE150
C25W65    2      2 SC4D7U10V3KX-GP_SMD-BCG-SC4D7UA     I2 @BASEBOARD_FAB2_LIB.BASEBOARD_FAB2(SCH_1):PAGE150
C25W71    2      B CAP_0402-1.0UF,6.3V,10%,X6S,D9A     I4 @BASEBOARD_FAB2_LIB.BASEBOARD_FAB2(SCH_1):PAGE150
C25W70    2      2 SC4D7U10V3KX-GP_SMD-BCG-SC4D7UA     I6 @BASEBOARD_FAB2_LIB.BASEBOARD_FAB2(SCH_1):PAGE150
C25W55    2      2 SCD1U16V2KX-3GP_SMD-BCG-SCD1U1A    I10 @BASEBOARD_FAB2_LIB.BASEBOARD_FAB2(SCH_1):PAGE150
C25W54    2      B CAP_0402-1.0UF,6.3V,10%,X6S,D9A    I12 @BASEBOARD_FAB2_LIB.BASEBOARD_FAB2(SCH_1):PAGE150
C25W53    2      B CAP_0402-1.0UF,6.3V,10%,X6S,D9A    I13 @BASEBOARD_FAB2_LIB.BASEBOARD_FAB2(SCH_1):PAGE150
C25W52    2      B CAP_0402-1.0UF,6.3V,10%,X6S,D9A    I14 @BASEBOARD_FAB2_LIB.BASEBOARD_FAB2(SCH_1):PAGE150
C25W39    2      2 SC4D7U10V3KX-GP_SMD-BCG-SC4D7UA    I17 @BASEBOARD_FAB2_LIB.BASEBOARD_FAB2(SCH_1):PAGE150
C25W38    2      2 SCD1U16V2KX-3GP_SMD-BCG-SCD1U1A    I18 @BASEBOARD_FAB2_LIB.BASEBOARD_FAB2(SCH_1):PAGE150
C25W51    2      B CAP_0402-1.0UF,6.3V,10%,X6S,D9A    I19 @BASEBOARD_FAB2_LIB.BASEBOARD_FAB2(SCH_1):PAGE150
C25W50    2      2 SC4D7U10V3KX-GP_SMD-BCG-SC4D7UA    I21 @BASEBOARD_FAB2_LIB.BASEBOARD_FAB2(SCH_1):PAGE150
C25W64    2      2 SCD1U16V2KX-3GP_SMD-BCG-SCD1U1A    I24 @BASEBOARD_FAB2_LIB.BASEBOARD_FAB2(SCH_1):PAGE150
C25W63    2      B CAP_0402-1.0UF,6.3V,10%,X6S,D9A    I25 @BASEBOARD_FAB2_LIB.BASEBOARD_FAB2(SCH_1):PAGE150
C25W69    2      2 SC4D7U10V3KX-GP_SMD-BCG-SC4D7UA    I28 @BASEBOARD_FAB2_LIB.BASEBOARD_FAB2(SCH_1):PAGE150
C25W68    2      2 SCD1U16V2KX-3GP_SMD-BCG-SCD1U1A    I30 @BASEBOARD_FAB2_LIB.BASEBOARD_FAB2(SCH_1):PAGE150
C25W67    2      B CAP_0402-1.0UF,6.3V,10%,X6S,D9A    I31 @BASEBOARD_FAB2_LIB.BASEBOARD_FAB2(SCH_1):PAGE150
C25W66    2      B CAP_0402-1.0UF,6.3V,10%,X6S,D9A    I33 @BASEBOARD_FAB2_LIB.BASEBOARD_FAB2(SCH_1):PAGE150
C25W37    2      B CAP_0402-1.0UF,6.3V,10%,X6S,D9A    I35 @BASEBOARD_FAB2_LIB.BASEBOARD_FAB2(SCH_1):PAGE150
C25W49    2      2 SCD1U16V2KX-3GP_SMD-BCG-SCD1U1A    I36 @BASEBOARD_FAB2_LIB.BASEBOARD_FAB2(SCH_1):PAGE150
C25W48    2      B CAP_0402-1.0UF,6.3V,10%,X6S,D9A    I38 @BASEBOARD_FAB2_LIB.BASEBOARD_FAB2(SCH_1):PAGE150
C25W30    2      2 SC4D7U10V3KX-GP_SMD-BCG-SC4D7UA    I43 @BASEBOARD_FAB2_LIB.BASEBOARD_FAB2(SCH_1):PAGE150
C25W29    2      B CAP_0805-10UF,16V,10%,X6S,C953A    I45 @BASEBOARD_FAB2_LIB.BASEBOARD_FAB2(SCH_1):PAGE150
C25W28    2      B CAP_0402-1.0UF,6.3V,10%,X6S,D9A    I46 @BASEBOARD_FAB2_LIB.BASEBOARD_FAB2(SCH_1):PAGE150
C25W27    2      B CAP_0402-1.0UF,6.3V,10%,X6S,D9A    I48 @BASEBOARD_FAB2_LIB.BASEBOARD_FAB2(SCH_1):PAGE150
C25W36    2      2 SC4D7U10V3KX-GP_SMD-BCG-SC4D7UA    I50 @BASEBOARD_FAB2_LIB.BASEBOARD_FAB2(SCH_1):PAGE150
C25W35    2      B CAP_0402-1.0UF,6.3V,10%,X6S,D9A    I51 @BASEBOARD_FAB2_LIB.BASEBOARD_FAB2(SCH_1):PAGE150
C25W34    2      2 SCD1U16V2KX-3GP_SMD-BCG-SCD1U1A    I53 @BASEBOARD_FAB2_LIB.BASEBOARD_FAB2(SCH_1):PAGE150
C25W47    2      2 SC4D7U10V3KX-GP_SMD-BCG-SC4D7UA    I54 @BASEBOARD_FAB2_LIB.BASEBOARD_FAB2(SCH_1):PAGE150
C25W46    2      B CAP_0805-10UF,16V,10%,X6S,C953A    I55 @BASEBOARD_FAB2_LIB.BASEBOARD_FAB2(SCH_1):PAGE150
C25W33    2      B CAP_0402-1.0UF,6.3V,10%,X6S,D9A    I59 @BASEBOARD_FAB2_LIB.BASEBOARD_FAB2(SCH_1):PAGE150
C25W45    2      2 SCD1U16V2KX-3GP_SMD-BCG-SCD1U1A    I61 @BASEBOARD_FAB2_LIB.BASEBOARD_FAB2(SCH_1):PAGE150
C25W44    2      B CAP_0402-1.0UF,6.3V,10%,X6S,D9A    I62 @BASEBOARD_FAB2_LIB.BASEBOARD_FAB2(SCH_1):PAGE150
C25W43    2      B CAP_0402-1.0UF,6.3V,10%,X6S,D9A    I63 @BASEBOARD_FAB2_LIB.BASEBOARD_FAB2(SCH_1):PAGE150
C25W62    2      2 SC4D7U10V3KX-GP_SMD-BCG-SC4D7UA    I65 @BASEBOARD_FAB2_LIB.BASEBOARD_FAB2(SCH_1):PAGE150
C25W61    2      2 SCD1U16V2KX-3GP_SMD-BCG-SCD1U1A    I67 @BASEBOARD_FAB2_LIB.BASEBOARD_FAB2(SCH_1):PAGE150
C25W59    2      2 SC4D7U10V3KX-GP_SMD-BCG-SC4D7UA    I69 @BASEBOARD_FAB2_LIB.BASEBOARD_FAB2(SCH_1):PAGE150
C25W26    2      B CAP_0402-1.0UF,6.3V,10%,X6S,D9A    I71 @BASEBOARD_FAB2_LIB.BASEBOARD_FAB2(SCH_1):PAGE150
C25W25    2      B CAP_0402-1.0UF,6.3V,10%,X6S,D9A    I72 @BASEBOARD_FAB2_LIB.BASEBOARD_FAB2(SCH_1):PAGE150
C25W24    2      B CAP_0402-1.0UF,6.3V,10%,X6S,D9A    I73 @BASEBOARD_FAB2_LIB.BASEBOARD_FAB2(SCH_1):PAGE150
C25W23    2      B CAP_0402-1.0UF,6.3V,10%,X6S,D9A    I75 @BASEBOARD_FAB2_LIB.BASEBOARD_FAB2(SCH_1):PAGE150
C25W32    2      B CAP_0402-1.0UF,6.3V,10%,X6S,D9A    I78 @BASEBOARD_FAB2_LIB.BASEBOARD_FAB2(SCH_1):PAGE150
C25W31    2      2 SCD1U16V2KX-3GP_SMD-BCG-SCD1U1A    I79 @BASEBOARD_FAB2_LIB.BASEBOARD_FAB2(SCH_1):PAGE150
C25W42    2      B CAP_0402-1.0UF,6.3V,10%,X6S,D9A    I80 @BASEBOARD_FAB2_LIB.BASEBOARD_FAB2(SCH_1):PAGE150
C25W41    2      B CAP_0402-1.0UF,6.3V,10%,X6S,D9A    I81 @BASEBOARD_FAB2_LIB.BASEBOARD_FAB2(SCH_1):PAGE150
C25W40    2      B CAP_0402-1.0UF,6.3V,10%,X6S,D9A    I82 @BASEBOARD_FAB2_LIB.BASEBOARD_FAB2(SCH_1):PAGE150
C25W58    2      2 SCD1U16V2KX-3GP_SMD-BCG-SCD1U1A    I85 @BASEBOARD_FAB2_LIB.BASEBOARD_FAB2(SCH_1):PAGE150
C25W57    2      B CAP_0402-1.0UF,6.3V,10%,X6S,D9A    I86 @BASEBOARD_FAB2_LIB.BASEBOARD_FAB2(SCH_1):PAGE150
C25W56    2      B CAP_0402-1.0UF,6.3V,10%,X6S,D9A    I87 @BASEBOARD_FAB2_LIB.BASEBOARD_FAB2(SCH_1):PAGE150
R25W63    2      B RES_0402-100.0K,1%,1/16W,CHIP,A    I65 @BASEBOARD_FAB2_LIB.BASEBOARD_FAB2(SCH_1):PAGE146
R25W66    2      B RES_0402-100.0K,1%,1/16W,CHIP,A    I76 @BASEBOARD_FAB2_LIB.BASEBOARD_FAB2(SCH_1):PAGE146
  R1U7    1      A RES_0402-10.0K,1%,1/16W,CHIP,GA    I78 @BASEBOARD_FAB2_LIB.BASEBOARD_FAB2(SCH_1):PAGE146
 C25W8    2      B CAP_0402-0.1UF,16V,10%,EMPTY,AA    I38 @BASEBOARD_FAB2_LIB.BASEBOARD_FAB2(SCH_1):PAGE147
R25W57    1      A RES_0402-2.7K,1%,1/16W,CHIP,G2A    I40 @BASEBOARD_FAB2_LIB.BASEBOARD_FAB2(SCH_1):PAGE147
  R1U4    2      B RES_0402-100.0K,1%,1/16W,CHIP,A    I65 @BASEBOARD_FAB2_LIB.BASEBOARD_FAB2(SCH_1):PAGE147
  R1U5    2      B RES_0402-100.0K,1%,1/16W,CHIP,A    I66 @BASEBOARD_FAB2_LIB.BASEBOARD_FAB2(SCH_1):PAGE147
  R1U1    2      B RES_0402-100.0K,1%,1/16W,CHIP,A    I61 @BASEBOARD_FAB2_LIB.BASEBOARD_FAB2(SCH_1):PAGE147
 C1T21    2      B CAP_A_0402V-1.0UF,6.3V,10%,X6SA    I20 @BASEBOARD_FAB2_LIB.BASEBOARD_FAB2(SCH_1):PAGE148
 U25W5   N9    TEN H5AN4G6NAFR-TFC-GP_MEMORY-G2-HA     I1 @BASEBOARD_FAB2_LIB.BASEBOARD_FAB2(SCH_1):PAGE149
 U25W5   R9 VPP<1> H5AN4G6NAFR-TFC-GP_MEMORY-G2-HA     I1 @BASEBOARD_FAB2_LIB.BASEBOARD_FAB2(SCH_1):PAGE149
 U25W5   B2 VSS<0> H5AN4G6NAFR-TFC-GP_MEMORY-G2-HA     I1 @BASEBOARD_FAB2_LIB.BASEBOARD_FAB2(SCH_1):PAGE149
 U25W5   E1 VSS<1> H5AN4G6NAFR-TFC-GP_MEMORY-G2-HA     I1 @BASEBOARD_FAB2_LIB.BASEBOARD_FAB2(SCH_1):PAGE149
 U25W5   E9 VSS<2> H5AN4G6NAFR-TFC-GP_MEMORY-G2-HA     I1 @BASEBOARD_FAB2_LIB.BASEBOARD_FAB2(SCH_1):PAGE149
 U25W5   G8 VSS<3> H5AN4G6NAFR-TFC-GP_MEMORY-G2-HA     I1 @BASEBOARD_FAB2_LIB.BASEBOARD_FAB2(SCH_1):PAGE149
 U25W5   K1 VSS<4> H5AN4G6NAFR-TFC-GP_MEMORY-G2-HA     I1 @BASEBOARD_FAB2_LIB.BASEBOARD_FAB2(SCH_1):PAGE149
 U25W5   K9 VSS<5> H5AN4G6NAFR-TFC-GP_MEMORY-G2-HA     I1 @BASEBOARD_FAB2_LIB.BASEBOARD_FAB2(SCH_1):PAGE149
 U25W5   M9 VSS<6> H5AN4G6NAFR-TFC-GP_MEMORY-G2-HA     I1 @BASEBOARD_FAB2_LIB.BASEBOARD_FAB2(SCH_1):PAGE149
 U25W5   N1 VSS<7> H5AN4G6NAFR-TFC-GP_MEMORY-G2-HA     I1 @BASEBOARD_FAB2_LIB.BASEBOARD_FAB2(SCH_1):PAGE149
 U25W5   T1 VSS<8> H5AN4G6NAFR-TFC-GP_MEMORY-G2-HA     I1 @BASEBOARD_FAB2_LIB.BASEBOARD_FAB2(SCH_1):PAGE149
 U25W5   A2 VSSQ<0> H5AN4G6NAFR-TFC-GP_MEMORY-G2-HA     I1 @BASEBOARD_FAB2_LIB.BASEBOARD_FAB2(SCH_1):PAGE149
 U25W5   A8 VSSQ<1> H5AN4G6NAFR-TFC-GP_MEMORY-G2-HA     I1 @BASEBOARD_FAB2_LIB.BASEBOARD_FAB2(SCH_1):PAGE149
 U25W5   C9 VSSQ<2> H5AN4G6NAFR-TFC-GP_MEMORY-G2-HA     I1 @BASEBOARD_FAB2_LIB.BASEBOARD_FAB2(SCH_1):PAGE149
 U25W5   D2 VSSQ<3> H5AN4G6NAFR-TFC-GP_MEMORY-G2-HA     I1 @BASEBOARD_FAB2_LIB.BASEBOARD_FAB2(SCH_1):PAGE149
 U25W5   D8 VSSQ<4> H5AN4G6NAFR-TFC-GP_MEMORY-G2-HA     I1 @BASEBOARD_FAB2_LIB.BASEBOARD_FAB2(SCH_1):PAGE149
 U25W5   E3 VSSQ<5> H5AN4G6NAFR-TFC-GP_MEMORY-G2-HA     I1 @BASEBOARD_FAB2_LIB.BASEBOARD_FAB2(SCH_1):PAGE149
 U25W5   E8 VSSQ<6> H5AN4G6NAFR-TFC-GP_MEMORY-G2-HA     I1 @BASEBOARD_FAB2_LIB.BASEBOARD_FAB2(SCH_1):PAGE149
 U25W5   F1 VSSQ<7> H5AN4G6NAFR-TFC-GP_MEMORY-G2-HA     I1 @BASEBOARD_FAB2_LIB.BASEBOARD_FAB2(SCH_1):PAGE149
 U25W5   H1 VSSQ<8> H5AN4G6NAFR-TFC-GP_MEMORY-G2-HA     I1 @BASEBOARD_FAB2_LIB.BASEBOARD_FAB2(SCH_1):PAGE149
 U25W5   H9 VSSQ<9> H5AN4G6NAFR-TFC-GP_MEMORY-G2-HA     I1 @BASEBOARD_FAB2_LIB.BASEBOARD_FAB2(SCH_1):PAGE149
C25W16    2      B CAP_0402LF-100.0PF,50V,5%,COG,A    I37 @BASEBOARD_FAB2_LIB.BASEBOARD_FAB2(SCH_1):PAGE149
C25W17    2      2 SC1U16V3KX-2GP_SMD-BCG-SC1U16VA    I38 @BASEBOARD_FAB2_LIB.BASEBOARD_FAB2(SCH_1):PAGE149
C25W15    2      2 SCD1U16V2KX-3GP_SMD-BCG-SCD1U1A    I39 @BASEBOARD_FAB2_LIB.BASEBOARD_FAB2(SCH_1):PAGE149
C25W14    2      2 SCD1U16V2KX-3GP_SMD-BCG-SCD1U1A    I44 @BASEBOARD_FAB2_LIB.BASEBOARD_FAB2(SCH_1):PAGE149
R25W117    2      B RES_0402-240,1.0%,1/16W,CHIP,GA    I55 @BASEBOARD_FAB2_LIB.BASEBOARD_FAB2(SCH_1):PAGE149
C25W13    2      B CAP_0402LF-0.1UF,16V,10%,X7R,AA    I65 @BASEBOARD_FAB2_LIB.BASEBOARD_FAB2(SCH_1):PAGE149
C25W18    2      2 SC1U16V3KX-2GP_SMD-BCG-SC1U16VA    I68 @BASEBOARD_FAB2_LIB.BASEBOARD_FAB2(SCH_1):PAGE149
C25W19    2      2 SC4D7U10V3KX-GP_SMD-BCG-SC4D7UA    I69 @BASEBOARD_FAB2_LIB.BASEBOARD_FAB2(SCH_1):PAGE149
 C25W1    2      B CAP_0402-1.0UF,16V,10%,X6S,D97A    I71 @BASEBOARD_FAB2_LIB.BASEBOARD_FAB2(SCH_1):PAGE149
 C25W2    2      B CAP_0402-1.0UF,16V,10%,X6S,D97A    I72 @BASEBOARD_FAB2_LIB.BASEBOARD_FAB2(SCH_1):PAGE149
 C25W3    2      B CAP_0402-1.0UF,16V,10%,X6S,D97A    I73 @BASEBOARD_FAB2_LIB.BASEBOARD_FAB2(SCH_1):PAGE149
 C25W4    2      B CAP_0402-1.0UF,16V,10%,X6S,D97A    I74 @BASEBOARD_FAB2_LIB.BASEBOARD_FAB2(SCH_1):PAGE149
 C25W5    2      B CAP_0402-1.0UF,16V,10%,X6S,D97A    I96 @BASEBOARD_FAB2_LIB.BASEBOARD_FAB2(SCH_1):PAGE149
 C25W6    2      B CAP_0402-1.0UF,16V,10%,X6S,D97A    I97 @BASEBOARD_FAB2_LIB.BASEBOARD_FAB2(SCH_1):PAGE149
  Q9E1    4 SOURCE<0> FET_N_DUAL_SMLF-NTJD4001N,FET,A   I109 @BASEBOARD_FAB2_LIB.BASEBOARD_FAB2(SCH_1):PAGE149
  Q9E1    1 SOURCE<0> FET_N_DUAL_SMLF-NTJD4001N,FET,A   I113 @BASEBOARD_FAB2_LIB.BASEBOARD_FAB2(SCH_1):PAGE149
R25W118    2      B RES_0402-4.75K,1%,1/16W,EMPTY,A   I122 @BASEBOARD_FAB2_LIB.BASEBOARD_FAB2(SCH_1):PAGE149
 R1T29    2      B RES_0402-1.00K,1%,1/16W,CHIP,GA   I125 @BASEBOARD_FAB2_LIB.BASEBOARD_FAB2(SCH_1):PAGE149
C25W12    2      B CAP_0402-1.0UF,6.3V,10%,X6S,D9A   I126 @BASEBOARD_FAB2_LIB.BASEBOARD_FAB2(SCH_1):PAGE149
C25W11    2      B CAP_0402LF-0.01UF,25V,10%,X7R,A   I159 @BASEBOARD_FAB2_LIB.BASEBOARD_FAB2(SCH_1):PAGE149
 R25W1    1      1 120R2F-GP_RCL_GP-120R2F-GP,64.A   I160 @BASEBOARD_FAB2_LIB.BASEBOARD_FAB2(SCH_1):PAGE149
 R25W2    1      1 120R2F-GP_RCL_GP-120R2F-GP,64.A   I161 @BASEBOARD_FAB2_LIB.BASEBOARD_FAB2(SCH_1):PAGE149
 R25W4    1      1 120R2F-GP_RCL_GP-120R2F-GP,64.A   I162 @BASEBOARD_FAB2_LIB.BASEBOARD_FAB2(SCH_1):PAGE149
 R25W3    1      1 120R2F-GP_RCL_GP-120R2F-GP,64.A   I163 @BASEBOARD_FAB2_LIB.BASEBOARD_FAB2(SCH_1):PAGE149
 R25W5    1      1 120R2F-GP_RCL_GP-120R2F-GP,64.A   I164 @BASEBOARD_FAB2_LIB.BASEBOARD_FAB2(SCH_1):PAGE149
 R25W6    1      1 120R2F-GP_RCL_GP-120R2F-GP,64.A   I165 @BASEBOARD_FAB2_LIB.BASEBOARD_FAB2(SCH_1):PAGE149
 R25W7    1      1 120R2F-GP_RCL_GP-120R2F-GP,64.A   I166 @BASEBOARD_FAB2_LIB.BASEBOARD_FAB2(SCH_1):PAGE149
 R25W8    1      1 120R2F-GP_RCL_GP-120R2F-GP,64.A   I167 @BASEBOARD_FAB2_LIB.BASEBOARD_FAB2(SCH_1):PAGE149
 R25W9    1      1 120R2F-GP_RCL_GP-120R2F-GP,64.A   I168 @BASEBOARD_FAB2_LIB.BASEBOARD_FAB2(SCH_1):PAGE149
R25W10    1      1 120R2F-GP_RCL_GP-120R2F-GP,64.A   I169 @BASEBOARD_FAB2_LIB.BASEBOARD_FAB2(SCH_1):PAGE149
R25W12    1      1 120R2F-GP_RCL_GP-120R2F-GP,64.A   I170 @BASEBOARD_FAB2_LIB.BASEBOARD_FAB2(SCH_1):PAGE149
R25W11    1      1 120R2F-GP_RCL_GP-120R2F-GP,64.A   I171 @BASEBOARD_FAB2_LIB.BASEBOARD_FAB2(SCH_1):PAGE149
R25W13    1      1 120R2F-GP_RCL_GP-120R2F-GP,64.A   I172 @BASEBOARD_FAB2_LIB.BASEBOARD_FAB2(SCH_1):PAGE149
R25W16    1      1 120R2F-GP_RCL_GP-120R2F-GP,64.A   I173 @BASEBOARD_FAB2_LIB.BASEBOARD_FAB2(SCH_1):PAGE149
R25W15    1      1 120R2F-GP_RCL_GP-120R2F-GP,64.A   I174 @BASEBOARD_FAB2_LIB.BASEBOARD_FAB2(SCH_1):PAGE149
R25W14    1      1 120R2F-GP_RCL_GP-120R2F-GP,64.A   I175 @BASEBOARD_FAB2_LIB.BASEBOARD_FAB2(SCH_1):PAGE149
R25W22    1      1 120R2F-GP_RCL_GP-120R2F-GP,64.A   I176 @BASEBOARD_FAB2_LIB.BASEBOARD_FAB2(SCH_1):PAGE149
R25W23    1      1 120R2F-GP_RCL_GP-120R2F-GP,64.A   I177 @BASEBOARD_FAB2_LIB.BASEBOARD_FAB2(SCH_1):PAGE149
R25W24    1      1 120R2F-GP_RCL_GP-120R2F-GP,64.A   I178 @BASEBOARD_FAB2_LIB.BASEBOARD_FAB2(SCH_1):PAGE149
R25W25    1      1 120R2F-GP_RCL_GP-120R2F-GP,64.A   I179 @BASEBOARD_FAB2_LIB.BASEBOARD_FAB2(SCH_1):PAGE149
R25W26    1      1 120R2F-GP_RCL_GP-120R2F-GP,64.A   I180 @BASEBOARD_FAB2_LIB.BASEBOARD_FAB2(SCH_1):PAGE149
R25W17    1      1 120R2F-GP_RCL_GP-120R2F-GP,64.A   I181 @BASEBOARD_FAB2_LIB.BASEBOARD_FAB2(SCH_1):PAGE149
R25W18    1      1 120R2F-GP_RCL_GP-120R2F-GP,64.A   I182 @BASEBOARD_FAB2_LIB.BASEBOARD_FAB2(SCH_1):PAGE149
R25W19    1      1 120R2F-GP_RCL_GP-120R2F-GP,64.A   I183 @BASEBOARD_FAB2_LIB.BASEBOARD_FAB2(SCH_1):PAGE149
R25W20    1      1 120R2F-GP_RCL_GP-120R2F-GP,64.A   I184 @BASEBOARD_FAB2_LIB.BASEBOARD_FAB2(SCH_1):PAGE149
R25W21    1      1 120R2F-GP_RCL_GP-120R2F-GP,64.A   I185 @BASEBOARD_FAB2_LIB.BASEBOARD_FAB2(SCH_1):PAGE149
 R2N13    2      B RES_0402-10.0K,1%,1/16W,CHIP,GA    I75 @BASEBOARD_FAB2_LIB.BASEBOARD_FAB2(SCH_1):PAGE147
 R1T23    2      B RES_0402-0.0,5%,1/16W,EMPTY,G2A   I101 @BASEBOARD_FAB2_LIB.BASEBOARD_FAB2(SCH_1):PAGE145
  U6W2    4    GND PCA9515ADGKR-1-GP_DISCRET-G5-PA    I77 @BASEBOARD_FAB2_LIB.BASEBOARD_FAB2(SCH_1):PAGE247
  C6W2    2      B CAP_0402LF-0.1UF,16V,10%,X7R,AA    I81 @BASEBOARD_FAB2_LIB.BASEBOARD_FAB2(SCH_1):PAGE247
  C6W3    2      B CAP_A_0402V-0.1UF,16V,10%,X7R,A    I85 @BASEBOARD_FAB2_LIB.BASEBOARD_FAB2(SCH_1):PAGE247
  U6W3    1     A0 AT24C64_SOICLF-IC,C47049-001-GA    I89 @BASEBOARD_FAB2_LIB.BASEBOARD_FAB2(SCH_1):PAGE247
  U6W3    2     A1 AT24C64_SOICLF-IC,C47049-001-GA    I89 @BASEBOARD_FAB2_LIB.BASEBOARD_FAB2(SCH_1):PAGE247
 R6W23    2      B RES_0402-1.00K,1%,1/16W,CHIP,GA    I92 @BASEBOARD_FAB2_LIB.BASEBOARD_FAB2(SCH_1):PAGE247
 U25W4   C1 RGMII2RXCTL_GPIOV3 AST2520A1-GP-GP_ASIC2-GB1-AST2A   I106 @BASEBOARD_FAB2_LIB.BASEBOARD_FAB2(SCH_1):PAGE147
 U25W4   D3 RGMIICK AST2520A1-GP-GP_ASIC2-GB1-AST2A   I106 @BASEBOARD_FAB2_LIB.BASEBOARD_FAB2(SCH_1):PAGE147
 U25W4   A1   GND0 AST2520A1-GP-GP_ASIC2-GB1-AST2A    I28 @BASEBOARD_FAB2_LIB.BASEBOARD_FAB2(SCH_1):PAGE148
 U25W4  A22   GND1 AST2520A1-GP-GP_ASIC2-GB1-AST2A    I28 @BASEBOARD_FAB2_LIB.BASEBOARD_FAB2(SCH_1):PAGE148
 U25W4 AA11   GND2 AST2520A1-GP-GP_ASIC2-GB1-AST2A    I28 @BASEBOARD_FAB2_LIB.BASEBOARD_FAB2(SCH_1):PAGE148
 U25W4 AA13   GND3 AST2520A1-GP-GP_ASIC2-GB1-AST2A    I28 @BASEBOARD_FAB2_LIB.BASEBOARD_FAB2(SCH_1):PAGE148
 U25W4 AA15   GND4 AST2520A1-GP-GP_ASIC2-GB1-AST2A    I28 @BASEBOARD_FAB2_LIB.BASEBOARD_FAB2(SCH_1):PAGE148
 U25W4  AA7   GND5 AST2520A1-GP-GP_ASIC2-GB1-AST2A    I28 @BASEBOARD_FAB2_LIB.BASEBOARD_FAB2(SCH_1):PAGE148
 U25W4  AA9   GND6 AST2520A1-GP-GP_ASIC2-GB1-AST2A    I28 @BASEBOARD_FAB2_LIB.BASEBOARD_FAB2(SCH_1):PAGE148
 U25W4  AB1   GND7 AST2520A1-GP-GP_ASIC2-GB1-AST2A    I28 @BASEBOARD_FAB2_LIB.BASEBOARD_FAB2(SCH_1):PAGE148
 U25W4 AB22   GND8 AST2520A1-GP-GP_ASIC2-GB1-AST2A    I28 @BASEBOARD_FAB2_LIB.BASEBOARD_FAB2(SCH_1):PAGE148
 U25W4   C6   GND9 AST2520A1-GP-GP_ASIC2-GB1-AST2A    I28 @BASEBOARD_FAB2_LIB.BASEBOARD_FAB2(SCH_1):PAGE148
 U25W4   E8  GND10 AST2520A1-GP-GP_ASIC2-GB1-AST2A    I28 @BASEBOARD_FAB2_LIB.BASEBOARD_FAB2(SCH_1):PAGE148
 U25W4  F16  GND11 AST2520A1-GP-GP_ASIC2-GB1-AST2A    I28 @BASEBOARD_FAB2_LIB.BASEBOARD_FAB2(SCH_1):PAGE148
 U25W4  G19  GND12 AST2520A1-GP-GP_ASIC2-GB1-AST2A    I28 @BASEBOARD_FAB2_LIB.BASEBOARD_FAB2(SCH_1):PAGE148
 U25W4   G6  GND13 AST2520A1-GP-GP_ASIC2-GB1-AST2A    I28 @BASEBOARD_FAB2_LIB.BASEBOARD_FAB2(SCH_1):PAGE148
 U25W4   H6  GND14 AST2520A1-GP-GP_ASIC2-GB1-AST2A    I28 @BASEBOARD_FAB2_LIB.BASEBOARD_FAB2(SCH_1):PAGE148
 U25W4  J10  GND15 AST2520A1-GP-GP_ASIC2-GB1-AST2A    I28 @BASEBOARD_FAB2_LIB.BASEBOARD_FAB2(SCH_1):PAGE148
 U25W4  J11  GND16 AST2520A1-GP-GP_ASIC2-GB1-AST2A    I28 @BASEBOARD_FAB2_LIB.BASEBOARD_FAB2(SCH_1):PAGE148
 U25W4  J12  GND17 AST2520A1-GP-GP_ASIC2-GB1-AST2A    I28 @BASEBOARD_FAB2_LIB.BASEBOARD_FAB2(SCH_1):PAGE148
 U25W4  J13  GND18 AST2520A1-GP-GP_ASIC2-GB1-AST2A    I28 @BASEBOARD_FAB2_LIB.BASEBOARD_FAB2(SCH_1):PAGE148
 U25W4  J14  GND19 AST2520A1-GP-GP_ASIC2-GB1-AST2A    I28 @BASEBOARD_FAB2_LIB.BASEBOARD_FAB2(SCH_1):PAGE148
 U25W4  J21  GND20 AST2520A1-GP-GP_ASIC2-GB1-AST2A    I28 @BASEBOARD_FAB2_LIB.BASEBOARD_FAB2(SCH_1):PAGE148
 U25W4  J22  GND21 AST2520A1-GP-GP_ASIC2-GB1-AST2A    I28 @BASEBOARD_FAB2_LIB.BASEBOARD_FAB2(SCH_1):PAGE148
 U25W4   J5  GND22 AST2520A1-GP-GP_ASIC2-GB1-AST2A    I28 @BASEBOARD_FAB2_LIB.BASEBOARD_FAB2(SCH_1):PAGE148
 U25W4   J9  GND23 AST2520A1-GP-GP_ASIC2-GB1-AST2A    I28 @BASEBOARD_FAB2_LIB.BASEBOARD_FAB2(SCH_1):PAGE148
 U25W4  K10  GND24 AST2520A1-GP-GP_ASIC2-GB1-AST2A    I28 @BASEBOARD_FAB2_LIB.BASEBOARD_FAB2(SCH_1):PAGE148
 U25W4  K11  GND25 AST2520A1-GP-GP_ASIC2-GB1-AST2A    I28 @BASEBOARD_FAB2_LIB.BASEBOARD_FAB2(SCH_1):PAGE148
 U25W4  K12  GND26 AST2520A1-GP-GP_ASIC2-GB1-AST2A    I28 @BASEBOARD_FAB2_LIB.BASEBOARD_FAB2(SCH_1):PAGE148
 U25W4  K13  GND27 AST2520A1-GP-GP_ASIC2-GB1-AST2A    I28 @BASEBOARD_FAB2_LIB.BASEBOARD_FAB2(SCH_1):PAGE148
 U25W4  K14  GND28 AST2520A1-GP-GP_ASIC2-GB1-AST2A    I28 @BASEBOARD_FAB2_LIB.BASEBOARD_FAB2(SCH_1):PAGE148
 U25W4  K16  GND29 AST2520A1-GP-GP_ASIC2-GB1-AST2A    I28 @BASEBOARD_FAB2_LIB.BASEBOARD_FAB2(SCH_1):PAGE148
 U25W4   K9  GND30 AST2520A1-GP-GP_ASIC2-GB1-AST2A    I28 @BASEBOARD_FAB2_LIB.BASEBOARD_FAB2(SCH_1):PAGE148
 U25W4  L10  GND31 AST2520A1-GP-GP_ASIC2-GB1-AST2A    I28 @BASEBOARD_FAB2_LIB.BASEBOARD_FAB2(SCH_1):PAGE148
 U25W4  L11  GND32 AST2520A1-GP-GP_ASIC2-GB1-AST2A    I28 @BASEBOARD_FAB2_LIB.BASEBOARD_FAB2(SCH_1):PAGE148
 U25W4  L12  GND33 AST2520A1-GP-GP_ASIC2-GB1-AST2A    I28 @BASEBOARD_FAB2_LIB.BASEBOARD_FAB2(SCH_1):PAGE148
 U25W4  L13  GND34 AST2520A1-GP-GP_ASIC2-GB1-AST2A    I28 @BASEBOARD_FAB2_LIB.BASEBOARD_FAB2(SCH_1):PAGE148
 U25W4  L14  GND35 AST2520A1-GP-GP_ASIC2-GB1-AST2A    I28 @BASEBOARD_FAB2_LIB.BASEBOARD_FAB2(SCH_1):PAGE148
 U25W4   L9  GND36 AST2520A1-GP-GP_ASIC2-GB1-AST2A    I28 @BASEBOARD_FAB2_LIB.BASEBOARD_FAB2(SCH_1):PAGE148
 U25W4   M1  GND37 AST2520A1-GP-GP_ASIC2-GB1-AST2A    I28 @BASEBOARD_FAB2_LIB.BASEBOARD_FAB2(SCH_1):PAGE148
 U25W4  M10  GND38 AST2520A1-GP-GP_ASIC2-GB1-AST2A    I28 @BASEBOARD_FAB2_LIB.BASEBOARD_FAB2(SCH_1):PAGE148
 U25W4  M11  GND39 AST2520A1-GP-GP_ASIC2-GB1-AST2A    I28 @BASEBOARD_FAB2_LIB.BASEBOARD_FAB2(SCH_1):PAGE148
 U25W4  M12  GND40 AST2520A1-GP-GP_ASIC2-GB1-AST2A    I28 @BASEBOARD_FAB2_LIB.BASEBOARD_FAB2(SCH_1):PAGE148
 U25W4  M13  GND41 AST2520A1-GP-GP_ASIC2-GB1-AST2A    I28 @BASEBOARD_FAB2_LIB.BASEBOARD_FAB2(SCH_1):PAGE148
 U25W4  M14  GND42 AST2520A1-GP-GP_ASIC2-GB1-AST2A    I28 @BASEBOARD_FAB2_LIB.BASEBOARD_FAB2(SCH_1):PAGE148
 U25W4  M16  GND43 AST2520A1-GP-GP_ASIC2-GB1-AST2A    I28 @BASEBOARD_FAB2_LIB.BASEBOARD_FAB2(SCH_1):PAGE148
 U25W4  M17  GND44 AST2520A1-GP-GP_ASIC2-GB1-AST2A    I28 @BASEBOARD_FAB2_LIB.BASEBOARD_FAB2(SCH_1):PAGE148
 U25W4   M2  GND45 AST2520A1-GP-GP_ASIC2-GB1-AST2A    I28 @BASEBOARD_FAB2_LIB.BASEBOARD_FAB2(SCH_1):PAGE148
 U25W4   M3  GND46 AST2520A1-GP-GP_ASIC2-GB1-AST2A    I28 @BASEBOARD_FAB2_LIB.BASEBOARD_FAB2(SCH_1):PAGE148
 U25W4   M4  GND47 AST2520A1-GP-GP_ASIC2-GB1-AST2A    I28 @BASEBOARD_FAB2_LIB.BASEBOARD_FAB2(SCH_1):PAGE148
 U25W4   M5  GND48 AST2520A1-GP-GP_ASIC2-GB1-AST2A    I28 @BASEBOARD_FAB2_LIB.BASEBOARD_FAB2(SCH_1):PAGE148
 U25W4   M6  GND49 AST2520A1-GP-GP_ASIC2-GB1-AST2A    I28 @BASEBOARD_FAB2_LIB.BASEBOARD_FAB2(SCH_1):PAGE148
 U25W4   M7  GND50 AST2520A1-GP-GP_ASIC2-GB1-AST2A    I28 @BASEBOARD_FAB2_LIB.BASEBOARD_FAB2(SCH_1):PAGE148
 U25W4   M9  GND51 AST2520A1-GP-GP_ASIC2-GB1-AST2A    I28 @BASEBOARD_FAB2_LIB.BASEBOARD_FAB2(SCH_1):PAGE148
 U25W4  N10  GND52 AST2520A1-GP-GP_ASIC2-GB1-AST2A    I28 @BASEBOARD_FAB2_LIB.BASEBOARD_FAB2(SCH_1):PAGE148
 U25W4  N11  GND53 AST2520A1-GP-GP_ASIC2-GB1-AST2A    I28 @BASEBOARD_FAB2_LIB.BASEBOARD_FAB2(SCH_1):PAGE148
 U25W4  N12  GND54 AST2520A1-GP-GP_ASIC2-GB1-AST2A    I28 @BASEBOARD_FAB2_LIB.BASEBOARD_FAB2(SCH_1):PAGE148
 U25W4  N13  GND55 AST2520A1-GP-GP_ASIC2-GB1-AST2A    I28 @BASEBOARD_FAB2_LIB.BASEBOARD_FAB2(SCH_1):PAGE148
 U25W4  N14  GND56 AST2520A1-GP-GP_ASIC2-GB1-AST2A    I28 @BASEBOARD_FAB2_LIB.BASEBOARD_FAB2(SCH_1):PAGE148
 U25W4   N9  GND57 AST2520A1-GP-GP_ASIC2-GB1-AST2A    I28 @BASEBOARD_FAB2_LIB.BASEBOARD_FAB2(SCH_1):PAGE148
 U25W4  T16  GND58 AST2520A1-GP-GP_ASIC2-GB1-AST2A    I28 @BASEBOARD_FAB2_LIB.BASEBOARD_FAB2(SCH_1):PAGE148
 U25W4   T6  GND59 AST2520A1-GP-GP_ASIC2-GB1-AST2A    I28 @BASEBOARD_FAB2_LIB.BASEBOARD_FAB2(SCH_1):PAGE148
 U25W4   T7  GND60 AST2520A1-GP-GP_ASIC2-GB1-AST2A    I28 @BASEBOARD_FAB2_LIB.BASEBOARD_FAB2(SCH_1):PAGE148
 U25W4  U11  GND61 AST2520A1-GP-GP_ASIC2-GB1-AST2A    I28 @BASEBOARD_FAB2_LIB.BASEBOARD_FAB2(SCH_1):PAGE148
 U25W4   U6  GND62 AST2520A1-GP-GP_ASIC2-GB1-AST2A    I28 @BASEBOARD_FAB2_LIB.BASEBOARD_FAB2(SCH_1):PAGE148
 U25W4  V10  GND63 AST2520A1-GP-GP_ASIC2-GB1-AST2A    I28 @BASEBOARD_FAB2_LIB.BASEBOARD_FAB2(SCH_1):PAGE148
 U25W4  V12  GND64 AST2520A1-GP-GP_ASIC2-GB1-AST2A    I28 @BASEBOARD_FAB2_LIB.BASEBOARD_FAB2(SCH_1):PAGE148
 U25W4  V14  GND65 AST2520A1-GP-GP_ASIC2-GB1-AST2A    I28 @BASEBOARD_FAB2_LIB.BASEBOARD_FAB2(SCH_1):PAGE148
 U25W4  V16  GND66 AST2520A1-GP-GP_ASIC2-GB1-AST2A    I28 @BASEBOARD_FAB2_LIB.BASEBOARD_FAB2(SCH_1):PAGE148
 U25W4   V8  GND67 AST2520A1-GP-GP_ASIC2-GB1-AST2A    I28 @BASEBOARD_FAB2_LIB.BASEBOARD_FAB2(SCH_1):PAGE148
 U25W4   E5  GND68 AST2520A1-GP-GP_ASIC2-GB1-AST2A    I28 @BASEBOARD_FAB2_LIB.BASEBOARD_FAB2(SCH_1):PAGE148
  U6W1   12    GND PCA9555PWRG4-GP_DISCRET-G5-PCAA    I97 @BASEBOARD_FAB2_LIB.BASEBOARD_FAB2(SCH_1):PAGE247

GND_LAN_TRCT1234_C @BASEBOARD_FAB2_LIB.BASEBOARD_FAB2(SCH_1):GND_LAN_TRCT1234_C
  C9G4    1      A CAP_A_0402V-0.1UF,16V,10%,X7R,A    I46 @BASEBOARD_FAB2_LIB.BASEBOARD_FAB2(SCH_1):PAGE141
  C9G6    1      A CAP_A_0402V-0.1UF,16V,10%,X7R,A    I47 @BASEBOARD_FAB2_LIB.BASEBOARD_FAB2(SCH_1):PAGE141
  C9G5    1      A CAP_0402-1.0UF,16V,10%,X7S,G71A    I48 @BASEBOARD_FAB2_LIB.BASEBOARD_FAB2(SCH_1):PAGE141
 JA9G1  R12  TRCT1 CONN17_H71061002_PIP1-CONN,H71A   I109 @BASEBOARD_FAB2_LIB.BASEBOARD_FAB2(SCH_1):PAGE141
 JA9G1   R6  TRCT2 CONN17_H71061002_PIP1-CONN,H71A   I109 @BASEBOARD_FAB2_LIB.BASEBOARD_FAB2(SCH_1):PAGE141
 JA9G1   R1  TRCT3 CONN17_H71061002_PIP1-CONN,H71A   I109 @BASEBOARD_FAB2_LIB.BASEBOARD_FAB2(SCH_1):PAGE141
 JA9G1   R7  TRCT4 CONN17_H71061002_PIP1-CONN,H71A   I109 @BASEBOARD_FAB2_LIB.BASEBOARD_FAB2(SCH_1):PAGE141

GND_NIC @BASEBOARD_FAB2_LIB.BASEBOARD_FAB2(SCH_1):GND_NIC
 JA9G1  MH1    MH1 CONN17_H71061002_PIP1-CONN,H71A   I109 @BASEBOARD_FAB2_LIB.BASEBOARD_FAB2(SCH_1):PAGE141
 JA9G1  MH2    MH2 CONN17_H71061002_PIP1-CONN,H71A   I109 @BASEBOARD_FAB2_LIB.BASEBOARD_FAB2(SCH_1):PAGE141
 R1U51    2      B RES_0402-0.0,5%,1/16W,CHIP,G21A   I112 @BASEBOARD_FAB2_LIB.BASEBOARD_FAB2(SCH_1):PAGE141
  R1U3    2      B RES_0402-0.0,5%,1/16W,CHIP,G21A   I114 @BASEBOARD_FAB2_LIB.BASEBOARD_FAB2(SCH_1):PAGE141

GPIOS7 @BASEBOARD_FAB2_LIB.BASEBOARD_FAB2(SCH_1):GPIOS7
R25W100    2      B RES_0402-4.75K,1%,1/16W,CHIP,GA    I13 @BASEBOARD_FAB2_LIB.BASEBOARD_FAB2(SCH_1):PAGE151
 U25W4 AA20 GPIOS7_VPOB9 AST2520A1-GP-GP_ASIC2-GB1-AST2A   I104 @BASEBOARD_FAB2_LIB.BASEBOARD_FAB2(SCH_1):PAGE146

HSC_SMBUS_SWITCH_EN @BASEBOARD_FAB2_LIB.BASEBOARD_FAB2(SCH_1):HSC_SMBUS_SWITCH_EN
R25W101    2      B RES_0402-4.75K,1%,1/16W,EMPTY,A    I27 @BASEBOARD_FAB2_LIB.BASEBOARD_FAB2(SCH_1):PAGE151
  U6W2    5     EN PCA9515ADGKR-1-GP_DISCRET-G5-PA    I77 @BASEBOARD_FAB2_LIB.BASEBOARD_FAB2(SCH_1):PAGE247
 U25W4  U21 GPIOZ4_VPOG6_NORA4 AST2520A1-GP-GP_ASIC2-GB1-AST2A   I104 @BASEBOARD_FAB2_LIB.BASEBOARD_FAB2(SCH_1):PAGE146

H_CPU0_ABC_MEMHOT_LVT3_R_N @BASEBOARD_FAB2_LIB.BASEBOARD_FAB2(SCH_1):H_CPU0_ABC_MEMHOT_LVT3_R_N
  U9G1    9     A3 GTL2014_SM-IC,D66151-001     I1 @BASEBOARD_FAB2_LIB.BASEBOARD_FAB2(SCH_1):PAGE152
 R1U59    1      A RES_0402-0.0,5%,1/16W,CHIP,G21A    I74 @BASEBOARD_FAB2_LIB.BASEBOARD_FAB2(SCH_1):PAGE152

H_CPU0_BMCINIT @BASEBOARD_FAB2_LIB.BASEBOARD_FAB2(SCH_1):H_CPU0_BMCINIT
  U5D1 BD23 BMCINIT SKX_EXT_B_BGA1-IC,TBD   I259 @BASEBOARD_FAB2_LIB.BASEBOARD_FAB2(SCH_1):PAGE21
  R6D7    2      B RES_0402-240,1.0%,1/16W,EMPTY,A    I31 @BASEBOARD_FAB2_LIB.BASEBOARD_FAB2(SCH_1):PAGE90
 R6D16    2      B RES_0402-0.0,5%,1/16W,EMPTY,G2A   I299 @BASEBOARD_FAB2_LIB.BASEBOARD_FAB2(SCH_1):PAGE156

H_CPU0_CATERR_G_N @BASEBOARD_FAB2_LIB.BASEBOARD_FAB2(SCH_1):H_CPU0_CATERR_G_N
  U5D1 AL14 CATERR_N SKX_EXT_B_BGA1-IC,TBD   I259 @BASEBOARD_FAB2_LIB.BASEBOARD_FAB2(SCH_1):PAGE21
 R3P59    1      A RES_0402-0.0,5%,1/16W,CHIP,G21A    I97 @BASEBOARD_FAB2_LIB.BASEBOARD_FAB2(SCH_1):PAGE92
  R4R2    2      B RES_0402-150.0,1%,1/16W,CHIP,GA   I101 @BASEBOARD_FAB2_LIB.BASEBOARD_FAB2(SCH_1):PAGE92

H_CPU0_DEF_MEMHOT_LVT3_R_N @BASEBOARD_FAB2_LIB.BASEBOARD_FAB2(SCH_1):H_CPU0_DEF_MEMHOT_LVT3_R_N
  U9G1   10     A2 GTL2014_SM-IC,D66151-001     I1 @BASEBOARD_FAB2_LIB.BASEBOARD_FAB2(SCH_1):PAGE152
 R9G33    1      A RES_0402-0.0,5%,1/16W,CHIP,G21A    I73 @BASEBOARD_FAB2_LIB.BASEBOARD_FAB2(SCH_1):PAGE152

H_CPU0_ERR0_G_N @BASEBOARD_FAB2_LIB.BASEBOARD_FAB2(SCH_1):H_CPU0_ERR0_G_N
  U5D1 AJ12 ERROR_N<0> SKX_EXT_B_BGA1-IC,TBD   I259 @BASEBOARD_FAB2_LIB.BASEBOARD_FAB2(SCH_1):PAGE21
 R2T17    1      A RES_0402-0.0,5%,1/16W,CHIP,G21A    I23 @BASEBOARD_FAB2_LIB.BASEBOARD_FAB2(SCH_1):PAGE93

H_CPU0_ERR1_G_N @BASEBOARD_FAB2_LIB.BASEBOARD_FAB2(SCH_1):H_CPU0_ERR1_G_N
  U5D1 AK11 ERROR_N<1> SKX_EXT_B_BGA1-IC,TBD   I259 @BASEBOARD_FAB2_LIB.BASEBOARD_FAB2(SCH_1):PAGE21
 R2T32    1      A RES_0402-0.0,5%,1/16W,CHIP,G21A    I15 @BASEBOARD_FAB2_LIB.BASEBOARD_FAB2(SCH_1):PAGE93

H_CPU0_ERR2_G_N @BASEBOARD_FAB2_LIB.BASEBOARD_FAB2(SCH_1):H_CPU0_ERR2_G_N
  U5D1 AL12 ERROR_N<2> SKX_EXT_B_BGA1-IC,TBD   I259 @BASEBOARD_FAB2_LIB.BASEBOARD_FAB2(SCH_1):PAGE21
 R2T40    1      A RES_0402-0.0,5%,1/16W,CHIP,G21A    I93 @BASEBOARD_FAB2_LIB.BASEBOARD_FAB2(SCH_1):PAGE92

H_CPU0_FAST_WAKE @BASEBOARD_FAB2_LIB.BASEBOARD_FAB2(SCH_1):H_CPU0_FAST_WAKE
  R2T5    2      B RES_0402-1.00K,1%,1/16W,CHIP,GA   I326 @BASEBOARD_FAB2_LIB.BASEBOARD_FAB2(SCH_1):PAGE157
  Q2T1    3      C NPN_SM-MMBT3904,IC,C52245-001   I330 @BASEBOARD_FAB2_LIB.BASEBOARD_FAB2(SCH_1):PAGE157
  Q2T2    1   GATE FET_N_SOT23LF-2N7002,FET,C7925A   I340 @BASEBOARD_FAB2_LIB.BASEBOARD_FAB2(SCH_1):PAGE157

H_CPU0_FAST_WAKE_B_N @BASEBOARD_FAB2_LIB.BASEBOARD_FAB2(SCH_1):H_CPU0_FAST_WAKE_B_N
  Q2T1    1      B NPN_SM-MMBT3904,IC,C52245-001   I330 @BASEBOARD_FAB2_LIB.BASEBOARD_FAB2(SCH_1):PAGE157
  R4R1    2      B RES_0402-1.00K,1%,1/16W,CHIP,GA   I368 @BASEBOARD_FAB2_LIB.BASEBOARD_FAB2(SCH_1):PAGE157

H_CPU0_FAST_WAKE_LVT3_N @BASEBOARD_FAB2_LIB.BASEBOARD_FAB2(SCH_1):H_CPU0_FAST_WAKE_LVT3_N
  U7C1 BV47 GPP_D10_SSATA_DEVSLP4 LBG_CORE_QAT_EXT_D_BGA1-IC,H91A   I115 @BASEBOARD_FAB2_LIB.BASEBOARD_FAB2(SCH_1):PAGE119
  R2T7    2      B RES_0402-1.00K,1%,1/16W,CHIP,GA   I327 @BASEBOARD_FAB2_LIB.BASEBOARD_FAB2(SCH_1):PAGE157
  Q2T2    3    DRN FET_N_SOT23LF-2N7002,FET,C7925A   I340 @BASEBOARD_FAB2_LIB.BASEBOARD_FAB2(SCH_1):PAGE157
 U25W4   B5 RGMII1TXCK_RMII1RCLKO_GPIOT0 AST2520A1-GP-GP_ASIC2-GB1-AST2A   I106 @BASEBOARD_FAB2_LIB.BASEBOARD_FAB2(SCH_1):PAGE147

H_CPU0_FAST_WAKE_N @BASEBOARD_FAB2_LIB.BASEBOARD_FAB2(SCH_1):H_CPU0_FAST_WAKE_N
  U5D1 AF15 PM_FAST_WAKE_N SKX_EXT_B_BGA1-IC,TBD   I259 @BASEBOARD_FAB2_LIB.BASEBOARD_FAB2(SCH_1):PAGE21
 R3D18    1      A RES_0402-0.0,5%,1/16W,CHIP,G21A    I33 @BASEBOARD_FAB2_LIB.BASEBOARD_FAB2(SCH_1):PAGE97
  R4R4    2      B RES_0402-150.0,1%,1/16W,CHIP,GA    I42 @BASEBOARD_FAB2_LIB.BASEBOARD_FAB2(SCH_1):PAGE97
  R4R1    1      A RES_0402-1.00K,1%,1/16W,CHIP,GA   I368 @BASEBOARD_FAB2_LIB.BASEBOARD_FAB2(SCH_1):PAGE157

H_CPU0_FIVR_FAULT_G @BASEBOARD_FAB2_LIB.BASEBOARD_FAB2(SCH_1):H_CPU0_FIVR_FAULT_G
  U5D1 AU14 FIVR_FAULT SKX_EXT_B_BGA1-IC,TBD   I204 @BASEBOARD_FAB2_LIB.BASEBOARD_FAB2(SCH_1):PAGE22
  U7D2    3     B1 GTL2014_SM-IC,D66151-001    I32 @BASEBOARD_FAB2_LIB.BASEBOARD_FAB2(SCH_1):PAGE92

H_CPU0_MEMABC_MEMHOT @BASEBOARD_FAB2_LIB.BASEBOARD_FAB2(SCH_1):H_CPU0_MEMABC_MEMHOT
  Q3U1    6 DRAIN<0> FET_N_DUAL_SMLF-NTJD4001N,FET,A    I49 @BASEBOARD_FAB2_LIB.BASEBOARD_FAB2(SCH_1):PAGE94
  R7G7    2      B RES_0402-4.75K,1%,1/16W,CHIP,GA    I51 @BASEBOARD_FAB2_LIB.BASEBOARD_FAB2(SCH_1):PAGE94
  Q3U1    5 GATE<0> FET_N_DUAL_SMLF-NTJD4001N,FET,A    I89 @BASEBOARD_FAB2_LIB.BASEBOARD_FAB2(SCH_1):PAGE94

H_CPU0_MEMABC_MEMHOT_G_N @BASEBOARD_FAB2_LIB.BASEBOARD_FAB2(SCH_1):H_CPU0_MEMABC_MEMHOT_G_N
  U5D1 AH13 MEM_HOT_C012_N SKX_EXT_B_BGA1-IC,TBD   I259 @BASEBOARD_FAB2_LIB.BASEBOARD_FAB2(SCH_1):PAGE21
  Q3U1    3 DRAIN<0> FET_N_DUAL_SMLF-NTJD4001N,FET,A    I89 @BASEBOARD_FAB2_LIB.BASEBOARD_FAB2(SCH_1):PAGE94
  Q2U1    6 DRAIN<0> FET_N_DUAL_SMLF-NTJD4001N,FET,A    I28 @BASEBOARD_FAB2_LIB.BASEBOARD_FAB2(SCH_1):PAGE95
 R9G34    1      A RES_0402-0.0,5%,1/16W,CHIP,G21A    I45 @BASEBOARD_FAB2_LIB.BASEBOARD_FAB2(SCH_1):PAGE152
 R2U51    2      B RES_0402-0.0,5%,1/16W,EMPTY,G2A    I51 @BASEBOARD_FAB2_LIB.BASEBOARD_FAB2(SCH_1):PAGE152
 R2U40    2      B RES_0402-150.0,1%,1/16W,CHIP,GA    I53 @BASEBOARD_FAB2_LIB.BASEBOARD_FAB2(SCH_1):PAGE152
 R4P17    1      A RES_0402-150.0,1%,1/16W,CHIP,GA    I58 @BASEBOARD_FAB2_LIB.BASEBOARD_FAB2(SCH_1):PAGE152

H_CPU0_MEMABC_MEMHOT_G_PCH_N @BASEBOARD_FAB2_LIB.BASEBOARD_FAB2(SCH_1):H_CPU0_MEMABC_MEMHOT_G_PCH_N
 R2U51    1      A RES_0402-0.0,5%,1/16W,EMPTY,G2A    I51 @BASEBOARD_FAB2_LIB.BASEBOARD_FAB2(SCH_1):PAGE152
 R2U49    1      A RES_0402-0.0,5%,1/16W,EMPTY,G2A    I66 @BASEBOARD_FAB2_LIB.BASEBOARD_FAB2(SCH_1):PAGE152

H_CPU0_MEMABC_MEMHOT_G_R_N @BASEBOARD_FAB2_LIB.BASEBOARD_FAB2(SCH_1):H_CPU0_MEMABC_MEMHOT_G_R_N
  U9G1    6     B3 GTL2014_SM-IC,D66151-001     I1 @BASEBOARD_FAB2_LIB.BASEBOARD_FAB2(SCH_1):PAGE152
 R9G34    2      B RES_0402-0.0,5%,1/16W,CHIP,G21A    I45 @BASEBOARD_FAB2_LIB.BASEBOARD_FAB2(SCH_1):PAGE152

H_CPU0_MEMABC_MEMHOT_LVT3_BMC_N @BASEBOARD_FAB2_LIB.BASEBOARD_FAB2(SCH_1):H_CPU0_MEMABC_MEMHOT_LVT3_BMC_N
 R2U47    2      B RES_0402-0.0,5%,1/16W,CHIP,G21A    I79 @BASEBOARD_FAB2_LIB.BASEBOARD_FAB2(SCH_1):PAGE152
R25W103    2      B RES_0402-4.75K,1%,1/16W,EMPTY,A    I29 @BASEBOARD_FAB2_LIB.BASEBOARD_FAB2(SCH_1):PAGE151
 U25W4  V22 GPIOZ6_VPOG8_NORA6 AST2520A1-GP-GP_ASIC2-GB1-AST2A   I104 @BASEBOARD_FAB2_LIB.BASEBOARD_FAB2(SCH_1):PAGE146

H_CPU0_MEMABC_MEMHOT_LVT3_K_N @BASEBOARD_FAB2_LIB.BASEBOARD_FAB2(SCH_1):H_CPU0_MEMABC_MEMHOT_LVT3_K_N
 R1U46    1      A RES_0402-33.2,1%,1/16W,CHIP,G2A     I6 @BASEBOARD_FAB2_LIB.BASEBOARD_FAB2(SCH_1):PAGE152
 R2U49    2      B RES_0402-0.0,5%,1/16W,EMPTY,G2A    I66 @BASEBOARD_FAB2_LIB.BASEBOARD_FAB2(SCH_1):PAGE152
 R1U59    2      B RES_0402-0.0,5%,1/16W,CHIP,G21A    I74 @BASEBOARD_FAB2_LIB.BASEBOARD_FAB2(SCH_1):PAGE152

H_CPU0_MEMABC_MEMHOT_LVT3_N @BASEBOARD_FAB2_LIB.BASEBOARD_FAB2(SCH_1):H_CPU0_MEMABC_MEMHOT_LVT3_N
 R1U46    2      B RES_0402-33.2,1%,1/16W,CHIP,G2A     I6 @BASEBOARD_FAB2_LIB.BASEBOARD_FAB2(SCH_1):PAGE152
 R2U47    1      A RES_0402-0.0,5%,1/16W,CHIP,G21A    I79 @BASEBOARD_FAB2_LIB.BASEBOARD_FAB2(SCH_1):PAGE152
 R3N30    1      A RES_0402-0.0,5%,1/16W,EMPTY,G2A    I95 @BASEBOARD_FAB2_LIB.BASEBOARD_FAB2(SCH_1):PAGE152

H_CPU0_MEMABC_MEMHOT_PCH_N @BASEBOARD_FAB2_LIB.BASEBOARD_FAB2(SCH_1):H_CPU0_MEMABC_MEMHOT_PCH_N
  U7C1  Y15 GPP_L12_TESTCH1_D1 LBG_CORE_QAT_EXT_D_BGA1-IC,H91A    I34 @BASEBOARD_FAB2_LIB.BASEBOARD_FAB2(SCH_1):PAGE121
 R3N30    2      B RES_0402-0.0,5%,1/16W,EMPTY,G2A    I95 @BASEBOARD_FAB2_LIB.BASEBOARD_FAB2(SCH_1):PAGE152

H_CPU0_MEMDEF_MEMHOT @BASEBOARD_FAB2_LIB.BASEBOARD_FAB2(SCH_1):H_CPU0_MEMDEF_MEMHOT
  Q7E1    6 DRAIN<0> FET_N_DUAL_SMLF-NTJD4001N,FET,A    I60 @BASEBOARD_FAB2_LIB.BASEBOARD_FAB2(SCH_1):PAGE94
  Q7E1    5 GATE<0> FET_N_DUAL_SMLF-NTJD4001N,FET,A    I64 @BASEBOARD_FAB2_LIB.BASEBOARD_FAB2(SCH_1):PAGE94
  R3R4    2      B RES_0402-4.75K,1%,1/16W,CHIP,GA    I66 @BASEBOARD_FAB2_LIB.BASEBOARD_FAB2(SCH_1):PAGE94

H_CPU0_MEMDEF_MEMHOT_G_N @BASEBOARD_FAB2_LIB.BASEBOARD_FAB2(SCH_1):H_CPU0_MEMDEF_MEMHOT_G_N
  U5D1 AF13 MEM_HOT_C345_N SKX_EXT_B_BGA1-IC,TBD   I259 @BASEBOARD_FAB2_LIB.BASEBOARD_FAB2(SCH_1):PAGE21
  Q7E1    3 DRAIN<0> FET_N_DUAL_SMLF-NTJD4001N,FET,A    I64 @BASEBOARD_FAB2_LIB.BASEBOARD_FAB2(SCH_1):PAGE94
  Q2U1    3 DRAIN<0> FET_N_DUAL_SMLF-NTJD4001N,FET,A   I113 @BASEBOARD_FAB2_LIB.BASEBOARD_FAB2(SCH_1):PAGE95
 R1U58    1      A RES_0402-0.0,5%,1/16W,CHIP,G21A    I49 @BASEBOARD_FAB2_LIB.BASEBOARD_FAB2(SCH_1):PAGE152
 R1U56    2      B RES_0402-0.0,5%,1/16W,EMPTY,G2A    I50 @BASEBOARD_FAB2_LIB.BASEBOARD_FAB2(SCH_1):PAGE152
 R2U41    2      B RES_0402-150.0,1%,1/16W,CHIP,GA    I54 @BASEBOARD_FAB2_LIB.BASEBOARD_FAB2(SCH_1):PAGE152
 R4P20    1      A RES_0402-150.0,1%,1/16W,CHIP,GA    I59 @BASEBOARD_FAB2_LIB.BASEBOARD_FAB2(SCH_1):PAGE152

H_CPU0_MEMDEF_MEMHOT_G_PCH_N @BASEBOARD_FAB2_LIB.BASEBOARD_FAB2(SCH_1):H_CPU0_MEMDEF_MEMHOT_G_PCH_N
 R9G27    1      A RES_0402-0.0,5%,1/16W,EMPTY,G2A    I47 @BASEBOARD_FAB2_LIB.BASEBOARD_FAB2(SCH_1):PAGE152
 R1U56    1      A RES_0402-0.0,5%,1/16W,EMPTY,G2A    I50 @BASEBOARD_FAB2_LIB.BASEBOARD_FAB2(SCH_1):PAGE152

H_CPU0_MEMDEF_MEMHOT_G_R_N @BASEBOARD_FAB2_LIB.BASEBOARD_FAB2(SCH_1):H_CPU0_MEMDEF_MEMHOT_G_R_N
  U9G1    5     B2 GTL2014_SM-IC,D66151-001     I1 @BASEBOARD_FAB2_LIB.BASEBOARD_FAB2(SCH_1):PAGE152
 R1U58    2      B RES_0402-0.0,5%,1/16W,CHIP,G21A    I49 @BASEBOARD_FAB2_LIB.BASEBOARD_FAB2(SCH_1):PAGE152

H_CPU0_MEMDEF_MEMHOT_LVT3_BMC_N @BASEBOARD_FAB2_LIB.BASEBOARD_FAB2(SCH_1):H_CPU0_MEMDEF_MEMHOT_LVT3_BMC_N
 R9G29    2      B RES_0402-0.0,5%,1/16W,CHIP,G21A    I92 @BASEBOARD_FAB2_LIB.BASEBOARD_FAB2(SCH_1):PAGE152
R25W98    2      B RES_0402-4.75K,1%,1/16W,CHIP,GA    I12 @BASEBOARD_FAB2_LIB.BASEBOARD_FAB2(SCH_1):PAGE151
 U25W4  R19 GPIOS4_VPOB6 AST2520A1-GP-GP_ASIC2-GB1-AST2A   I104 @BASEBOARD_FAB2_LIB.BASEBOARD_FAB2(SCH_1):PAGE146

H_CPU0_MEMDEF_MEMHOT_LVT3_K_N @BASEBOARD_FAB2_LIB.BASEBOARD_FAB2(SCH_1):H_CPU0_MEMDEF_MEMHOT_LVT3_K_N
 R9G31    1      A RES_0402-33.2,1%,1/16W,CHIP,G2A    I14 @BASEBOARD_FAB2_LIB.BASEBOARD_FAB2(SCH_1):PAGE152
 R9G27    2      B RES_0402-0.0,5%,1/16W,EMPTY,G2A    I47 @BASEBOARD_FAB2_LIB.BASEBOARD_FAB2(SCH_1):PAGE152
 R9G33    2      B RES_0402-0.0,5%,1/16W,CHIP,G21A    I73 @BASEBOARD_FAB2_LIB.BASEBOARD_FAB2(SCH_1):PAGE152

H_CPU0_MEMDEF_MEMHOT_LVT3_N @BASEBOARD_FAB2_LIB.BASEBOARD_FAB2(SCH_1):H_CPU0_MEMDEF_MEMHOT_LVT3_N
 R9G31    2      B RES_0402-33.2,1%,1/16W,CHIP,G2A    I14 @BASEBOARD_FAB2_LIB.BASEBOARD_FAB2(SCH_1):PAGE152
 R9G29    1      A RES_0402-0.0,5%,1/16W,CHIP,G21A    I92 @BASEBOARD_FAB2_LIB.BASEBOARD_FAB2(SCH_1):PAGE152
 R9G30    1      A RES_0402-0.0,5%,1/16W,EMPTY,G2A    I98 @BASEBOARD_FAB2_LIB.BASEBOARD_FAB2(SCH_1):PAGE152

H_CPU0_MEMDEF_MEMHOT_PCH_N @BASEBOARD_FAB2_LIB.BASEBOARD_FAB2(SCH_1):H_CPU0_MEMDEF_MEMHOT_PCH_N
  U7C1 AD13 GPP_L13_TESTCH1_D2 LBG_CORE_QAT_EXT_D_BGA1-IC,H91A    I34 @BASEBOARD_FAB2_LIB.BASEBOARD_FAB2(SCH_1):PAGE121
 R9G30    2      B RES_0402-0.0,5%,1/16W,EMPTY,G2A    I98 @BASEBOARD_FAB2_LIB.BASEBOARD_FAB2(SCH_1):PAGE152

H_CPU0_MSMI_G_N @BASEBOARD_FAB2_LIB.BASEBOARD_FAB2(SCH_1):H_CPU0_MSMI_G_N
  U5D1 AN20 MSMI_N SKX_EXT_B_BGA1-IC,TBD   I259 @BASEBOARD_FAB2_LIB.BASEBOARD_FAB2(SCH_1):PAGE21
  R6D9    2      B RES_0402-150.0,1%,1/16W,CHIP,GA    I64 @BASEBOARD_FAB2_LIB.BASEBOARD_FAB2(SCH_1):PAGE92
 R7D27    1      A RES_0402-0.0,5%,1/16W,CHIP,G21A    I68 @BASEBOARD_FAB2_LIB.BASEBOARD_FAB2(SCH_1):PAGE92

H_CPU0_PROCHOT_G_N @BASEBOARD_FAB2_LIB.BASEBOARD_FAB2(SCH_1):H_CPU0_PROCHOT_G_N
  U5D1 AC16 PROCHOT_N SKX_EXT_B_BGA1-IC,TBD   I259 @BASEBOARD_FAB2_LIB.BASEBOARD_FAB2(SCH_1):PAGE21
  R4R3    2      B RES_0402-150.0,1%,1/16W,CHIP,GA    I79 @BASEBOARD_FAB2_LIB.BASEBOARD_FAB2(SCH_1):PAGE93
 R2T60    1      A RES_0402-0.0,5%,1/16W,CHIP,G21A   I103 @BASEBOARD_FAB2_LIB.BASEBOARD_FAB2(SCH_1):PAGE93
 R2T59    1      A RES_0402-0.0,5%,1/16W,EMPTY,G2A   I107 @BASEBOARD_FAB2_LIB.BASEBOARD_FAB2(SCH_1):PAGE93
 R2T72    2      B RES_0402-150.0,1%,1/16W,CHIP,GA   I143 @BASEBOARD_FAB2_LIB.BASEBOARD_FAB2(SCH_1):PAGE93
  Q7E3    6 DRAIN<0> FET_N_DUAL_SMLF-NTJD4001N,FET,A    I52 @BASEBOARD_FAB2_LIB.BASEBOARD_FAB2(SCH_1):PAGE95
  Q7E5    3 DRAIN<0> FET_N_DUAL_SMLF-NTJD4001N,FET,A    I59 @BASEBOARD_FAB2_LIB.BASEBOARD_FAB2(SCH_1):PAGE95

H_CPU0_PROCHOT_G_PCH_N @BASEBOARD_FAB2_LIB.BASEBOARD_FAB2(SCH_1):H_CPU0_PROCHOT_G_PCH_N
 R2T59    2      B RES_0402-0.0,5%,1/16W,EMPTY,G2A   I107 @BASEBOARD_FAB2_LIB.BASEBOARD_FAB2(SCH_1):PAGE93
 R2T71    2      B RES_0402-0.0,5%,1/16W,EMPTY,G2A   I109 @BASEBOARD_FAB2_LIB.BASEBOARD_FAB2(SCH_1):PAGE93

H_CPU0_PROCHOT_G_R_N @BASEBOARD_FAB2_LIB.BASEBOARD_FAB2(SCH_1):H_CPU0_PROCHOT_G_R_N
  U2T4    3     B1 GTL2014_SM-IC,D66151-001    I30 @BASEBOARD_FAB2_LIB.BASEBOARD_FAB2(SCH_1):PAGE93
 R2T60    2      B RES_0402-0.0,5%,1/16W,CHIP,G21A   I103 @BASEBOARD_FAB2_LIB.BASEBOARD_FAB2(SCH_1):PAGE93

H_CPU0_THERMTRIP_G_N @BASEBOARD_FAB2_LIB.BASEBOARD_FAB2(SCH_1):H_CPU0_THERMTRIP_G_N
  U5D1 AB15 THERMTRIP_N SKX_EXT_B_BGA1-IC,TBD   I259 @BASEBOARD_FAB2_LIB.BASEBOARD_FAB2(SCH_1):PAGE21
  R7E2    2      B RES_0402-75,1.0%,1/16W,CHIP,G2A    I19 @BASEBOARD_FAB2_LIB.BASEBOARD_FAB2(SCH_1):PAGE92
  U7D2    6     B3 GTL2014_SM-IC,D66151-001    I32 @BASEBOARD_FAB2_LIB.BASEBOARD_FAB2(SCH_1):PAGE92

H_CPU1_BMCINIT @BASEBOARD_FAB2_LIB.BASEBOARD_FAB2(SCH_1):H_CPU1_BMCINIT
  U2D1 BD23 BMCINIT SKX_EXT_B_BGA1-IC,TBD   I172 @BASEBOARD_FAB2_LIB.BASEBOARD_FAB2(SCH_1):PAGE55
 R3D16    2      B RES_0402-240,1.0%,1/16W,EMPTY,A    I24 @BASEBOARD_FAB2_LIB.BASEBOARD_FAB2(SCH_1):PAGE90
 R3D31    2      B RES_0402-0.0,5%,1/16W,EMPTY,G2A   I300 @BASEBOARD_FAB2_LIB.BASEBOARD_FAB2(SCH_1):PAGE156

H_CPU1_CATERR_G_N @BASEBOARD_FAB2_LIB.BASEBOARD_FAB2(SCH_1):H_CPU1_CATERR_G_N
  U2D1 AL14 CATERR_N SKX_EXT_B_BGA1-IC,TBD   I172 @BASEBOARD_FAB2_LIB.BASEBOARD_FAB2(SCH_1):PAGE55
 R3P58    1      A RES_0402-0.0,5%,1/16W,CHIP,G21A    I98 @BASEBOARD_FAB2_LIB.BASEBOARD_FAB2(SCH_1):PAGE92
 R7P18    2      B RES_0402-150.0,1%,1/16W,CHIP,GA   I100 @BASEBOARD_FAB2_LIB.BASEBOARD_FAB2(SCH_1):PAGE92

H_CPU1_ERR0_G_N @BASEBOARD_FAB2_LIB.BASEBOARD_FAB2(SCH_1):H_CPU1_ERR0_G_N
  U2D1 AJ12 ERROR_N<0> SKX_EXT_B_BGA1-IC,TBD   I172 @BASEBOARD_FAB2_LIB.BASEBOARD_FAB2(SCH_1):PAGE55
 R2T20    1      A RES_0402-0.0,5%,1/16W,CHIP,G21A    I16 @BASEBOARD_FAB2_LIB.BASEBOARD_FAB2(SCH_1):PAGE93

H_CPU1_ERR1_G_N @BASEBOARD_FAB2_LIB.BASEBOARD_FAB2(SCH_1):H_CPU1_ERR1_G_N
  U2D1 AK11 ERROR_N<1> SKX_EXT_B_BGA1-IC,TBD   I172 @BASEBOARD_FAB2_LIB.BASEBOARD_FAB2(SCH_1):PAGE55
 R2T27    1      A RES_0402-0.0,5%,1/16W,CHIP,G21A    I13 @BASEBOARD_FAB2_LIB.BASEBOARD_FAB2(SCH_1):PAGE93

H_CPU1_ERR2_G_N @BASEBOARD_FAB2_LIB.BASEBOARD_FAB2(SCH_1):H_CPU1_ERR2_G_N
  U2D1 AL12 ERROR_N<2> SKX_EXT_B_BGA1-IC,TBD   I172 @BASEBOARD_FAB2_LIB.BASEBOARD_FAB2(SCH_1):PAGE55
 R2T44    1      A RES_0402-0.0,5%,1/16W,CHIP,G21A    I92 @BASEBOARD_FAB2_LIB.BASEBOARD_FAB2(SCH_1):PAGE92

H_CPU1_FAST_WAKE_N @BASEBOARD_FAB2_LIB.BASEBOARD_FAB2(SCH_1):H_CPU1_FAST_WAKE_N
  U2D1 AF15 PM_FAST_WAKE_N SKX_EXT_B_BGA1-IC,TBD   I172 @BASEBOARD_FAB2_LIB.BASEBOARD_FAB2(SCH_1):PAGE55
 R3D18    2      B RES_0402-0.0,5%,1/16W,CHIP,G21A    I33 @BASEBOARD_FAB2_LIB.BASEBOARD_FAB2(SCH_1):PAGE97
 R7P20    2      B RES_0402-150.0,1%,1/16W,CHIP,GA    I44 @BASEBOARD_FAB2_LIB.BASEBOARD_FAB2(SCH_1):PAGE97

H_CPU1_FIVR_FAULT_G @BASEBOARD_FAB2_LIB.BASEBOARD_FAB2(SCH_1):H_CPU1_FIVR_FAULT_G
  U2D1 AU14 FIVR_FAULT SKX_EXT_B_BGA1-IC,TBD   I169 @BASEBOARD_FAB2_LIB.BASEBOARD_FAB2(SCH_1):PAGE56
  U3P2    3     B1 GTL2014_SM-IC,D66151-001     I1 @BASEBOARD_FAB2_LIB.BASEBOARD_FAB2(SCH_1):PAGE92
  R3R2    1      A RES_0402-1.00K,1%,1/16W,CHIP,GA    I75 @BASEBOARD_FAB2_LIB.BASEBOARD_FAB2(SCH_1):PAGE92

H_CPU1_GHJ_MEMHOT_LVT3_R_N @BASEBOARD_FAB2_LIB.BASEBOARD_FAB2(SCH_1):H_CPU1_GHJ_MEMHOT_LVT3_R_N
  U9G1   12     A1 GTL2014_SM-IC,D66151-001     I1 @BASEBOARD_FAB2_LIB.BASEBOARD_FAB2(SCH_1):PAGE152
 R9G32    1      A RES_0402-0.0,5%,1/16W,CHIP,G21A    I72 @BASEBOARD_FAB2_LIB.BASEBOARD_FAB2(SCH_1):PAGE152

H_CPU1_KLM_MEMHOT_LVT3_R_N @BASEBOARD_FAB2_LIB.BASEBOARD_FAB2(SCH_1):H_CPU1_KLM_MEMHOT_LVT3_R_N
  U9G1   13     A0 GTL2014_SM-IC,D66151-001     I1 @BASEBOARD_FAB2_LIB.BASEBOARD_FAB2(SCH_1):PAGE152
 R9G28    1      A RES_0402-0.0,5%,1/16W,CHIP,G21A    I71 @BASEBOARD_FAB2_LIB.BASEBOARD_FAB2(SCH_1):PAGE152

H_CPU1_MEMGHJ_MEMHOT @BASEBOARD_FAB2_LIB.BASEBOARD_FAB2(SCH_1):H_CPU1_MEMGHJ_MEMHOT
  Q7E2    6 DRAIN<0> FET_N_DUAL_SMLF-NTJD4001N,FET,A    I69 @BASEBOARD_FAB2_LIB.BASEBOARD_FAB2(SCH_1):PAGE94
  Q7E2    5 GATE<0> FET_N_DUAL_SMLF-NTJD4001N,FET,A    I75 @BASEBOARD_FAB2_LIB.BASEBOARD_FAB2(SCH_1):PAGE94
 R3R10    2      B RES_0402-4.75K,1%,1/16W,CHIP,GA    I79 @BASEBOARD_FAB2_LIB.BASEBOARD_FAB2(SCH_1):PAGE94

H_CPU1_MEMGHJ_MEMHOT_G_N @BASEBOARD_FAB2_LIB.BASEBOARD_FAB2(SCH_1):H_CPU1_MEMGHJ_MEMHOT_G_N
  U2D1 AH13 MEM_HOT_C012_N SKX_EXT_B_BGA1-IC,TBD   I172 @BASEBOARD_FAB2_LIB.BASEBOARD_FAB2(SCH_1):PAGE55
  Q7E2    3 DRAIN<0> FET_N_DUAL_SMLF-NTJD4001N,FET,A    I75 @BASEBOARD_FAB2_LIB.BASEBOARD_FAB2(SCH_1):PAGE94
  Q4B2    6 DRAIN<0> FET_N_DUAL_SMLF-NTJD4001N,FET,A    I32 @BASEBOARD_FAB2_LIB.BASEBOARD_FAB2(SCH_1):PAGE95
 R1U41    2      B RES_0402-150.0,1%,1/16W,CHIP,GA    I56 @BASEBOARD_FAB2_LIB.BASEBOARD_FAB2(SCH_1):PAGE152
  R7P5    1      A RES_0402-150.0,1%,1/16W,CHIP,GA    I61 @BASEBOARD_FAB2_LIB.BASEBOARD_FAB2(SCH_1):PAGE152
 R1U53    1      A RES_0402-0.0,5%,1/16W,CHIP,G21A    I64 @BASEBOARD_FAB2_LIB.BASEBOARD_FAB2(SCH_1):PAGE152
 R1U55    1      A RES_0402-0.0,5%,1/16W,EMPTY,G2A    I67 @BASEBOARD_FAB2_LIB.BASEBOARD_FAB2(SCH_1):PAGE152

H_CPU1_MEMGHJ_MEMHOT_G_PCH_N @BASEBOARD_FAB2_LIB.BASEBOARD_FAB2(SCH_1):H_CPU1_MEMGHJ_MEMHOT_G_PCH_N
 R1U55    2      B RES_0402-0.0,5%,1/16W,EMPTY,G2A    I67 @BASEBOARD_FAB2_LIB.BASEBOARD_FAB2(SCH_1):PAGE152
 R1U57    2      B RES_0402-0.0,5%,1/16W,EMPTY,G2A    I69 @BASEBOARD_FAB2_LIB.BASEBOARD_FAB2(SCH_1):PAGE152

H_CPU1_MEMGHJ_MEMHOT_G_R_N @BASEBOARD_FAB2_LIB.BASEBOARD_FAB2(SCH_1):H_CPU1_MEMGHJ_MEMHOT_G_R_N
  U9G1    3     B1 GTL2014_SM-IC,D66151-001     I1 @BASEBOARD_FAB2_LIB.BASEBOARD_FAB2(SCH_1):PAGE152
 R1U53    2      B RES_0402-0.0,5%,1/16W,CHIP,G21A    I64 @BASEBOARD_FAB2_LIB.BASEBOARD_FAB2(SCH_1):PAGE152

H_CPU1_MEMGHJ_MEMHOT_LVT3_BMC_N @BASEBOARD_FAB2_LIB.BASEBOARD_FAB2(SCH_1):H_CPU1_MEMGHJ_MEMHOT_LVT3_BMC_N
 R1U54    2      B RES_0402-0.0,5%,1/16W,CHIP,G21A    I93 @BASEBOARD_FAB2_LIB.BASEBOARD_FAB2(SCH_1):PAGE152
 U25W4  D15 GPIOG6_SGPS2I0_SALT3 AST2520A1-GP-GP_ASIC2-GB1-AST2A   I117 @BASEBOARD_FAB2_LIB.BASEBOARD_FAB2(SCH_1):PAGE145

H_CPU1_MEMGHJ_MEMHOT_LVT3_K_N @BASEBOARD_FAB2_LIB.BASEBOARD_FAB2(SCH_1):H_CPU1_MEMGHJ_MEMHOT_LVT3_K_N
 R1U36    1      A RES_0402-33.2,1%,1/16W,CHIP,G2A    I15 @BASEBOARD_FAB2_LIB.BASEBOARD_FAB2(SCH_1):PAGE152
 R1U57    1      A RES_0402-0.0,5%,1/16W,EMPTY,G2A    I69 @BASEBOARD_FAB2_LIB.BASEBOARD_FAB2(SCH_1):PAGE152
 R9G32    2      B RES_0402-0.0,5%,1/16W,CHIP,G21A    I72 @BASEBOARD_FAB2_LIB.BASEBOARD_FAB2(SCH_1):PAGE152

H_CPU1_MEMGHJ_MEMHOT_LVT3_N @BASEBOARD_FAB2_LIB.BASEBOARD_FAB2(SCH_1):H_CPU1_MEMGHJ_MEMHOT_LVT3_N
 R1U36    2      B RES_0402-33.2,1%,1/16W,CHIP,G2A    I15 @BASEBOARD_FAB2_LIB.BASEBOARD_FAB2(SCH_1):PAGE152
 R1U54    1      A RES_0402-0.0,5%,1/16W,CHIP,G21A    I93 @BASEBOARD_FAB2_LIB.BASEBOARD_FAB2(SCH_1):PAGE152
 R3P63    1      A RES_0402-0.0,5%,1/16W,EMPTY,G2A   I100 @BASEBOARD_FAB2_LIB.BASEBOARD_FAB2(SCH_1):PAGE152

H_CPU1_MEMGHJ_MEMHOT_PCH_N @BASEBOARD_FAB2_LIB.BASEBOARD_FAB2(SCH_1):H_CPU1_MEMGHJ_MEMHOT_PCH_N
  U7C1 AA13 GPP_L14_TESTCH1_D3 LBG_CORE_QAT_EXT_D_BGA1-IC,H91A    I34 @BASEBOARD_FAB2_LIB.BASEBOARD_FAB2(SCH_1):PAGE121
 R3P63    2      B RES_0402-0.0,5%,1/16W,EMPTY,G2A   I100 @BASEBOARD_FAB2_LIB.BASEBOARD_FAB2(SCH_1):PAGE152

H_CPU1_MEMKLM_MEMHOT @BASEBOARD_FAB2_LIB.BASEBOARD_FAB2(SCH_1):H_CPU1_MEMKLM_MEMHOT
  Q4B1    5 GATE<0> FET_N_DUAL_SMLF-NTJD4001N,FET,A    I77 @BASEBOARD_FAB2_LIB.BASEBOARD_FAB2(SCH_1):PAGE94
  R6M4    2      B RES_0402-4.75K,1%,1/16W,CHIP,GA    I82 @BASEBOARD_FAB2_LIB.BASEBOARD_FAB2(SCH_1):PAGE94
  Q4B1    6 DRAIN<0> FET_N_DUAL_SMLF-NTJD4001N,FET,A    I84 @BASEBOARD_FAB2_LIB.BASEBOARD_FAB2(SCH_1):PAGE94

H_CPU1_MEMKLM_MEMHOT_G_N @BASEBOARD_FAB2_LIB.BASEBOARD_FAB2(SCH_1):H_CPU1_MEMKLM_MEMHOT_G_N
  U2D1 AF13 MEM_HOT_C345_N SKX_EXT_B_BGA1-IC,TBD   I172 @BASEBOARD_FAB2_LIB.BASEBOARD_FAB2(SCH_1):PAGE55
  Q4B1    3 DRAIN<0> FET_N_DUAL_SMLF-NTJD4001N,FET,A    I77 @BASEBOARD_FAB2_LIB.BASEBOARD_FAB2(SCH_1):PAGE94
  Q4B2    3 DRAIN<0> FET_N_DUAL_SMLF-NTJD4001N,FET,A    I33 @BASEBOARD_FAB2_LIB.BASEBOARD_FAB2(SCH_1):PAGE95
 R1U35    2      B RES_0402-150.0,1%,1/16W,CHIP,GA    I57 @BASEBOARD_FAB2_LIB.BASEBOARD_FAB2(SCH_1):PAGE152
 R7P21    1      A RES_0402-150.0,1%,1/16W,CHIP,GA    I62 @BASEBOARD_FAB2_LIB.BASEBOARD_FAB2(SCH_1):PAGE152
 R1U60    1      A RES_0402-0.0,5%,1/16W,CHIP,G21A    I65 @BASEBOARD_FAB2_LIB.BASEBOARD_FAB2(SCH_1):PAGE152
 R1U62    1      A RES_0402-0.0,5%,1/16W,EMPTY,G2A    I68 @BASEBOARD_FAB2_LIB.BASEBOARD_FAB2(SCH_1):PAGE152

H_CPU1_MEMKLM_MEMHOT_G_PCH_N @BASEBOARD_FAB2_LIB.BASEBOARD_FAB2(SCH_1):H_CPU1_MEMKLM_MEMHOT_G_PCH_N
 R1U62    2      B RES_0402-0.0,5%,1/16W,EMPTY,G2A    I68 @BASEBOARD_FAB2_LIB.BASEBOARD_FAB2(SCH_1):PAGE152
 R1U61    2      B RES_0402-0.0,5%,1/16W,EMPTY,G2A    I70 @BASEBOARD_FAB2_LIB.BASEBOARD_FAB2(SCH_1):PAGE152

H_CPU1_MEMKLM_MEMHOT_G_R_N @BASEBOARD_FAB2_LIB.BASEBOARD_FAB2(SCH_1):H_CPU1_MEMKLM_MEMHOT_G_R_N
  U9G1    2     B0 GTL2014_SM-IC,D66151-001     I1 @BASEBOARD_FAB2_LIB.BASEBOARD_FAB2(SCH_1):PAGE152
 R1U60    2      B RES_0402-0.0,5%,1/16W,CHIP,G21A    I65 @BASEBOARD_FAB2_LIB.BASEBOARD_FAB2(SCH_1):PAGE152

H_CPU1_MEMKLM_MEMHOT_LVT3_BMC_N @BASEBOARD_FAB2_LIB.BASEBOARD_FAB2(SCH_1):H_CPU1_MEMKLM_MEMHOT_LVT3_BMC_N
 R2U46    2      B RES_0402-0.0,5%,1/16W,CHIP,G21A    I94 @BASEBOARD_FAB2_LIB.BASEBOARD_FAB2(SCH_1):PAGE152
 U25W4   A4 RGMII1RXCTL_GPIOU5 AST2520A1-GP-GP_ASIC2-GB1-AST2A   I106 @BASEBOARD_FAB2_LIB.BASEBOARD_FAB2(SCH_1):PAGE147

H_CPU1_MEMKLM_MEMHOT_LVT3_K_N @BASEBOARD_FAB2_LIB.BASEBOARD_FAB2(SCH_1):H_CPU1_MEMKLM_MEMHOT_LVT3_K_N
 R1U34    1      A RES_0402-33.2,1%,1/16W,CHIP,G2A    I16 @BASEBOARD_FAB2_LIB.BASEBOARD_FAB2(SCH_1):PAGE152
 R1U61    1      A RES_0402-0.0,5%,1/16W,EMPTY,G2A    I70 @BASEBOARD_FAB2_LIB.BASEBOARD_FAB2(SCH_1):PAGE152
 R9G28    2      B RES_0402-0.0,5%,1/16W,CHIP,G21A    I71 @BASEBOARD_FAB2_LIB.BASEBOARD_FAB2(SCH_1):PAGE152

H_CPU1_MEMKLM_MEMHOT_LVT3_N @BASEBOARD_FAB2_LIB.BASEBOARD_FAB2(SCH_1):H_CPU1_MEMKLM_MEMHOT_LVT3_N
 R1U34    2      B RES_0402-33.2,1%,1/16W,CHIP,G2A    I16 @BASEBOARD_FAB2_LIB.BASEBOARD_FAB2(SCH_1):PAGE152
 R2U46    1      A RES_0402-0.0,5%,1/16W,CHIP,G21A    I94 @BASEBOARD_FAB2_LIB.BASEBOARD_FAB2(SCH_1):PAGE152
 R2U45    1      A RES_0402-0.0,5%,1/16W,EMPTY,G2A   I102 @BASEBOARD_FAB2_LIB.BASEBOARD_FAB2(SCH_1):PAGE152

H_CPU1_MEMKLM_MEMHOT_PCH_N @BASEBOARD_FAB2_LIB.BASEBOARD_FAB2(SCH_1):H_CPU1_MEMKLM_MEMHOT_PCH_N
  U7C1  Y11 GPP_L15_TESTCH1_D4 LBG_CORE_QAT_EXT_D_BGA1-IC,H91A    I34 @BASEBOARD_FAB2_LIB.BASEBOARD_FAB2(SCH_1):PAGE121
 R2U45    2      B RES_0402-0.0,5%,1/16W,EMPTY,G2A   I102 @BASEBOARD_FAB2_LIB.BASEBOARD_FAB2(SCH_1):PAGE152

H_CPU1_MSMI_G_N @BASEBOARD_FAB2_LIB.BASEBOARD_FAB2(SCH_1):H_CPU1_MSMI_G_N
  U2D1 AN20 MSMI_N SKX_EXT_B_BGA1-IC,TBD   I172 @BASEBOARD_FAB2_LIB.BASEBOARD_FAB2(SCH_1):PAGE55
 R7P27    2      B RES_0402-150.0,1%,1/16W,CHIP,GA    I65 @BASEBOARD_FAB2_LIB.BASEBOARD_FAB2(SCH_1):PAGE92
 R7D28    1      A RES_0402-0.0,5%,1/16W,CHIP,G21A    I67 @BASEBOARD_FAB2_LIB.BASEBOARD_FAB2(SCH_1):PAGE92

H_CPU1_PROCHOT_G_N @BASEBOARD_FAB2_LIB.BASEBOARD_FAB2(SCH_1):H_CPU1_PROCHOT_G_N
  U2D1 AC16 PROCHOT_N SKX_EXT_B_BGA1-IC,TBD   I172 @BASEBOARD_FAB2_LIB.BASEBOARD_FAB2(SCH_1):PAGE55
 R2T68    1      A RES_0402-0.0,5%,1/16W,CHIP,G21A   I102 @BASEBOARD_FAB2_LIB.BASEBOARD_FAB2(SCH_1):PAGE93
 R7P28    2      B RES_0402-150.0,1%,1/16W,CHIP,GA   I106 @BASEBOARD_FAB2_LIB.BASEBOARD_FAB2(SCH_1):PAGE93
 R2T69    1      A RES_0402-0.0,5%,1/16W,EMPTY,G2A   I108 @BASEBOARD_FAB2_LIB.BASEBOARD_FAB2(SCH_1):PAGE93
 R2T73    2      B RES_0402-150.0,1%,1/16W,CHIP,GA   I144 @BASEBOARD_FAB2_LIB.BASEBOARD_FAB2(SCH_1):PAGE93
  Q7E3    3 DRAIN<0> FET_N_DUAL_SMLF-NTJD4001N,FET,A    I51 @BASEBOARD_FAB2_LIB.BASEBOARD_FAB2(SCH_1):PAGE95
  Q7E6    3 DRAIN<0> FET_N_DUAL_SMLF-NTJD4001N,FET,A    I69 @BASEBOARD_FAB2_LIB.BASEBOARD_FAB2(SCH_1):PAGE95

H_CPU1_PROCHOT_G_PCH_N @BASEBOARD_FAB2_LIB.BASEBOARD_FAB2(SCH_1):H_CPU1_PROCHOT_G_PCH_N
 R2T69    2      B RES_0402-0.0,5%,1/16W,EMPTY,G2A   I108 @BASEBOARD_FAB2_LIB.BASEBOARD_FAB2(SCH_1):PAGE93
 R7D43    2      B RES_0402-0.0,5%,1/16W,EMPTY,G2A   I110 @BASEBOARD_FAB2_LIB.BASEBOARD_FAB2(SCH_1):PAGE93

H_CPU1_PROCHOT_G_R_N @BASEBOARD_FAB2_LIB.BASEBOARD_FAB2(SCH_1):H_CPU1_PROCHOT_G_R_N
  U2T4    2     B0 GTL2014_SM-IC,D66151-001    I30 @BASEBOARD_FAB2_LIB.BASEBOARD_FAB2(SCH_1):PAGE93
 R2T68    2      B RES_0402-0.0,5%,1/16W,CHIP,G21A   I102 @BASEBOARD_FAB2_LIB.BASEBOARD_FAB2(SCH_1):PAGE93

H_CPU1_THERMTRIP_G_N @BASEBOARD_FAB2_LIB.BASEBOARD_FAB2(SCH_1):H_CPU1_THERMTRIP_G_N
  U2D1 AB15 THERMTRIP_N SKX_EXT_B_BGA1-IC,TBD   I172 @BASEBOARD_FAB2_LIB.BASEBOARD_FAB2(SCH_1):PAGE55
  U3P2    6     B3 GTL2014_SM-IC,D66151-001     I1 @BASEBOARD_FAB2_LIB.BASEBOARD_FAB2(SCH_1):PAGE92
 R3P41    2      B RES_0402-75,1.0%,1/16W,CHIP,G2A     I9 @BASEBOARD_FAB2_LIB.BASEBOARD_FAB2(SCH_1):PAGE92

H_CPU_CATERR_G_N @BASEBOARD_FAB2_LIB.BASEBOARD_FAB2(SCH_1):H_CPU_CATERR_G_N
  U3P2    5     B2 GTL2014_SM-IC,D66151-001     I1 @BASEBOARD_FAB2_LIB.BASEBOARD_FAB2(SCH_1):PAGE92
 R3P59    2      B RES_0402-0.0,5%,1/16W,CHIP,G21A    I97 @BASEBOARD_FAB2_LIB.BASEBOARD_FAB2(SCH_1):PAGE92
 R3P58    2      B RES_0402-0.0,5%,1/16W,CHIP,G21A    I98 @BASEBOARD_FAB2_LIB.BASEBOARD_FAB2(SCH_1):PAGE92

H_CPU_ERR0_GTL_N @BASEBOARD_FAB2_LIB.BASEBOARD_FAB2(SCH_1):H_CPU_ERR0_GTL_N
  U2T4    6     B3 GTL2014_SM-IC,D66151-001    I30 @BASEBOARD_FAB2_LIB.BASEBOARD_FAB2(SCH_1):PAGE93
 R2T16    2      B RES_0402-75,1.0%,1/16W,CHIP,G2A    I67 @BASEBOARD_FAB2_LIB.BASEBOARD_FAB2(SCH_1):PAGE93

H_CPU_ERR0_GTL_R_N @BASEBOARD_FAB2_LIB.BASEBOARD_FAB2(SCH_1):H_CPU_ERR0_GTL_R_N
 R2T20    2      B RES_0402-0.0,5%,1/16W,CHIP,G21A    I16 @BASEBOARD_FAB2_LIB.BASEBOARD_FAB2(SCH_1):PAGE93
 R2T17    2      B RES_0402-0.0,5%,1/16W,CHIP,G21A    I23 @BASEBOARD_FAB2_LIB.BASEBOARD_FAB2(SCH_1):PAGE93
 R2T19    2      B RES_0402-200.0,1%,1/16W,CHIP,GA    I63 @BASEBOARD_FAB2_LIB.BASEBOARD_FAB2(SCH_1):PAGE93
 R2T16    1      A RES_0402-75,1.0%,1/16W,CHIP,G2A    I67 @BASEBOARD_FAB2_LIB.BASEBOARD_FAB2(SCH_1):PAGE93
 R2T57    2      B RES_0402-0.0,5%,1/16W,EMPTY,G2A    I88 @BASEBOARD_FAB2_LIB.BASEBOARD_FAB2(SCH_1):PAGE93

H_CPU_ERR0_PCH_N @BASEBOARD_FAB2_LIB.BASEBOARD_FAB2(SCH_1):H_CPU_ERR0_PCH_N
 R2T57    1      A RES_0402-0.0,5%,1/16W,EMPTY,G2A    I88 @BASEBOARD_FAB2_LIB.BASEBOARD_FAB2(SCH_1):PAGE93
 R2T58    1      A RES_0402-0.0,5%,1/16W,EMPTY,G2A    I94 @BASEBOARD_FAB2_LIB.BASEBOARD_FAB2(SCH_1):PAGE93

H_CPU_ERR1_GTL_N @BASEBOARD_FAB2_LIB.BASEBOARD_FAB2(SCH_1):H_CPU_ERR1_GTL_N
  U2T4    5     B2 GTL2014_SM-IC,D66151-001    I30 @BASEBOARD_FAB2_LIB.BASEBOARD_FAB2(SCH_1):PAGE93
 R2T31    2      B RES_0402-75,1.0%,1/16W,CHIP,G2A    I68 @BASEBOARD_FAB2_LIB.BASEBOARD_FAB2(SCH_1):PAGE93

H_CPU_ERR1_GTL_R_N @BASEBOARD_FAB2_LIB.BASEBOARD_FAB2(SCH_1):H_CPU_ERR1_GTL_R_N
 R2T27    2      B RES_0402-0.0,5%,1/16W,CHIP,G21A    I13 @BASEBOARD_FAB2_LIB.BASEBOARD_FAB2(SCH_1):PAGE93
 R2T32    2      B RES_0402-0.0,5%,1/16W,CHIP,G21A    I15 @BASEBOARD_FAB2_LIB.BASEBOARD_FAB2(SCH_1):PAGE93
 R2T31    1      A RES_0402-75,1.0%,1/16W,CHIP,G2A    I68 @BASEBOARD_FAB2_LIB.BASEBOARD_FAB2(SCH_1):PAGE93
 R2T26    2      B RES_0402-200.0,1%,1/16W,CHIP,GA    I87 @BASEBOARD_FAB2_LIB.BASEBOARD_FAB2(SCH_1):PAGE93
 R2T61    2      B RES_0402-0.0,5%,1/16W,EMPTY,G2A    I89 @BASEBOARD_FAB2_LIB.BASEBOARD_FAB2(SCH_1):PAGE93

H_CPU_ERR1_PCH_N @BASEBOARD_FAB2_LIB.BASEBOARD_FAB2(SCH_1):H_CPU_ERR1_PCH_N
 R2T61    1      A RES_0402-0.0,5%,1/16W,EMPTY,G2A    I89 @BASEBOARD_FAB2_LIB.BASEBOARD_FAB2(SCH_1):PAGE93
 R2T62    1      A RES_0402-0.0,5%,1/16W,EMPTY,G2A    I93 @BASEBOARD_FAB2_LIB.BASEBOARD_FAB2(SCH_1):PAGE93

H_CPU_ERR2_GTL_N @BASEBOARD_FAB2_LIB.BASEBOARD_FAB2(SCH_1):H_CPU_ERR2_GTL_N
  U7D2    5     B2 GTL2014_SM-IC,D66151-001    I32 @BASEBOARD_FAB2_LIB.BASEBOARD_FAB2(SCH_1):PAGE92
 R2T43    2      B RES_0402-75,1.0%,1/16W,CHIP,G2A    I96 @BASEBOARD_FAB2_LIB.BASEBOARD_FAB2(SCH_1):PAGE92

H_CPU_ERR2_G_R_N @BASEBOARD_FAB2_LIB.BASEBOARD_FAB2(SCH_1):H_CPU_ERR2_G_R_N
 R2T44    2      B RES_0402-0.0,5%,1/16W,CHIP,G21A    I92 @BASEBOARD_FAB2_LIB.BASEBOARD_FAB2(SCH_1):PAGE92
 R2T40    2      B RES_0402-0.0,5%,1/16W,CHIP,G21A    I93 @BASEBOARD_FAB2_LIB.BASEBOARD_FAB2(SCH_1):PAGE92
 R2T37    2      B RES_0402-200.0,1%,1/16W,CHIP,GA    I94 @BASEBOARD_FAB2_LIB.BASEBOARD_FAB2(SCH_1):PAGE92
 R2T43    1      A RES_0402-75,1.0%,1/16W,CHIP,G2A    I96 @BASEBOARD_FAB2_LIB.BASEBOARD_FAB2(SCH_1):PAGE92

H_CPU_MSMI_G_N @BASEBOARD_FAB2_LIB.BASEBOARD_FAB2(SCH_1):H_CPU_MSMI_G_N
  U7D2    2     B0 GTL2014_SM-IC,D66151-001    I32 @BASEBOARD_FAB2_LIB.BASEBOARD_FAB2(SCH_1):PAGE92
 R7D28    2      B RES_0402-0.0,5%,1/16W,CHIP,G21A    I67 @BASEBOARD_FAB2_LIB.BASEBOARD_FAB2(SCH_1):PAGE92
 R7D27    2      B RES_0402-0.0,5%,1/16W,CHIP,G21A    I68 @BASEBOARD_FAB2_LIB.BASEBOARD_FAB2(SCH_1):PAGE92

H_PMSYNC_CLK_24M @BASEBOARD_FAB2_LIB.BASEBOARD_FAB2(SCH_1):H_PMSYNC_CLK_24M
 R4P19    2      B RES_0402-49.9,1%,1/16W,CHIP,G2A   I219 @BASEBOARD_FAB2_LIB.BASEBOARD_FAB2(SCH_1):PAGE21
 R7P26    2      B RES_0402-49.9,1%,1/16W,CHIP,G2A   I156 @BASEBOARD_FAB2_LIB.BASEBOARD_FAB2(SCH_1):PAGE55
 R8B20    2      B RES_0402-10.0,1%,1/16W,CHIP,G2A   I110 @BASEBOARD_FAB2_LIB.BASEBOARD_FAB2(SCH_1):PAGE114
 R8B21    1      A RES_0402-49.9,1%,1/16W,EMPTY,GA   I124 @BASEBOARD_FAB2_LIB.BASEBOARD_FAB2(SCH_1):PAGE114

H_PMSYNC_CLK_24M_CPU0 @BASEBOARD_FAB2_LIB.BASEBOARD_FAB2(SCH_1):H_PMSYNC_CLK_24M_CPU0
 R4P19    1      A RES_0402-49.9,1%,1/16W,CHIP,G2A   I219 @BASEBOARD_FAB2_LIB.BASEBOARD_FAB2(SCH_1):PAGE21
  U5D1 AT19 PMSYNC_CLK SKX_EXT_B_BGA1-IC,TBD   I259 @BASEBOARD_FAB2_LIB.BASEBOARD_FAB2(SCH_1):PAGE21

H_PMSYNC_CLK_24M_CPU1 @BASEBOARD_FAB2_LIB.BASEBOARD_FAB2(SCH_1):H_PMSYNC_CLK_24M_CPU1
 R7P26    1      A RES_0402-49.9,1%,1/16W,CHIP,G2A   I156 @BASEBOARD_FAB2_LIB.BASEBOARD_FAB2(SCH_1):PAGE55
  U2D1 AT19 PMSYNC_CLK SKX_EXT_B_BGA1-IC,TBD   I172 @BASEBOARD_FAB2_LIB.BASEBOARD_FAB2(SCH_1):PAGE55

H_PMSYNC_CLK_24M_R @BASEBOARD_FAB2_LIB.BASEBOARD_FAB2(SCH_1):H_PMSYNC_CLK_24M_R
  U7C1 BY51 CLOCKSE_PMSYNCCLK1 LBG_CORE_QAT_EXT_D_BGA1-IC,H91A    I40 @BASEBOARD_FAB2_LIB.BASEBOARD_FAB2(SCH_1):PAGE114
 R8B20    1      A RES_0402-10.0,1%,1/16W,CHIP,G2A   I110 @BASEBOARD_FAB2_LIB.BASEBOARD_FAB2(SCH_1):PAGE114

H_PM_SYNC1_GTL_R @BASEBOARD_FAB2_LIB.BASEBOARD_FAB2(SCH_1):H_PM_SYNC1_GTL_R
  R3N9    1      A RES_0402-10.0,1%,1/16W,CHIP,G2A    I66 @BASEBOARD_FAB2_LIB.BASEBOARD_FAB2(SCH_1):PAGE118
  U7C1  U13 PM_SYNC LBG_CORE_QAT_EXT_D_BGA1-IC,H91A    I73 @BASEBOARD_FAB2_LIB.BASEBOARD_FAB2(SCH_1):PAGE118

H_PM_SYNC_GTL @BASEBOARD_FAB2_LIB.BASEBOARD_FAB2(SCH_1):H_PM_SYNC_GTL
 R4P18    2      B RES_0402-49.9,1%,1/16W,CHIP,G2A   I244 @BASEBOARD_FAB2_LIB.BASEBOARD_FAB2(SCH_1):PAGE21
 R7P25    2      B RES_0402-49.9,1%,1/16W,CHIP,G2A   I170 @BASEBOARD_FAB2_LIB.BASEBOARD_FAB2(SCH_1):PAGE55
  R3N9    2      B RES_0402-10.0,1%,1/16W,CHIP,G2A    I66 @BASEBOARD_FAB2_LIB.BASEBOARD_FAB2(SCH_1):PAGE118
 R3N14    1      A RES_0402-49.9,1%,1/16W,EMPTY,GA    I67 @BASEBOARD_FAB2_LIB.BASEBOARD_FAB2(SCH_1):PAGE118

H_PM_SYNC_GTL_R1 @BASEBOARD_FAB2_LIB.BASEBOARD_FAB2(SCH_1):H_PM_SYNC_GTL_R1
 R4P18    1      A RES_0402-49.9,1%,1/16W,CHIP,G2A   I244 @BASEBOARD_FAB2_LIB.BASEBOARD_FAB2(SCH_1):PAGE21
  U5D1 AR14 PMSYNC SKX_EXT_B_BGA1-IC,TBD   I259 @BASEBOARD_FAB2_LIB.BASEBOARD_FAB2(SCH_1):PAGE21

H_PM_SYNC_GTL_R2 @BASEBOARD_FAB2_LIB.BASEBOARD_FAB2(SCH_1):H_PM_SYNC_GTL_R2
 R7P25    1      A RES_0402-49.9,1%,1/16W,CHIP,G2A   I170 @BASEBOARD_FAB2_LIB.BASEBOARD_FAB2(SCH_1):PAGE55
  U2D1 AR14 PMSYNC SKX_EXT_B_BGA1-IC,TBD   I172 @BASEBOARD_FAB2_LIB.BASEBOARD_FAB2(SCH_1):PAGE55

IRQ_BMC_PCH_NMI_STBY_N @BASEBOARD_FAB2_LIB.BASEBOARD_FAB2(SCH_1):IRQ_BMC_PCH_NMI_STBY_N
  U7C1 BB52 GPP_E6_SATA_DEVSLP2 LBG_CORE_QAT_EXT_D_BGA1-IC,H91A   I147 @BASEBOARD_FAB2_LIB.BASEBOARD_FAB2(SCH_1):PAGE120
 R8E24    1      A RES_0402-33.2,1%,1/16W,CHIP,G2A   I214 @BASEBOARD_FAB2_LIB.BASEBOARD_FAB2(SCH_1):PAGE156
 R8E22    2      B RES_0402-4.75K,1%,1/16W,CHIP,GA   I215 @BASEBOARD_FAB2_LIB.BASEBOARD_FAB2(SCH_1):PAGE156
 U25W4  D19 GPIOE5_NRTS3 AST2520A1-GP-GP_ASIC2-GB1-AST2A   I117 @BASEBOARD_FAB2_LIB.BASEBOARD_FAB2(SCH_1):PAGE145

IRQ_BMC_PCH_NMI_STBY_R_N @BASEBOARD_FAB2_LIB.BASEBOARD_FAB2(SCH_1):IRQ_BMC_PCH_NMI_STBY_R_N
  U7C1 BR42 GPP_D0 LBG_CORE_QAT_EXT_D_BGA1-IC,H91A   I115 @BASEBOARD_FAB2_LIB.BASEBOARD_FAB2(SCH_1):PAGE119
 R8E24    2      B RES_0402-33.2,1%,1/16W,CHIP,G2A   I214 @BASEBOARD_FAB2_LIB.BASEBOARD_FAB2(SCH_1):PAGE156

IRQ_BMC_PCH_SCI_LPC_N @BASEBOARD_FAB2_LIB.BASEBOARD_FAB2(SCH_1):IRQ_BMC_PCH_SCI_LPC_N
  U7C1 BY38 GPP_C14 LBG_CORE_QAT_EXT_D_BGA1-IC,H91A   I115 @BASEBOARD_FAB2_LIB.BASEBOARD_FAB2(SCH_1):PAGE119
  U7C1 BN48 GPP_E10_USB2_OC1_N LBG_CORE_QAT_EXT_D_BGA1-IC,H91A   I147 @BASEBOARD_FAB2_LIB.BASEBOARD_FAB2(SCH_1):PAGE120
  R8C2    2      B RES_0402-4.75K,1%,1/16W,CHIP,GA   I304 @BASEBOARD_FAB2_LIB.BASEBOARD_FAB2(SCH_1):PAGE133
 U25W4 AA21 GPIOZ3_VPOG5_NORA3_SIOSCI# AST2520A1-GP-GP_ASIC2-GB1-AST2A   I104 @BASEBOARD_FAB2_LIB.BASEBOARD_FAB2(SCH_1):PAGE146

IRQ_BMC_PCH_SMI_LPC_N @BASEBOARD_FAB2_LIB.BASEBOARD_FAB2(SCH_1):IRQ_BMC_PCH_SMI_LPC_N
  U7C1 CA34 GPP_C22 LBG_CORE_QAT_EXT_D_BGA1-IC,H91A   I115 @BASEBOARD_FAB2_LIB.BASEBOARD_FAB2(SCH_1):PAGE119
  U7C1 AW54 GPP_E11_USB2_OC2_N LBG_CORE_QAT_EXT_D_BGA1-IC,H91A   I147 @BASEBOARD_FAB2_LIB.BASEBOARD_FAB2(SCH_1):PAGE120
  R8C4    2      B RES_0402-1.00K,1%,1/16W,CHIP,GA   I286 @BASEBOARD_FAB2_LIB.BASEBOARD_FAB2(SCH_1):PAGE133
 U25W4  H21 GPIOB5_LPCPD#_LPCSMI# AST2520A1-GP-GP_ASIC2-GB1-AST2A    I95 @BASEBOARD_FAB2_LIB.BASEBOARD_FAB2(SCH_1):PAGE144

IRQ_BOARD_BMC_ALERT_N @BASEBOARD_FAB2_LIB.BASEBOARD_FAB2(SCH_1):IRQ_BOARD_BMC_ALERT_N
  U7C1 BW24 GPP_I5_DO_RESET_OUT_N LBG_CORE_QAT_EXT_D_BGA1-IC,H91A   I147 @BASEBOARD_FAB2_LIB.BASEBOARD_FAB2(SCH_1):PAGE120
  R2N7    2      B RES_0402-4.75K,1%,1/16W,CHIP,GA   I309 @BASEBOARD_FAB2_LIB.BASEBOARD_FAB2(SCH_1):PAGE133
  J1C1   B5   IOB5 CONN76_H22707001_THMT1-CONN,H2A    I18 @BASEBOARD_FAB2_LIB.BASEBOARD_FAB2(SCH_1):PAGE182
  R1C9    1      A RES_0402-0.0,5%,1/16W,EMPTY,G2A   I104 @BASEBOARD_FAB2_LIB.BASEBOARD_FAB2(SCH_1):PAGE182
 U25W4  AA1 GPIOM2_NDSR2_VPIB4 AST2520A1-GP-GP_ASIC2-GB1-AST2A   I117 @BASEBOARD_FAB2_LIB.BASEBOARD_FAB2(SCH_1):PAGE145

IRQ_CPU0_PROCHOT_G_N @BASEBOARD_FAB2_LIB.BASEBOARD_FAB2(SCH_1):IRQ_CPU0_PROCHOT_G_N
  Q7E5    2 GATE<0> FET_N_DUAL_SMLF-NTJD4001N,FET,A   I111 @BASEBOARD_FAB2_LIB.BASEBOARD_FAB2(SCH_1):PAGE95
  U7E2    4   Y<0> TTL1G08_SOTLF-NC7SZ08,IC,D1032B   I117 @BASEBOARD_FAB2_LIB.BASEBOARD_FAB2(SCH_1):PAGE95

IRQ_CPU0_VRHOT @BASEBOARD_FAB2_LIB.BASEBOARD_FAB2(SCH_1):IRQ_CPU0_VRHOT
  Q7E5    5 GATE<0> FET_N_DUAL_SMLF-NTJD4001N,FET,A    I59 @BASEBOARD_FAB2_LIB.BASEBOARD_FAB2(SCH_1):PAGE95
 R7E10    2      B RES_0402-4.75K,1%,1/16W,CHIP,GA    I62 @BASEBOARD_FAB2_LIB.BASEBOARD_FAB2(SCH_1):PAGE95
  Q7E5    6 DRAIN<0> FET_N_DUAL_SMLF-NTJD4001N,FET,A   I111 @BASEBOARD_FAB2_LIB.BASEBOARD_FAB2(SCH_1):PAGE95

IRQ_CPU1_PROCHOT_G_N @BASEBOARD_FAB2_LIB.BASEBOARD_FAB2(SCH_1):IRQ_CPU1_PROCHOT_G_N
  Q7E6    2 GATE<0> FET_N_DUAL_SMLF-NTJD4001N,FET,A   I112 @BASEBOARD_FAB2_LIB.BASEBOARD_FAB2(SCH_1):PAGE95
  U7E3    4   Y<0> TTL1G08_SOTLF-NC7SZ08,IC,D1032B   I118 @BASEBOARD_FAB2_LIB.BASEBOARD_FAB2(SCH_1):PAGE95

IRQ_CPU1_VRHOT @BASEBOARD_FAB2_LIB.BASEBOARD_FAB2(SCH_1):IRQ_CPU1_VRHOT
  Q7E6    5 GATE<0> FET_N_DUAL_SMLF-NTJD4001N,FET,A    I69 @BASEBOARD_FAB2_LIB.BASEBOARD_FAB2(SCH_1):PAGE95
 R7E11    2      B RES_0402-4.75K,1%,1/16W,CHIP,GA    I72 @BASEBOARD_FAB2_LIB.BASEBOARD_FAB2(SCH_1):PAGE95
  Q7E6    6 DRAIN<0> FET_N_DUAL_SMLF-NTJD4001N,FET,A   I112 @BASEBOARD_FAB2_LIB.BASEBOARD_FAB2(SCH_1):PAGE95

IRQ_DIMM_SAVE_LVT3 @BASEBOARD_FAB2_LIB.BASEBOARD_FAB2(SCH_1):IRQ_DIMM_SAVE_LVT3
 R8D29    2      B RES_0402-4.75K,1%,1/16W,CHIP,GA    I26 @BASEBOARD_FAB2_LIB.BASEBOARD_FAB2(SCH_1):PAGE89
  Q8D1    3   C<0> NPN_DUAL_SSOPLF-MBT3904,XSTR,CA    I35 @BASEBOARD_FAB2_LIB.BASEBOARD_FAB2(SCH_1):PAGE89
  Q8D1    2   B<0> NPN_DUAL_SSOPLF-MBT3904,XSTR,CA    I36 @BASEBOARD_FAB2_LIB.BASEBOARD_FAB2(SCH_1):PAGE89

IRQ_DIMM_SAVE_LVT3_N @BASEBOARD_FAB2_LIB.BASEBOARD_FAB2(SCH_1):IRQ_DIMM_SAVE_LVT3_N
 R2P12    1      A RES_0402-0.0,5%,1/16W,EMPTY,G2A    I23 @BASEBOARD_FAB2_LIB.BASEBOARD_FAB2(SCH_1):PAGE89
 R8D31    2      B RES_0402-4.75K,1%,1/16W,CHIP,GA    I27 @BASEBOARD_FAB2_LIB.BASEBOARD_FAB2(SCH_1):PAGE89
  Q8D1    6   C<0> NPN_DUAL_SSOPLF-MBT3904,XSTR,CA    I36 @BASEBOARD_FAB2_LIB.BASEBOARD_FAB2(SCH_1):PAGE89
  U7C1 BW20 GPP_I4_DO_RESET_IN_N LBG_CORE_QAT_EXT_D_BGA1-IC,H91A   I147 @BASEBOARD_FAB2_LIB.BASEBOARD_FAB2(SCH_1):PAGE120
 U25W4  A14 GPIOI6_SPI1MOSI_VBMOSI AST2520A1-GP-GP_ASIC2-GB1-AST2A    I95 @BASEBOARD_FAB2_LIB.BASEBOARD_FAB2(SCH_1):PAGE144

IRQ_DIMM_SAVE_N @BASEBOARD_FAB2_LIB.BASEBOARD_FAB2(SCH_1):IRQ_DIMM_SAVE_N
  R6F4    1      A RES_0402-49.9,1%,1/16W,CHIP,G2A     I3 @BASEBOARD_FAB2_LIB.BASEBOARD_FAB2(SCH_1):PAGE89
  R6F1    1      A RES_0402-49.9,1%,1/16W,CHIP,G2A     I4 @BASEBOARD_FAB2_LIB.BASEBOARD_FAB2(SCH_1):PAGE89
  R6F5    1      A RES_0402-49.9,1%,1/16W,CHIP,G2A     I5 @BASEBOARD_FAB2_LIB.BASEBOARD_FAB2(SCH_1):PAGE89
  R6F2    1      A RES_0402-49.9,1%,1/16W,CHIP,G2A     I6 @BASEBOARD_FAB2_LIB.BASEBOARD_FAB2(SCH_1):PAGE89
  R6F3    2      B RES_0402-10.0K,1%,1/16W,CHIP,GA     I7 @BASEBOARD_FAB2_LIB.BASEBOARD_FAB2(SCH_1):PAGE89
  Q6F1    3    DRN FET_N_SOT23-2N7002,FET,C79254-A    I18 @BASEBOARD_FAB2_LIB.BASEBOARD_FAB2(SCH_1):PAGE89
 R8D30    1      A RES_0402-10.0K,1%,1/16W,CHIP,GA    I34 @BASEBOARD_FAB2_LIB.BASEBOARD_FAB2(SCH_1):PAGE89

IRQ_DIMM_SAVE_R_N @BASEBOARD_FAB2_LIB.BASEBOARD_FAB2(SCH_1):IRQ_DIMM_SAVE_R_N
 R8D30    2      B RES_0402-10.0K,1%,1/16W,CHIP,GA    I34 @BASEBOARD_FAB2_LIB.BASEBOARD_FAB2(SCH_1):PAGE89
  Q8D1    5   B<0> NPN_DUAL_SSOPLF-MBT3904,XSTR,CA    I35 @BASEBOARD_FAB2_LIB.BASEBOARD_FAB2(SCH_1):PAGE89

IRQ_FORCE_NM_THROTTLE_N @BASEBOARD_FAB2_LIB.BASEBOARD_FAB2(SCH_1):IRQ_FORCE_NM_THROTTLE_N
  U7C1 BY42 GPP_D9_SSATA_DEVSLP3 LBG_CORE_QAT_EXT_D_BGA1-IC,H91A   I115 @BASEBOARD_FAB2_LIB.BASEBOARD_FAB2(SCH_1):PAGE119
  U7C1 BA17 GPP_G20_SSATA_DEVSLP0 LBG_CORE_QAT_EXT_D_BGA1-IC,H91A   I147 @BASEBOARD_FAB2_LIB.BASEBOARD_FAB2(SCH_1):PAGE120
  U8E1    1   A<0> TTL08_QFN15-74LVC08A,IC,D90404B    I10 @BASEBOARD_FAB2_LIB.BASEBOARD_FAB2(SCH_1):PAGE170
  R2P4    2      B RES_0402-33.2,1%,1/16W,CHIP,G2A    I74 @BASEBOARD_FAB2_LIB.BASEBOARD_FAB2(SCH_1):PAGE170
 R2T41    1      A RES_0402-22.1,1.0%,1/16W,CHIP,A    I96 @BASEBOARD_FAB2_LIB.BASEBOARD_FAB2(SCH_1):PAGE146

IRQ_FORCE_NM_THROTTLE_R_N @BASEBOARD_FAB2_LIB.BASEBOARD_FAB2(SCH_1):IRQ_FORCE_NM_THROTTLE_R_N
  R2P3    2      B RES_0402-4.75K,1%,1/16W,CHIP,GA     I2 @BASEBOARD_FAB2_LIB.BASEBOARD_FAB2(SCH_1):PAGE170
  U8D3    4      Y TTL1G07_A_SOP-74LVC1G07,IC,C88B     I4 @BASEBOARD_FAB2_LIB.BASEBOARD_FAB2(SCH_1):PAGE170
  R2P4    1      A RES_0402-33.2,1%,1/16W,CHIP,G2A    I74 @BASEBOARD_FAB2_LIB.BASEBOARD_FAB2(SCH_1):PAGE170

IRQ_HFI0_CPU0_LVT2_N @BASEBOARD_FAB2_LIB.BASEBOARD_FAB2(SCH_1):IRQ_HFI0_CPU0_LVT2_N
  U5D1 BP19 CD_HFI0_INT_N SKX_EXT_B_BGA1-IC,TBD    I61 @BASEBOARD_FAB2_LIB.BASEBOARD_FAB2(SCH_1):PAGE29
  J8B1    8    IO8 SCONN24_H46321001_SM-SCONN,H46A     I1 @BASEBOARD_FAB2_LIB.BASEBOARD_FAB2(SCH_1):PAGE91
 R8B10    2      B RES_0402-4.75K,1%,1/16W,CHIP,GA    I16 @BASEBOARD_FAB2_LIB.BASEBOARD_FAB2(SCH_1):PAGE91

IRQ_HFI1_CPU0_LVT2_N @BASEBOARD_FAB2_LIB.BASEBOARD_FAB2(SCH_1):IRQ_HFI1_CPU0_LVT2_N
  U5D1 BM21 CD_HFI1_INT_N SKX_EXT_B_BGA1-IC,TBD    I61 @BASEBOARD_FAB2_LIB.BASEBOARD_FAB2(SCH_1):PAGE29
  J8B1   16   IO16 SCONN24_H46321001_SM-SCONN,H46A     I1 @BASEBOARD_FAB2_LIB.BASEBOARD_FAB2(SCH_1):PAGE91
 R8B17    2      B RES_0402-4.75K,1%,1/16W,CHIP,GA    I18 @BASEBOARD_FAB2_LIB.BASEBOARD_FAB2(SCH_1):PAGE91

IRQ_HSC_FAULT_N @BASEBOARD_FAB2_LIB.BASEBOARD_FAB2(SCH_1):IRQ_HSC_FAULT_N
  U7C1 BJ44 GPP_D2 LBG_CORE_QAT_EXT_D_BGA1-IC,H91A   I115 @BASEBOARD_FAB2_LIB.BASEBOARD_FAB2(SCH_1):PAGE119
  R2M4    2      B RES_0402-1.00K,1%,1/16W,CHIP,GA   I284 @BASEBOARD_FAB2_LIB.BASEBOARD_FAB2(SCH_1):PAGE133
 R1D30    2      B RES_0402-33.2,1%,1/16W,CHIP,G2A   I110 @BASEBOARD_FAB2_LIB.BASEBOARD_FAB2(SCH_1):PAGE199
 U25W4  C18 GPIOI0_SYSCS# AST2520A1-GP-GP_ASIC2-GB1-AST2A    I95 @BASEBOARD_FAB2_LIB.BASEBOARD_FAB2(SCH_1):PAGE144

IRQ_HSC_FAULT_R_N @BASEBOARD_FAB2_LIB.BASEBOARD_FAB2(SCH_1):IRQ_HSC_FAULT_R_N
 EU1D2    6 FAULT_N ADM1278_SM-IC,G99251-001    I10 @BASEBOARD_FAB2_LIB.BASEBOARD_FAB2(SCH_1):PAGE199
 R1D30    1      A RES_0402-33.2,1%,1/16W,CHIP,G2A   I110 @BASEBOARD_FAB2_LIB.BASEBOARD_FAB2(SCH_1):PAGE199

IRQ_LOM_ALERT_N @BASEBOARD_FAB2_LIB.BASEBOARD_FAB2(SCH_1):IRQ_LOM_ALERT_N
  U7C1 BY47 GPP_D11_SSATA_DEVSLP5 LBG_CORE_QAT_EXT_D_BGA1-IC,H91A   I115 @BASEBOARD_FAB2_LIB.BASEBOARD_FAB2(SCH_1):PAGE119
 EU9E1   35 SMB_ALRT_N SPRINGVILLE_SM1-IC,G47144-004    I72 @BASEBOARD_FAB2_LIB.BASEBOARD_FAB2(SCH_1):PAGE139
  R9E7    2      B RES_0402-3.32K,1%,1/16W,CHIP,GA   I193 @BASEBOARD_FAB2_LIB.BASEBOARD_FAB2(SCH_1):PAGE139
 U25W4  P18 GPIOS3_VPOB5_SALT6 AST2520A1-GP-GP_ASIC2-GB1-AST2A   I104 @BASEBOARD_FAB2_LIB.BASEBOARD_FAB2(SCH_1):PAGE146

IRQ_LPC_SERIRQ_N @BASEBOARD_FAB2_LIB.BASEBOARD_FAB2(SCH_1):IRQ_LPC_SERIRQ_N
  U7C1   P2 GPP_A6_SERIRQ_ESPI_CS1_N LBG_CORE_QAT_EXT_D_BGA1-IC,H91A   I115 @BASEBOARD_FAB2_LIB.BASEBOARD_FAB2(SCH_1):PAGE119
  R7D3    2      B RES_0402-4.75K,1%,1/16W,CHIP,GA   I243 @BASEBOARD_FAB2_LIB.BASEBOARD_FAB2(SCH_1):PAGE133
R25W73    1      A RES_0402-33.2,1%,1/16W,CHIP,G2A    I73 @BASEBOARD_FAB2_LIB.BASEBOARD_FAB2(SCH_1):PAGE146

IRQ_LPC_SERIRQ_R @BASEBOARD_FAB2_LIB.BASEBOARD_FAB2(SCH_1):IRQ_LPC_SERIRQ_R
R25W73    2      B RES_0402-33.2,1%,1/16W,CHIP,G2A    I73 @BASEBOARD_FAB2_LIB.BASEBOARD_FAB2(SCH_1):PAGE146
 U25W4  F22 GPIOAC6_ESPIALT#_LSIRQ# AST2520A1-GP-GP_ASIC2-GB1-AST2A   I105 @BASEBOARD_FAB2_LIB.BASEBOARD_FAB2(SCH_1):PAGE146

IRQ_LVC3_WAKE_N @BASEBOARD_FAB2_LIB.BASEBOARD_FAB2(SCH_1):IRQ_LVC3_WAKE_N
 R3N13    2      B RES_0402-4.75K,1%,1/16W,CHIP,GA    I71 @BASEBOARD_FAB2_LIB.BASEBOARD_FAB2(SCH_1):PAGE118
  U7C1   K9 WAKE_N LBG_CORE_QAT_EXT_D_BGA1-IC,H91A    I73 @BASEBOARD_FAB2_LIB.BASEBOARD_FAB2(SCH_1):PAGE118
 R8E17    2      B RES_0402-33.2,1%,1/16W,CHIP,G2A     I2 @BASEBOARD_FAB2_LIB.BASEBOARD_FAB2(SCH_1):PAGE142

IRQ_LVC3_WAKE_R_N @BASEBOARD_FAB2_LIB.BASEBOARD_FAB2(SCH_1):IRQ_LVC3_WAKE_R_N
  U8E4    4      Y TTL1G126_A_SOT-74HC1G126,IC,A7B     I1 @BASEBOARD_FAB2_LIB.BASEBOARD_FAB2(SCH_1):PAGE142
 R8E17    1      A RES_0402-33.2,1%,1/16W,CHIP,G2A     I2 @BASEBOARD_FAB2_LIB.BASEBOARD_FAB2(SCH_1):PAGE142

IRQ_MEZZ_LAN_ALERT_N @BASEBOARD_FAB2_LIB.BASEBOARD_FAB2(SCH_1):IRQ_MEZZ_LAN_ALERT_N
  U7C1 BW45 GPP_D3 LBG_CORE_QAT_EXT_D_BGA1-IC,H91A   I115 @BASEBOARD_FAB2_LIB.BASEBOARD_FAB2(SCH_1):PAGE119
 R8F23    2      B RES_0402-2.21K,1%,1/16W,CHIP,GA   I296 @BASEBOARD_FAB2_LIB.BASEBOARD_FAB2(SCH_1):PAGE157
  J9B3   28   IO28 SCONN120_A28699018_SM-SCONN,A2A   I336 @BASEBOARD_FAB2_LIB.BASEBOARD_FAB2(SCH_1):PAGE186
 U25W4  R18 GPIOS2_VPOB4_SALT5 AST2520A1-GP-GP_ASIC2-GB1-AST2A   I104 @BASEBOARD_FAB2_LIB.BASEBOARD_FAB2(SCH_1):PAGE146

IRQ_OC_DETECT_N @BASEBOARD_FAB2_LIB.BASEBOARD_FAB2(SCH_1):IRQ_OC_DETECT_N
  U7C1  AG7 GPP_F0_SATAXPCIE3_SATAGP3 LBG_CORE_QAT_EXT_D_BGA1-IC,H91A   I147 @BASEBOARD_FAB2_LIB.BASEBOARD_FAB2(SCH_1):PAGE120
  U1D1    2      A TTL1G126_A_SOT-74HC1G126,IC,A7B   I103 @BASEBOARD_FAB2_LIB.BASEBOARD_FAB2(SCH_1):PAGE200
  U1D2    1   OUTB TPS3700_SM-IC,H69492-001   I170 @BASEBOARD_FAB2_LIB.BASEBOARD_FAB2(SCH_1):PAGE200
 R1D23    2      B RES_0402-10.0K,1%,1/16W,CHIP,GA   I191 @BASEBOARD_FAB2_LIB.BASEBOARD_FAB2(SCH_1):PAGE200
 R9P15    2      B RES_0402-0.0,5%,1/16W,EMPTY,G2A   I198 @BASEBOARD_FAB2_LIB.BASEBOARD_FAB2(SCH_1):PAGE200
 U25W4   T1 GPIOL1_NDCD1_VPIDE AST2520A1-GP-GP_ASIC2-GB1-AST2A   I117 @BASEBOARD_FAB2_LIB.BASEBOARD_FAB2(SCH_1):PAGE145

IRQ_OOB_MGMT_RISER_ALERT_N @BASEBOARD_FAB2_LIB.BASEBOARD_FAB2(SCH_1):IRQ_OOB_MGMT_RISER_ALERT_N
  J8G1   16   IO16 SCONN200_H68296001_SM-CONN,H68A   I258 @BASEBOARD_FAB2_LIB.BASEBOARD_FAB2(SCH_1):PAGE108
  U7C1 BV42 GPP_D16_SML0BALERT_IE_N LBG_CORE_QAT_EXT_D_BGA1-IC,H91A   I115 @BASEBOARD_FAB2_LIB.BASEBOARD_FAB2(SCH_1):PAGE119
 R2T29    2      B RES_0402-2.21K,1%,1/16W,CHIP,GA   I298 @BASEBOARD_FAB2_LIB.BASEBOARD_FAB2(SCH_1):PAGE157
 U25W4  Y22 GPIOAA2_VPOR4_NORD2_SALT9 AST2520A1-GP-GP_ASIC2-GB1-AST2A   I104 @BASEBOARD_FAB2_LIB.BASEBOARD_FAB2(SCH_1):PAGE146

IRQ_PCH_NIC_ALERT_N @BASEBOARD_FAB2_LIB.BASEBOARD_FAB2(SCH_1):IRQ_PCH_NIC_ALERT_N
  U7C1 BG22 GPP_B16 LBG_CORE_QAT_EXT_D_BGA1-IC,H91A   I115 @BASEBOARD_FAB2_LIB.BASEBOARD_FAB2(SCH_1):PAGE119
  U7C1 AR17 GPP_F21_LAN_SMBALRT_N LBG_CORE_QAT_EXT_D_BGA1-IC,H91A   I147 @BASEBOARD_FAB2_LIB.BASEBOARD_FAB2(SCH_1):PAGE120
 R8C25    2      B RES_0402-4.75K,1%,1/16W,CHIP,GA   I333 @BASEBOARD_FAB2_LIB.BASEBOARD_FAB2(SCH_1):PAGE133

IRQ_PIRQA_SPI_TPM_N @BASEBOARD_FAB2_LIB.BASEBOARD_FAB2(SCH_1):IRQ_PIRQA_SPI_TPM_N
  U7C1  AA2 GPP_A7_PIRQA_N_ESPI_ALERT0_N LBG_CORE_QAT_EXT_D_BGA1-IC,H91A   I115 @BASEBOARD_FAB2_LIB.BASEBOARD_FAB2(SCH_1):PAGE119
  R7D7    2      B RES_0402-1.00K,1%,1/16W,CHIP,GA   I331 @BASEBOARD_FAB2_LIB.BASEBOARD_FAB2(SCH_1):PAGE133
  R8E1    2      B RES_0402-0.0,5%,1/16W,CHIP,G21A    I99 @BASEBOARD_FAB2_LIB.BASEBOARD_FAB2(SCH_1):PAGE184

IRQ_PVCCIN_CPU0_VRHOT_LVC3_N @BASEBOARD_FAB2_LIB.BASEBOARD_FAB2(SCH_1):IRQ_PVCCIN_CPU0_VRHOT_LVC3_N
  U7E2    2   B<0> TTL1G08_SOTLF-NC7SZ08,IC,D1032B   I117 @BASEBOARD_FAB2_LIB.BASEBOARD_FAB2(SCH_1):PAGE95
  U7C1  BA9 GPP_G4_FANTACH4_FANTACH4IE LBG_CORE_QAT_EXT_D_BGA1-IC,H91A   I147 @BASEBOARD_FAB2_LIB.BASEBOARD_FAB2(SCH_1):PAGE120
 R6P45    2      B RES_0402-33.2,1%,1/16W,CHIP,G2A   I128 @BASEBOARD_FAB2_LIB.BASEBOARD_FAB2(SCH_1):PAGE201
 U25W4  B22 GPIOF2_NDSR4_LHAD2 AST2520A1-GP-GP_ASIC2-GB1-AST2A   I117 @BASEBOARD_FAB2_LIB.BASEBOARD_FAB2(SCH_1):PAGE145

IRQ_PVCCIN_CPU0_VRHOT_LVC3_R_N @BASEBOARD_FAB2_LIB.BASEBOARD_FAB2(SCH_1):IRQ_PVCCIN_CPU0_VRHOT_LVC3_R_N
  R4E3    2      B RES_0402-1.00K,1%,1/16W,CHIP,GA   I111 @BASEBOARD_FAB2_LIB.BASEBOARD_FAB2(SCH_1):PAGE201
 R6P45    1      A RES_0402-33.2,1%,1/16W,CHIP,G2A   I128 @BASEBOARD_FAB2_LIB.BASEBOARD_FAB2(SCH_1):PAGE201
 EU4D4   13 VRHOT_N PXE1610B_QFN-IC,H79206-001   I155 @BASEBOARD_FAB2_LIB.BASEBOARD_FAB2(SCH_1):PAGE201

IRQ_PVCCIN_CPU1_VRHOT_LVC3_N @BASEBOARD_FAB2_LIB.BASEBOARD_FAB2(SCH_1):IRQ_PVCCIN_CPU1_VRHOT_LVC3_N
  U7E3    2   B<0> TTL1G08_SOTLF-NC7SZ08,IC,D1032B   I118 @BASEBOARD_FAB2_LIB.BASEBOARD_FAB2(SCH_1):PAGE95
  U7C1 AW20 GPP_G5_FANTACH5_FANTACH5IE LBG_CORE_QAT_EXT_D_BGA1-IC,H91A   I147 @BASEBOARD_FAB2_LIB.BASEBOARD_FAB2(SCH_1):PAGE120
  R9P3    2      B RES_0402-33.2,1%,1/16W,CHIP,G2A   I117 @BASEBOARD_FAB2_LIB.BASEBOARD_FAB2(SCH_1):PAGE206
 U25W4  B21 GPIOF3_NRI4_LHAD3 AST2520A1-GP-GP_ASIC2-GB1-AST2A   I117 @BASEBOARD_FAB2_LIB.BASEBOARD_FAB2(SCH_1):PAGE145

IRQ_PVCCIN_CPU1_VRHOT_LVC3_R_N @BASEBOARD_FAB2_LIB.BASEBOARD_FAB2(SCH_1):IRQ_PVCCIN_CPU1_VRHOT_LVC3_R_N
  R1D6    2      B RES_0402-1.00K,1%,1/16W,CHIP,GA     I6 @BASEBOARD_FAB2_LIB.BASEBOARD_FAB2(SCH_1):PAGE206
  R9P3    1      A RES_0402-33.2,1%,1/16W,CHIP,G2A   I117 @BASEBOARD_FAB2_LIB.BASEBOARD_FAB2(SCH_1):PAGE206
 EU1C2   13 VRHOT_N PXE1610B_QFN-IC,H79206-001   I130 @BASEBOARD_FAB2_LIB.BASEBOARD_FAB2(SCH_1):PAGE206

IRQ_PVCCIO_CPU0_VRHOT_N @BASEBOARD_FAB2_LIB.BASEBOARD_FAB2(SCH_1):IRQ_PVCCIO_CPU0_VRHOT_N
 R3P18    2      B RES_0402-1.00K,1%,1/16W,CHIP,GA    I64 @BASEBOARD_FAB2_LIB.BASEBOARD_FAB2(SCH_1):PAGE211
 EU3P1   11 VRHOT_N PXE1110B_QFN-IC,H89187-001    I93 @BASEBOARD_FAB2_LIB.BASEBOARD_FAB2(SCH_1):PAGE211

IRQ_PVCCIO_CPU1_VRHOT_N @BASEBOARD_FAB2_LIB.BASEBOARD_FAB2(SCH_1):IRQ_PVCCIO_CPU1_VRHOT_N
 R4D49    2      B RES_0402-1.00K,1%,1/16W,CHIP,GA    I63 @BASEBOARD_FAB2_LIB.BASEBOARD_FAB2(SCH_1):PAGE213
 EU4D5   11 VRHOT_N PXE1110B_QFN-IC,H89187-001    I96 @BASEBOARD_FAB2_LIB.BASEBOARD_FAB2(SCH_1):PAGE213

IRQ_PVDDQ_ABC_VRHOT_LVT3_N @BASEBOARD_FAB2_LIB.BASEBOARD_FAB2(SCH_1):IRQ_PVDDQ_ABC_VRHOT_LVT3_N
  Q3U1    2 GATE<0> FET_N_DUAL_SMLF-NTJD4001N,FET,A    I49 @BASEBOARD_FAB2_LIB.BASEBOARD_FAB2(SCH_1):PAGE94
  U7C1  BN7 GPP_B4_CPU_GP3 LBG_CORE_QAT_EXT_D_BGA1-IC,H91A   I115 @BASEBOARD_FAB2_LIB.BASEBOARD_FAB2(SCH_1):PAGE119
 R7F23    2      B RES_0402-33.2,1%,1/16W,CHIP,G2A   I297 @BASEBOARD_FAB2_LIB.BASEBOARD_FAB2(SCH_1):PAGE215
 U25W4  J19 GPIOF0_NCTS4_LHAD0 AST2520A1-GP-GP_ASIC2-GB1-AST2A   I117 @BASEBOARD_FAB2_LIB.BASEBOARD_FAB2(SCH_1):PAGE145

IRQ_PVDDQ_ABC_VRHOT_LVT3_R_N @BASEBOARD_FAB2_LIB.BASEBOARD_FAB2(SCH_1):IRQ_PVDDQ_ABC_VRHOT_LVT3_R_N
 R7F23    1      A RES_0402-33.2,1%,1/16W,CHIP,G2A   I297 @BASEBOARD_FAB2_LIB.BASEBOARD_FAB2(SCH_1):PAGE215
 R7F27    2      B RES_0402-1.00K,1%,1/16W,CHIP,GA   I303 @BASEBOARD_FAB2_LIB.BASEBOARD_FAB2(SCH_1):PAGE215
 EU7G1   11 VRHOT_N PXM1310B_QFN-IC,H89186-001   I358 @BASEBOARD_FAB2_LIB.BASEBOARD_FAB2(SCH_1):PAGE215

IRQ_PVDDQ_DEF_VRHOT_LVT3_N @BASEBOARD_FAB2_LIB.BASEBOARD_FAB2(SCH_1):IRQ_PVDDQ_DEF_VRHOT_LVT3_N
  Q7E1    2 GATE<0> FET_N_DUAL_SMLF-NTJD4001N,FET,A    I60 @BASEBOARD_FAB2_LIB.BASEBOARD_FAB2(SCH_1):PAGE94
  U7C1 BK17 GPP_B5_SRCCLKREQ0_N LBG_CORE_QAT_EXT_D_BGA1-IC,H91A   I115 @BASEBOARD_FAB2_LIB.BASEBOARD_FAB2(SCH_1):PAGE119
  R7B1    2      B RES_0402-33.2,1%,1/16W,CHIP,G2A    I12 @BASEBOARD_FAB2_LIB.BASEBOARD_FAB2(SCH_1):PAGE218
 U25W4  A15 GPIOI7_SPI1MISO_VBMISO AST2520A1-GP-GP_ASIC2-GB1-AST2A    I95 @BASEBOARD_FAB2_LIB.BASEBOARD_FAB2(SCH_1):PAGE144

IRQ_PVDDQ_DEF_VRHOT_LVT3_R_N @BASEBOARD_FAB2_LIB.BASEBOARD_FAB2(SCH_1):IRQ_PVDDQ_DEF_VRHOT_LVT3_R_N
  R7B1    1      A RES_0402-33.2,1%,1/16W,CHIP,G2A    I12 @BASEBOARD_FAB2_LIB.BASEBOARD_FAB2(SCH_1):PAGE218
  R7B4    2      B RES_0402-1.00K,1%,1/16W,CHIP,GA    I17 @BASEBOARD_FAB2_LIB.BASEBOARD_FAB2(SCH_1):PAGE218
 EU7A5   11 VRHOT_N PXM1310B_QFN-IC,H89186-001    I75 @BASEBOARD_FAB2_LIB.BASEBOARD_FAB2(SCH_1):PAGE218

IRQ_PVDDQ_GHJ_VRHOT_LVT3_N @BASEBOARD_FAB2_LIB.BASEBOARD_FAB2(SCH_1):IRQ_PVDDQ_GHJ_VRHOT_LVT3_N
  Q7E2    2 GATE<0> FET_N_DUAL_SMLF-NTJD4001N,FET,A    I69 @BASEBOARD_FAB2_LIB.BASEBOARD_FAB2(SCH_1):PAGE94
  U7C1 BG18 GPP_B6_SRCCLKREQ1_N LBG_CORE_QAT_EXT_D_BGA1-IC,H91A   I115 @BASEBOARD_FAB2_LIB.BASEBOARD_FAB2(SCH_1):PAGE119
  R1G8    2      B RES_0402-33.2,1%,1/16W,CHIP,G2A    I82 @BASEBOARD_FAB2_LIB.BASEBOARD_FAB2(SCH_1):PAGE223
 U25W4  H20 GPIOB7 AST2520A1-GP-GP_ASIC2-GB1-AST2A    I95 @BASEBOARD_FAB2_LIB.BASEBOARD_FAB2(SCH_1):PAGE144

IRQ_PVDDQ_GHJ_VRHOT_LVT3_R_N @BASEBOARD_FAB2_LIB.BASEBOARD_FAB2(SCH_1):IRQ_PVDDQ_GHJ_VRHOT_LVT3_R_N
 R1G11    2      B RES_0402-1.00K,1%,1/16W,CHIP,GA    I79 @BASEBOARD_FAB2_LIB.BASEBOARD_FAB2(SCH_1):PAGE223
  R1G8    1      A RES_0402-33.2,1%,1/16W,CHIP,G2A    I82 @BASEBOARD_FAB2_LIB.BASEBOARD_FAB2(SCH_1):PAGE223
 EU1G2   11 VRHOT_N PXM1310B_QFN-IC,H89186-001    I90 @BASEBOARD_FAB2_LIB.BASEBOARD_FAB2(SCH_1):PAGE223

IRQ_PVDDQ_KLM_VRHOT_LVT3_N @BASEBOARD_FAB2_LIB.BASEBOARD_FAB2(SCH_1):IRQ_PVDDQ_KLM_VRHOT_LVT3_N
  Q4B1    2 GATE<0> FET_N_DUAL_SMLF-NTJD4001N,FET,A    I84 @BASEBOARD_FAB2_LIB.BASEBOARD_FAB2(SCH_1):PAGE94
  U7C1 BR13 GPP_B7_SRCCLKREQ2_N LBG_CORE_QAT_EXT_D_BGA1-IC,H91A   I115 @BASEBOARD_FAB2_LIB.BASEBOARD_FAB2(SCH_1):PAGE119
  R1B4    2      B RES_0402-33.2,1%,1/16W,CHIP,G2A    I82 @BASEBOARD_FAB2_LIB.BASEBOARD_FAB2(SCH_1):PAGE226
 U25W4  A21 GPIOF4_NDTR4_LHCLK AST2520A1-GP-GP_ASIC2-GB1-AST2A   I117 @BASEBOARD_FAB2_LIB.BASEBOARD_FAB2(SCH_1):PAGE145

IRQ_PVDDQ_KLM_VRHOT_LVT3_R_N @BASEBOARD_FAB2_LIB.BASEBOARD_FAB2(SCH_1):IRQ_PVDDQ_KLM_VRHOT_LVT3_R_N
  R1B1    2      B RES_0402-1.00K,1%,1/16W,CHIP,GA    I79 @BASEBOARD_FAB2_LIB.BASEBOARD_FAB2(SCH_1):PAGE226
  R1B4    1      A RES_0402-33.2,1%,1/16W,CHIP,G2A    I82 @BASEBOARD_FAB2_LIB.BASEBOARD_FAB2(SCH_1):PAGE226
 EU1B1   11 VRHOT_N PXM1310B_QFN-IC,H89186-001    I90 @BASEBOARD_FAB2_LIB.BASEBOARD_FAB2(SCH_1):PAGE226

IRQ_PVNN_PCH_VRHOT_N @BASEBOARD_FAB2_LIB.BASEBOARD_FAB2(SCH_1):IRQ_PVNN_PCH_VRHOT_N
  R8A5    2      B RES_0402-1.00K,1%,1/16W,CHIP,GA   I216 @BASEBOARD_FAB2_LIB.BASEBOARD_FAB2(SCH_1):PAGE235
 EU8A1   11 VRHOT_N PXE1110B_QFN-IC,H89187-001   I229 @BASEBOARD_FAB2_LIB.BASEBOARD_FAB2(SCH_1):PAGE235

IRQ_SML0_ALERT_N @BASEBOARD_FAB2_LIB.BASEBOARD_FAB2(SCH_1):IRQ_SML0_ALERT_N
  U7C1 BW34 GPP_C5_SML0ALERT_IE_N LBG_CORE_QAT_EXT_D_BGA1-IC,H91A   I115 @BASEBOARD_FAB2_LIB.BASEBOARD_FAB2(SCH_1):PAGE119
  Q8E2    3    DRN FET_N_SOT23LF-2N7002,FET,C7925A    I13 @BASEBOARD_FAB2_LIB.BASEBOARD_FAB2(SCH_1):PAGE126
  R8C9    2      B RES_0402-4.75K,1%,1/16W,CHIP,GA    I20 @BASEBOARD_FAB2_LIB.BASEBOARD_FAB2(SCH_1):PAGE126
R25W84    1      A RES_0402-0.0,5%,1/16W,CHIP,G21A    I27 @BASEBOARD_FAB2_LIB.BASEBOARD_FAB2(SCH_1):PAGE146

IRQ_SML1_PMBUS_ALERT_BUF_N @BASEBOARD_FAB2_LIB.BASEBOARD_FAB2(SCH_1):IRQ_SML1_PMBUS_ALERT_BUF_N
  U8D3    2      A TTL1G07_A_SOP-74LVC1G07,IC,C88B     I4 @BASEBOARD_FAB2_LIB.BASEBOARD_FAB2(SCH_1):PAGE170
  U8D5    4      Y TTL1G126_A_SOT-74HC1G126,IC,A7B    I38 @BASEBOARD_FAB2_LIB.BASEBOARD_FAB2(SCH_1):PAGE170
 R8D26    2      B RES_0402-4.75K,1%,1/16W,CHIP,GA    I71 @BASEBOARD_FAB2_LIB.BASEBOARD_FAB2(SCH_1):PAGE170

IRQ_SML1_PMBUS_ALERT_N @BASEBOARD_FAB2_LIB.BASEBOARD_FAB2(SCH_1):IRQ_SML1_PMBUS_ALERT_N
  U7C1  C13 GPD8_SUSCLK LBG_CORE_QAT_EXT_D_BGA1-IC,H91A    I73 @BASEBOARD_FAB2_LIB.BASEBOARD_FAB2(SCH_1):PAGE118
  U8D5    2      A TTL1G126_A_SOT-74HC1G126,IC,A7B    I38 @BASEBOARD_FAB2_LIB.BASEBOARD_FAB2(SCH_1):PAGE170
  C8D3    1      A CAP_0402LF-470PF,50V,10%,EMPTYA    I42 @BASEBOARD_FAB2_LIB.BASEBOARD_FAB2(SCH_1):PAGE170
  R2P8    2      B RES_0402-560,5%,1/16W,CHIP,G21A    I52 @BASEBOARD_FAB2_LIB.BASEBOARD_FAB2(SCH_1):PAGE170
 R1D26    2      B RES_0402-33.2,1%,1/16W,CHIP,G2A   I109 @BASEBOARD_FAB2_LIB.BASEBOARD_FAB2(SCH_1):PAGE199
 U25W4  V21 GPIOAA1_VPOR3_NORD1_SALT8 AST2520A1-GP-GP_ASIC2-GB1-AST2A   I104 @BASEBOARD_FAB2_LIB.BASEBOARD_FAB2(SCH_1):PAGE146

IRQ_SML1_PMBUS_ALERT_R_N @BASEBOARD_FAB2_LIB.BASEBOARD_FAB2(SCH_1):IRQ_SML1_PMBUS_ALERT_R_N
  J1F1   A6  GNDA6 CONN76_H22707001_THMT1-CONN,H2A   I111 @BASEBOARD_FAB2_LIB.BASEBOARD_FAB2(SCH_1):PAGE181
  J1F3    5    IO5 CONN8_H62179001_PIP-CONN,H6217A   I189 @BASEBOARD_FAB2_LIB.BASEBOARD_FAB2(SCH_1):PAGE181
 EU1D2   13 GPO1_ALERT1_N_CONV ADM1278_SM-IC,G99251-001    I10 @BASEBOARD_FAB2_LIB.BASEBOARD_FAB2(SCH_1):PAGE199
 R1D26    1      A RES_0402-33.2,1%,1/16W,CHIP,G2A   I109 @BASEBOARD_FAB2_LIB.BASEBOARD_FAB2(SCH_1):PAGE199

IRQ_SPI_TPM_N_R @BASEBOARD_FAB2_LIB.BASEBOARD_FAB2(SCH_1):IRQ_SPI_TPM_N_R
  J8E1    9    IO9 SCONN11_H67026001_SM-CONN,H670A    I87 @BASEBOARD_FAB2_LIB.BASEBOARD_FAB2(SCH_1):PAGE184
  R8E1    1      A RES_0402-0.0,5%,1/16W,CHIP,G21A    I99 @BASEBOARD_FAB2_LIB.BASEBOARD_FAB2(SCH_1):PAGE184

IRQ_UV_DETECT_N @BASEBOARD_FAB2_LIB.BASEBOARD_FAB2(SCH_1):IRQ_UV_DETECT_N
  U7C1 AU58 GPP_E12_USB2_OC3_N LBG_CORE_QAT_EXT_D_BGA1-IC,H91A   I147 @BASEBOARD_FAB2_LIB.BASEBOARD_FAB2(SCH_1):PAGE120
  U8E1    4   A<0> TTL08_QFN15-74LVC08A,IC,D90404B    I11 @BASEBOARD_FAB2_LIB.BASEBOARD_FAB2(SCH_1):PAGE170
  Q9P1    3 DRAIN<0> FET_N_DUAL_SMLF-2N7002DW,FET,DA   I199 @BASEBOARD_FAB2_LIB.BASEBOARD_FAB2(SCH_1):PAGE200
  R9P4    2      B RES_0402-2.7K,1%,1/16W,CHIP,G2A   I210 @BASEBOARD_FAB2_LIB.BASEBOARD_FAB2(SCH_1):PAGE200
 CR9P1    1      C DIODE_SMLF-BAT54WS,IC,C73510-0A   I214 @BASEBOARD_FAB2_LIB.BASEBOARD_FAB2(SCH_1):PAGE200
 U25W4   T2 GPIOL0_NCTS1 AST2520A1-GP-GP_ASIC2-GB1-AST2A   I117 @BASEBOARD_FAB2_LIB.BASEBOARD_FAB2(SCH_1):PAGE145

IRQ_VM_INT_N @BASEBOARD_FAB2_LIB.BASEBOARD_FAB2(SCH_1):IRQ_VM_INT_N
  U7C1  AA4 GPP_A10_CLKOUT_LPC1 LBG_CORE_QAT_EXT_D_BGA1-IC,H91A   I115 @BASEBOARD_FAB2_LIB.BASEBOARD_FAB2(SCH_1):PAGE119
 R1U40    2      B RES_0402-33.2,1%,1/16W,CHIP,G2A    I81 @BASEBOARD_FAB2_LIB.BASEBOARD_FAB2(SCH_1):PAGE165

IRQ_VM_INT_R_N @BASEBOARD_FAB2_LIB.BASEBOARD_FAB2(SCH_1):IRQ_VM_INT_R_N
 EU9G1    6  INT_N ADC128D818_SM-IC,H63642-001    I52 @BASEBOARD_FAB2_LIB.BASEBOARD_FAB2(SCH_1):PAGE165
 R9G21    2      B RES_0402-4.75K,1%,1/16W,CHIP,GA    I69 @BASEBOARD_FAB2_LIB.BASEBOARD_FAB2(SCH_1):PAGE165
 R1U40    1      A RES_0402-33.2,1%,1/16W,CHIP,G2A    I81 @BASEBOARD_FAB2_LIB.BASEBOARD_FAB2(SCH_1):PAGE165

ISENSE_P1V05_PCH_STBY_PH1_IMON @BASEBOARD_FAB2_LIB.BASEBOARD_FAB2(SCH_1):ISENSE_P1V05_PCH_STBY_PH1_IMON
 EU8A1   26 BISEN1 PXE1110B_QFN-IC,H89187-001   I229 @BASEBOARD_FAB2_LIB.BASEBOARD_FAB2(SCH_1):PAGE235
 EU7A2   38   IOUT IR354XX_SM-IR35412,IC,H73684-0A   I117 @BASEBOARD_FAB2_LIB.BASEBOARD_FAB2(SCH_1):PAGE236

ISENSE_PVCCIN_CPU0_PH1_IMON @BASEBOARD_FAB2_LIB.BASEBOARD_FAB2(SCH_1):ISENSE_PVCCIN_CPU0_PH1_IMON
 EU4D4   24 AISEN1 PXE1610B_QFN-IC,H79206-001   I155 @BASEBOARD_FAB2_LIB.BASEBOARD_FAB2(SCH_1):PAGE201
 EU4E1   38   IOUT IR354XX_SM-IR35411,IC,H73688-0A    I63 @BASEBOARD_FAB2_LIB.BASEBOARD_FAB2(SCH_1):PAGE202

ISENSE_PVCCIN_CPU0_PH2_IMON @BASEBOARD_FAB2_LIB.BASEBOARD_FAB2(SCH_1):ISENSE_PVCCIN_CPU0_PH2_IMON
 EU4D4   26 AISEN2 PXE1610B_QFN-IC,H79206-001   I155 @BASEBOARD_FAB2_LIB.BASEBOARD_FAB2(SCH_1):PAGE201
 EU4D6   38   IOUT IR354XX_SM-IR35411,IC,H73688-0A    I64 @BASEBOARD_FAB2_LIB.BASEBOARD_FAB2(SCH_1):PAGE202

ISENSE_PVCCIN_CPU0_PH3_IMON @BASEBOARD_FAB2_LIB.BASEBOARD_FAB2(SCH_1):ISENSE_PVCCIN_CPU0_PH3_IMON
 EU4D4   28 AISEN3 PXE1610B_QFN-IC,H79206-001   I155 @BASEBOARD_FAB2_LIB.BASEBOARD_FAB2(SCH_1):PAGE201
 EU4D3   38   IOUT IR354XX_SM-IR35411,IC,H73688-0A    I70 @BASEBOARD_FAB2_LIB.BASEBOARD_FAB2(SCH_1):PAGE203

ISENSE_PVCCIN_CPU0_PH4_IMON @BASEBOARD_FAB2_LIB.BASEBOARD_FAB2(SCH_1):ISENSE_PVCCIN_CPU0_PH4_IMON
 EU4D4   30 AISEN4 PXE1610B_QFN-IC,H79206-001   I155 @BASEBOARD_FAB2_LIB.BASEBOARD_FAB2(SCH_1):PAGE201
 EU4D1   38   IOUT IR354XX_SM-IR35411,IC,H73688-0A    I71 @BASEBOARD_FAB2_LIB.BASEBOARD_FAB2(SCH_1):PAGE203

ISENSE_PVCCIN_CPU0_PH5_IMON @BASEBOARD_FAB2_LIB.BASEBOARD_FAB2(SCH_1):ISENSE_PVCCIN_CPU0_PH5_IMON
 EU4D4   32 AISEN5 PXE1610B_QFN-IC,H79206-001   I155 @BASEBOARD_FAB2_LIB.BASEBOARD_FAB2(SCH_1):PAGE201
 EU4C2   38   IOUT IR354XX_SM-IR35411,IC,H73688-0A    I71 @BASEBOARD_FAB2_LIB.BASEBOARD_FAB2(SCH_1):PAGE204

ISENSE_PVCCIN_CPU1_PH1_IMON @BASEBOARD_FAB2_LIB.BASEBOARD_FAB2(SCH_1):ISENSE_PVCCIN_CPU1_PH1_IMON
 EU1C2   24 AISEN1 PXE1610B_QFN-IC,H79206-001   I130 @BASEBOARD_FAB2_LIB.BASEBOARD_FAB2(SCH_1):PAGE206
 EU1E2   38   IOUT IR354XX_SM-IR35411,IC,H73688-0A    I20 @BASEBOARD_FAB2_LIB.BASEBOARD_FAB2(SCH_1):PAGE207

ISENSE_PVCCIN_CPU1_PH2_IMON @BASEBOARD_FAB2_LIB.BASEBOARD_FAB2(SCH_1):ISENSE_PVCCIN_CPU1_PH2_IMON
 EU1C2   26 AISEN2 PXE1610B_QFN-IC,H79206-001   I130 @BASEBOARD_FAB2_LIB.BASEBOARD_FAB2(SCH_1):PAGE206
 EU1D4   38   IOUT IR354XX_SM-IR35411,IC,H73688-0A    I24 @BASEBOARD_FAB2_LIB.BASEBOARD_FAB2(SCH_1):PAGE207

ISENSE_PVCCIN_CPU1_PH3_IMON @BASEBOARD_FAB2_LIB.BASEBOARD_FAB2(SCH_1):ISENSE_PVCCIN_CPU1_PH3_IMON
 EU1C2   28 AISEN3 PXE1610B_QFN-IC,H79206-001   I130 @BASEBOARD_FAB2_LIB.BASEBOARD_FAB2(SCH_1):PAGE206
 EU1D3   38   IOUT IR354XX_SM-IR35411,IC,H73688-0A    I27 @BASEBOARD_FAB2_LIB.BASEBOARD_FAB2(SCH_1):PAGE208

ISENSE_PVCCIN_CPU1_PH4_IMON @BASEBOARD_FAB2_LIB.BASEBOARD_FAB2(SCH_1):ISENSE_PVCCIN_CPU1_PH4_IMON
 EU1C2   30 AISEN4 PXE1610B_QFN-IC,H79206-001   I130 @BASEBOARD_FAB2_LIB.BASEBOARD_FAB2(SCH_1):PAGE206
 EU1D1   38   IOUT IR354XX_SM-IR35411,IC,H73688-0A    I71 @BASEBOARD_FAB2_LIB.BASEBOARD_FAB2(SCH_1):PAGE208

ISENSE_PVCCIN_CPU1_PH5_IMON @BASEBOARD_FAB2_LIB.BASEBOARD_FAB2(SCH_1):ISENSE_PVCCIN_CPU1_PH5_IMON
 EU1C2   32 AISEN5 PXE1610B_QFN-IC,H79206-001   I130 @BASEBOARD_FAB2_LIB.BASEBOARD_FAB2(SCH_1):PAGE206
 EU1C3   38   IOUT IR354XX_SM-IR35411,IC,H73688-0A    I56 @BASEBOARD_FAB2_LIB.BASEBOARD_FAB2(SCH_1):PAGE209

ISENSE_PVCCIO_CPU0_PH1_IMON @BASEBOARD_FAB2_LIB.BASEBOARD_FAB2(SCH_1):ISENSE_PVCCIO_CPU0_PH1_IMON
 EU3P1   22 AISEN1 PXE1110B_QFN-IC,H89187-001    I93 @BASEBOARD_FAB2_LIB.BASEBOARD_FAB2(SCH_1):PAGE211
 EU7C1   38   IOUT IR354XX_SM-IR35412,IC,H73684-0A   I101 @BASEBOARD_FAB2_LIB.BASEBOARD_FAB2(SCH_1):PAGE212

ISENSE_PVCCIO_CPU1_PH1_IMON @BASEBOARD_FAB2_LIB.BASEBOARD_FAB2(SCH_1):ISENSE_PVCCIO_CPU1_PH1_IMON
 EU4D5   22 AISEN1 PXE1110B_QFN-IC,H89187-001    I96 @BASEBOARD_FAB2_LIB.BASEBOARD_FAB2(SCH_1):PAGE213
 EU4E2   38   IOUT IR354XX_SM-IR35412,IC,H73684-0A   I126 @BASEBOARD_FAB2_LIB.BASEBOARD_FAB2(SCH_1):PAGE214

ISENSE_PVDDQ_ABC_PH1_IMON @BASEBOARD_FAB2_LIB.BASEBOARD_FAB2(SCH_1):ISENSE_PVDDQ_ABC_PH1_IMON
 EU7G1   22 AISEN1 PXM1310B_QFN-IC,H89186-001   I358 @BASEBOARD_FAB2_LIB.BASEBOARD_FAB2(SCH_1):PAGE215
 EU7G2   38   IOUT IR354XX_SM-IR35411,IC,H73688-0A   I102 @BASEBOARD_FAB2_LIB.BASEBOARD_FAB2(SCH_1):PAGE216

ISENSE_PVDDQ_ABC_PH2_IMON @BASEBOARD_FAB2_LIB.BASEBOARD_FAB2(SCH_1):ISENSE_PVDDQ_ABC_PH2_IMON
 EU7G1   24 AISEN2 PXM1310B_QFN-IC,H89186-001   I358 @BASEBOARD_FAB2_LIB.BASEBOARD_FAB2(SCH_1):PAGE215
 EU7G3   38   IOUT IR354XX_SM-IR35411,IC,H73688-0A   I103 @BASEBOARD_FAB2_LIB.BASEBOARD_FAB2(SCH_1):PAGE216

ISENSE_PVDDQ_DEF_PH1_IMON @BASEBOARD_FAB2_LIB.BASEBOARD_FAB2(SCH_1):ISENSE_PVDDQ_DEF_PH1_IMON
 EU7A5   22 AISEN1 PXM1310B_QFN-IC,H89186-001    I75 @BASEBOARD_FAB2_LIB.BASEBOARD_FAB2(SCH_1):PAGE218
 EU7A1   38   IOUT IR354XX_SM-IR35411,IC,H73688-0A   I106 @BASEBOARD_FAB2_LIB.BASEBOARD_FAB2(SCH_1):PAGE219

ISENSE_PVDDQ_DEF_PH2_IMON @BASEBOARD_FAB2_LIB.BASEBOARD_FAB2(SCH_1):ISENSE_PVDDQ_DEF_PH2_IMON
 EU7A5   24 AISEN2 PXM1310B_QFN-IC,H89186-001    I75 @BASEBOARD_FAB2_LIB.BASEBOARD_FAB2(SCH_1):PAGE218
 EU7A4   38   IOUT IR354XX_SM-IR35411,IC,H73688-0A   I107 @BASEBOARD_FAB2_LIB.BASEBOARD_FAB2(SCH_1):PAGE219

ISENSE_PVDDQ_GHJ_PH1_IMON @BASEBOARD_FAB2_LIB.BASEBOARD_FAB2(SCH_1):ISENSE_PVDDQ_GHJ_PH1_IMON
 EU1G2   22 AISEN1 PXM1310B_QFN-IC,H89186-001    I90 @BASEBOARD_FAB2_LIB.BASEBOARD_FAB2(SCH_1):PAGE223
 EU1G1   38   IOUT IR354XX_SM-IR35411,IC,H73688-0A   I110 @BASEBOARD_FAB2_LIB.BASEBOARD_FAB2(SCH_1):PAGE224

ISENSE_PVDDQ_GHJ_PH2_IMON @BASEBOARD_FAB2_LIB.BASEBOARD_FAB2(SCH_1):ISENSE_PVDDQ_GHJ_PH2_IMON
 EU1G2   24 AISEN2 PXM1310B_QFN-IC,H89186-001    I90 @BASEBOARD_FAB2_LIB.BASEBOARD_FAB2(SCH_1):PAGE223
 EU1F1   38   IOUT IR354XX_SM-IR35411,IC,H73688-0A   I111 @BASEBOARD_FAB2_LIB.BASEBOARD_FAB2(SCH_1):PAGE224

ISENSE_PVDDQ_KLM_PH1_IMON @BASEBOARD_FAB2_LIB.BASEBOARD_FAB2(SCH_1):ISENSE_PVDDQ_KLM_PH1_IMON
 EU1B1   22 AISEN1 PXM1310B_QFN-IC,H89186-001    I90 @BASEBOARD_FAB2_LIB.BASEBOARD_FAB2(SCH_1):PAGE226
 EU1A2   38   IOUT IR354XX_SM-IR35411,IC,H73688-0A   I101 @BASEBOARD_FAB2_LIB.BASEBOARD_FAB2(SCH_1):PAGE227

ISENSE_PVDDQ_KLM_PH2_IMON @BASEBOARD_FAB2_LIB.BASEBOARD_FAB2(SCH_1):ISENSE_PVDDQ_KLM_PH2_IMON
 EU1B1   24 AISEN2 PXM1310B_QFN-IC,H89186-001    I90 @BASEBOARD_FAB2_LIB.BASEBOARD_FAB2(SCH_1):PAGE226
 EU1A1   38   IOUT IR354XX_SM-IR35411,IC,H73688-0A   I102 @BASEBOARD_FAB2_LIB.BASEBOARD_FAB2(SCH_1):PAGE227

ISENSE_PVNN_PCH_PH1_IMON @BASEBOARD_FAB2_LIB.BASEBOARD_FAB2(SCH_1):ISENSE_PVNN_PCH_PH1_IMON
 EU8A1   22 AISEN1 PXE1110B_QFN-IC,H89187-001   I229 @BASEBOARD_FAB2_LIB.BASEBOARD_FAB2(SCH_1):PAGE235
 EU7A3   38   IOUT IR354XX_SM-IR35412,IC,H73684-0A   I116 @BASEBOARD_FAB2_LIB.BASEBOARD_FAB2(SCH_1):PAGE236

ISENSE_PVSA_CPU0_IMON @BASEBOARD_FAB2_LIB.BASEBOARD_FAB2(SCH_1):ISENSE_PVSA_CPU0_IMON
 EU4D4   38 BISEN1 PXE1610B_QFN-IC,H79206-001   I155 @BASEBOARD_FAB2_LIB.BASEBOARD_FAB2(SCH_1):PAGE201
 EU4C1   38   IOUT IR354XX_SM-IR35412,IC,H73684-0A    I46 @BASEBOARD_FAB2_LIB.BASEBOARD_FAB2(SCH_1):PAGE205

ISENSE_PVSA_CPU1_IMON @BASEBOARD_FAB2_LIB.BASEBOARD_FAB2(SCH_1):ISENSE_PVSA_CPU1_IMON
 EU1C2   38 BISEN1 PXE1610B_QFN-IC,H79206-001   I130 @BASEBOARD_FAB2_LIB.BASEBOARD_FAB2(SCH_1):PAGE206
 EU1C1   38   IOUT IR354XX_SM-IR35412,IC,H73684-0A    I51 @BASEBOARD_FAB2_LIB.BASEBOARD_FAB2(SCH_1):PAGE210

ISENSE_TMP421_1_BC @BASEBOARD_FAB2_LIB.BASEBOARD_FAB2(SCH_1):ISENSE_TMP421_1_BC
  Q9B1    1      B PNP_TO92-MPS2907,IC,G73554-001     I3 @BASEBOARD_FAB2_LIB.BASEBOARD_FAB2(SCH_1):PAGE167
  Q9B1    3      C PNP_TO92-MPS2907,IC,G73554-001     I3 @BASEBOARD_FAB2_LIB.BASEBOARD_FAB2(SCH_1):PAGE167
  R9B5    1      A RES_0402-49.9,1%,1/16W,CHIP,G2A     I5 @BASEBOARD_FAB2_LIB.BASEBOARD_FAB2(SCH_1):PAGE167

ISENSE_TMP421_1_DXN @BASEBOARD_FAB2_LIB.BASEBOARD_FAB2(SCH_1):ISENSE_TMP421_1_DXN
  U9B4    2    DXN TMP421_TSSOP-IC,G62962-001     I1 @BASEBOARD_FAB2_LIB.BASEBOARD_FAB2(SCH_1):PAGE167
  R9B5    2      B RES_0402-49.9,1%,1/16W,CHIP,G2A     I5 @BASEBOARD_FAB2_LIB.BASEBOARD_FAB2(SCH_1):PAGE167
  C1M4    2      B CAP_0402LF-47.0PF,50V,5%,EMPTYA     I7 @BASEBOARD_FAB2_LIB.BASEBOARD_FAB2(SCH_1):PAGE167

ISENSE_TMP421_1_DXP @BASEBOARD_FAB2_LIB.BASEBOARD_FAB2(SCH_1):ISENSE_TMP421_1_DXP
  U9B4    1    DXP TMP421_TSSOP-IC,G62962-001     I1 @BASEBOARD_FAB2_LIB.BASEBOARD_FAB2(SCH_1):PAGE167
  R9B4    2      B RES_0402-49.9,1%,1/16W,CHIP,G2A     I6 @BASEBOARD_FAB2_LIB.BASEBOARD_FAB2(SCH_1):PAGE167
  C1M4    1      A CAP_0402LF-47.0PF,50V,5%,EMPTYA     I7 @BASEBOARD_FAB2_LIB.BASEBOARD_FAB2(SCH_1):PAGE167

ISENSE_TMP421_1_E @BASEBOARD_FAB2_LIB.BASEBOARD_FAB2(SCH_1):ISENSE_TMP421_1_E
  Q9B1    2      E PNP_TO92-MPS2907,IC,G73554-001     I3 @BASEBOARD_FAB2_LIB.BASEBOARD_FAB2(SCH_1):PAGE167
  R9B4    1      A RES_0402-49.9,1%,1/16W,CHIP,G2A     I6 @BASEBOARD_FAB2_LIB.BASEBOARD_FAB2(SCH_1):PAGE167

ISENSE_TMP421_2_BC @BASEBOARD_FAB2_LIB.BASEBOARD_FAB2(SCH_1):ISENSE_TMP421_2_BC
  R9R6    1      A RES_0402-49.9,1%,1/16W,CHIP,G2A    I26 @BASEBOARD_FAB2_LIB.BASEBOARD_FAB2(SCH_1):PAGE167
  Q1E1    1      B PNP_TO92-MPS2907,IC,G73554-001    I27 @BASEBOARD_FAB2_LIB.BASEBOARD_FAB2(SCH_1):PAGE167
  Q1E1    3      C PNP_TO92-MPS2907,IC,G73554-001    I27 @BASEBOARD_FAB2_LIB.BASEBOARD_FAB2(SCH_1):PAGE167

ISENSE_TMP421_2_DXN @BASEBOARD_FAB2_LIB.BASEBOARD_FAB2(SCH_1):ISENSE_TMP421_2_DXN
 C1E19    2      B CAP_0402LF-47.0PF,50V,5%,EMPTYA    I24 @BASEBOARD_FAB2_LIB.BASEBOARD_FAB2(SCH_1):PAGE167
  R9R6    2      B RES_0402-49.9,1%,1/16W,CHIP,G2A    I26 @BASEBOARD_FAB2_LIB.BASEBOARD_FAB2(SCH_1):PAGE167
  U1E1    2    DXN TMP421_TSSOP-IC,G62962-001    I30 @BASEBOARD_FAB2_LIB.BASEBOARD_FAB2(SCH_1):PAGE167

ISENSE_TMP421_2_DXP @BASEBOARD_FAB2_LIB.BASEBOARD_FAB2(SCH_1):ISENSE_TMP421_2_DXP
 C1E19    1      A CAP_0402LF-47.0PF,50V,5%,EMPTYA    I24 @BASEBOARD_FAB2_LIB.BASEBOARD_FAB2(SCH_1):PAGE167
  R9R5    2      B RES_0402-49.9,1%,1/16W,CHIP,G2A    I25 @BASEBOARD_FAB2_LIB.BASEBOARD_FAB2(SCH_1):PAGE167
  U1E1    1    DXP TMP421_TSSOP-IC,G62962-001    I30 @BASEBOARD_FAB2_LIB.BASEBOARD_FAB2(SCH_1):PAGE167

ISENSE_TMP421_2_E @BASEBOARD_FAB2_LIB.BASEBOARD_FAB2(SCH_1):ISENSE_TMP421_2_E
  R9R5    1      A RES_0402-49.9,1%,1/16W,CHIP,G2A    I25 @BASEBOARD_FAB2_LIB.BASEBOARD_FAB2(SCH_1):PAGE167
  Q1E1    2      E PNP_TO92-MPS2907,IC,G73554-001    I27 @BASEBOARD_FAB2_LIB.BASEBOARD_FAB2(SCH_1):PAGE167

JTAG_BMC_TCK @BASEBOARD_FAB2_LIB.BASEBOARD_FAB2(SCH_1):JTAG_BMC_TCK
 R8G17    1      A RES_0402-0.0,5%,1/16W,CHIP,G21A    I25 @BASEBOARD_FAB2_LIB.BASEBOARD_FAB2(SCH_1):PAGE189
 U25W4  C10    TCK AST2520A1-GP-GP_ASIC2-GB1-AST2A    I95 @BASEBOARD_FAB2_LIB.BASEBOARD_FAB2(SCH_1):PAGE144

JTAG_BMC_TDI @BASEBOARD_FAB2_LIB.BASEBOARD_FAB2(SCH_1):JTAG_BMC_TDI
  R8G8    1      A RES_0402-0.0,5%,1/16W,CHIP,G21A    I17 @BASEBOARD_FAB2_LIB.BASEBOARD_FAB2(SCH_1):PAGE189
 U25W4  D12    TDI AST2520A1-GP-GP_ASIC2-GB1-AST2A    I95 @BASEBOARD_FAB2_LIB.BASEBOARD_FAB2(SCH_1):PAGE144

JTAG_BMC_TDO @BASEBOARD_FAB2_LIB.BASEBOARD_FAB2(SCH_1):JTAG_BMC_TDO
 R7G17    1      A RES_0402-0.0,5%,1/16W,CHIP,G21A    I37 @BASEBOARD_FAB2_LIB.BASEBOARD_FAB2(SCH_1):PAGE189
 U25W4  D11    TDO AST2520A1-GP-GP_ASIC2-GB1-AST2A    I95 @BASEBOARD_FAB2_LIB.BASEBOARD_FAB2(SCH_1):PAGE144

JTAG_BMC_TMS @BASEBOARD_FAB2_LIB.BASEBOARD_FAB2(SCH_1):JTAG_BMC_TMS
 R8G14    1      A RES_0402-0.0,5%,1/16W,CHIP,G21A    I20 @BASEBOARD_FAB2_LIB.BASEBOARD_FAB2(SCH_1):PAGE189
 U25W4   C8    TMS AST2520A1-GP-GP_ASIC2-GB1-AST2A    I95 @BASEBOARD_FAB2_LIB.BASEBOARD_FAB2(SCH_1):PAGE144

JTAG_BMC_TRST_N @BASEBOARD_FAB2_LIB.BASEBOARD_FAB2(SCH_1):JTAG_BMC_TRST_N
 R8G10    1      A RES_0402-0.0,5%,1/16W,CHIP,G21A     I7 @BASEBOARD_FAB2_LIB.BASEBOARD_FAB2(SCH_1):PAGE189
R25W105    2      B RES_0402-4.75K,1%,1/16W,EMPTY,A    I31 @BASEBOARD_FAB2_LIB.BASEBOARD_FAB2(SCH_1):PAGE151
 U25W4  E11  NTRST AST2520A1-GP-GP_ASIC2-GB1-AST2A    I95 @BASEBOARD_FAB2_LIB.BASEBOARD_FAB2(SCH_1):PAGE144

JTAG_MCP_CPU0_TDI @BASEBOARD_FAB2_LIB.BASEBOARD_FAB2(SCH_1):JTAG_MCP_CPU0_TDI
  U5D1 BY21 CD_TDI SKX_EXT_B_BGA1-IC,TBD    I61 @BASEBOARD_FAB2_LIB.BASEBOARD_FAB2(SCH_1):PAGE29
  R4R6    2      B RES_0402-49.9,1%,1/16W,CHIP,G2A   I134 @BASEBOARD_FAB2_LIB.BASEBOARD_FAB2(SCH_1):PAGE113
  U2M1    1     B1 NC7SB3157_SMLF-IC,C99406-001   I255 @BASEBOARD_FAB2_LIB.BASEBOARD_FAB2(SCH_1):PAGE113

JTAG_MCP_CPU0_TDI_R @BASEBOARD_FAB2_LIB.BASEBOARD_FAB2(SCH_1):JTAG_MCP_CPU0_TDI_R
  R4R6    1      A RES_0402-49.9,1%,1/16W,CHIP,G2A   I134 @BASEBOARD_FAB2_LIB.BASEBOARD_FAB2(SCH_1):PAGE113
  U4R1    4      B 74CBTLV1G125_SMLF-IC,C88177-00A   I206 @BASEBOARD_FAB2_LIB.BASEBOARD_FAB2(SCH_1):PAGE113
  C4R2    1      A CAP_A_0402V-0.1UF,16V,10%,X7R,A   I246 @BASEBOARD_FAB2_LIB.BASEBOARD_FAB2(SCH_1):PAGE113

JTAG_MCP_CPU0_TDO @BASEBOARD_FAB2_LIB.BASEBOARD_FAB2(SCH_1):JTAG_MCP_CPU0_TDO
  U5D1 CC22 CD_TDO SKX_EXT_B_BGA1-IC,TBD    I61 @BASEBOARD_FAB2_LIB.BASEBOARD_FAB2(SCH_1):PAGE29
  U1M2    1     B1 NC7SB3157_SMLF-IC,C99406-001   I107 @BASEBOARD_FAB2_LIB.BASEBOARD_FAB2(SCH_1):PAGE113
  U1M6    2      A 74CBTLV1G125_SMLF-IC,C88177-00A   I127 @BASEBOARD_FAB2_LIB.BASEBOARD_FAB2(SCH_1):PAGE113

JTAG_MCP_CPU1_TDI @BASEBOARD_FAB2_LIB.BASEBOARD_FAB2(SCH_1):JTAG_MCP_CPU1_TDI
  U2D1 BY21 CD_TDI SKX_EXT_B_BGA1-IC,TBD    I23 @BASEBOARD_FAB2_LIB.BASEBOARD_FAB2(SCH_1):PAGE63
  U1M6    4      B 74CBTLV1G125_SMLF-IC,C88177-00A   I127 @BASEBOARD_FAB2_LIB.BASEBOARD_FAB2(SCH_1):PAGE113
  R6M8    2      B RES_0402-49.9,1%,1/16W,CHIP,G2A   I188 @BASEBOARD_FAB2_LIB.BASEBOARD_FAB2(SCH_1):PAGE113
  U2M1    3     B0 NC7SB3157_SMLF-IC,C99406-001   I255 @BASEBOARD_FAB2_LIB.BASEBOARD_FAB2(SCH_1):PAGE113

JTAG_MCP_CPU1_TDI_R @BASEBOARD_FAB2_LIB.BASEBOARD_FAB2(SCH_1):JTAG_MCP_CPU1_TDI_R
  R6M8    1      A RES_0402-49.9,1%,1/16W,CHIP,G2A   I188 @BASEBOARD_FAB2_LIB.BASEBOARD_FAB2(SCH_1):PAGE113
  U6M1    4      B 74CBTLV1G125_SMLF-IC,C88177-00A   I190 @BASEBOARD_FAB2_LIB.BASEBOARD_FAB2(SCH_1):PAGE113
  C6M6    1      A CAP_A_0402V-0.1UF,16V,10%,X7R,A   I250 @BASEBOARD_FAB2_LIB.BASEBOARD_FAB2(SCH_1):PAGE113

JTAG_MCP_CPU1_TDO @BASEBOARD_FAB2_LIB.BASEBOARD_FAB2(SCH_1):JTAG_MCP_CPU1_TDO
  U2D1 CC22 CD_TDO SKX_EXT_B_BGA1-IC,TBD    I23 @BASEBOARD_FAB2_LIB.BASEBOARD_FAB2(SCH_1):PAGE63
  U1M2    3     B0 NC7SB3157_SMLF-IC,C99406-001   I107 @BASEBOARD_FAB2_LIB.BASEBOARD_FAB2(SCH_1):PAGE113

JTAG_MCP_MUX_TDI @BASEBOARD_FAB2_LIB.BASEBOARD_FAB2(SCH_1):JTAG_MCP_MUX_TDI
  J9B4    9    IO9 SCONN10_C12536004_SMLF-CONN,C1A   I175 @BASEBOARD_FAB2_LIB.BASEBOARD_FAB2(SCH_1):PAGE113
 R1M20    2      B RES_0402-1.00K,1%,1/16W,CHIP,GA   I204 @BASEBOARD_FAB2_LIB.BASEBOARD_FAB2(SCH_1):PAGE113
  U2M1    4      A NC7SB3157_SMLF-IC,C99406-001   I255 @BASEBOARD_FAB2_LIB.BASEBOARD_FAB2(SCH_1):PAGE113

JTAG_MCP_MUX_TDO @BASEBOARD_FAB2_LIB.BASEBOARD_FAB2(SCH_1):JTAG_MCP_MUX_TDO
  U1M2    4      A NC7SB3157_SMLF-IC,C99406-001   I107 @BASEBOARD_FAB2_LIB.BASEBOARD_FAB2(SCH_1):PAGE113
  J9B4    3    IO3 SCONN10_C12536004_SMLF-CONN,C1A   I175 @BASEBOARD_FAB2_LIB.BASEBOARD_FAB2(SCH_1):PAGE113
 R9B12    2      B RES_0402-1.00K,1%,1/16W,CHIP,GA   I203 @BASEBOARD_FAB2_LIB.BASEBOARD_FAB2(SCH_1):PAGE113

JTAG_MCP_TCK @BASEBOARD_FAB2_LIB.BASEBOARD_FAB2(SCH_1):JTAG_MCP_TCK
  U5D1 CB23 CD_TCLK SKX_EXT_B_BGA1-IC,TBD    I61 @BASEBOARD_FAB2_LIB.BASEBOARD_FAB2(SCH_1):PAGE29
  U2D1 CB23 CD_TCLK SKX_EXT_B_BGA1-IC,TBD    I23 @BASEBOARD_FAB2_LIB.BASEBOARD_FAB2(SCH_1):PAGE63
  R9B9    1      A RES_0402-1.00K,1%,1/16W,CHIP,GA   I179 @BASEBOARD_FAB2_LIB.BASEBOARD_FAB2(SCH_1):PAGE113
 R9B10    1      A RES_0402-49.9,1%,1/16W,CHIP,G2A   I180 @BASEBOARD_FAB2_LIB.BASEBOARD_FAB2(SCH_1):PAGE113
 R9B11    1      A RES_0402-0.0,5%,1/16W,CHIP,G21A   I239 @BASEBOARD_FAB2_LIB.BASEBOARD_FAB2(SCH_1):PAGE113

JTAG_MCP_TCK_R @BASEBOARD_FAB2_LIB.BASEBOARD_FAB2(SCH_1):JTAG_MCP_TCK_R
  J9B4    1    IO1 SCONN10_C12536004_SMLF-CONN,C1A   I175 @BASEBOARD_FAB2_LIB.BASEBOARD_FAB2(SCH_1):PAGE113
 R9B10    2      B RES_0402-49.9,1%,1/16W,CHIP,G2A   I180 @BASEBOARD_FAB2_LIB.BASEBOARD_FAB2(SCH_1):PAGE113
  U9A5    2      A 74CBTLV1G125_SMLF-IC,C88177-00A   I185 @BASEBOARD_FAB2_LIB.BASEBOARD_FAB2(SCH_1):PAGE113
 R9B11    2      B RES_0402-0.0,5%,1/16W,CHIP,G21A   I239 @BASEBOARD_FAB2_LIB.BASEBOARD_FAB2(SCH_1):PAGE113

JTAG_MCP_TMS @BASEBOARD_FAB2_LIB.BASEBOARD_FAB2(SCH_1):JTAG_MCP_TMS
  U5D1 CE24 CD_TMS SKX_EXT_B_BGA1-IC,TBD    I61 @BASEBOARD_FAB2_LIB.BASEBOARD_FAB2(SCH_1):PAGE29
  U2D1 CE24 CD_TMS SKX_EXT_B_BGA1-IC,TBD    I23 @BASEBOARD_FAB2_LIB.BASEBOARD_FAB2(SCH_1):PAGE63
 R1M22    2      B RES_0402-49.9,1%,1/16W,CHIP,G2A   I195 @BASEBOARD_FAB2_LIB.BASEBOARD_FAB2(SCH_1):PAGE113
 R1M19    2      B RES_0402-1.00K,1%,1/16W,CHIP,GA   I202 @BASEBOARD_FAB2_LIB.BASEBOARD_FAB2(SCH_1):PAGE113
 R9B13    1      A RES_0402-0.0,5%,1/16W,CHIP,G21A   I240 @BASEBOARD_FAB2_LIB.BASEBOARD_FAB2(SCH_1):PAGE113

JTAG_MCP_TMS_R @BASEBOARD_FAB2_LIB.BASEBOARD_FAB2(SCH_1):JTAG_MCP_TMS_R
  J9B4    5    IO5 SCONN10_C12536004_SMLF-CONN,C1A   I175 @BASEBOARD_FAB2_LIB.BASEBOARD_FAB2(SCH_1):PAGE113
 R9B13    2      B RES_0402-0.0,5%,1/16W,CHIP,G21A   I240 @BASEBOARD_FAB2_LIB.BASEBOARD_FAB2(SCH_1):PAGE113

JTAG_MCP_TMS_R1 @BASEBOARD_FAB2_LIB.BASEBOARD_FAB2(SCH_1):JTAG_MCP_TMS_R1
 R1M22    1      A RES_0402-49.9,1%,1/16W,CHIP,G2A   I195 @BASEBOARD_FAB2_LIB.BASEBOARD_FAB2(SCH_1):PAGE113
  U1M5    4      B 74CBTLV1G125_SMLF-IC,C88177-00A   I196 @BASEBOARD_FAB2_LIB.BASEBOARD_FAB2(SCH_1):PAGE113
 C1M33    1      A CAP_A_0402V-0.1UF,16V,10%,X7R,A   I248 @BASEBOARD_FAB2_LIB.BASEBOARD_FAB2(SCH_1):PAGE113

JTAG_MCP_TRST_N @BASEBOARD_FAB2_LIB.BASEBOARD_FAB2(SCH_1):JTAG_MCP_TRST_N
  U5D1 CD23 CD_TRST_N SKX_EXT_B_BGA1-IC,TBD    I61 @BASEBOARD_FAB2_LIB.BASEBOARD_FAB2(SCH_1):PAGE29
  U2D1 CD23 CD_TRST_N SKX_EXT_B_BGA1-IC,TBD    I23 @BASEBOARD_FAB2_LIB.BASEBOARD_FAB2(SCH_1):PAGE63
  J9B4    6    IO6 SCONN10_C12536004_SMLF-CONN,C1A   I175 @BASEBOARD_FAB2_LIB.BASEBOARD_FAB2(SCH_1):PAGE113
 R1M23    1      A RES_0402-1.00K,1%,1/16W,EMPTY,A   I199 @BASEBOARD_FAB2_LIB.BASEBOARD_FAB2(SCH_1):PAGE113
 R1M21    2      B RES_0402-1.00K,1%,1/16W,CHIP,GA   I205 @BASEBOARD_FAB2_LIB.BASEBOARD_FAB2(SCH_1):PAGE113

JTAG_PCH_GBE_CLK @BASEBOARD_FAB2_LIB.BASEBOARD_FAB2(SCH_1):JTAG_PCH_GBE_CLK
  U7C1 BV21 GPP_I1_LAN_TCK LBG_CORE_QAT_EXT_D_BGA1-IC,H91A   I147 @BASEBOARD_FAB2_LIB.BASEBOARD_FAB2(SCH_1):PAGE120
 R8G15    1      A RES_0402-0.0,5%,1/16W,EMPTY,G2A    I24 @BASEBOARD_FAB2_LIB.BASEBOARD_FAB2(SCH_1):PAGE189

JTAG_PCH_GBE_TDI @BASEBOARD_FAB2_LIB.BASEBOARD_FAB2(SCH_1):JTAG_PCH_GBE_TDI
  U7C1 BY23 GPP_I3_LAN_TDI LBG_CORE_QAT_EXT_D_BGA1-IC,H91A   I147 @BASEBOARD_FAB2_LIB.BASEBOARD_FAB2(SCH_1):PAGE120
 R7G19    1      A RES_0402-0.0,5%,1/16W,EMPTY,G2A     I8 @BASEBOARD_FAB2_LIB.BASEBOARD_FAB2(SCH_1):PAGE189

JTAG_PCH_GBE_TDO @BASEBOARD_FAB2_LIB.BASEBOARD_FAB2(SCH_1):JTAG_PCH_GBE_TDO
  U7C1 CA20 GPP_I0_LAN_TDO LBG_CORE_QAT_EXT_D_BGA1-IC,H91A   I147 @BASEBOARD_FAB2_LIB.BASEBOARD_FAB2(SCH_1):PAGE120
 R7G16    1      A RES_0402-0.0,5%,1/16W,EMPTY,G2A    I27 @BASEBOARD_FAB2_LIB.BASEBOARD_FAB2(SCH_1):PAGE189

JTAG_PCH_GBE_TMS @BASEBOARD_FAB2_LIB.BASEBOARD_FAB2(SCH_1):JTAG_PCH_GBE_TMS
  U7C1 CA22 GPP_I2_LAN_TMS LBG_CORE_QAT_EXT_D_BGA1-IC,H91A   I147 @BASEBOARD_FAB2_LIB.BASEBOARD_FAB2(SCH_1):PAGE120
 R8G12    1      A RES_0402-0.0,5%,1/16W,EMPTY,G2A    I21 @BASEBOARD_FAB2_LIB.BASEBOARD_FAB2(SCH_1):PAGE189

JTAG_PCH_GBE_TRST_N @BASEBOARD_FAB2_LIB.BASEBOARD_FAB2(SCH_1):JTAG_PCH_GBE_TRST_N
  U7C1 CA24 GPP_I7_LAN_TRST_N LBG_CORE_QAT_EXT_D_BGA1-IC,H91A   I147 @BASEBOARD_FAB2_LIB.BASEBOARD_FAB2(SCH_1):PAGE120
  R8G9    1      A RES_0402-0.0,5%,1/16W,EMPTY,G2A     I9 @BASEBOARD_FAB2_LIB.BASEBOARD_FAB2(SCH_1):PAGE189

JTAG_PCH_PLD_TCK @BASEBOARD_FAB2_LIB.BASEBOARD_FAB2(SCH_1):JTAG_PCH_PLD_TCK
  U7C1 AL18 GPP_F6_SATA_DEVSLP4 LBG_CORE_QAT_EXT_D_BGA1-IC,H91A   I147 @BASEBOARD_FAB2_LIB.BASEBOARD_FAB2(SCH_1):PAGE120
 R8G16    1      A RES_0402-0.0,5%,1/16W,EMPTY,G2A    I22 @BASEBOARD_FAB2_LIB.BASEBOARD_FAB2(SCH_1):PAGE189

JTAG_PCH_PLD_TDI @BASEBOARD_FAB2_LIB.BASEBOARD_FAB2(SCH_1):JTAG_PCH_PLD_TDI
  U7C1 AK17 GPP_F7_SATA_DEVSLP5 LBG_CORE_QAT_EXT_D_BGA1-IC,H91A   I147 @BASEBOARD_FAB2_LIB.BASEBOARD_FAB2(SCH_1):PAGE120
 R7G18    1      A RES_0402-0.0,5%,1/16W,EMPTY,G2A    I13 @BASEBOARD_FAB2_LIB.BASEBOARD_FAB2(SCH_1):PAGE189

JTAG_PCH_PLD_TDO @BASEBOARD_FAB2_LIB.BASEBOARD_FAB2(SCH_1):JTAG_PCH_PLD_TDO
  U7C1 AR20 GPP_F9_SATA_DEVSLP7 LBG_CORE_QAT_EXT_D_BGA1-IC,H91A   I147 @BASEBOARD_FAB2_LIB.BASEBOARD_FAB2(SCH_1):PAGE120
 R7G15    1      A RES_0402-0.0,5%,1/16W,EMPTY,G2A    I36 @BASEBOARD_FAB2_LIB.BASEBOARD_FAB2(SCH_1):PAGE189

JTAG_PCH_PLD_TMS @BASEBOARD_FAB2_LIB.BASEBOARD_FAB2(SCH_1):JTAG_PCH_PLD_TMS
  U7C1  AH9 GPP_F8_SATA_DEVSLP6 LBG_CORE_QAT_EXT_D_BGA1-IC,H91A   I147 @BASEBOARD_FAB2_LIB.BASEBOARD_FAB2(SCH_1):PAGE120
 R8G11    1      A RES_0402-0.0,5%,1/16W,EMPTY,G2A    I19 @BASEBOARD_FAB2_LIB.BASEBOARD_FAB2(SCH_1):PAGE189

JTAG_PLD_TCK @BASEBOARD_FAB2_LIB.BASEBOARD_FAB2(SCH_1):JTAG_PLD_TCK
 R8G18    1      A RES_0402-0.0,5%,1/16W,CHIP,G21A    I26 @BASEBOARD_FAB2_LIB.BASEBOARD_FAB2(SCH_1):PAGE189
  U8D7   A7 PT16C_TCK LCMXO2_A_256BGA-IC,H63395-001    I59 @BASEBOARD_FAB2_LIB.BASEBOARD_FAB2(SCH_1):PAGE191

JTAG_PLD_TDI @BASEBOARD_FAB2_LIB.BASEBOARD_FAB2(SCH_1):JTAG_PLD_TDI
  R8G7    1      A RES_0402-0.0,5%,1/16W,CHIP,G21A    I18 @BASEBOARD_FAB2_LIB.BASEBOARD_FAB2(SCH_1):PAGE189
  U8D7   A6 PT12D_TDI LCMXO2_A_256BGA-IC,H63395-001    I59 @BASEBOARD_FAB2_LIB.BASEBOARD_FAB2(SCH_1):PAGE191

JTAG_PLD_TDO @BASEBOARD_FAB2_LIB.BASEBOARD_FAB2(SCH_1):JTAG_PLD_TDO
 R7G14    1      A RES_0402-0.0,5%,1/16W,CHIP,G21A    I38 @BASEBOARD_FAB2_LIB.BASEBOARD_FAB2(SCH_1):PAGE189
  U8D7   C6 PT12C_TDO LCMXO2_A_256BGA-IC,H63395-001    I59 @BASEBOARD_FAB2_LIB.BASEBOARD_FAB2(SCH_1):PAGE191

JTAG_PLD_TMS @BASEBOARD_FAB2_LIB.BASEBOARD_FAB2(SCH_1):JTAG_PLD_TMS
 R8G13    1      A RES_0402-0.0,5%,1/16W,CHIP,G21A    I23 @BASEBOARD_FAB2_LIB.BASEBOARD_FAB2(SCH_1):PAGE189
  U8D7   B8 PT16D_TMS LCMXO2_A_256BGA-IC,H63395-001    I59 @BASEBOARD_FAB2_LIB.BASEBOARD_FAB2(SCH_1):PAGE191

JTAG_TCK @BASEBOARD_FAB2_LIB.BASEBOARD_FAB2(SCH_1):JTAG_TCK
 R8G16    2      B RES_0402-0.0,5%,1/16W,EMPTY,G2A    I22 @BASEBOARD_FAB2_LIB.BASEBOARD_FAB2(SCH_1):PAGE189
 R8G15    2      B RES_0402-0.0,5%,1/16W,EMPTY,G2A    I24 @BASEBOARD_FAB2_LIB.BASEBOARD_FAB2(SCH_1):PAGE189
 R8G17    2      B RES_0402-0.0,5%,1/16W,CHIP,G21A    I25 @BASEBOARD_FAB2_LIB.BASEBOARD_FAB2(SCH_1):PAGE189
 R8G18    2      B RES_0402-0.0,5%,1/16W,CHIP,G21A    I26 @BASEBOARD_FAB2_LIB.BASEBOARD_FAB2(SCH_1):PAGE189
 R8G22    1      A RES_0402-0.0,5%,1/16W,CHIP,G21A    I66 @BASEBOARD_FAB2_LIB.BASEBOARD_FAB2(SCH_1):PAGE189

JTAG_TCK_R @BASEBOARD_FAB2_LIB.BASEBOARD_FAB2(SCH_1):JTAG_TCK_R
  J7G2    8    IO8 CONN8_C77962004_PIP-CONN,C7796A    I47 @BASEBOARD_FAB2_LIB.BASEBOARD_FAB2(SCH_1):PAGE189
 R8G23    1      A RES_0402-4.75K,1%,1/16W,CHIP,GA    I56 @BASEBOARD_FAB2_LIB.BASEBOARD_FAB2(SCH_1):PAGE189
 R8G22    2      B RES_0402-0.0,5%,1/16W,CHIP,G21A    I66 @BASEBOARD_FAB2_LIB.BASEBOARD_FAB2(SCH_1):PAGE189

JTAG_TDI @BASEBOARD_FAB2_LIB.BASEBOARD_FAB2(SCH_1):JTAG_TDI
 R7G19    2      B RES_0402-0.0,5%,1/16W,EMPTY,G2A     I8 @BASEBOARD_FAB2_LIB.BASEBOARD_FAB2(SCH_1):PAGE189
 R7G18    2      B RES_0402-0.0,5%,1/16W,EMPTY,G2A    I13 @BASEBOARD_FAB2_LIB.BASEBOARD_FAB2(SCH_1):PAGE189
  R8G8    2      B RES_0402-0.0,5%,1/16W,CHIP,G21A    I17 @BASEBOARD_FAB2_LIB.BASEBOARD_FAB2(SCH_1):PAGE189
  R8G7    2      B RES_0402-0.0,5%,1/16W,CHIP,G21A    I18 @BASEBOARD_FAB2_LIB.BASEBOARD_FAB2(SCH_1):PAGE189
 R8G19    1      A RES_0402-0.0,5%,1/16W,CHIP,G21A    I64 @BASEBOARD_FAB2_LIB.BASEBOARD_FAB2(SCH_1):PAGE189

JTAG_TDI_R @BASEBOARD_FAB2_LIB.BASEBOARD_FAB2(SCH_1):JTAG_TDI_R
  J7G2    3    IO3 CONN8_C77962004_PIP-CONN,C7796A    I47 @BASEBOARD_FAB2_LIB.BASEBOARD_FAB2(SCH_1):PAGE189
 R7G23    2      B RES_0402-10.0K,1%,1/16W,CHIP,GA    I51 @BASEBOARD_FAB2_LIB.BASEBOARD_FAB2(SCH_1):PAGE189
 R8G19    2      B RES_0402-0.0,5%,1/16W,CHIP,G21A    I64 @BASEBOARD_FAB2_LIB.BASEBOARD_FAB2(SCH_1):PAGE189

JTAG_TDO @BASEBOARD_FAB2_LIB.BASEBOARD_FAB2(SCH_1):JTAG_TDO
 R7G16    2      B RES_0402-0.0,5%,1/16W,EMPTY,G2A    I27 @BASEBOARD_FAB2_LIB.BASEBOARD_FAB2(SCH_1):PAGE189
 R7G15    2      B RES_0402-0.0,5%,1/16W,EMPTY,G2A    I36 @BASEBOARD_FAB2_LIB.BASEBOARD_FAB2(SCH_1):PAGE189
 R7G17    2      B RES_0402-0.0,5%,1/16W,CHIP,G21A    I37 @BASEBOARD_FAB2_LIB.BASEBOARD_FAB2(SCH_1):PAGE189
 R7G14    2      B RES_0402-0.0,5%,1/16W,CHIP,G21A    I38 @BASEBOARD_FAB2_LIB.BASEBOARD_FAB2(SCH_1):PAGE189
 R7G21    1      A RES_0402-0.0,5%,1/16W,CHIP,G21A    I63 @BASEBOARD_FAB2_LIB.BASEBOARD_FAB2(SCH_1):PAGE189

JTAG_TDO_R @BASEBOARD_FAB2_LIB.BASEBOARD_FAB2(SCH_1):JTAG_TDO_R
  J7G2    2    IO2 CONN8_C77962004_PIP-CONN,C7796A    I47 @BASEBOARD_FAB2_LIB.BASEBOARD_FAB2(SCH_1):PAGE189
 R7G22    2      B RES_0402-10.0K,1%,1/16W,CHIP,GA    I53 @BASEBOARD_FAB2_LIB.BASEBOARD_FAB2(SCH_1):PAGE189
 R7G21    2      B RES_0402-0.0,5%,1/16W,CHIP,G21A    I63 @BASEBOARD_FAB2_LIB.BASEBOARD_FAB2(SCH_1):PAGE189

JTAG_TMS @BASEBOARD_FAB2_LIB.BASEBOARD_FAB2(SCH_1):JTAG_TMS
 R8G11    2      B RES_0402-0.0,5%,1/16W,EMPTY,G2A    I19 @BASEBOARD_FAB2_LIB.BASEBOARD_FAB2(SCH_1):PAGE189
 R8G14    2      B RES_0402-0.0,5%,1/16W,CHIP,G21A    I20 @BASEBOARD_FAB2_LIB.BASEBOARD_FAB2(SCH_1):PAGE189
 R8G12    2      B RES_0402-0.0,5%,1/16W,EMPTY,G2A    I21 @BASEBOARD_FAB2_LIB.BASEBOARD_FAB2(SCH_1):PAGE189
 R8G13    2      B RES_0402-0.0,5%,1/16W,CHIP,G21A    I23 @BASEBOARD_FAB2_LIB.BASEBOARD_FAB2(SCH_1):PAGE189
 R8G21    1      A RES_0402-0.0,5%,1/16W,CHIP,G21A    I65 @BASEBOARD_FAB2_LIB.BASEBOARD_FAB2(SCH_1):PAGE189

JTAG_TMS_R @BASEBOARD_FAB2_LIB.BASEBOARD_FAB2(SCH_1):JTAG_TMS_R
  J7G2    6    IO6 CONN8_C77962004_PIP-CONN,C7796A    I47 @BASEBOARD_FAB2_LIB.BASEBOARD_FAB2(SCH_1):PAGE189
 R8G20    2      B RES_0402-10.0K,1%,1/16W,CHIP,GA    I50 @BASEBOARD_FAB2_LIB.BASEBOARD_FAB2(SCH_1):PAGE189
 R8G21    2      B RES_0402-0.0,5%,1/16W,CHIP,G21A    I65 @BASEBOARD_FAB2_LIB.BASEBOARD_FAB2(SCH_1):PAGE189

JTAG_TRST_N @BASEBOARD_FAB2_LIB.BASEBOARD_FAB2(SCH_1):JTAG_TRST_N
 R8G10    2      B RES_0402-0.0,5%,1/16W,CHIP,G21A     I7 @BASEBOARD_FAB2_LIB.BASEBOARD_FAB2(SCH_1):PAGE189
  R8G9    2      B RES_0402-0.0,5%,1/16W,EMPTY,G2A     I9 @BASEBOARD_FAB2_LIB.BASEBOARD_FAB2(SCH_1):PAGE189
  J7G2    4    IO4 CONN8_C77962004_PIP-CONN,C7796A    I47 @BASEBOARD_FAB2_LIB.BASEBOARD_FAB2(SCH_1):PAGE189

KR_P0_OCP_RX_C_DN @BASEBOARD_FAB2_LIB.BASEBOARD_FAB2(SCH_1):KR_P0_OCP_RX_C_DN
  U7C1 BH31 LAN_RX_P0N LBG_CORE_QAT_EXT_D_BGA1-IC,H91A    I73 @BASEBOARD_FAB2_LIB.BASEBOARD_FAB2(SCH_1):PAGE118
 C8C14    2      B CAP_A_0402V-0.1UF,16V,10%,X7R,A    I86 @BASEBOARD_FAB2_LIB.BASEBOARD_FAB2(SCH_1):PAGE188

KR_P0_OCP_RX_C_DP @BASEBOARD_FAB2_LIB.BASEBOARD_FAB2(SCH_1):KR_P0_OCP_RX_C_DP
  U7C1 BF31 LAN_RX_P0P LBG_CORE_QAT_EXT_D_BGA1-IC,H91A    I73 @BASEBOARD_FAB2_LIB.BASEBOARD_FAB2(SCH_1):PAGE118
 C8C15    2      B CAP_A_0402V-0.1UF,16V,10%,X7R,A    I82 @BASEBOARD_FAB2_LIB.BASEBOARD_FAB2(SCH_1):PAGE188

KR_P0_OCP_RX_DN @BASEBOARD_FAB2_LIB.BASEBOARD_FAB2(SCH_1):KR_P0_OCP_RX_DN
  J8E4   53   IO53 SCONN64_H87568002_A_SMT-CONN,HA    I27 @BASEBOARD_FAB2_LIB.BASEBOARD_FAB2(SCH_1):PAGE188
 C8C14    1      A CAP_A_0402V-0.1UF,16V,10%,X7R,A    I86 @BASEBOARD_FAB2_LIB.BASEBOARD_FAB2(SCH_1):PAGE188

KR_P0_OCP_RX_DP @BASEBOARD_FAB2_LIB.BASEBOARD_FAB2(SCH_1):KR_P0_OCP_RX_DP
  J8E4   52   IO52 SCONN64_H87568002_A_SMT-CONN,HA    I27 @BASEBOARD_FAB2_LIB.BASEBOARD_FAB2(SCH_1):PAGE188
 C8C15    1      A CAP_A_0402V-0.1UF,16V,10%,X7R,A    I82 @BASEBOARD_FAB2_LIB.BASEBOARD_FAB2(SCH_1):PAGE188

KR_P0_OCP_TX_DN @BASEBOARD_FAB2_LIB.BASEBOARD_FAB2(SCH_1):KR_P0_OCP_TX_DN
  U7C1 BM27 LAN_TX_P0N LBG_CORE_QAT_EXT_D_BGA1-IC,H91A    I73 @BASEBOARD_FAB2_LIB.BASEBOARD_FAB2(SCH_1):PAGE118
  J8E4   41   IO41 SCONN64_H87568002_A_SMT-CONN,HA    I27 @BASEBOARD_FAB2_LIB.BASEBOARD_FAB2(SCH_1):PAGE188

KR_P0_OCP_TX_DP @BASEBOARD_FAB2_LIB.BASEBOARD_FAB2(SCH_1):KR_P0_OCP_TX_DP
  U7C1 BR27 LAN_TX_P0P LBG_CORE_QAT_EXT_D_BGA1-IC,H91A    I73 @BASEBOARD_FAB2_LIB.BASEBOARD_FAB2(SCH_1):PAGE118
  J8E4   40   IO40 SCONN64_H87568002_A_SMT-CONN,HA    I27 @BASEBOARD_FAB2_LIB.BASEBOARD_FAB2(SCH_1):PAGE188

KR_P1_OCP_RX_C_DN @BASEBOARD_FAB2_LIB.BASEBOARD_FAB2(SCH_1):KR_P1_OCP_RX_C_DN
  U7C1 BG29 LAN_RX_P1N LBG_CORE_QAT_EXT_D_BGA1-IC,H91A    I73 @BASEBOARD_FAB2_LIB.BASEBOARD_FAB2(SCH_1):PAGE118
 C8C13    2      B CAP_A_0402V-0.1UF,16V,10%,X7R,A    I81 @BASEBOARD_FAB2_LIB.BASEBOARD_FAB2(SCH_1):PAGE188

KR_P1_OCP_RX_C_DP @BASEBOARD_FAB2_LIB.BASEBOARD_FAB2(SCH_1):KR_P1_OCP_RX_C_DP
  U7C1 BJ29 LAN_RX_P1P LBG_CORE_QAT_EXT_D_BGA1-IC,H91A    I73 @BASEBOARD_FAB2_LIB.BASEBOARD_FAB2(SCH_1):PAGE118
 C8C12    2      B CAP_A_0402V-0.1UF,16V,10%,X7R,A    I80 @BASEBOARD_FAB2_LIB.BASEBOARD_FAB2(SCH_1):PAGE188

KR_P1_OCP_RX_DN @BASEBOARD_FAB2_LIB.BASEBOARD_FAB2(SCH_1):KR_P1_OCP_RX_DN
  J8E4   59   IO59 SCONN64_H87568002_A_SMT-CONN,HA    I27 @BASEBOARD_FAB2_LIB.BASEBOARD_FAB2(SCH_1):PAGE188
 C8C13    1      A CAP_A_0402V-0.1UF,16V,10%,X7R,A    I81 @BASEBOARD_FAB2_LIB.BASEBOARD_FAB2(SCH_1):PAGE188

KR_P1_OCP_RX_DP @BASEBOARD_FAB2_LIB.BASEBOARD_FAB2(SCH_1):KR_P1_OCP_RX_DP
  J8E4   58   IO58 SCONN64_H87568002_A_SMT-CONN,HA    I27 @BASEBOARD_FAB2_LIB.BASEBOARD_FAB2(SCH_1):PAGE188
 C8C12    1      A CAP_A_0402V-0.1UF,16V,10%,X7R,A    I80 @BASEBOARD_FAB2_LIB.BASEBOARD_FAB2(SCH_1):PAGE188

KR_P1_OCP_TX_DN @BASEBOARD_FAB2_LIB.BASEBOARD_FAB2(SCH_1):KR_P1_OCP_TX_DN
  U7C1 BM24 LAN_TX_P1N LBG_CORE_QAT_EXT_D_BGA1-IC,H91A    I73 @BASEBOARD_FAB2_LIB.BASEBOARD_FAB2(SCH_1):PAGE118
  J8E4   47   IO47 SCONN64_H87568002_A_SMT-CONN,HA    I27 @BASEBOARD_FAB2_LIB.BASEBOARD_FAB2(SCH_1):PAGE188

KR_P1_OCP_TX_DP @BASEBOARD_FAB2_LIB.BASEBOARD_FAB2(SCH_1):KR_P1_OCP_TX_DP
  U7C1 BR24 LAN_TX_P1P LBG_CORE_QAT_EXT_D_BGA1-IC,H91A    I73 @BASEBOARD_FAB2_LIB.BASEBOARD_FAB2(SCH_1):PAGE118
  J8E4   46   IO46 SCONN64_H87568002_A_SMT-CONN,HA    I27 @BASEBOARD_FAB2_LIB.BASEBOARD_FAB2(SCH_1):PAGE188

KR_P2_OCP_RX_C_DN @BASEBOARD_FAB2_LIB.BASEBOARD_FAB2(SCH_1):KR_P2_OCP_RX_C_DN
  U7C1 BJ37 LAN_RX_P2N LBG_CORE_QAT_EXT_D_BGA1-IC,H91A    I73 @BASEBOARD_FAB2_LIB.BASEBOARD_FAB2(SCH_1):PAGE118
 C8C10    2      B CAP_A_0402V-0.1UF,16V,10%,X7R,A    I73 @BASEBOARD_FAB2_LIB.BASEBOARD_FAB2(SCH_1):PAGE188

KR_P2_OCP_RX_C_DP @BASEBOARD_FAB2_LIB.BASEBOARD_FAB2(SCH_1):KR_P2_OCP_RX_C_DP
  U7C1 BG37 LAN_RX_P2P LBG_CORE_QAT_EXT_D_BGA1-IC,H91A    I73 @BASEBOARD_FAB2_LIB.BASEBOARD_FAB2(SCH_1):PAGE118
 C8C11    2      B CAP_A_0402V-0.1UF,16V,10%,X7R,A    I72 @BASEBOARD_FAB2_LIB.BASEBOARD_FAB2(SCH_1):PAGE188

KR_P2_OCP_RX_DN @BASEBOARD_FAB2_LIB.BASEBOARD_FAB2(SCH_1):KR_P2_OCP_RX_DN
  J8E4   18   IO18 SCONN64_H87568002_A_SMT-CONN,HA    I27 @BASEBOARD_FAB2_LIB.BASEBOARD_FAB2(SCH_1):PAGE188
 C8C10    1      A CAP_A_0402V-0.1UF,16V,10%,X7R,A    I73 @BASEBOARD_FAB2_LIB.BASEBOARD_FAB2(SCH_1):PAGE188

KR_P2_OCP_RX_DP @BASEBOARD_FAB2_LIB.BASEBOARD_FAB2(SCH_1):KR_P2_OCP_RX_DP
  J8E4   17   IO17 SCONN64_H87568002_A_SMT-CONN,HA    I27 @BASEBOARD_FAB2_LIB.BASEBOARD_FAB2(SCH_1):PAGE188
 C8C11    1      A CAP_A_0402V-0.1UF,16V,10%,X7R,A    I72 @BASEBOARD_FAB2_LIB.BASEBOARD_FAB2(SCH_1):PAGE188

KR_P2_OCP_TX_DN @BASEBOARD_FAB2_LIB.BASEBOARD_FAB2(SCH_1):KR_P2_OCP_TX_DN
  U7C1 BM35 LAN_TX_P2N LBG_CORE_QAT_EXT_D_BGA1-IC,H91A    I73 @BASEBOARD_FAB2_LIB.BASEBOARD_FAB2(SCH_1):PAGE118
  J8E4    6    IO6 SCONN64_H87568002_A_SMT-CONN,HA    I27 @BASEBOARD_FAB2_LIB.BASEBOARD_FAB2(SCH_1):PAGE188

KR_P2_OCP_TX_DP @BASEBOARD_FAB2_LIB.BASEBOARD_FAB2(SCH_1):KR_P2_OCP_TX_DP
  U7C1 BR35 LAN_TX_P2P LBG_CORE_QAT_EXT_D_BGA1-IC,H91A    I73 @BASEBOARD_FAB2_LIB.BASEBOARD_FAB2(SCH_1):PAGE118
  J8E4    5    IO5 SCONN64_H87568002_A_SMT-CONN,HA    I27 @BASEBOARD_FAB2_LIB.BASEBOARD_FAB2(SCH_1):PAGE188

KR_P3_OCP_RX_C_DN @BASEBOARD_FAB2_LIB.BASEBOARD_FAB2(SCH_1):KR_P3_OCP_RX_C_DN
  U7C1 BF35 LAN_RX_P3N LBG_CORE_QAT_EXT_D_BGA1-IC,H91A    I73 @BASEBOARD_FAB2_LIB.BASEBOARD_FAB2(SCH_1):PAGE118
  C8C9    2      B CAP_A_0402V-0.1UF,16V,10%,X7R,A    I68 @BASEBOARD_FAB2_LIB.BASEBOARD_FAB2(SCH_1):PAGE188

KR_P3_OCP_RX_C_DP @BASEBOARD_FAB2_LIB.BASEBOARD_FAB2(SCH_1):KR_P3_OCP_RX_C_DP
  U7C1 BH35 LAN_RX_P3P LBG_CORE_QAT_EXT_D_BGA1-IC,H91A    I73 @BASEBOARD_FAB2_LIB.BASEBOARD_FAB2(SCH_1):PAGE118
  C8C8    2      B CAP_A_0402V-0.1UF,16V,10%,X7R,A    I64 @BASEBOARD_FAB2_LIB.BASEBOARD_FAB2(SCH_1):PAGE188

KR_P3_OCP_RX_DN @BASEBOARD_FAB2_LIB.BASEBOARD_FAB2(SCH_1):KR_P3_OCP_RX_DN
  J8E4   24   IO24 SCONN64_H87568002_A_SMT-CONN,HA    I27 @BASEBOARD_FAB2_LIB.BASEBOARD_FAB2(SCH_1):PAGE188
  C8C9    1      A CAP_A_0402V-0.1UF,16V,10%,X7R,A    I68 @BASEBOARD_FAB2_LIB.BASEBOARD_FAB2(SCH_1):PAGE188

KR_P3_OCP_RX_DP @BASEBOARD_FAB2_LIB.BASEBOARD_FAB2(SCH_1):KR_P3_OCP_RX_DP
  J8E4   23   IO23 SCONN64_H87568002_A_SMT-CONN,HA    I27 @BASEBOARD_FAB2_LIB.BASEBOARD_FAB2(SCH_1):PAGE188
  C8C8    1      A CAP_A_0402V-0.1UF,16V,10%,X7R,A    I64 @BASEBOARD_FAB2_LIB.BASEBOARD_FAB2(SCH_1):PAGE188

KR_P3_OCP_TX_DN @BASEBOARD_FAB2_LIB.BASEBOARD_FAB2(SCH_1):KR_P3_OCP_TX_DN
  U7C1 BR31 LAN_TX_P3N LBG_CORE_QAT_EXT_D_BGA1-IC,H91A    I73 @BASEBOARD_FAB2_LIB.BASEBOARD_FAB2(SCH_1):PAGE118
  J8E4   12   IO12 SCONN64_H87568002_A_SMT-CONN,HA    I27 @BASEBOARD_FAB2_LIB.BASEBOARD_FAB2(SCH_1):PAGE188

KR_P3_OCP_TX_DP @BASEBOARD_FAB2_LIB.BASEBOARD_FAB2(SCH_1):KR_P3_OCP_TX_DP
  U7C1 BM31 LAN_TX_P3P LBG_CORE_QAT_EXT_D_BGA1-IC,H91A    I73 @BASEBOARD_FAB2_LIB.BASEBOARD_FAB2(SCH_1):PAGE118
  J8E4   11   IO11 SCONN64_H87568002_A_SMT-CONN,HA    I27 @BASEBOARD_FAB2_LIB.BASEBOARD_FAB2(SCH_1):PAGE188

LED_GBE_P0_0 @BASEBOARD_FAB2_LIB.BASEBOARD_FAB2(SCH_1):LED_GBE_P0_0
  U7C1  BL1 GPP_J0_LAN_LED_P0_0 LBG_CORE_QAT_EXT_D_BGA1-IC,H91A   I147 @BASEBOARD_FAB2_LIB.BASEBOARD_FAB2(SCH_1):PAGE120
  J8E4   43   IO43 SCONN64_H87568002_A_SMT-CONN,HA    I27 @BASEBOARD_FAB2_LIB.BASEBOARD_FAB2(SCH_1):PAGE188

LED_GBE_P0_1 @BASEBOARD_FAB2_LIB.BASEBOARD_FAB2(SCH_1):LED_GBE_P0_1
  U7C1  BK4 GPP_J1_LAN_LED_P0_1 LBG_CORE_QAT_EXT_D_BGA1-IC,H91A   I147 @BASEBOARD_FAB2_LIB.BASEBOARD_FAB2(SCH_1):PAGE120
  J8E4   44   IO44 SCONN64_H87568002_A_SMT-CONN,HA    I27 @BASEBOARD_FAB2_LIB.BASEBOARD_FAB2(SCH_1):PAGE188

LED_GBE_P1_0 @BASEBOARD_FAB2_LIB.BASEBOARD_FAB2(SCH_1):LED_GBE_P1_0
  U7C1  BP4 GPP_J2_LAN_LED_P1_0 LBG_CORE_QAT_EXT_D_BGA1-IC,H91A   I147 @BASEBOARD_FAB2_LIB.BASEBOARD_FAB2(SCH_1):PAGE120
  J8E4    8    IO8 SCONN64_H87568002_A_SMT-CONN,HA    I27 @BASEBOARD_FAB2_LIB.BASEBOARD_FAB2(SCH_1):PAGE188

LED_GBE_P1_1 @BASEBOARD_FAB2_LIB.BASEBOARD_FAB2(SCH_1):LED_GBE_P1_1
  U7C1  BK2 GPP_J3_LAN_LED_P1_1 LBG_CORE_QAT_EXT_D_BGA1-IC,H91A   I147 @BASEBOARD_FAB2_LIB.BASEBOARD_FAB2(SCH_1):PAGE120
  J8E4    9    IO9 SCONN64_H87568002_A_SMT-CONN,HA    I27 @BASEBOARD_FAB2_LIB.BASEBOARD_FAB2(SCH_1):PAGE188

LED_GBE_P2_0 @BASEBOARD_FAB2_LIB.BASEBOARD_FAB2(SCH_1):LED_GBE_P2_0
  U7C1  BL3 GPP_J4_LAN_LED_P2_0 LBG_CORE_QAT_EXT_D_BGA1-IC,H91A   I147 @BASEBOARD_FAB2_LIB.BASEBOARD_FAB2(SCH_1):PAGE120
  J8E4   14   IO14 SCONN64_H87568002_A_SMT-CONN,HA    I27 @BASEBOARD_FAB2_LIB.BASEBOARD_FAB2(SCH_1):PAGE188

LED_GBE_P2_1 @BASEBOARD_FAB2_LIB.BASEBOARD_FAB2(SCH_1):LED_GBE_P2_1
  U7C1  BU6 GPP_J5_LAN_LED_P2_1 LBG_CORE_QAT_EXT_D_BGA1-IC,H91A   I147 @BASEBOARD_FAB2_LIB.BASEBOARD_FAB2(SCH_1):PAGE120
  J8E4   15   IO15 SCONN64_H87568002_A_SMT-CONN,HA    I27 @BASEBOARD_FAB2_LIB.BASEBOARD_FAB2(SCH_1):PAGE188

LED_GBE_P3_0 @BASEBOARD_FAB2_LIB.BASEBOARD_FAB2(SCH_1):LED_GBE_P3_0
  U7C1 CA13 GPP_J6_LAN_LED_P3_0 LBG_CORE_QAT_EXT_D_BGA1-IC,H91A   I147 @BASEBOARD_FAB2_LIB.BASEBOARD_FAB2(SCH_1):PAGE120
  J8E4   55   IO55 SCONN64_H87568002_A_SMT-CONN,HA    I27 @BASEBOARD_FAB2_LIB.BASEBOARD_FAB2(SCH_1):PAGE188

LED_GBE_P3_1 @BASEBOARD_FAB2_LIB.BASEBOARD_FAB2(SCH_1):LED_GBE_P3_1
  U7C1  BM2 GPP_J7_LAN_LED_P3_1 LBG_CORE_QAT_EXT_D_BGA1-IC,H91A   I147 @BASEBOARD_FAB2_LIB.BASEBOARD_FAB2(SCH_1):PAGE120
  J8E4   56   IO56 SCONN64_H87568002_A_SMT-CONN,HA    I27 @BASEBOARD_FAB2_LIB.BASEBOARD_FAB2(SCH_1):PAGE188

LED_HFI0_CPU0_N @BASEBOARD_FAB2_LIB.BASEBOARD_FAB2(SCH_1):LED_HFI0_CPU0_N
  U5D1 BK21 CD_HFI0_LED_N SKX_EXT_B_BGA1-IC,TBD    I61 @BASEBOARD_FAB2_LIB.BASEBOARD_FAB2(SCH_1):PAGE29
  J8B1    5    IO5 SCONN24_H46321001_SM-SCONN,H46A     I1 @BASEBOARD_FAB2_LIB.BASEBOARD_FAB2(SCH_1):PAGE91
  R8B5    2      B RES_0402-4.75K,1%,1/16W,CHIP,GA    I22 @BASEBOARD_FAB2_LIB.BASEBOARD_FAB2(SCH_1):PAGE91

LED_HFI1_CPU0_N @BASEBOARD_FAB2_LIB.BASEBOARD_FAB2(SCH_1):LED_HFI1_CPU0_N
  U5D1 BM23 CD_HFI1_LED_N SKX_EXT_B_BGA1-IC,TBD    I61 @BASEBOARD_FAB2_LIB.BASEBOARD_FAB2(SCH_1):PAGE29
  J8B1   13   IO13 SCONN24_H46321001_SM-SCONN,H46A     I1 @BASEBOARD_FAB2_LIB.BASEBOARD_FAB2(SCH_1):PAGE91
 R8B18    2      B RES_0402-4.75K,1%,1/16W,CHIP,GA    I20 @BASEBOARD_FAB2_LIB.BASEBOARD_FAB2(SCH_1):PAGE91

LED_LAN_0_N @BASEBOARD_FAB2_LIB.BASEBOARD_FAB2(SCH_1):LED_LAN_0_N
 EU9E1   31   LED0 SPRINGVILLE_SM1-IC,G47144-004    I72 @BASEBOARD_FAB2_LIB.BASEBOARD_FAB2(SCH_1):PAGE139
  R9G3    2      B RES_0402-150.0,1%,1/16W,CHIP,GA    I28 @BASEBOARD_FAB2_LIB.BASEBOARD_FAB2(SCH_1):PAGE141
  C9G3    1      A CAP_0402LF-470PF,50V,10%,X7R,AA    I59 @BASEBOARD_FAB2_LIB.BASEBOARD_FAB2(SCH_1):PAGE141

LED_LAN_0_R_N @BASEBOARD_FAB2_LIB.BASEBOARD_FAB2(SCH_1):LED_LAN_0_R_N
  R9G3    1      A RES_0402-150.0,1%,1/16W,CHIP,GA    I28 @BASEBOARD_FAB2_LIB.BASEBOARD_FAB2(SCH_1):PAGE141
 JA9G1   L1     L1 CONN17_H71061002_PIP1-CONN,H71A   I109 @BASEBOARD_FAB2_LIB.BASEBOARD_FAB2(SCH_1):PAGE141

LED_LAN_1_N @BASEBOARD_FAB2_LIB.BASEBOARD_FAB2(SCH_1):LED_LAN_1_N
 EU9E1   30   LED1 SPRINGVILLE_SM1-IC,G47144-004    I72 @BASEBOARD_FAB2_LIB.BASEBOARD_FAB2(SCH_1):PAGE139
  R9G1    1      A RES_0402-150.0,1%,1/16W,CHIP,GA    I54 @BASEBOARD_FAB2_LIB.BASEBOARD_FAB2(SCH_1):PAGE141
 C9F22    1      A CAP_0402LF-470PF,50V,10%,X7R,AA    I60 @BASEBOARD_FAB2_LIB.BASEBOARD_FAB2(SCH_1):PAGE141

LED_LAN_1_R_N @BASEBOARD_FAB2_LIB.BASEBOARD_FAB2(SCH_1):LED_LAN_1_R_N
  R9G1    2      B RES_0402-150.0,1%,1/16W,CHIP,GA    I54 @BASEBOARD_FAB2_LIB.BASEBOARD_FAB2(SCH_1):PAGE141
 JA9G1   L5     L5 CONN17_H71061002_PIP1-CONN,H71A   I109 @BASEBOARD_FAB2_LIB.BASEBOARD_FAB2(SCH_1):PAGE141

LED_LAN_2_N @BASEBOARD_FAB2_LIB.BASEBOARD_FAB2(SCH_1):LED_LAN_2_N
 EU9E1   33   LED2 SPRINGVILLE_SM1-IC,G47144-004    I72 @BASEBOARD_FAB2_LIB.BASEBOARD_FAB2(SCH_1):PAGE139
  R9G2    2      B RES_0402-150.0,1%,1/16W,CHIP,GA    I30 @BASEBOARD_FAB2_LIB.BASEBOARD_FAB2(SCH_1):PAGE141
  C9G1    1      A CAP_0402LF-470PF,50V,10%,X7R,AA    I58 @BASEBOARD_FAB2_LIB.BASEBOARD_FAB2(SCH_1):PAGE141

LED_LAN_2_R_N @BASEBOARD_FAB2_LIB.BASEBOARD_FAB2(SCH_1):LED_LAN_2_R_N
  R9G2    1      A RES_0402-150.0,1%,1/16W,CHIP,GA    I30 @BASEBOARD_FAB2_LIB.BASEBOARD_FAB2(SCH_1):PAGE141
 JA9G1   L3     L3 CONN17_H71061002_PIP1-CONN,H71A   I109 @BASEBOARD_FAB2_LIB.BASEBOARD_FAB2(SCH_1):PAGE141

LED_P5V_STBY @BASEBOARD_FAB2_LIB.BASEBOARD_FAB2(SCH_1):LED_P5V_STBY
 DS9A6    1      A LED_A1LF-GREEN,IC,C97278-010    I31 @BASEBOARD_FAB2_LIB.BASEBOARD_FAB2(SCH_1):PAGE177
 R1L37    2      B RES_0402-301.0,1%,1/16W,CHIP,GA    I33 @BASEBOARD_FAB2_LIB.BASEBOARD_FAB2(SCH_1):PAGE177

LED_PCH_SATA_HDD_N @BASEBOARD_FAB2_LIB.BASEBOARD_FAB2(SCH_1):LED_PCH_SATA_HDD_N
  U7C1 AV56 GPP_E8_SATA_LED_N LBG_CORE_QAT_EXT_D_BGA1-IC,H91A   I147 @BASEBOARD_FAB2_LIB.BASEBOARD_FAB2(SCH_1):PAGE120
 R1M10    1      A RES_0402-0.0,5%,1/16W,CHIP,G21A     I6 @BASEBOARD_FAB2_LIB.BASEBOARD_FAB2(SCH_1):PAGE177

LED_PCH_SSATA_HDD_N @BASEBOARD_FAB2_LIB.BASEBOARD_FAB2(SCH_1):LED_PCH_SSATA_HDD_N
  U7C1 AL11 GPP_F14_SSATA_LED_N LBG_CORE_QAT_EXT_D_BGA1-IC,H91A   I147 @BASEBOARD_FAB2_LIB.BASEBOARD_FAB2(SCH_1):PAGE120
 R1M13    1      A RES_0402-0.0,5%,1/16W,CHIP,G21A     I3 @BASEBOARD_FAB2_LIB.BASEBOARD_FAB2(SCH_1):PAGE177

LED_POSTCODE_0 @BASEBOARD_FAB2_LIB.BASEBOARD_FAB2(SCH_1):LED_POSTCODE_0
  U7C1  AV3 GPP_H2_SRCCLKREQ8_N LBG_CORE_QAT_EXT_D_BGA1-IC,H91A   I147 @BASEBOARD_FAB2_LIB.BASEBOARD_FAB2(SCH_1):PAGE120
 R1L32    1      A RES_0402-10.0,1%,1/16W,CHIP,G2A    I65 @BASEBOARD_FAB2_LIB.BASEBOARD_FAB2(SCH_1):PAGE155
 U25W4  A18 GPIOH0_NCTS6 AST2520A1-GP-GP_ASIC2-GB1-AST2A   I104 @BASEBOARD_FAB2_LIB.BASEBOARD_FAB2(SCH_1):PAGE146

LED_POSTCODE_0_R @BASEBOARD_FAB2_LIB.BASEBOARD_FAB2(SCH_1):LED_POSTCODE_0_R
 R1L32    2      B RES_0402-10.0,1%,1/16W,CHIP,G2A    I65 @BASEBOARD_FAB2_LIB.BASEBOARD_FAB2(SCH_1):PAGE155
  J9A2    1    IO1 CONN14_H54902001_PIP-CONN,H549A   I171 @BASEBOARD_FAB2_LIB.BASEBOARD_FAB2(SCH_1):PAGE155
  U6W1    4     P0 PCA9555PWRG4-GP_DISCRET-G5-PCAA    I97 @BASEBOARD_FAB2_LIB.BASEBOARD_FAB2(SCH_1):PAGE247

LED_POSTCODE_1 @BASEBOARD_FAB2_LIB.BASEBOARD_FAB2(SCH_1):LED_POSTCODE_1
  U7C1  AR1 GPP_H3_SRCCLKREQ9_N LBG_CORE_QAT_EXT_D_BGA1-IC,H91A   I147 @BASEBOARD_FAB2_LIB.BASEBOARD_FAB2(SCH_1):PAGE120
 R1L30    1      A RES_0402-10.0,1%,1/16W,CHIP,G2A    I66 @BASEBOARD_FAB2_LIB.BASEBOARD_FAB2(SCH_1):PAGE155
 U25W4  B18 GPIOH1_NDCD6 AST2520A1-GP-GP_ASIC2-GB1-AST2A   I104 @BASEBOARD_FAB2_LIB.BASEBOARD_FAB2(SCH_1):PAGE146

LED_POSTCODE_1_R @BASEBOARD_FAB2_LIB.BASEBOARD_FAB2(SCH_1):LED_POSTCODE_1_R
 R1L30    2      B RES_0402-10.0,1%,1/16W,CHIP,G2A    I66 @BASEBOARD_FAB2_LIB.BASEBOARD_FAB2(SCH_1):PAGE155
  J9A2    2    IO2 CONN14_H54902001_PIP-CONN,H549A   I171 @BASEBOARD_FAB2_LIB.BASEBOARD_FAB2(SCH_1):PAGE155
  U6W1    5     P1 PCA9555PWRG4-GP_DISCRET-G5-PCAA    I97 @BASEBOARD_FAB2_LIB.BASEBOARD_FAB2(SCH_1):PAGE247

LED_POSTCODE_2 @BASEBOARD_FAB2_LIB.BASEBOARD_FAB2(SCH_1):LED_POSTCODE_2
  U7C1  AT2 GPP_H4_SRCCLKREQ10_N LBG_CORE_QAT_EXT_D_BGA1-IC,H91A   I147 @BASEBOARD_FAB2_LIB.BASEBOARD_FAB2(SCH_1):PAGE120
 R1L25    1      A RES_0402-10.0,1%,1/16W,CHIP,G2A    I67 @BASEBOARD_FAB2_LIB.BASEBOARD_FAB2(SCH_1):PAGE155
 U25W4  D17 GPIOH2_NDSR6 AST2520A1-GP-GP_ASIC2-GB1-AST2A   I104 @BASEBOARD_FAB2_LIB.BASEBOARD_FAB2(SCH_1):PAGE146

LED_POSTCODE_2_R @BASEBOARD_FAB2_LIB.BASEBOARD_FAB2(SCH_1):LED_POSTCODE_2_R
 R1L25    2      B RES_0402-10.0,1%,1/16W,CHIP,G2A    I67 @BASEBOARD_FAB2_LIB.BASEBOARD_FAB2(SCH_1):PAGE155
  J9A2    3    IO3 CONN14_H54902001_PIP-CONN,H549A   I171 @BASEBOARD_FAB2_LIB.BASEBOARD_FAB2(SCH_1):PAGE155
  U6W1    6     P2 PCA9555PWRG4-GP_DISCRET-G5-PCAA    I97 @BASEBOARD_FAB2_LIB.BASEBOARD_FAB2(SCH_1):PAGE247

LED_POSTCODE_3 @BASEBOARD_FAB2_LIB.BASEBOARD_FAB2(SCH_1):LED_POSTCODE_3
  U7C1  AY3 GPP_H5_SRCCLKREQ11_N LBG_CORE_QAT_EXT_D_BGA1-IC,H91A   I147 @BASEBOARD_FAB2_LIB.BASEBOARD_FAB2(SCH_1):PAGE120
 R1L24    1      A RES_0402-10.0,1%,1/16W,CHIP,G2A    I68 @BASEBOARD_FAB2_LIB.BASEBOARD_FAB2(SCH_1):PAGE155
 U25W4  C17 GPIOH3_NRI6 AST2520A1-GP-GP_ASIC2-GB1-AST2A   I104 @BASEBOARD_FAB2_LIB.BASEBOARD_FAB2(SCH_1):PAGE146

LED_POSTCODE_3_R @BASEBOARD_FAB2_LIB.BASEBOARD_FAB2(SCH_1):LED_POSTCODE_3_R
 R1L24    2      B RES_0402-10.0,1%,1/16W,CHIP,G2A    I68 @BASEBOARD_FAB2_LIB.BASEBOARD_FAB2(SCH_1):PAGE155
  J9A2    4    IO4 CONN14_H54902001_PIP-CONN,H549A   I171 @BASEBOARD_FAB2_LIB.BASEBOARD_FAB2(SCH_1):PAGE155
  U6W1    7     P3 PCA9555PWRG4-GP_DISCRET-G5-PCAA    I97 @BASEBOARD_FAB2_LIB.BASEBOARD_FAB2(SCH_1):PAGE247

LED_POSTCODE_4 @BASEBOARD_FAB2_LIB.BASEBOARD_FAB2(SCH_1):LED_POSTCODE_4
  U7C1  AW2 GPP_H6_SRCCLKREQ12_N LBG_CORE_QAT_EXT_D_BGA1-IC,H91A   I147 @BASEBOARD_FAB2_LIB.BASEBOARD_FAB2(SCH_1):PAGE120
 R1L20    1      A RES_0402-10.0,1%,1/16W,CHIP,G2A    I73 @BASEBOARD_FAB2_LIB.BASEBOARD_FAB2(SCH_1):PAGE155
 U25W4  A17 GPIOH4_NDTR6 AST2520A1-GP-GP_ASIC2-GB1-AST2A   I104 @BASEBOARD_FAB2_LIB.BASEBOARD_FAB2(SCH_1):PAGE146

LED_POSTCODE_4_R @BASEBOARD_FAB2_LIB.BASEBOARD_FAB2(SCH_1):LED_POSTCODE_4_R
 R1L20    2      B RES_0402-10.0,1%,1/16W,CHIP,G2A    I73 @BASEBOARD_FAB2_LIB.BASEBOARD_FAB2(SCH_1):PAGE155
  J9A2    5    IO5 CONN14_H54902001_PIP-CONN,H549A   I171 @BASEBOARD_FAB2_LIB.BASEBOARD_FAB2(SCH_1):PAGE155
  U6W1    8     P4 PCA9555PWRG4-GP_DISCRET-G5-PCAA    I97 @BASEBOARD_FAB2_LIB.BASEBOARD_FAB2(SCH_1):PAGE247

LED_POSTCODE_5 @BASEBOARD_FAB2_LIB.BASEBOARD_FAB2(SCH_1):LED_POSTCODE_5
  U7C1  AV1 GPP_H7_SRCCLKREQ13_N LBG_CORE_QAT_EXT_D_BGA1-IC,H91A   I147 @BASEBOARD_FAB2_LIB.BASEBOARD_FAB2(SCH_1):PAGE120
 R1L18    1      A RES_0402-10.0,1%,1/16W,CHIP,G2A    I74 @BASEBOARD_FAB2_LIB.BASEBOARD_FAB2(SCH_1):PAGE155
 U25W4  B17 GPIOH5_NRTS6 AST2520A1-GP-GP_ASIC2-GB1-AST2A   I104 @BASEBOARD_FAB2_LIB.BASEBOARD_FAB2(SCH_1):PAGE146

LED_POSTCODE_5_R @BASEBOARD_FAB2_LIB.BASEBOARD_FAB2(SCH_1):LED_POSTCODE_5_R
 R1L18    2      B RES_0402-10.0,1%,1/16W,CHIP,G2A    I74 @BASEBOARD_FAB2_LIB.BASEBOARD_FAB2(SCH_1):PAGE155
  J9A2    6    IO6 CONN14_H54902001_PIP-CONN,H549A   I171 @BASEBOARD_FAB2_LIB.BASEBOARD_FAB2(SCH_1):PAGE155
  U6W1    9     P5 PCA9555PWRG4-GP_DISCRET-G5-PCAA    I97 @BASEBOARD_FAB2_LIB.BASEBOARD_FAB2(SCH_1):PAGE247

LED_POSTCODE_6 @BASEBOARD_FAB2_LIB.BASEBOARD_FAB2(SCH_1):LED_POSTCODE_6
  U7C1  AR3 GPP_H8_SRCCLKREQ14_N LBG_CORE_QAT_EXT_D_BGA1-IC,H91A   I147 @BASEBOARD_FAB2_LIB.BASEBOARD_FAB2(SCH_1):PAGE120
 R1L14    1      A RES_0402-10.0,1%,1/16W,CHIP,G2A    I75 @BASEBOARD_FAB2_LIB.BASEBOARD_FAB2(SCH_1):PAGE155
 U25W4  A16 GPIOH6_TXD6 AST2520A1-GP-GP_ASIC2-GB1-AST2A   I104 @BASEBOARD_FAB2_LIB.BASEBOARD_FAB2(SCH_1):PAGE146

LED_POSTCODE_6_R @BASEBOARD_FAB2_LIB.BASEBOARD_FAB2(SCH_1):LED_POSTCODE_6_R
 R1L14    2      B RES_0402-10.0,1%,1/16W,CHIP,G2A    I75 @BASEBOARD_FAB2_LIB.BASEBOARD_FAB2(SCH_1):PAGE155
  J9A2    7    IO7 CONN14_H54902001_PIP-CONN,H549A   I171 @BASEBOARD_FAB2_LIB.BASEBOARD_FAB2(SCH_1):PAGE155
  U6W1   10     P6 PCA9555PWRG4-GP_DISCRET-G5-PCAA    I97 @BASEBOARD_FAB2_LIB.BASEBOARD_FAB2(SCH_1):PAGE247

LED_POSTCODE_7 @BASEBOARD_FAB2_LIB.BASEBOARD_FAB2(SCH_1):LED_POSTCODE_7
  U7C1  BE2 GPP_H9_SRCCLKREQ15_N LBG_CORE_QAT_EXT_D_BGA1-IC,H91A   I147 @BASEBOARD_FAB2_LIB.BASEBOARD_FAB2(SCH_1):PAGE120
 R1L11    1      A RES_0402-10.0,1%,1/16W,CHIP,G2A    I76 @BASEBOARD_FAB2_LIB.BASEBOARD_FAB2(SCH_1):PAGE155
 U25W4  D18 GPIOH7_RXD6 AST2520A1-GP-GP_ASIC2-GB1-AST2A   I104 @BASEBOARD_FAB2_LIB.BASEBOARD_FAB2(SCH_1):PAGE146

LED_POSTCODE_7_R @BASEBOARD_FAB2_LIB.BASEBOARD_FAB2(SCH_1):LED_POSTCODE_7_R
 R1L11    2      B RES_0402-10.0,1%,1/16W,CHIP,G2A    I76 @BASEBOARD_FAB2_LIB.BASEBOARD_FAB2(SCH_1):PAGE155
  J9A2    8    IO8 CONN14_H54902001_PIP-CONN,H549A   I171 @BASEBOARD_FAB2_LIB.BASEBOARD_FAB2(SCH_1):PAGE155
  U6W1   11     P7 PCA9555PWRG4-GP_DISCRET-G5-PCAA    I97 @BASEBOARD_FAB2_LIB.BASEBOARD_FAB2(SCH_1):PAGE247

LED_SAS_ACT_R_N @BASEBOARD_FAB2_LIB.BASEBOARD_FAB2(SCH_1):LED_SAS_ACT_R_N
 R1M13    2      B RES_0402-0.0,5%,1/16W,CHIP,G21A     I3 @BASEBOARD_FAB2_LIB.BASEBOARD_FAB2(SCH_1):PAGE177
 R1M12    2      B RES_0402-10.0K,1%,1/16W,CHIP,GA     I8 @BASEBOARD_FAB2_LIB.BASEBOARD_FAB2(SCH_1):PAGE177
  U1M1    2   B<0> TTL1G08_SOTLF-NC7SZ08,IC,D1032C    I70 @BASEBOARD_FAB2_LIB.BASEBOARD_FAB2(SCH_1):PAGE177

LED_SATA_ACT_R_N @BASEBOARD_FAB2_LIB.BASEBOARD_FAB2(SCH_1):LED_SATA_ACT_R_N
 R1M10    2      B RES_0402-0.0,5%,1/16W,CHIP,G21A     I6 @BASEBOARD_FAB2_LIB.BASEBOARD_FAB2(SCH_1):PAGE177
 R1M11    2      B RES_0402-10.0K,1%,1/16W,CHIP,GA     I9 @BASEBOARD_FAB2_LIB.BASEBOARD_FAB2(SCH_1):PAGE177
  U1M1    1   A<0> TTL1G08_SOTLF-NC7SZ08,IC,D1032C    I70 @BASEBOARD_FAB2_LIB.BASEBOARD_FAB2(SCH_1):PAGE177

LPC_LAD0_IO0 @BASEBOARD_FAB2_LIB.BASEBOARD_FAB2(SCH_1):LPC_LAD0_IO0
  U7C1   Y3 GPP_A1_LAD0_ESPI_IO0 LBG_CORE_QAT_EXT_D_BGA1-IC,H91A   I115 @BASEBOARD_FAB2_LIB.BASEBOARD_FAB2(SCH_1):PAGE119
 R3N26    1      A RES_0402-33.2,1%,1/16W,CHIP,G2A    I75 @BASEBOARD_FAB2_LIB.BASEBOARD_FAB2(SCH_1):PAGE146

LPC_LAD0_IO0_R @BASEBOARD_FAB2_LIB.BASEBOARD_FAB2(SCH_1):LPC_LAD0_IO0_R
 R3N26    2      B RES_0402-33.2,1%,1/16W,CHIP,G2A    I75 @BASEBOARD_FAB2_LIB.BASEBOARD_FAB2(SCH_1):PAGE146
 U25W4  G21 GPIOAC0_ESPID0_LAD0 AST2520A1-GP-GP_ASIC2-GB1-AST2A   I105 @BASEBOARD_FAB2_LIB.BASEBOARD_FAB2(SCH_1):PAGE146

LPC_LAD1_IO1 @BASEBOARD_FAB2_LIB.BASEBOARD_FAB2(SCH_1):LPC_LAD1_IO1
  U7C1   N1 GPP_A2_LAD1_ESPI_IO1 LBG_CORE_QAT_EXT_D_BGA1-IC,H91A   I115 @BASEBOARD_FAB2_LIB.BASEBOARD_FAB2(SCH_1):PAGE119
R25W69    1      A RES_0402-33.2,1%,1/16W,CHIP,G2A    I85 @BASEBOARD_FAB2_LIB.BASEBOARD_FAB2(SCH_1):PAGE146

LPC_LAD1_IO1_R @BASEBOARD_FAB2_LIB.BASEBOARD_FAB2(SCH_1):LPC_LAD1_IO1_R
R25W69    2      B RES_0402-33.2,1%,1/16W,CHIP,G2A    I85 @BASEBOARD_FAB2_LIB.BASEBOARD_FAB2(SCH_1):PAGE146
 U25W4  G20 GPIOAC1_ESPID1_LAD1 AST2520A1-GP-GP_ASIC2-GB1-AST2A   I105 @BASEBOARD_FAB2_LIB.BASEBOARD_FAB2(SCH_1):PAGE146

LPC_LAD2_IO2 @BASEBOARD_FAB2_LIB.BASEBOARD_FAB2(SCH_1):LPC_LAD2_IO2
  U7C1   W2 GPP_A3_LAD2_ESPI_IO2 LBG_CORE_QAT_EXT_D_BGA1-IC,H91A   I115 @BASEBOARD_FAB2_LIB.BASEBOARD_FAB2(SCH_1):PAGE119
 R3N24    1      A RES_0402-33.2,1%,1/16W,CHIP,G2A    I74 @BASEBOARD_FAB2_LIB.BASEBOARD_FAB2(SCH_1):PAGE146

LPC_LAD2_IO2_R @BASEBOARD_FAB2_LIB.BASEBOARD_FAB2(SCH_1):LPC_LAD2_IO2_R
 R3N24    2      B RES_0402-33.2,1%,1/16W,CHIP,G2A    I74 @BASEBOARD_FAB2_LIB.BASEBOARD_FAB2(SCH_1):PAGE146
 U25W4  D22 GPIOAC2_ESPID2_LAD2 AST2520A1-GP-GP_ASIC2-GB1-AST2A   I105 @BASEBOARD_FAB2_LIB.BASEBOARD_FAB2(SCH_1):PAGE146

LPC_LAD3_IO3 @BASEBOARD_FAB2_LIB.BASEBOARD_FAB2(SCH_1):LPC_LAD3_IO3
  U7C1   Y1 GPP_A4_LAD3_ESPI_IO3 LBG_CORE_QAT_EXT_D_BGA1-IC,H91A   I115 @BASEBOARD_FAB2_LIB.BASEBOARD_FAB2(SCH_1):PAGE119
R25W68    1      A RES_0402-33.2,1%,1/16W,CHIP,G2A    I84 @BASEBOARD_FAB2_LIB.BASEBOARD_FAB2(SCH_1):PAGE146

LPC_LAD3_IO3_R @BASEBOARD_FAB2_LIB.BASEBOARD_FAB2(SCH_1):LPC_LAD3_IO3_R
R25W68    2      B RES_0402-33.2,1%,1/16W,CHIP,G2A    I84 @BASEBOARD_FAB2_LIB.BASEBOARD_FAB2(SCH_1):PAGE146
 U25W4  E22 GPIOAC3_ESPID3_LAD3 AST2520A1-GP-GP_ASIC2-GB1-AST2A   I105 @BASEBOARD_FAB2_LIB.BASEBOARD_FAB2(SCH_1):PAGE146

LPC_LFRAME_N_CS0_N @BASEBOARD_FAB2_LIB.BASEBOARD_FAB2(SCH_1):LPC_LFRAME_N_CS0_N
  U7C1   P4 GPP_A5_LFRAME_N_ESPI_CS0_N LBG_CORE_QAT_EXT_D_BGA1-IC,H91A   I115 @BASEBOARD_FAB2_LIB.BASEBOARD_FAB2(SCH_1):PAGE119
R25W72    1      A RES_0402-33.2,1%,1/16W,CHIP,G2A    I71 @BASEBOARD_FAB2_LIB.BASEBOARD_FAB2(SCH_1):PAGE146

LPC_LFRAME_N_CS0_R_N @BASEBOARD_FAB2_LIB.BASEBOARD_FAB2(SCH_1):LPC_LFRAME_N_CS0_R_N
R25W72    2      B RES_0402-33.2,1%,1/16W,CHIP,G2A    I71 @BASEBOARD_FAB2_LIB.BASEBOARD_FAB2(SCH_1):PAGE146
 U25W4  F21 GPIOAC5_ESPICS#_LFRAME# AST2520A1-GP-GP_ASIC2-GB1-AST2A   I105 @BASEBOARD_FAB2_LIB.BASEBOARD_FAB2(SCH_1):PAGE146

M_ABC_RST_N @BASEBOARD_FAB2_LIB.BASEBOARD_FAB2(SCH_1):M_ABC_RST_N
  U5D1  U64 DDR012_RESET_N SKX_EXT_B_BGA1-IC,TBD   I259 @BASEBOARD_FAB2_LIB.BASEBOARD_FAB2(SCH_1):PAGE21
  J4G1   58 RESET_N SCONN288_H44441004_PIP-SCONN,HA     I1 @BASEBOARD_FAB2_LIB.BASEBOARD_FAB2(SCH_1):PAGE43
  J6T1   58 RESET_N SCONN288_H44441003_PIP-SCONN,HA    I13 @BASEBOARD_FAB2_LIB.BASEBOARD_FAB2(SCH_1):PAGE44
  J4G2   58 RESET_N SCONN288_H44441004_PIP-SCONN,HA   I111 @BASEBOARD_FAB2_LIB.BASEBOARD_FAB2(SCH_1):PAGE45
  J6U1   58 RESET_N SCONN288_H44441003_PIP-SCONN,HA    I14 @BASEBOARD_FAB2_LIB.BASEBOARD_FAB2(SCH_1):PAGE46
  J4G3   58 RESET_N SCONN288_H44441004_PIP-SCONN,HA   I111 @BASEBOARD_FAB2_LIB.BASEBOARD_FAB2(SCH_1):PAGE47
  J6U2   58 RESET_N SCONN288_H44441003_PIP-SCONN,HA   I111 @BASEBOARD_FAB2_LIB.BASEBOARD_FAB2(SCH_1):PAGE48

M_A_ACT_N @BASEBOARD_FAB2_LIB.BASEBOARD_FAB2(SCH_1):M_A_ACT_N
  U5D1  J60 DDR0_ACT_N SKX_EXT_B_BGA1-IC,TBD   I172 @BASEBOARD_FAB2_LIB.BASEBOARD_FAB2(SCH_1):PAGE23
  J4G1   62  ACT_N SCONN288_H44441004_PIP-SCONN,HA     I1 @BASEBOARD_FAB2_LIB.BASEBOARD_FAB2(SCH_1):PAGE43
  J6T1   62  ACT_N SCONN288_H44441003_PIP-SCONN,HA    I13 @BASEBOARD_FAB2_LIB.BASEBOARD_FAB2(SCH_1):PAGE44

M_A_ALERT_N @BASEBOARD_FAB2_LIB.BASEBOARD_FAB2(SCH_1):M_A_ALERT_N
  U5D1  B61 DDR0_ALERT_N SKX_EXT_B_BGA1-IC,TBD   I172 @BASEBOARD_FAB2_LIB.BASEBOARD_FAB2(SCH_1):PAGE23
  J4G1  208 ALERT_N SCONN288_H44441004_PIP-SCONN,HA     I1 @BASEBOARD_FAB2_LIB.BASEBOARD_FAB2(SCH_1):PAGE43
  J6T1  208 ALERT_N SCONN288_H44441003_PIP-SCONN,HA    I13 @BASEBOARD_FAB2_LIB.BASEBOARD_FAB2(SCH_1):PAGE44

M_A_BA<0> @BASEBOARD_FAB2_LIB.BASEBOARD_FAB2(SCH_1):M_A_BA(0)
  U5D1  C52 DDR0_BA<0> SKX_EXT_B_BGA1-IC,TBD   I172 @BASEBOARD_FAB2_LIB.BASEBOARD_FAB2(SCH_1):PAGE23
  J4G1   81  BA<0> SCONN288_H44441004_PIP-SCONN,HA     I1 @BASEBOARD_FAB2_LIB.BASEBOARD_FAB2(SCH_1):PAGE43
  J6T1   81  BA<0> SCONN288_H44441003_PIP-SCONN,HA    I13 @BASEBOARD_FAB2_LIB.BASEBOARD_FAB2(SCH_1):PAGE44

M_A_BA<1> @BASEBOARD_FAB2_LIB.BASEBOARD_FAB2(SCH_1):M_A_BA(1)
  U5D1  G54 DDR0_BA<1> SKX_EXT_B_BGA1-IC,TBD   I172 @BASEBOARD_FAB2_LIB.BASEBOARD_FAB2(SCH_1):PAGE23
  J4G1  224  BA<1> SCONN288_H44441004_PIP-SCONN,HA     I1 @BASEBOARD_FAB2_LIB.BASEBOARD_FAB2(SCH_1):PAGE43
  J6T1  224  BA<1> SCONN288_H44441003_PIP-SCONN,HA    I13 @BASEBOARD_FAB2_LIB.BASEBOARD_FAB2(SCH_1):PAGE44

M_A_BG<0> @BASEBOARD_FAB2_LIB.BASEBOARD_FAB2(SCH_1):M_A_BG(0)
  U5D1  D61 DDR0_BG<0> SKX_EXT_B_BGA1-IC,TBD   I172 @BASEBOARD_FAB2_LIB.BASEBOARD_FAB2(SCH_1):PAGE23
  J4G1   63  BG<0> SCONN288_H44441004_PIP-SCONN,HA     I1 @BASEBOARD_FAB2_LIB.BASEBOARD_FAB2(SCH_1):PAGE43
  J6T1   63  BG<0> SCONN288_H44441003_PIP-SCONN,HA    I13 @BASEBOARD_FAB2_LIB.BASEBOARD_FAB2(SCH_1):PAGE44

M_A_BG<1> @BASEBOARD_FAB2_LIB.BASEBOARD_FAB2(SCH_1):M_A_BG(1)
  U5D1  F63 DDR0_BG<1> SKX_EXT_B_BGA1-IC,TBD   I172 @BASEBOARD_FAB2_LIB.BASEBOARD_FAB2(SCH_1):PAGE23
  J4G1  207  BG<1> SCONN288_H44441004_PIP-SCONN,HA     I1 @BASEBOARD_FAB2_LIB.BASEBOARD_FAB2(SCH_1):PAGE43
  J6T1  207  BG<1> SCONN288_H44441003_PIP-SCONN,HA    I13 @BASEBOARD_FAB2_LIB.BASEBOARD_FAB2(SCH_1):PAGE44

M_A_C<2> @BASEBOARD_FAB2_LIB.BASEBOARD_FAB2(SCH_1):M_A_C(2)
  U5D1  G46 DDR0_CID<2> SKX_EXT_B_BGA1-IC,TBD   I172 @BASEBOARD_FAB2_LIB.BASEBOARD_FAB2(SCH_1):PAGE23
  J4G1  235   C<2> SCONN288_H44441004_PIP-SCONN,HA     I1 @BASEBOARD_FAB2_LIB.BASEBOARD_FAB2(SCH_1):PAGE43
  J6T1  235   C<2> SCONN288_H44441003_PIP-SCONN,HA    I13 @BASEBOARD_FAB2_LIB.BASEBOARD_FAB2(SCH_1):PAGE44

M_A_CKE<0> @BASEBOARD_FAB2_LIB.BASEBOARD_FAB2(SCH_1):M_A_CKE(0)
  U5D1  C62 DDR0_CKE<0> SKX_EXT_B_BGA1-IC,TBD   I172 @BASEBOARD_FAB2_LIB.BASEBOARD_FAB2(SCH_1):PAGE23
  J4G1   60 CKE<0> SCONN288_H44441004_PIP-SCONN,HA     I1 @BASEBOARD_FAB2_LIB.BASEBOARD_FAB2(SCH_1):PAGE43

M_A_CKE<1> @BASEBOARD_FAB2_LIB.BASEBOARD_FAB2(SCH_1):M_A_CKE(1)
  U5D1  C64 DDR0_CKE<1> SKX_EXT_B_BGA1-IC,TBD   I172 @BASEBOARD_FAB2_LIB.BASEBOARD_FAB2(SCH_1):PAGE23
  J4G1  203 CKE<1> SCONN288_H44441004_PIP-SCONN,HA     I1 @BASEBOARD_FAB2_LIB.BASEBOARD_FAB2(SCH_1):PAGE43

M_A_CKE<2> @BASEBOARD_FAB2_LIB.BASEBOARD_FAB2(SCH_1):M_A_CKE(2)
  U5D1  B63 DDR0_CKE<2> SKX_EXT_B_BGA1-IC,TBD   I172 @BASEBOARD_FAB2_LIB.BASEBOARD_FAB2(SCH_1):PAGE23
  J6T1   60 CKE<0> SCONN288_H44441003_PIP-SCONN,HA    I13 @BASEBOARD_FAB2_LIB.BASEBOARD_FAB2(SCH_1):PAGE44

M_A_CKE<3> @BASEBOARD_FAB2_LIB.BASEBOARD_FAB2(SCH_1):M_A_CKE(3)
  U5D1  D63 DDR0_CKE<3> SKX_EXT_B_BGA1-IC,TBD   I172 @BASEBOARD_FAB2_LIB.BASEBOARD_FAB2(SCH_1):PAGE23
  J6T1  203 CKE<1> SCONN288_H44441003_PIP-SCONN,HA    I13 @BASEBOARD_FAB2_LIB.BASEBOARD_FAB2(SCH_1):PAGE44

M_A_CLK_DN<0> @BASEBOARD_FAB2_LIB.BASEBOARD_FAB2(SCH_1):M_A_CLK_DN(0)
  U5D1  F55 DDR0_CLK_DN<0> SKX_EXT_B_BGA1-IC,TBD   I172 @BASEBOARD_FAB2_LIB.BASEBOARD_FAB2(SCH_1):PAGE23
  J4G1   75   CK0N SCONN288_H44441004_PIP-SCONN,HA     I1 @BASEBOARD_FAB2_LIB.BASEBOARD_FAB2(SCH_1):PAGE43

M_A_CLK_DN<1> @BASEBOARD_FAB2_LIB.BASEBOARD_FAB2(SCH_1):M_A_CLK_DN(1)
  U5D1  C54 DDR0_CLK_DN<1> SKX_EXT_B_BGA1-IC,TBD   I172 @BASEBOARD_FAB2_LIB.BASEBOARD_FAB2(SCH_1):PAGE23
  J4G1  219   CK1N SCONN288_H44441004_PIP-SCONN,HA     I1 @BASEBOARD_FAB2_LIB.BASEBOARD_FAB2(SCH_1):PAGE43

M_A_CLK_DN<2> @BASEBOARD_FAB2_LIB.BASEBOARD_FAB2(SCH_1):M_A_CLK_DN(2)
  U5D1  J56 DDR0_CLK_DN<2> SKX_EXT_B_BGA1-IC,TBD   I172 @BASEBOARD_FAB2_LIB.BASEBOARD_FAB2(SCH_1):PAGE23
  J6T1   75   CK0N SCONN288_H44441003_PIP-SCONN,HA    I13 @BASEBOARD_FAB2_LIB.BASEBOARD_FAB2(SCH_1):PAGE44

M_A_CLK_DN<3> @BASEBOARD_FAB2_LIB.BASEBOARD_FAB2(SCH_1):M_A_CLK_DN(3)
  U5D1  C56 DDR0_CLK_DN<3> SKX_EXT_B_BGA1-IC,TBD   I172 @BASEBOARD_FAB2_LIB.BASEBOARD_FAB2(SCH_1):PAGE23
  J6T1  219   CK1N SCONN288_H44441003_PIP-SCONN,HA    I13 @BASEBOARD_FAB2_LIB.BASEBOARD_FAB2(SCH_1):PAGE44

M_A_CLK_DP<0> @BASEBOARD_FAB2_LIB.BASEBOARD_FAB2(SCH_1):M_A_CLK_DP(0)
  U5D1  D55 DDR0_CLK_DP<0> SKX_EXT_B_BGA1-IC,TBD   I172 @BASEBOARD_FAB2_LIB.BASEBOARD_FAB2(SCH_1):PAGE23
  J4G1   74   CK0P SCONN288_H44441004_PIP-SCONN,HA     I1 @BASEBOARD_FAB2_LIB.BASEBOARD_FAB2(SCH_1):PAGE43

M_A_CLK_DP<1> @BASEBOARD_FAB2_LIB.BASEBOARD_FAB2(SCH_1):M_A_CLK_DP(1)
  U5D1  B55 DDR0_CLK_DP<1> SKX_EXT_B_BGA1-IC,TBD   I172 @BASEBOARD_FAB2_LIB.BASEBOARD_FAB2(SCH_1):PAGE23
  J4G1  218   CK1P SCONN288_H44441004_PIP-SCONN,HA     I1 @BASEBOARD_FAB2_LIB.BASEBOARD_FAB2(SCH_1):PAGE43

M_A_CLK_DP<2> @BASEBOARD_FAB2_LIB.BASEBOARD_FAB2(SCH_1):M_A_CLK_DP(2)
  U5D1  G56 DDR0_CLK_DP<2> SKX_EXT_B_BGA1-IC,TBD   I172 @BASEBOARD_FAB2_LIB.BASEBOARD_FAB2(SCH_1):PAGE23
  J6T1   74   CK0P SCONN288_H44441003_PIP-SCONN,HA    I13 @BASEBOARD_FAB2_LIB.BASEBOARD_FAB2(SCH_1):PAGE44

M_A_CLK_DP<3> @BASEBOARD_FAB2_LIB.BASEBOARD_FAB2(SCH_1):M_A_CLK_DP(3)
  U5D1  B57 DDR0_CLK_DP<3> SKX_EXT_B_BGA1-IC,TBD   I172 @BASEBOARD_FAB2_LIB.BASEBOARD_FAB2(SCH_1):PAGE23
  J6T1  218   CK1P SCONN288_H44441003_PIP-SCONN,HA    I13 @BASEBOARD_FAB2_LIB.BASEBOARD_FAB2(SCH_1):PAGE44

M_A_CPU_VREF @BASEBOARD_FAB2_LIB.BASEBOARD_FAB2(SCH_1):M_A_CPU_VREF
  U5D1 AJ64 DDR0_CAVREF SKX_EXT_B_BGA1-IC,TBD   I259 @BASEBOARD_FAB2_LIB.BASEBOARD_FAB2(SCH_1):PAGE21
  R4F3    1      A RES_0402-2,1.0%,1/16W,CHIP,G21A     I5 @BASEBOARD_FAB2_LIB.BASEBOARD_FAB2(SCH_1):PAGE98
  C4F9    1      A CAP_A_0402V-0.01UF,25V,10%,X7RA     I7 @BASEBOARD_FAB2_LIB.BASEBOARD_FAB2(SCH_1):PAGE98

M_A_CS_N<0> @BASEBOARD_FAB2_LIB.BASEBOARD_FAB2(SCH_1):M_A_CS_N(0)
  U5D1  G52 DDR0_CS_N<0> SKX_EXT_B_BGA1-IC,TBD   I172 @BASEBOARD_FAB2_LIB.BASEBOARD_FAB2(SCH_1):PAGE23
  J4G1   84   S0_N SCONN288_H44441004_PIP-SCONN,HA     I1 @BASEBOARD_FAB2_LIB.BASEBOARD_FAB2(SCH_1):PAGE43

M_A_CS_N<1> @BASEBOARD_FAB2_LIB.BASEBOARD_FAB2(SCH_1):M_A_CS_N(1)
  U5D1  F49 DDR0_CS_N<1> SKX_EXT_B_BGA1-IC,TBD   I172 @BASEBOARD_FAB2_LIB.BASEBOARD_FAB2(SCH_1):PAGE23
  J4G1   89   S1_N SCONN288_H44441004_PIP-SCONN,HA     I1 @BASEBOARD_FAB2_LIB.BASEBOARD_FAB2(SCH_1):PAGE43

M_A_CS_N<2> @BASEBOARD_FAB2_LIB.BASEBOARD_FAB2(SCH_1):M_A_CS_N(2)
  U5D1  D47 DDR0_CS_N<2> SKX_EXT_B_BGA1-IC,TBD   I172 @BASEBOARD_FAB2_LIB.BASEBOARD_FAB2(SCH_1):PAGE23
  J4G1   93 S2_N_C<0> SCONN288_H44441004_PIP-SCONN,HA     I1 @BASEBOARD_FAB2_LIB.BASEBOARD_FAB2(SCH_1):PAGE43

M_A_CS_N<3> @BASEBOARD_FAB2_LIB.BASEBOARD_FAB2(SCH_1):M_A_CS_N(3)
  U5D1  F47 DDR0_CS_N<3> SKX_EXT_B_BGA1-IC,TBD   I172 @BASEBOARD_FAB2_LIB.BASEBOARD_FAB2(SCH_1):PAGE23
  J4G1  237 S3_N_C<1> SCONN288_H44441004_PIP-SCONN,HA     I1 @BASEBOARD_FAB2_LIB.BASEBOARD_FAB2(SCH_1):PAGE43

M_A_CS_N<4> @BASEBOARD_FAB2_LIB.BASEBOARD_FAB2(SCH_1):M_A_CS_N(4)
  U5D1  B51 DDR0_CS_N<4> SKX_EXT_B_BGA1-IC,TBD   I172 @BASEBOARD_FAB2_LIB.BASEBOARD_FAB2(SCH_1):PAGE23
  J6T1   84   S0_N SCONN288_H44441003_PIP-SCONN,HA    I13 @BASEBOARD_FAB2_LIB.BASEBOARD_FAB2(SCH_1):PAGE44

M_A_CS_N<5> @BASEBOARD_FAB2_LIB.BASEBOARD_FAB2(SCH_1):M_A_CS_N(5)
  U5D1  D49 DDR0_CS_N<5> SKX_EXT_B_BGA1-IC,TBD   I172 @BASEBOARD_FAB2_LIB.BASEBOARD_FAB2(SCH_1):PAGE23
  J6T1   89   S1_N SCONN288_H44441003_PIP-SCONN,HA    I13 @BASEBOARD_FAB2_LIB.BASEBOARD_FAB2(SCH_1):PAGE44

M_A_CS_N<6> @BASEBOARD_FAB2_LIB.BASEBOARD_FAB2(SCH_1):M_A_CS_N(6)
  U5D1  F45 DDR0_CS_N<6> SKX_EXT_B_BGA1-IC,TBD   I172 @BASEBOARD_FAB2_LIB.BASEBOARD_FAB2(SCH_1):PAGE23
  J6T1   93 S2_N_C<0> SCONN288_H44441003_PIP-SCONN,HA    I13 @BASEBOARD_FAB2_LIB.BASEBOARD_FAB2(SCH_1):PAGE44

M_A_CS_N<7> @BASEBOARD_FAB2_LIB.BASEBOARD_FAB2(SCH_1):M_A_CS_N(7)
  U5D1  K45 DDR0_CS_N<7> SKX_EXT_B_BGA1-IC,TBD   I172 @BASEBOARD_FAB2_LIB.BASEBOARD_FAB2(SCH_1):PAGE23
  J6T1  237 S3_N_C<1> SCONN288_H44441003_PIP-SCONN,HA    I13 @BASEBOARD_FAB2_LIB.BASEBOARD_FAB2(SCH_1):PAGE44

M_A_DQ<0> @BASEBOARD_FAB2_LIB.BASEBOARD_FAB2(SCH_1):M_A_DQ(0)
  U5D1 AN86 DDR0_DQ<0> SKX_EXT_B_BGA1-IC,TBD   I172 @BASEBOARD_FAB2_LIB.BASEBOARD_FAB2(SCH_1):PAGE23
  J4G1  150  DQ<1> SCONN288_H44441004_PIP-SCONN,HA     I1 @BASEBOARD_FAB2_LIB.BASEBOARD_FAB2(SCH_1):PAGE43
  J6T1    5  DQ<0> SCONN288_H44441003_PIP-SCONN,HA    I13 @BASEBOARD_FAB2_LIB.BASEBOARD_FAB2(SCH_1):PAGE44

M_A_DQ<10> @BASEBOARD_FAB2_LIB.BASEBOARD_FAB2(SCH_1):M_A_DQ(10)
  U5D1  L86 DDR0_DQ<10> SKX_EXT_B_BGA1-IC,TBD   I172 @BASEBOARD_FAB2_LIB.BASEBOARD_FAB2(SCH_1):PAGE23
  J4G1  168 DQ<11> SCONN288_H44441004_PIP-SCONN,HA     I1 @BASEBOARD_FAB2_LIB.BASEBOARD_FAB2(SCH_1):PAGE43
  J6T1   23 DQ<10> SCONN288_H44441003_PIP-SCONN,HA    I13 @BASEBOARD_FAB2_LIB.BASEBOARD_FAB2(SCH_1):PAGE44

M_A_DQ<11> @BASEBOARD_FAB2_LIB.BASEBOARD_FAB2(SCH_1):M_A_DQ(11)
  U5D1  L84 DDR0_DQ<11> SKX_EXT_B_BGA1-IC,TBD   I172 @BASEBOARD_FAB2_LIB.BASEBOARD_FAB2(SCH_1):PAGE23
  J4G1   23 DQ<10> SCONN288_H44441004_PIP-SCONN,HA     I1 @BASEBOARD_FAB2_LIB.BASEBOARD_FAB2(SCH_1):PAGE43
  J6T1  168 DQ<11> SCONN288_H44441003_PIP-SCONN,HA    I13 @BASEBOARD_FAB2_LIB.BASEBOARD_FAB2(SCH_1):PAGE44

M_A_DQ<12> @BASEBOARD_FAB2_LIB.BASEBOARD_FAB2(SCH_1):M_A_DQ(12)
  U5D1 AA86 DDR0_DQ<12> SKX_EXT_B_BGA1-IC,TBD   I172 @BASEBOARD_FAB2_LIB.BASEBOARD_FAB2(SCH_1):PAGE23
  J4G1  159 DQ<13> SCONN288_H44441004_PIP-SCONN,HA     I1 @BASEBOARD_FAB2_LIB.BASEBOARD_FAB2(SCH_1):PAGE43
  J6T1   14 DQ<12> SCONN288_H44441003_PIP-SCONN,HA    I13 @BASEBOARD_FAB2_LIB.BASEBOARD_FAB2(SCH_1):PAGE44

M_A_DQ<13> @BASEBOARD_FAB2_LIB.BASEBOARD_FAB2(SCH_1):M_A_DQ(13)
  U5D1 AA84 DDR0_DQ<13> SKX_EXT_B_BGA1-IC,TBD   I172 @BASEBOARD_FAB2_LIB.BASEBOARD_FAB2(SCH_1):PAGE23
  J4G1   14 DQ<12> SCONN288_H44441004_PIP-SCONN,HA     I1 @BASEBOARD_FAB2_LIB.BASEBOARD_FAB2(SCH_1):PAGE43
  J6T1  159 DQ<13> SCONN288_H44441003_PIP-SCONN,HA    I13 @BASEBOARD_FAB2_LIB.BASEBOARD_FAB2(SCH_1):PAGE44

M_A_DQ<14> @BASEBOARD_FAB2_LIB.BASEBOARD_FAB2(SCH_1):M_A_DQ(14)
  U5D1  N86 DDR0_DQ<14> SKX_EXT_B_BGA1-IC,TBD   I172 @BASEBOARD_FAB2_LIB.BASEBOARD_FAB2(SCH_1):PAGE23
  J4G1  166 DQ<15> SCONN288_H44441004_PIP-SCONN,HA     I1 @BASEBOARD_FAB2_LIB.BASEBOARD_FAB2(SCH_1):PAGE43
  J6T1   21 DQ<14> SCONN288_H44441003_PIP-SCONN,HA    I13 @BASEBOARD_FAB2_LIB.BASEBOARD_FAB2(SCH_1):PAGE44

M_A_DQ<15> @BASEBOARD_FAB2_LIB.BASEBOARD_FAB2(SCH_1):M_A_DQ(15)
  U5D1  N84 DDR0_DQ<15> SKX_EXT_B_BGA1-IC,TBD   I172 @BASEBOARD_FAB2_LIB.BASEBOARD_FAB2(SCH_1):PAGE23
  J4G1   21 DQ<14> SCONN288_H44441004_PIP-SCONN,HA     I1 @BASEBOARD_FAB2_LIB.BASEBOARD_FAB2(SCH_1):PAGE43
  J6T1  166 DQ<15> SCONN288_H44441003_PIP-SCONN,HA    I13 @BASEBOARD_FAB2_LIB.BASEBOARD_FAB2(SCH_1):PAGE44

M_A_DQ<16> @BASEBOARD_FAB2_LIB.BASEBOARD_FAB2(SCH_1):M_A_DQ(16)
  U5D1  V81 DDR0_DQ<16> SKX_EXT_B_BGA1-IC,TBD   I172 @BASEBOARD_FAB2_LIB.BASEBOARD_FAB2(SCH_1):PAGE23
  J4G1  172 DQ<17> SCONN288_H44441004_PIP-SCONN,HA     I1 @BASEBOARD_FAB2_LIB.BASEBOARD_FAB2(SCH_1):PAGE43
  J6T1   27 DQ<16> SCONN288_H44441003_PIP-SCONN,HA    I13 @BASEBOARD_FAB2_LIB.BASEBOARD_FAB2(SCH_1):PAGE44

M_A_DQ<17> @BASEBOARD_FAB2_LIB.BASEBOARD_FAB2(SCH_1):M_A_DQ(17)
  U5D1  T79 DDR0_DQ<17> SKX_EXT_B_BGA1-IC,TBD   I172 @BASEBOARD_FAB2_LIB.BASEBOARD_FAB2(SCH_1):PAGE23
  J4G1   27 DQ<16> SCONN288_H44441004_PIP-SCONN,HA     I1 @BASEBOARD_FAB2_LIB.BASEBOARD_FAB2(SCH_1):PAGE43
  J6T1  172 DQ<17> SCONN288_H44441003_PIP-SCONN,HA    I13 @BASEBOARD_FAB2_LIB.BASEBOARD_FAB2(SCH_1):PAGE44

M_A_DQ<18> @BASEBOARD_FAB2_LIB.BASEBOARD_FAB2(SCH_1):M_A_DQ(18)
  U5D1  N82 DDR0_DQ<18> SKX_EXT_B_BGA1-IC,TBD   I172 @BASEBOARD_FAB2_LIB.BASEBOARD_FAB2(SCH_1):PAGE23
  J4G1  179 DQ<19> SCONN288_H44441004_PIP-SCONN,HA     I1 @BASEBOARD_FAB2_LIB.BASEBOARD_FAB2(SCH_1):PAGE43
  J6T1   34 DQ<18> SCONN288_H44441003_PIP-SCONN,HA    I13 @BASEBOARD_FAB2_LIB.BASEBOARD_FAB2(SCH_1):PAGE44

M_A_DQ<19> @BASEBOARD_FAB2_LIB.BASEBOARD_FAB2(SCH_1):M_A_DQ(19)
  U5D1  M81 DDR0_DQ<19> SKX_EXT_B_BGA1-IC,TBD   I172 @BASEBOARD_FAB2_LIB.BASEBOARD_FAB2(SCH_1):PAGE23
  J4G1   34 DQ<18> SCONN288_H44441004_PIP-SCONN,HA     I1 @BASEBOARD_FAB2_LIB.BASEBOARD_FAB2(SCH_1):PAGE43
  J6T1  179 DQ<19> SCONN288_H44441003_PIP-SCONN,HA    I13 @BASEBOARD_FAB2_LIB.BASEBOARD_FAB2(SCH_1):PAGE44

M_A_DQ<1> @BASEBOARD_FAB2_LIB.BASEBOARD_FAB2(SCH_1):M_A_DQ(1)
  U5D1 AN84 DDR0_DQ<1> SKX_EXT_B_BGA1-IC,TBD   I172 @BASEBOARD_FAB2_LIB.BASEBOARD_FAB2(SCH_1):PAGE23
  J4G1    5  DQ<0> SCONN288_H44441004_PIP-SCONN,HA     I1 @BASEBOARD_FAB2_LIB.BASEBOARD_FAB2(SCH_1):PAGE43
  J6T1  150  DQ<1> SCONN288_H44441003_PIP-SCONN,HA    I13 @BASEBOARD_FAB2_LIB.BASEBOARD_FAB2(SCH_1):PAGE44

M_A_DQ<20> @BASEBOARD_FAB2_LIB.BASEBOARD_FAB2(SCH_1):M_A_DQ(20)
  U5D1  W80 DDR0_DQ<20> SKX_EXT_B_BGA1-IC,TBD   I172 @BASEBOARD_FAB2_LIB.BASEBOARD_FAB2(SCH_1):PAGE23
  J4G1  170 DQ<21> SCONN288_H44441004_PIP-SCONN,HA     I1 @BASEBOARD_FAB2_LIB.BASEBOARD_FAB2(SCH_1):PAGE43
  J6T1   25 DQ<20> SCONN288_H44441003_PIP-SCONN,HA    I13 @BASEBOARD_FAB2_LIB.BASEBOARD_FAB2(SCH_1):PAGE44

M_A_DQ<21> @BASEBOARD_FAB2_LIB.BASEBOARD_FAB2(SCH_1):M_A_DQ(21)
  U5D1  V79 DDR0_DQ<21> SKX_EXT_B_BGA1-IC,TBD   I172 @BASEBOARD_FAB2_LIB.BASEBOARD_FAB2(SCH_1):PAGE23
  J4G1   25 DQ<20> SCONN288_H44441004_PIP-SCONN,HA     I1 @BASEBOARD_FAB2_LIB.BASEBOARD_FAB2(SCH_1):PAGE43
  J6T1  170 DQ<21> SCONN288_H44441003_PIP-SCONN,HA    I13 @BASEBOARD_FAB2_LIB.BASEBOARD_FAB2(SCH_1):PAGE44

M_A_DQ<22> @BASEBOARD_FAB2_LIB.BASEBOARD_FAB2(SCH_1):M_A_DQ(22)
  U5D1  R82 DDR0_DQ<22> SKX_EXT_B_BGA1-IC,TBD   I172 @BASEBOARD_FAB2_LIB.BASEBOARD_FAB2(SCH_1):PAGE23
  J4G1  177 DQ<23> SCONN288_H44441004_PIP-SCONN,HA     I1 @BASEBOARD_FAB2_LIB.BASEBOARD_FAB2(SCH_1):PAGE43
  J6T1   32 DQ<22> SCONN288_H44441003_PIP-SCONN,HA    I13 @BASEBOARD_FAB2_LIB.BASEBOARD_FAB2(SCH_1):PAGE44

M_A_DQ<23> @BASEBOARD_FAB2_LIB.BASEBOARD_FAB2(SCH_1):M_A_DQ(23)
  U5D1  N80 DDR0_DQ<23> SKX_EXT_B_BGA1-IC,TBD   I172 @BASEBOARD_FAB2_LIB.BASEBOARD_FAB2(SCH_1):PAGE23
  J4G1   32 DQ<22> SCONN288_H44441004_PIP-SCONN,HA     I1 @BASEBOARD_FAB2_LIB.BASEBOARD_FAB2(SCH_1):PAGE43
  J6T1  177 DQ<23> SCONN288_H44441003_PIP-SCONN,HA    I13 @BASEBOARD_FAB2_LIB.BASEBOARD_FAB2(SCH_1):PAGE44

M_A_DQ<24> @BASEBOARD_FAB2_LIB.BASEBOARD_FAB2(SCH_1):M_A_DQ(24)
  U5D1  L76 DDR0_DQ<24> SKX_EXT_B_BGA1-IC,TBD   I172 @BASEBOARD_FAB2_LIB.BASEBOARD_FAB2(SCH_1):PAGE23
  J4G1  183 DQ<25> SCONN288_H44441004_PIP-SCONN,HA     I1 @BASEBOARD_FAB2_LIB.BASEBOARD_FAB2(SCH_1):PAGE43
  J6T1   38 DQ<24> SCONN288_H44441003_PIP-SCONN,HA    I13 @BASEBOARD_FAB2_LIB.BASEBOARD_FAB2(SCH_1):PAGE44

M_A_DQ<25> @BASEBOARD_FAB2_LIB.BASEBOARD_FAB2(SCH_1):M_A_DQ(25)
  U5D1  R76 DDR0_DQ<25> SKX_EXT_B_BGA1-IC,TBD   I172 @BASEBOARD_FAB2_LIB.BASEBOARD_FAB2(SCH_1):PAGE23
  J4G1   38 DQ<24> SCONN288_H44441004_PIP-SCONN,HA     I1 @BASEBOARD_FAB2_LIB.BASEBOARD_FAB2(SCH_1):PAGE43
  J6T1  183 DQ<25> SCONN288_H44441003_PIP-SCONN,HA    I13 @BASEBOARD_FAB2_LIB.BASEBOARD_FAB2(SCH_1):PAGE44

M_A_DQ<26> @BASEBOARD_FAB2_LIB.BASEBOARD_FAB2(SCH_1):M_A_DQ(26)
  U5D1  M73 DDR0_DQ<26> SKX_EXT_B_BGA1-IC,TBD   I172 @BASEBOARD_FAB2_LIB.BASEBOARD_FAB2(SCH_1):PAGE23
  J4G1  190 DQ<27> SCONN288_H44441004_PIP-SCONN,HA     I1 @BASEBOARD_FAB2_LIB.BASEBOARD_FAB2(SCH_1):PAGE43
  J6T1   45 DQ<26> SCONN288_H44441003_PIP-SCONN,HA    I13 @BASEBOARD_FAB2_LIB.BASEBOARD_FAB2(SCH_1):PAGE44

M_A_DQ<27> @BASEBOARD_FAB2_LIB.BASEBOARD_FAB2(SCH_1):M_A_DQ(27)
  U5D1  P73 DDR0_DQ<27> SKX_EXT_B_BGA1-IC,TBD   I172 @BASEBOARD_FAB2_LIB.BASEBOARD_FAB2(SCH_1):PAGE23
  J4G1   45 DQ<26> SCONN288_H44441004_PIP-SCONN,HA     I1 @BASEBOARD_FAB2_LIB.BASEBOARD_FAB2(SCH_1):PAGE43
  J6T1  190 DQ<27> SCONN288_H44441003_PIP-SCONN,HA    I13 @BASEBOARD_FAB2_LIB.BASEBOARD_FAB2(SCH_1):PAGE44

M_A_DQ<28> @BASEBOARD_FAB2_LIB.BASEBOARD_FAB2(SCH_1):M_A_DQ(28)
  U5D1  M77 DDR0_DQ<28> SKX_EXT_B_BGA1-IC,TBD   I172 @BASEBOARD_FAB2_LIB.BASEBOARD_FAB2(SCH_1):PAGE23
  J4G1  181 DQ<29> SCONN288_H44441004_PIP-SCONN,HA     I1 @BASEBOARD_FAB2_LIB.BASEBOARD_FAB2(SCH_1):PAGE43
  J6T1   36 DQ<28> SCONN288_H44441003_PIP-SCONN,HA    I13 @BASEBOARD_FAB2_LIB.BASEBOARD_FAB2(SCH_1):PAGE44

M_A_DQ<29> @BASEBOARD_FAB2_LIB.BASEBOARD_FAB2(SCH_1):M_A_DQ(29)
  U5D1  P77 DDR0_DQ<29> SKX_EXT_B_BGA1-IC,TBD   I172 @BASEBOARD_FAB2_LIB.BASEBOARD_FAB2(SCH_1):PAGE23
  J4G1   36 DQ<28> SCONN288_H44441004_PIP-SCONN,HA     I1 @BASEBOARD_FAB2_LIB.BASEBOARD_FAB2(SCH_1):PAGE43
  J6T1  181 DQ<29> SCONN288_H44441003_PIP-SCONN,HA    I13 @BASEBOARD_FAB2_LIB.BASEBOARD_FAB2(SCH_1):PAGE44

M_A_DQ<2> @BASEBOARD_FAB2_LIB.BASEBOARD_FAB2(SCH_1):M_A_DQ(2)
  U5D1 AE86 DDR0_DQ<2> SKX_EXT_B_BGA1-IC,TBD   I172 @BASEBOARD_FAB2_LIB.BASEBOARD_FAB2(SCH_1):PAGE23
  J4G1  157  DQ<3> SCONN288_H44441004_PIP-SCONN,HA     I1 @BASEBOARD_FAB2_LIB.BASEBOARD_FAB2(SCH_1):PAGE43
  J6T1   12  DQ<2> SCONN288_H44441003_PIP-SCONN,HA    I13 @BASEBOARD_FAB2_LIB.BASEBOARD_FAB2(SCH_1):PAGE44

M_A_DQ<30> @BASEBOARD_FAB2_LIB.BASEBOARD_FAB2(SCH_1):M_A_DQ(30)
  U5D1  L74 DDR0_DQ<30> SKX_EXT_B_BGA1-IC,TBD   I172 @BASEBOARD_FAB2_LIB.BASEBOARD_FAB2(SCH_1):PAGE23
  J4G1  188 DQ<31> SCONN288_H44441004_PIP-SCONN,HA     I1 @BASEBOARD_FAB2_LIB.BASEBOARD_FAB2(SCH_1):PAGE43
  J6T1   43 DQ<30> SCONN288_H44441003_PIP-SCONN,HA    I13 @BASEBOARD_FAB2_LIB.BASEBOARD_FAB2(SCH_1):PAGE44

M_A_DQ<31> @BASEBOARD_FAB2_LIB.BASEBOARD_FAB2(SCH_1):M_A_DQ(31)
  U5D1  R74 DDR0_DQ<31> SKX_EXT_B_BGA1-IC,TBD   I172 @BASEBOARD_FAB2_LIB.BASEBOARD_FAB2(SCH_1):PAGE23
  J4G1   43 DQ<30> SCONN288_H44441004_PIP-SCONN,HA     I1 @BASEBOARD_FAB2_LIB.BASEBOARD_FAB2(SCH_1):PAGE43
  J6T1  188 DQ<31> SCONN288_H44441003_PIP-SCONN,HA    I13 @BASEBOARD_FAB2_LIB.BASEBOARD_FAB2(SCH_1):PAGE44

M_A_DQ<32> @BASEBOARD_FAB2_LIB.BASEBOARD_FAB2(SCH_1):M_A_DQ(32)
  U5D1  C42 DDR0_DQ<32> SKX_EXT_B_BGA1-IC,TBD   I172 @BASEBOARD_FAB2_LIB.BASEBOARD_FAB2(SCH_1):PAGE23
  J4G1  242 DQ<33> SCONN288_H44441004_PIP-SCONN,HA     I1 @BASEBOARD_FAB2_LIB.BASEBOARD_FAB2(SCH_1):PAGE43
  J6T1   97 DQ<32> SCONN288_H44441003_PIP-SCONN,HA    I13 @BASEBOARD_FAB2_LIB.BASEBOARD_FAB2(SCH_1):PAGE44

M_A_DQ<33> @BASEBOARD_FAB2_LIB.BASEBOARD_FAB2(SCH_1):M_A_DQ(33)
  U5D1  B41 DDR0_DQ<33> SKX_EXT_B_BGA1-IC,TBD   I172 @BASEBOARD_FAB2_LIB.BASEBOARD_FAB2(SCH_1):PAGE23
  J4G1   97 DQ<32> SCONN288_H44441004_PIP-SCONN,HA     I1 @BASEBOARD_FAB2_LIB.BASEBOARD_FAB2(SCH_1):PAGE43
  J6T1  242 DQ<33> SCONN288_H44441003_PIP-SCONN,HA    I13 @BASEBOARD_FAB2_LIB.BASEBOARD_FAB2(SCH_1):PAGE44

M_A_DQ<34> @BASEBOARD_FAB2_LIB.BASEBOARD_FAB2(SCH_1):M_A_DQ(34)
  U5D1  C38 DDR0_DQ<34> SKX_EXT_B_BGA1-IC,TBD   I172 @BASEBOARD_FAB2_LIB.BASEBOARD_FAB2(SCH_1):PAGE23
  J4G1  249 DQ<35> SCONN288_H44441004_PIP-SCONN,HA     I1 @BASEBOARD_FAB2_LIB.BASEBOARD_FAB2(SCH_1):PAGE43
  J6T1  104 DQ<34> SCONN288_H44441003_PIP-SCONN,HA    I13 @BASEBOARD_FAB2_LIB.BASEBOARD_FAB2(SCH_1):PAGE44

M_A_DQ<35> @BASEBOARD_FAB2_LIB.BASEBOARD_FAB2(SCH_1):M_A_DQ(35)
  U5D1  E38 DDR0_DQ<35> SKX_EXT_B_BGA1-IC,TBD   I172 @BASEBOARD_FAB2_LIB.BASEBOARD_FAB2(SCH_1):PAGE23
  J4G1  104 DQ<34> SCONN288_H44441004_PIP-SCONN,HA     I1 @BASEBOARD_FAB2_LIB.BASEBOARD_FAB2(SCH_1):PAGE43
  J6T1  249 DQ<35> SCONN288_H44441003_PIP-SCONN,HA    I13 @BASEBOARD_FAB2_LIB.BASEBOARD_FAB2(SCH_1):PAGE44

M_A_DQ<36> @BASEBOARD_FAB2_LIB.BASEBOARD_FAB2(SCH_1):M_A_DQ(36)
  U5D1  E42 DDR0_DQ<36> SKX_EXT_B_BGA1-IC,TBD   I172 @BASEBOARD_FAB2_LIB.BASEBOARD_FAB2(SCH_1):PAGE23
  J4G1  240 DQ<37> SCONN288_H44441004_PIP-SCONN,HA     I1 @BASEBOARD_FAB2_LIB.BASEBOARD_FAB2(SCH_1):PAGE43
  J6T1   95 DQ<36> SCONN288_H44441003_PIP-SCONN,HA    I13 @BASEBOARD_FAB2_LIB.BASEBOARD_FAB2(SCH_1):PAGE44

M_A_DQ<37> @BASEBOARD_FAB2_LIB.BASEBOARD_FAB2(SCH_1):M_A_DQ(37)
  U5D1  F41 DDR0_DQ<37> SKX_EXT_B_BGA1-IC,TBD   I172 @BASEBOARD_FAB2_LIB.BASEBOARD_FAB2(SCH_1):PAGE23
  J4G1   95 DQ<36> SCONN288_H44441004_PIP-SCONN,HA     I1 @BASEBOARD_FAB2_LIB.BASEBOARD_FAB2(SCH_1):PAGE43
  J6T1  240 DQ<37> SCONN288_H44441003_PIP-SCONN,HA    I13 @BASEBOARD_FAB2_LIB.BASEBOARD_FAB2(SCH_1):PAGE44

M_A_DQ<38> @BASEBOARD_FAB2_LIB.BASEBOARD_FAB2(SCH_1):M_A_DQ(38)
  U5D1  B39 DDR0_DQ<38> SKX_EXT_B_BGA1-IC,TBD   I172 @BASEBOARD_FAB2_LIB.BASEBOARD_FAB2(SCH_1):PAGE23
  J4G1  247 DQ<39> SCONN288_H44441004_PIP-SCONN,HA     I1 @BASEBOARD_FAB2_LIB.BASEBOARD_FAB2(SCH_1):PAGE43
  J6T1  102 DQ<38> SCONN288_H44441003_PIP-SCONN,HA    I13 @BASEBOARD_FAB2_LIB.BASEBOARD_FAB2(SCH_1):PAGE44

M_A_DQ<39> @BASEBOARD_FAB2_LIB.BASEBOARD_FAB2(SCH_1):M_A_DQ(39)
  U5D1  F39 DDR0_DQ<39> SKX_EXT_B_BGA1-IC,TBD   I172 @BASEBOARD_FAB2_LIB.BASEBOARD_FAB2(SCH_1):PAGE23
  J4G1  102 DQ<38> SCONN288_H44441004_PIP-SCONN,HA     I1 @BASEBOARD_FAB2_LIB.BASEBOARD_FAB2(SCH_1):PAGE43
  J6T1  247 DQ<39> SCONN288_H44441003_PIP-SCONN,HA    I13 @BASEBOARD_FAB2_LIB.BASEBOARD_FAB2(SCH_1):PAGE44

M_A_DQ<3> @BASEBOARD_FAB2_LIB.BASEBOARD_FAB2(SCH_1):M_A_DQ(3)
  U5D1 AE84 DDR0_DQ<3> SKX_EXT_B_BGA1-IC,TBD   I172 @BASEBOARD_FAB2_LIB.BASEBOARD_FAB2(SCH_1):PAGE23
  J4G1   12  DQ<2> SCONN288_H44441004_PIP-SCONN,HA     I1 @BASEBOARD_FAB2_LIB.BASEBOARD_FAB2(SCH_1):PAGE43
  J6T1  157  DQ<3> SCONN288_H44441003_PIP-SCONN,HA    I13 @BASEBOARD_FAB2_LIB.BASEBOARD_FAB2(SCH_1):PAGE44

M_A_DQ<40> @BASEBOARD_FAB2_LIB.BASEBOARD_FAB2(SCH_1):M_A_DQ(40)
  U5D1  K37 DDR0_DQ<40> SKX_EXT_B_BGA1-IC,TBD   I172 @BASEBOARD_FAB2_LIB.BASEBOARD_FAB2(SCH_1):PAGE23
  J4G1  253 DQ<41> SCONN288_H44441004_PIP-SCONN,HA     I1 @BASEBOARD_FAB2_LIB.BASEBOARD_FAB2(SCH_1):PAGE43
  J6T1  108 DQ<40> SCONN288_H44441003_PIP-SCONN,HA    I13 @BASEBOARD_FAB2_LIB.BASEBOARD_FAB2(SCH_1):PAGE44

M_A_DQ<41> @BASEBOARD_FAB2_LIB.BASEBOARD_FAB2(SCH_1):M_A_DQ(41)
  U5D1  P37 DDR0_DQ<41> SKX_EXT_B_BGA1-IC,TBD   I172 @BASEBOARD_FAB2_LIB.BASEBOARD_FAB2(SCH_1):PAGE23
  J4G1  108 DQ<40> SCONN288_H44441004_PIP-SCONN,HA     I1 @BASEBOARD_FAB2_LIB.BASEBOARD_FAB2(SCH_1):PAGE43
  J6T1  253 DQ<41> SCONN288_H44441003_PIP-SCONN,HA    I13 @BASEBOARD_FAB2_LIB.BASEBOARD_FAB2(SCH_1):PAGE44

M_A_DQ<42> @BASEBOARD_FAB2_LIB.BASEBOARD_FAB2(SCH_1):M_A_DQ(42)
  U5D1  L34 DDR0_DQ<42> SKX_EXT_B_BGA1-IC,TBD   I172 @BASEBOARD_FAB2_LIB.BASEBOARD_FAB2(SCH_1):PAGE23
  J4G1  260 DQ<43> SCONN288_H44441004_PIP-SCONN,HA     I1 @BASEBOARD_FAB2_LIB.BASEBOARD_FAB2(SCH_1):PAGE43
  J6T1  115 DQ<42> SCONN288_H44441003_PIP-SCONN,HA    I13 @BASEBOARD_FAB2_LIB.BASEBOARD_FAB2(SCH_1):PAGE44

M_A_DQ<43> @BASEBOARD_FAB2_LIB.BASEBOARD_FAB2(SCH_1):M_A_DQ(43)
  U5D1  N34 DDR0_DQ<43> SKX_EXT_B_BGA1-IC,TBD   I172 @BASEBOARD_FAB2_LIB.BASEBOARD_FAB2(SCH_1):PAGE23
  J4G1  115 DQ<42> SCONN288_H44441004_PIP-SCONN,HA     I1 @BASEBOARD_FAB2_LIB.BASEBOARD_FAB2(SCH_1):PAGE43
  J6T1  260 DQ<43> SCONN288_H44441003_PIP-SCONN,HA    I13 @BASEBOARD_FAB2_LIB.BASEBOARD_FAB2(SCH_1):PAGE44

M_A_DQ<44> @BASEBOARD_FAB2_LIB.BASEBOARD_FAB2(SCH_1):M_A_DQ(44)
  U5D1  L38 DDR0_DQ<44> SKX_EXT_B_BGA1-IC,TBD   I172 @BASEBOARD_FAB2_LIB.BASEBOARD_FAB2(SCH_1):PAGE23
  J4G1  251 DQ<45> SCONN288_H44441004_PIP-SCONN,HA     I1 @BASEBOARD_FAB2_LIB.BASEBOARD_FAB2(SCH_1):PAGE43
  J6T1  106 DQ<44> SCONN288_H44441003_PIP-SCONN,HA    I13 @BASEBOARD_FAB2_LIB.BASEBOARD_FAB2(SCH_1):PAGE44

M_A_DQ<45> @BASEBOARD_FAB2_LIB.BASEBOARD_FAB2(SCH_1):M_A_DQ(45)
  U5D1  N38 DDR0_DQ<45> SKX_EXT_B_BGA1-IC,TBD   I172 @BASEBOARD_FAB2_LIB.BASEBOARD_FAB2(SCH_1):PAGE23
  J4G1  106 DQ<44> SCONN288_H44441004_PIP-SCONN,HA     I1 @BASEBOARD_FAB2_LIB.BASEBOARD_FAB2(SCH_1):PAGE43
  J6T1  251 DQ<45> SCONN288_H44441003_PIP-SCONN,HA    I13 @BASEBOARD_FAB2_LIB.BASEBOARD_FAB2(SCH_1):PAGE44

M_A_DQ<46> @BASEBOARD_FAB2_LIB.BASEBOARD_FAB2(SCH_1):M_A_DQ(46)
  U5D1  K35 DDR0_DQ<46> SKX_EXT_B_BGA1-IC,TBD   I172 @BASEBOARD_FAB2_LIB.BASEBOARD_FAB2(SCH_1):PAGE23
  J4G1  258 DQ<47> SCONN288_H44441004_PIP-SCONN,HA     I1 @BASEBOARD_FAB2_LIB.BASEBOARD_FAB2(SCH_1):PAGE43
  J6T1  113 DQ<46> SCONN288_H44441003_PIP-SCONN,HA    I13 @BASEBOARD_FAB2_LIB.BASEBOARD_FAB2(SCH_1):PAGE44

M_A_DQ<47> @BASEBOARD_FAB2_LIB.BASEBOARD_FAB2(SCH_1):M_A_DQ(47)
  U5D1  P35 DDR0_DQ<47> SKX_EXT_B_BGA1-IC,TBD   I172 @BASEBOARD_FAB2_LIB.BASEBOARD_FAB2(SCH_1):PAGE23
  J4G1  113 DQ<46> SCONN288_H44441004_PIP-SCONN,HA     I1 @BASEBOARD_FAB2_LIB.BASEBOARD_FAB2(SCH_1):PAGE43
  J6T1  258 DQ<47> SCONN288_H44441003_PIP-SCONN,HA    I13 @BASEBOARD_FAB2_LIB.BASEBOARD_FAB2(SCH_1):PAGE44

M_A_DQ<48> @BASEBOARD_FAB2_LIB.BASEBOARD_FAB2(SCH_1):M_A_DQ(48)
  U5D1  K31 DDR0_DQ<48> SKX_EXT_B_BGA1-IC,TBD   I172 @BASEBOARD_FAB2_LIB.BASEBOARD_FAB2(SCH_1):PAGE23
  J4G1  264 DQ<49> SCONN288_H44441004_PIP-SCONN,HA     I1 @BASEBOARD_FAB2_LIB.BASEBOARD_FAB2(SCH_1):PAGE43
  J6T1  119 DQ<48> SCONN288_H44441003_PIP-SCONN,HA    I13 @BASEBOARD_FAB2_LIB.BASEBOARD_FAB2(SCH_1):PAGE44

M_A_DQ<49> @BASEBOARD_FAB2_LIB.BASEBOARD_FAB2(SCH_1):M_A_DQ(49)
  U5D1  P31 DDR0_DQ<49> SKX_EXT_B_BGA1-IC,TBD   I172 @BASEBOARD_FAB2_LIB.BASEBOARD_FAB2(SCH_1):PAGE23
  J4G1  119 DQ<48> SCONN288_H44441004_PIP-SCONN,HA     I1 @BASEBOARD_FAB2_LIB.BASEBOARD_FAB2(SCH_1):PAGE43
  J6T1  264 DQ<49> SCONN288_H44441003_PIP-SCONN,HA    I13 @BASEBOARD_FAB2_LIB.BASEBOARD_FAB2(SCH_1):PAGE44

M_A_DQ<4> @BASEBOARD_FAB2_LIB.BASEBOARD_FAB2(SCH_1):M_A_DQ(4)
  U5D1 AR86 DDR0_DQ<4> SKX_EXT_B_BGA1-IC,TBD   I172 @BASEBOARD_FAB2_LIB.BASEBOARD_FAB2(SCH_1):PAGE23
  J4G1  148  DQ<5> SCONN288_H44441004_PIP-SCONN,HA     I1 @BASEBOARD_FAB2_LIB.BASEBOARD_FAB2(SCH_1):PAGE43
  J6T1    3  DQ<4> SCONN288_H44441003_PIP-SCONN,HA    I13 @BASEBOARD_FAB2_LIB.BASEBOARD_FAB2(SCH_1):PAGE44

M_A_DQ<50> @BASEBOARD_FAB2_LIB.BASEBOARD_FAB2(SCH_1):M_A_DQ(50)
  U5D1  L28 DDR0_DQ<50> SKX_EXT_B_BGA1-IC,TBD   I172 @BASEBOARD_FAB2_LIB.BASEBOARD_FAB2(SCH_1):PAGE23
  J4G1  271 DQ<51> SCONN288_H44441004_PIP-SCONN,HA     I1 @BASEBOARD_FAB2_LIB.BASEBOARD_FAB2(SCH_1):PAGE43
  J6T1  126 DQ<50> SCONN288_H44441003_PIP-SCONN,HA    I13 @BASEBOARD_FAB2_LIB.BASEBOARD_FAB2(SCH_1):PAGE44

M_A_DQ<51> @BASEBOARD_FAB2_LIB.BASEBOARD_FAB2(SCH_1):M_A_DQ(51)
  U5D1  N28 DDR0_DQ<51> SKX_EXT_B_BGA1-IC,TBD   I172 @BASEBOARD_FAB2_LIB.BASEBOARD_FAB2(SCH_1):PAGE23
  J4G1  126 DQ<50> SCONN288_H44441004_PIP-SCONN,HA     I1 @BASEBOARD_FAB2_LIB.BASEBOARD_FAB2(SCH_1):PAGE43
  J6T1  271 DQ<51> SCONN288_H44441003_PIP-SCONN,HA    I13 @BASEBOARD_FAB2_LIB.BASEBOARD_FAB2(SCH_1):PAGE44

M_A_DQ<52> @BASEBOARD_FAB2_LIB.BASEBOARD_FAB2(SCH_1):M_A_DQ(52)
  U5D1  L32 DDR0_DQ<52> SKX_EXT_B_BGA1-IC,TBD   I172 @BASEBOARD_FAB2_LIB.BASEBOARD_FAB2(SCH_1):PAGE23
  J4G1  262 DQ<53> SCONN288_H44441004_PIP-SCONN,HA     I1 @BASEBOARD_FAB2_LIB.BASEBOARD_FAB2(SCH_1):PAGE43
  J6T1  117 DQ<52> SCONN288_H44441003_PIP-SCONN,HA    I13 @BASEBOARD_FAB2_LIB.BASEBOARD_FAB2(SCH_1):PAGE44

M_A_DQ<53> @BASEBOARD_FAB2_LIB.BASEBOARD_FAB2(SCH_1):M_A_DQ(53)
  U5D1  N32 DDR0_DQ<53> SKX_EXT_B_BGA1-IC,TBD   I172 @BASEBOARD_FAB2_LIB.BASEBOARD_FAB2(SCH_1):PAGE23
  J4G1  117 DQ<52> SCONN288_H44441004_PIP-SCONN,HA     I1 @BASEBOARD_FAB2_LIB.BASEBOARD_FAB2(SCH_1):PAGE43
  J6T1  262 DQ<53> SCONN288_H44441003_PIP-SCONN,HA    I13 @BASEBOARD_FAB2_LIB.BASEBOARD_FAB2(SCH_1):PAGE44

M_A_DQ<54> @BASEBOARD_FAB2_LIB.BASEBOARD_FAB2(SCH_1):M_A_DQ(54)
  U5D1  K29 DDR0_DQ<54> SKX_EXT_B_BGA1-IC,TBD   I172 @BASEBOARD_FAB2_LIB.BASEBOARD_FAB2(SCH_1):PAGE23
  J4G1  269 DQ<55> SCONN288_H44441004_PIP-SCONN,HA     I1 @BASEBOARD_FAB2_LIB.BASEBOARD_FAB2(SCH_1):PAGE43
  J6T1  124 DQ<54> SCONN288_H44441003_PIP-SCONN,HA    I13 @BASEBOARD_FAB2_LIB.BASEBOARD_FAB2(SCH_1):PAGE44

M_A_DQ<55> @BASEBOARD_FAB2_LIB.BASEBOARD_FAB2(SCH_1):M_A_DQ(55)
  U5D1  P29 DDR0_DQ<55> SKX_EXT_B_BGA1-IC,TBD   I172 @BASEBOARD_FAB2_LIB.BASEBOARD_FAB2(SCH_1):PAGE23
  J4G1  124 DQ<54> SCONN288_H44441004_PIP-SCONN,HA     I1 @BASEBOARD_FAB2_LIB.BASEBOARD_FAB2(SCH_1):PAGE43
  J6T1  269 DQ<55> SCONN288_H44441003_PIP-SCONN,HA    I13 @BASEBOARD_FAB2_LIB.BASEBOARD_FAB2(SCH_1):PAGE44

M_A_DQ<56> @BASEBOARD_FAB2_LIB.BASEBOARD_FAB2(SCH_1):M_A_DQ(56)
  U5D1  K25 DDR0_DQ<56> SKX_EXT_B_BGA1-IC,TBD   I172 @BASEBOARD_FAB2_LIB.BASEBOARD_FAB2(SCH_1):PAGE23
  J4G1  275 DQ<57> SCONN288_H44441004_PIP-SCONN,HA     I1 @BASEBOARD_FAB2_LIB.BASEBOARD_FAB2(SCH_1):PAGE43
  J6T1  130 DQ<56> SCONN288_H44441003_PIP-SCONN,HA    I13 @BASEBOARD_FAB2_LIB.BASEBOARD_FAB2(SCH_1):PAGE44

M_A_DQ<57> @BASEBOARD_FAB2_LIB.BASEBOARD_FAB2(SCH_1):M_A_DQ(57)
  U5D1  P25 DDR0_DQ<57> SKX_EXT_B_BGA1-IC,TBD   I172 @BASEBOARD_FAB2_LIB.BASEBOARD_FAB2(SCH_1):PAGE23
  J4G1  130 DQ<56> SCONN288_H44441004_PIP-SCONN,HA     I1 @BASEBOARD_FAB2_LIB.BASEBOARD_FAB2(SCH_1):PAGE43
  J6T1  275 DQ<57> SCONN288_H44441003_PIP-SCONN,HA    I13 @BASEBOARD_FAB2_LIB.BASEBOARD_FAB2(SCH_1):PAGE44

M_A_DQ<58> @BASEBOARD_FAB2_LIB.BASEBOARD_FAB2(SCH_1):M_A_DQ(58)
  U5D1  P23 DDR0_DQ<58> SKX_EXT_B_BGA1-IC,TBD   I172 @BASEBOARD_FAB2_LIB.BASEBOARD_FAB2(SCH_1):PAGE23
  J4G1  282 DQ<59> SCONN288_H44441004_PIP-SCONN,HA     I1 @BASEBOARD_FAB2_LIB.BASEBOARD_FAB2(SCH_1):PAGE43
  J6T1  137 DQ<58> SCONN288_H44441003_PIP-SCONN,HA    I13 @BASEBOARD_FAB2_LIB.BASEBOARD_FAB2(SCH_1):PAGE44

M_A_DQ<59> @BASEBOARD_FAB2_LIB.BASEBOARD_FAB2(SCH_1):M_A_DQ(59)
  U5D1  T23 DDR0_DQ<59> SKX_EXT_B_BGA1-IC,TBD   I172 @BASEBOARD_FAB2_LIB.BASEBOARD_FAB2(SCH_1):PAGE23
  J4G1  137 DQ<58> SCONN288_H44441004_PIP-SCONN,HA     I1 @BASEBOARD_FAB2_LIB.BASEBOARD_FAB2(SCH_1):PAGE43
  J6T1  282 DQ<59> SCONN288_H44441003_PIP-SCONN,HA    I13 @BASEBOARD_FAB2_LIB.BASEBOARD_FAB2(SCH_1):PAGE44

M_A_DQ<5> @BASEBOARD_FAB2_LIB.BASEBOARD_FAB2(SCH_1):M_A_DQ(5)
  U5D1 AR84 DDR0_DQ<5> SKX_EXT_B_BGA1-IC,TBD   I172 @BASEBOARD_FAB2_LIB.BASEBOARD_FAB2(SCH_1):PAGE23
  J4G1    3  DQ<4> SCONN288_H44441004_PIP-SCONN,HA     I1 @BASEBOARD_FAB2_LIB.BASEBOARD_FAB2(SCH_1):PAGE43
  J6T1  148  DQ<5> SCONN288_H44441003_PIP-SCONN,HA    I13 @BASEBOARD_FAB2_LIB.BASEBOARD_FAB2(SCH_1):PAGE44

M_A_DQ<60> @BASEBOARD_FAB2_LIB.BASEBOARD_FAB2(SCH_1):M_A_DQ(60)
  U5D1  L26 DDR0_DQ<60> SKX_EXT_B_BGA1-IC,TBD   I172 @BASEBOARD_FAB2_LIB.BASEBOARD_FAB2(SCH_1):PAGE23
  J4G1  273 DQ<61> SCONN288_H44441004_PIP-SCONN,HA     I1 @BASEBOARD_FAB2_LIB.BASEBOARD_FAB2(SCH_1):PAGE43
  J6T1  128 DQ<60> SCONN288_H44441003_PIP-SCONN,HA    I13 @BASEBOARD_FAB2_LIB.BASEBOARD_FAB2(SCH_1):PAGE44

M_A_DQ<61> @BASEBOARD_FAB2_LIB.BASEBOARD_FAB2(SCH_1):M_A_DQ(61)
  U5D1  N26 DDR0_DQ<61> SKX_EXT_B_BGA1-IC,TBD   I172 @BASEBOARD_FAB2_LIB.BASEBOARD_FAB2(SCH_1):PAGE23
  J4G1  128 DQ<60> SCONN288_H44441004_PIP-SCONN,HA     I1 @BASEBOARD_FAB2_LIB.BASEBOARD_FAB2(SCH_1):PAGE43
  J6T1  273 DQ<61> SCONN288_H44441003_PIP-SCONN,HA    I13 @BASEBOARD_FAB2_LIB.BASEBOARD_FAB2(SCH_1):PAGE44

M_A_DQ<62> @BASEBOARD_FAB2_LIB.BASEBOARD_FAB2(SCH_1):M_A_DQ(62)
  U5D1  H23 DDR0_DQ<62> SKX_EXT_B_BGA1-IC,TBD   I172 @BASEBOARD_FAB2_LIB.BASEBOARD_FAB2(SCH_1):PAGE23
  J4G1  280 DQ<63> SCONN288_H44441004_PIP-SCONN,HA     I1 @BASEBOARD_FAB2_LIB.BASEBOARD_FAB2(SCH_1):PAGE43
  J6T1  135 DQ<62> SCONN288_H44441003_PIP-SCONN,HA    I13 @BASEBOARD_FAB2_LIB.BASEBOARD_FAB2(SCH_1):PAGE44

M_A_DQ<63> @BASEBOARD_FAB2_LIB.BASEBOARD_FAB2(SCH_1):M_A_DQ(63)
  U5D1  K23 DDR0_DQ<63> SKX_EXT_B_BGA1-IC,TBD   I172 @BASEBOARD_FAB2_LIB.BASEBOARD_FAB2(SCH_1):PAGE23
  J4G1  135 DQ<62> SCONN288_H44441004_PIP-SCONN,HA     I1 @BASEBOARD_FAB2_LIB.BASEBOARD_FAB2(SCH_1):PAGE43
  J6T1  280 DQ<63> SCONN288_H44441003_PIP-SCONN,HA    I13 @BASEBOARD_FAB2_LIB.BASEBOARD_FAB2(SCH_1):PAGE44

M_A_DQ<6> @BASEBOARD_FAB2_LIB.BASEBOARD_FAB2(SCH_1):M_A_DQ(6)
  U5D1 AG86 DDR0_DQ<6> SKX_EXT_B_BGA1-IC,TBD   I172 @BASEBOARD_FAB2_LIB.BASEBOARD_FAB2(SCH_1):PAGE23
  J4G1  155  DQ<7> SCONN288_H44441004_PIP-SCONN,HA     I1 @BASEBOARD_FAB2_LIB.BASEBOARD_FAB2(SCH_1):PAGE43
  J6T1   10  DQ<6> SCONN288_H44441003_PIP-SCONN,HA    I13 @BASEBOARD_FAB2_LIB.BASEBOARD_FAB2(SCH_1):PAGE44

M_A_DQ<7> @BASEBOARD_FAB2_LIB.BASEBOARD_FAB2(SCH_1):M_A_DQ(7)
  U5D1 AG84 DDR0_DQ<7> SKX_EXT_B_BGA1-IC,TBD   I172 @BASEBOARD_FAB2_LIB.BASEBOARD_FAB2(SCH_1):PAGE23
  J4G1   10  DQ<6> SCONN288_H44441004_PIP-SCONN,HA     I1 @BASEBOARD_FAB2_LIB.BASEBOARD_FAB2(SCH_1):PAGE43
  J6T1  155  DQ<7> SCONN288_H44441003_PIP-SCONN,HA    I13 @BASEBOARD_FAB2_LIB.BASEBOARD_FAB2(SCH_1):PAGE44

M_A_DQ<8> @BASEBOARD_FAB2_LIB.BASEBOARD_FAB2(SCH_1):M_A_DQ(8)
  U5D1  W86 DDR0_DQ<8> SKX_EXT_B_BGA1-IC,TBD   I172 @BASEBOARD_FAB2_LIB.BASEBOARD_FAB2(SCH_1):PAGE23
  J4G1  161  DQ<9> SCONN288_H44441004_PIP-SCONN,HA     I1 @BASEBOARD_FAB2_LIB.BASEBOARD_FAB2(SCH_1):PAGE43
  J6T1   16  DQ<8> SCONN288_H44441003_PIP-SCONN,HA    I13 @BASEBOARD_FAB2_LIB.BASEBOARD_FAB2(SCH_1):PAGE44

M_A_DQ<9> @BASEBOARD_FAB2_LIB.BASEBOARD_FAB2(SCH_1):M_A_DQ(9)
  U5D1  W84 DDR0_DQ<9> SKX_EXT_B_BGA1-IC,TBD   I172 @BASEBOARD_FAB2_LIB.BASEBOARD_FAB2(SCH_1):PAGE23
  J4G1   16  DQ<8> SCONN288_H44441004_PIP-SCONN,HA     I1 @BASEBOARD_FAB2_LIB.BASEBOARD_FAB2(SCH_1):PAGE43
  J6T1  161  DQ<9> SCONN288_H44441003_PIP-SCONN,HA    I13 @BASEBOARD_FAB2_LIB.BASEBOARD_FAB2(SCH_1):PAGE44

M_A_DQS_DN<0> @BASEBOARD_FAB2_LIB.BASEBOARD_FAB2(SCH_1):M_A_DQS_DN(0)
  U5D1 AJ84 DDR0_DQS_DN<0> SKX_EXT_B_BGA1-IC,TBD   I172 @BASEBOARD_FAB2_LIB.BASEBOARD_FAB2(SCH_1):PAGE23
  J4G1  152  DQS0N SCONN288_H44441004_PIP-SCONN,HA     I2 @BASEBOARD_FAB2_LIB.BASEBOARD_FAB2(SCH_1):PAGE43
  J6T1  152  DQS0N SCONN288_H44441003_PIP-SCONN,HA   I120 @BASEBOARD_FAB2_LIB.BASEBOARD_FAB2(SCH_1):PAGE44

M_A_DQS_DN<10> @BASEBOARD_FAB2_LIB.BASEBOARD_FAB2(SCH_1):M_A_DQS_DN(10)
  U5D1  U84 DDR0_DQS_DN<10> SKX_EXT_B_BGA1-IC,TBD   I172 @BASEBOARD_FAB2_LIB.BASEBOARD_FAB2(SCH_1):PAGE23
  J4G1   19 DQS10N SCONN288_H44441004_PIP-SCONN,HA     I2 @BASEBOARD_FAB2_LIB.BASEBOARD_FAB2(SCH_1):PAGE43
  J6T1   19 DQS10N SCONN288_H44441003_PIP-SCONN,HA   I120 @BASEBOARD_FAB2_LIB.BASEBOARD_FAB2(SCH_1):PAGE44

M_A_DQS_DN<11> @BASEBOARD_FAB2_LIB.BASEBOARD_FAB2(SCH_1):M_A_DQS_DN(11)
  U5D1  U82 DDR0_DQS_DN<11> SKX_EXT_B_BGA1-IC,TBD   I172 @BASEBOARD_FAB2_LIB.BASEBOARD_FAB2(SCH_1):PAGE23
  J4G1   30 DQS11N SCONN288_H44441004_PIP-SCONN,HA     I2 @BASEBOARD_FAB2_LIB.BASEBOARD_FAB2(SCH_1):PAGE43
  J6T1   30 DQS11N SCONN288_H44441003_PIP-SCONN,HA   I120 @BASEBOARD_FAB2_LIB.BASEBOARD_FAB2(SCH_1):PAGE44

M_A_DQS_DN<12> @BASEBOARD_FAB2_LIB.BASEBOARD_FAB2(SCH_1):M_A_DQS_DN(12)
  U5D1  K75 DDR0_DQS_DN<12> SKX_EXT_B_BGA1-IC,TBD   I172 @BASEBOARD_FAB2_LIB.BASEBOARD_FAB2(SCH_1):PAGE23
  J4G1   41 DQS12N SCONN288_H44441004_PIP-SCONN,HA     I2 @BASEBOARD_FAB2_LIB.BASEBOARD_FAB2(SCH_1):PAGE43
  J6T1   41 DQS12N SCONN288_H44441003_PIP-SCONN,HA   I120 @BASEBOARD_FAB2_LIB.BASEBOARD_FAB2(SCH_1):PAGE44

M_A_DQS_DN<13> @BASEBOARD_FAB2_LIB.BASEBOARD_FAB2(SCH_1):M_A_DQS_DN(13)
  U5D1  A40 DDR0_DQS_DN<13> SKX_EXT_B_BGA1-IC,TBD   I172 @BASEBOARD_FAB2_LIB.BASEBOARD_FAB2(SCH_1):PAGE23
  J4G1  100 DQS13N SCONN288_H44441004_PIP-SCONN,HA     I2 @BASEBOARD_FAB2_LIB.BASEBOARD_FAB2(SCH_1):PAGE43
  J6T1  100 DQS13N SCONN288_H44441003_PIP-SCONN,HA   I120 @BASEBOARD_FAB2_LIB.BASEBOARD_FAB2(SCH_1):PAGE44

M_A_DQS_DN<14> @BASEBOARD_FAB2_LIB.BASEBOARD_FAB2(SCH_1):M_A_DQS_DN(14)
  U5D1  J36 DDR0_DQS_DN<14> SKX_EXT_B_BGA1-IC,TBD   I172 @BASEBOARD_FAB2_LIB.BASEBOARD_FAB2(SCH_1):PAGE23
  J4G1  111 DQS14N SCONN288_H44441004_PIP-SCONN,HA     I2 @BASEBOARD_FAB2_LIB.BASEBOARD_FAB2(SCH_1):PAGE43
  J6T1  111 DQS14N SCONN288_H44441003_PIP-SCONN,HA   I120 @BASEBOARD_FAB2_LIB.BASEBOARD_FAB2(SCH_1):PAGE44

M_A_DQS_DN<15> @BASEBOARD_FAB2_LIB.BASEBOARD_FAB2(SCH_1):M_A_DQS_DN(15)
  U5D1  J30 DDR0_DQS_DN<15> SKX_EXT_B_BGA1-IC,TBD   I172 @BASEBOARD_FAB2_LIB.BASEBOARD_FAB2(SCH_1):PAGE23
  J4G1  122 DQS15N SCONN288_H44441004_PIP-SCONN,HA     I2 @BASEBOARD_FAB2_LIB.BASEBOARD_FAB2(SCH_1):PAGE43
  J6T1  122 DQS15N SCONN288_H44441003_PIP-SCONN,HA   I120 @BASEBOARD_FAB2_LIB.BASEBOARD_FAB2(SCH_1):PAGE44

M_A_DQS_DN<16> @BASEBOARD_FAB2_LIB.BASEBOARD_FAB2(SCH_1):M_A_DQS_DN(16)
  U5D1  J24 DDR0_DQS_DN<16> SKX_EXT_B_BGA1-IC,TBD   I172 @BASEBOARD_FAB2_LIB.BASEBOARD_FAB2(SCH_1):PAGE23
  J4G1  133 DQS16N SCONN288_H44441004_PIP-SCONN,HA     I2 @BASEBOARD_FAB2_LIB.BASEBOARD_FAB2(SCH_1):PAGE43
  J6T1  133 DQS16N SCONN288_H44441003_PIP-SCONN,HA   I120 @BASEBOARD_FAB2_LIB.BASEBOARD_FAB2(SCH_1):PAGE44

M_A_DQS_DN<17> @BASEBOARD_FAB2_LIB.BASEBOARD_FAB2(SCH_1):M_A_DQS_DN(17)
  U5D1 AB67 DDR0_DQS_DN<17> SKX_EXT_B_BGA1-IC,TBD   I172 @BASEBOARD_FAB2_LIB.BASEBOARD_FAB2(SCH_1):PAGE23
  J4G1   52 DQS17N SCONN288_H44441004_PIP-SCONN,HA     I2 @BASEBOARD_FAB2_LIB.BASEBOARD_FAB2(SCH_1):PAGE43
  J6T1   52 DQS17N SCONN288_H44441003_PIP-SCONN,HA   I120 @BASEBOARD_FAB2_LIB.BASEBOARD_FAB2(SCH_1):PAGE44

M_A_DQS_DN<1> @BASEBOARD_FAB2_LIB.BASEBOARD_FAB2(SCH_1):M_A_DQS_DN(1)
  U5D1  R84 DDR0_DQS_DN<1> SKX_EXT_B_BGA1-IC,TBD   I172 @BASEBOARD_FAB2_LIB.BASEBOARD_FAB2(SCH_1):PAGE23
  J4G1  163  DQS1N SCONN288_H44441004_PIP-SCONN,HA     I2 @BASEBOARD_FAB2_LIB.BASEBOARD_FAB2(SCH_1):PAGE43
  J6T1  163  DQS1N SCONN288_H44441003_PIP-SCONN,HA   I120 @BASEBOARD_FAB2_LIB.BASEBOARD_FAB2(SCH_1):PAGE44

M_A_DQS_DN<2> @BASEBOARD_FAB2_LIB.BASEBOARD_FAB2(SCH_1):M_A_DQS_DN(2)
  U5D1  P79 DDR0_DQS_DN<2> SKX_EXT_B_BGA1-IC,TBD   I172 @BASEBOARD_FAB2_LIB.BASEBOARD_FAB2(SCH_1):PAGE23
  J4G1  174  DQS2N SCONN288_H44441004_PIP-SCONN,HA     I2 @BASEBOARD_FAB2_LIB.BASEBOARD_FAB2(SCH_1):PAGE43
  J6T1  174  DQS2N SCONN288_H44441003_PIP-SCONN,HA   I120 @BASEBOARD_FAB2_LIB.BASEBOARD_FAB2(SCH_1):PAGE44

M_A_DQS_DN<3> @BASEBOARD_FAB2_LIB.BASEBOARD_FAB2(SCH_1):M_A_DQS_DN(3)
  U5D1  T75 DDR0_DQS_DN<3> SKX_EXT_B_BGA1-IC,TBD   I172 @BASEBOARD_FAB2_LIB.BASEBOARD_FAB2(SCH_1):PAGE23
  J4G1  185  DQS3N SCONN288_H44441004_PIP-SCONN,HA     I2 @BASEBOARD_FAB2_LIB.BASEBOARD_FAB2(SCH_1):PAGE43
  J6T1  185  DQS3N SCONN288_H44441003_PIP-SCONN,HA   I120 @BASEBOARD_FAB2_LIB.BASEBOARD_FAB2(SCH_1):PAGE44

M_A_DQS_DN<4> @BASEBOARD_FAB2_LIB.BASEBOARD_FAB2(SCH_1):M_A_DQS_DN(4)
  U5D1  G40 DDR0_DQS_DN<4> SKX_EXT_B_BGA1-IC,TBD   I172 @BASEBOARD_FAB2_LIB.BASEBOARD_FAB2(SCH_1):PAGE23
  J4G1  244  DQS4N SCONN288_H44441004_PIP-SCONN,HA     I2 @BASEBOARD_FAB2_LIB.BASEBOARD_FAB2(SCH_1):PAGE43
  J6T1  244  DQS4N SCONN288_H44441003_PIP-SCONN,HA   I120 @BASEBOARD_FAB2_LIB.BASEBOARD_FAB2(SCH_1):PAGE44

M_A_DQS_DN<5> @BASEBOARD_FAB2_LIB.BASEBOARD_FAB2(SCH_1):M_A_DQS_DN(5)
  U5D1  R36 DDR0_DQS_DN<5> SKX_EXT_B_BGA1-IC,TBD   I172 @BASEBOARD_FAB2_LIB.BASEBOARD_FAB2(SCH_1):PAGE23
  J4G1  255  DQS5N SCONN288_H44441004_PIP-SCONN,HA     I2 @BASEBOARD_FAB2_LIB.BASEBOARD_FAB2(SCH_1):PAGE43
  J6T1  255  DQS5N SCONN288_H44441003_PIP-SCONN,HA   I120 @BASEBOARD_FAB2_LIB.BASEBOARD_FAB2(SCH_1):PAGE44

M_A_DQS_DN<6> @BASEBOARD_FAB2_LIB.BASEBOARD_FAB2(SCH_1):M_A_DQS_DN(6)
  U5D1  R30 DDR0_DQS_DN<6> SKX_EXT_B_BGA1-IC,TBD   I172 @BASEBOARD_FAB2_LIB.BASEBOARD_FAB2(SCH_1):PAGE23
  J4G1  266  DQS6N SCONN288_H44441004_PIP-SCONN,HA     I2 @BASEBOARD_FAB2_LIB.BASEBOARD_FAB2(SCH_1):PAGE43
  J6T1  266  DQS6N SCONN288_H44441003_PIP-SCONN,HA   I120 @BASEBOARD_FAB2_LIB.BASEBOARD_FAB2(SCH_1):PAGE44

M_A_DQS_DN<7> @BASEBOARD_FAB2_LIB.BASEBOARD_FAB2(SCH_1):M_A_DQS_DN(7)
  U5D1  N24 DDR0_DQS_DN<7> SKX_EXT_B_BGA1-IC,TBD   I172 @BASEBOARD_FAB2_LIB.BASEBOARD_FAB2(SCH_1):PAGE23
  J4G1  277  DQS7N SCONN288_H44441004_PIP-SCONN,HA     I2 @BASEBOARD_FAB2_LIB.BASEBOARD_FAB2(SCH_1):PAGE43
  J6T1  277  DQS7N SCONN288_H44441003_PIP-SCONN,HA   I120 @BASEBOARD_FAB2_LIB.BASEBOARD_FAB2(SCH_1):PAGE44

M_A_DQS_DN<8> @BASEBOARD_FAB2_LIB.BASEBOARD_FAB2(SCH_1):M_A_DQS_DN(8)
  U5D1 AH67 DDR0_DQS_DN<8> SKX_EXT_B_BGA1-IC,TBD   I172 @BASEBOARD_FAB2_LIB.BASEBOARD_FAB2(SCH_1):PAGE23
  J4G1  196  DQS8N SCONN288_H44441004_PIP-SCONN,HA     I2 @BASEBOARD_FAB2_LIB.BASEBOARD_FAB2(SCH_1):PAGE43
  J6T1  196  DQS8N SCONN288_H44441003_PIP-SCONN,HA   I120 @BASEBOARD_FAB2_LIB.BASEBOARD_FAB2(SCH_1):PAGE44

M_A_DQS_DN<9> @BASEBOARD_FAB2_LIB.BASEBOARD_FAB2(SCH_1):M_A_DQS_DN(9)
  U5D1 AL84 DDR0_DQS_DN<9> SKX_EXT_B_BGA1-IC,TBD   I172 @BASEBOARD_FAB2_LIB.BASEBOARD_FAB2(SCH_1):PAGE23
  J4G1    8  DQS9N SCONN288_H44441004_PIP-SCONN,HA     I2 @BASEBOARD_FAB2_LIB.BASEBOARD_FAB2(SCH_1):PAGE43
  J6T1    8  DQS9N SCONN288_H44441003_PIP-SCONN,HA   I120 @BASEBOARD_FAB2_LIB.BASEBOARD_FAB2(SCH_1):PAGE44

M_A_DQS_DP<0> @BASEBOARD_FAB2_LIB.BASEBOARD_FAB2(SCH_1):M_A_DQS_DP(0)
  U5D1 AH85 DDR0_DQS_DP<0> SKX_EXT_B_BGA1-IC,TBD   I172 @BASEBOARD_FAB2_LIB.BASEBOARD_FAB2(SCH_1):PAGE23
  J4G1  153  DQS0P SCONN288_H44441004_PIP-SCONN,HA     I2 @BASEBOARD_FAB2_LIB.BASEBOARD_FAB2(SCH_1):PAGE43
  J6T1  153  DQS0P SCONN288_H44441003_PIP-SCONN,HA   I120 @BASEBOARD_FAB2_LIB.BASEBOARD_FAB2(SCH_1):PAGE44

M_A_DQS_DP<10> @BASEBOARD_FAB2_LIB.BASEBOARD_FAB2(SCH_1):M_A_DQS_DP(10)
  U5D1  V85 DDR0_DQS_DP<10> SKX_EXT_B_BGA1-IC,TBD   I172 @BASEBOARD_FAB2_LIB.BASEBOARD_FAB2(SCH_1):PAGE23
  J4G1   18 DQS10P SCONN288_H44441004_PIP-SCONN,HA     I2 @BASEBOARD_FAB2_LIB.BASEBOARD_FAB2(SCH_1):PAGE43
  J6T1   18 DQS10P SCONN288_H44441003_PIP-SCONN,HA   I120 @BASEBOARD_FAB2_LIB.BASEBOARD_FAB2(SCH_1):PAGE44

M_A_DQS_DP<11> @BASEBOARD_FAB2_LIB.BASEBOARD_FAB2(SCH_1):M_A_DQS_DP(11)
  U5D1  T81 DDR0_DQS_DP<11> SKX_EXT_B_BGA1-IC,TBD   I172 @BASEBOARD_FAB2_LIB.BASEBOARD_FAB2(SCH_1):PAGE23
  J4G1   29 DQS11P SCONN288_H44441004_PIP-SCONN,HA     I2 @BASEBOARD_FAB2_LIB.BASEBOARD_FAB2(SCH_1):PAGE43
  J6T1   29 DQS11P SCONN288_H44441003_PIP-SCONN,HA   I120 @BASEBOARD_FAB2_LIB.BASEBOARD_FAB2(SCH_1):PAGE44

M_A_DQS_DP<12> @BASEBOARD_FAB2_LIB.BASEBOARD_FAB2(SCH_1):M_A_DQS_DP(12)
  U5D1  M75 DDR0_DQS_DP<12> SKX_EXT_B_BGA1-IC,TBD   I172 @BASEBOARD_FAB2_LIB.BASEBOARD_FAB2(SCH_1):PAGE23
  J4G1   40 DQS12P SCONN288_H44441004_PIP-SCONN,HA     I2 @BASEBOARD_FAB2_LIB.BASEBOARD_FAB2(SCH_1):PAGE43
  J6T1   40 DQS12P SCONN288_H44441003_PIP-SCONN,HA   I120 @BASEBOARD_FAB2_LIB.BASEBOARD_FAB2(SCH_1):PAGE44

M_A_DQS_DP<13> @BASEBOARD_FAB2_LIB.BASEBOARD_FAB2(SCH_1):M_A_DQS_DP(13)
  U5D1  C40 DDR0_DQS_DP<13> SKX_EXT_B_BGA1-IC,TBD   I172 @BASEBOARD_FAB2_LIB.BASEBOARD_FAB2(SCH_1):PAGE23
  J4G1   99 DQS13P SCONN288_H44441004_PIP-SCONN,HA     I2 @BASEBOARD_FAB2_LIB.BASEBOARD_FAB2(SCH_1):PAGE43
  J6T1   99 DQS13P SCONN288_H44441003_PIP-SCONN,HA   I120 @BASEBOARD_FAB2_LIB.BASEBOARD_FAB2(SCH_1):PAGE44

M_A_DQS_DP<14> @BASEBOARD_FAB2_LIB.BASEBOARD_FAB2(SCH_1):M_A_DQS_DP(14)
  U5D1  L36 DDR0_DQS_DP<14> SKX_EXT_B_BGA1-IC,TBD   I172 @BASEBOARD_FAB2_LIB.BASEBOARD_FAB2(SCH_1):PAGE23
  J4G1  110 DQS14P SCONN288_H44441004_PIP-SCONN,HA     I2 @BASEBOARD_FAB2_LIB.BASEBOARD_FAB2(SCH_1):PAGE43
  J6T1  110 DQS14P SCONN288_H44441003_PIP-SCONN,HA   I120 @BASEBOARD_FAB2_LIB.BASEBOARD_FAB2(SCH_1):PAGE44

M_A_DQS_DP<15> @BASEBOARD_FAB2_LIB.BASEBOARD_FAB2(SCH_1):M_A_DQS_DP(15)
  U5D1  L30 DDR0_DQS_DP<15> SKX_EXT_B_BGA1-IC,TBD   I172 @BASEBOARD_FAB2_LIB.BASEBOARD_FAB2(SCH_1):PAGE23
  J4G1  121 DQS15P SCONN288_H44441004_PIP-SCONN,HA     I2 @BASEBOARD_FAB2_LIB.BASEBOARD_FAB2(SCH_1):PAGE43
  J6T1  121 DQS15P SCONN288_H44441003_PIP-SCONN,HA   I120 @BASEBOARD_FAB2_LIB.BASEBOARD_FAB2(SCH_1):PAGE44

M_A_DQS_DP<16> @BASEBOARD_FAB2_LIB.BASEBOARD_FAB2(SCH_1):M_A_DQS_DP(16)
  U5D1  L24 DDR0_DQS_DP<16> SKX_EXT_B_BGA1-IC,TBD   I172 @BASEBOARD_FAB2_LIB.BASEBOARD_FAB2(SCH_1):PAGE23
  J4G1  132 DQS16P SCONN288_H44441004_PIP-SCONN,HA     I2 @BASEBOARD_FAB2_LIB.BASEBOARD_FAB2(SCH_1):PAGE43
  J6T1  132 DQS16P SCONN288_H44441003_PIP-SCONN,HA   I120 @BASEBOARD_FAB2_LIB.BASEBOARD_FAB2(SCH_1):PAGE44

M_A_DQS_DP<17> @BASEBOARD_FAB2_LIB.BASEBOARD_FAB2(SCH_1):M_A_DQS_DP(17)
  U5D1 AD67 DDR0_DQS_DP<17> SKX_EXT_B_BGA1-IC,TBD   I172 @BASEBOARD_FAB2_LIB.BASEBOARD_FAB2(SCH_1):PAGE23
  J4G1   51 DQS17P SCONN288_H44441004_PIP-SCONN,HA     I2 @BASEBOARD_FAB2_LIB.BASEBOARD_FAB2(SCH_1):PAGE43
  J6T1   51 DQS17P SCONN288_H44441003_PIP-SCONN,HA   I120 @BASEBOARD_FAB2_LIB.BASEBOARD_FAB2(SCH_1):PAGE44

M_A_DQS_DP<1> @BASEBOARD_FAB2_LIB.BASEBOARD_FAB2(SCH_1):M_A_DQS_DP(1)
  U5D1  P85 DDR0_DQS_DP<1> SKX_EXT_B_BGA1-IC,TBD   I172 @BASEBOARD_FAB2_LIB.BASEBOARD_FAB2(SCH_1):PAGE23
  J4G1  164  DQS1P SCONN288_H44441004_PIP-SCONN,HA     I2 @BASEBOARD_FAB2_LIB.BASEBOARD_FAB2(SCH_1):PAGE43
  J6T1  164  DQS1P SCONN288_H44441003_PIP-SCONN,HA   I120 @BASEBOARD_FAB2_LIB.BASEBOARD_FAB2(SCH_1):PAGE44

M_A_DQS_DP<2> @BASEBOARD_FAB2_LIB.BASEBOARD_FAB2(SCH_1):M_A_DQS_DP(2)
  U5D1  R80 DDR0_DQS_DP<2> SKX_EXT_B_BGA1-IC,TBD   I172 @BASEBOARD_FAB2_LIB.BASEBOARD_FAB2(SCH_1):PAGE23
  J4G1  175  DQS2P SCONN288_H44441004_PIP-SCONN,HA     I2 @BASEBOARD_FAB2_LIB.BASEBOARD_FAB2(SCH_1):PAGE43
  J6T1  175  DQS2P SCONN288_H44441003_PIP-SCONN,HA   I120 @BASEBOARD_FAB2_LIB.BASEBOARD_FAB2(SCH_1):PAGE44

M_A_DQS_DP<3> @BASEBOARD_FAB2_LIB.BASEBOARD_FAB2(SCH_1):M_A_DQS_DP(3)
  U5D1  P75 DDR0_DQS_DP<3> SKX_EXT_B_BGA1-IC,TBD   I172 @BASEBOARD_FAB2_LIB.BASEBOARD_FAB2(SCH_1):PAGE23
  J4G1  186  DQS3P SCONN288_H44441004_PIP-SCONN,HA     I2 @BASEBOARD_FAB2_LIB.BASEBOARD_FAB2(SCH_1):PAGE43
  J6T1  186  DQS3P SCONN288_H44441003_PIP-SCONN,HA   I120 @BASEBOARD_FAB2_LIB.BASEBOARD_FAB2(SCH_1):PAGE44

M_A_DQS_DP<4> @BASEBOARD_FAB2_LIB.BASEBOARD_FAB2(SCH_1):M_A_DQS_DP(4)
  U5D1  E40 DDR0_DQS_DP<4> SKX_EXT_B_BGA1-IC,TBD   I172 @BASEBOARD_FAB2_LIB.BASEBOARD_FAB2(SCH_1):PAGE23
  J4G1  245  DQS4P SCONN288_H44441004_PIP-SCONN,HA     I2 @BASEBOARD_FAB2_LIB.BASEBOARD_FAB2(SCH_1):PAGE43
  J6T1  245  DQS4P SCONN288_H44441003_PIP-SCONN,HA   I120 @BASEBOARD_FAB2_LIB.BASEBOARD_FAB2(SCH_1):PAGE44

M_A_DQS_DP<5> @BASEBOARD_FAB2_LIB.BASEBOARD_FAB2(SCH_1):M_A_DQS_DP(5)
  U5D1  N36 DDR0_DQS_DP<5> SKX_EXT_B_BGA1-IC,TBD   I172 @BASEBOARD_FAB2_LIB.BASEBOARD_FAB2(SCH_1):PAGE23
  J4G1  256  DQS5P SCONN288_H44441004_PIP-SCONN,HA     I2 @BASEBOARD_FAB2_LIB.BASEBOARD_FAB2(SCH_1):PAGE43
  J6T1  256  DQS5P SCONN288_H44441003_PIP-SCONN,HA   I120 @BASEBOARD_FAB2_LIB.BASEBOARD_FAB2(SCH_1):PAGE44

M_A_DQS_DP<6> @BASEBOARD_FAB2_LIB.BASEBOARD_FAB2(SCH_1):M_A_DQS_DP(6)
  U5D1  N30 DDR0_DQS_DP<6> SKX_EXT_B_BGA1-IC,TBD   I172 @BASEBOARD_FAB2_LIB.BASEBOARD_FAB2(SCH_1):PAGE23
  J4G1  267  DQS6P SCONN288_H44441004_PIP-SCONN,HA     I2 @BASEBOARD_FAB2_LIB.BASEBOARD_FAB2(SCH_1):PAGE43
  J6T1  267  DQS6P SCONN288_H44441003_PIP-SCONN,HA   I120 @BASEBOARD_FAB2_LIB.BASEBOARD_FAB2(SCH_1):PAGE44

M_A_DQS_DP<7> @BASEBOARD_FAB2_LIB.BASEBOARD_FAB2(SCH_1):M_A_DQS_DP(7)
  U5D1  R24 DDR0_DQS_DP<7> SKX_EXT_B_BGA1-IC,TBD   I172 @BASEBOARD_FAB2_LIB.BASEBOARD_FAB2(SCH_1):PAGE23
  J4G1  278  DQS7P SCONN288_H44441004_PIP-SCONN,HA     I2 @BASEBOARD_FAB2_LIB.BASEBOARD_FAB2(SCH_1):PAGE43
  J6T1  278  DQS7P SCONN288_H44441003_PIP-SCONN,HA   I120 @BASEBOARD_FAB2_LIB.BASEBOARD_FAB2(SCH_1):PAGE44

M_A_DQS_DP<8> @BASEBOARD_FAB2_LIB.BASEBOARD_FAB2(SCH_1):M_A_DQS_DP(8)
  U5D1 AF67 DDR0_DQS_DP<8> SKX_EXT_B_BGA1-IC,TBD   I172 @BASEBOARD_FAB2_LIB.BASEBOARD_FAB2(SCH_1):PAGE23
  J4G1  197  DQS8P SCONN288_H44441004_PIP-SCONN,HA     I2 @BASEBOARD_FAB2_LIB.BASEBOARD_FAB2(SCH_1):PAGE43
  J6T1  197  DQS8P SCONN288_H44441003_PIP-SCONN,HA   I120 @BASEBOARD_FAB2_LIB.BASEBOARD_FAB2(SCH_1):PAGE44

M_A_DQS_DP<9> @BASEBOARD_FAB2_LIB.BASEBOARD_FAB2(SCH_1):M_A_DQS_DP(9)
  U5D1 AM85 DDR0_DQS_DP<9> SKX_EXT_B_BGA1-IC,TBD   I172 @BASEBOARD_FAB2_LIB.BASEBOARD_FAB2(SCH_1):PAGE23
  J4G1    7  DQS9P SCONN288_H44441004_PIP-SCONN,HA     I2 @BASEBOARD_FAB2_LIB.BASEBOARD_FAB2(SCH_1):PAGE43
  J6T1    7  DQS9P SCONN288_H44441003_PIP-SCONN,HA   I120 @BASEBOARD_FAB2_LIB.BASEBOARD_FAB2(SCH_1):PAGE44

M_A_ECC<0> @BASEBOARD_FAB2_LIB.BASEBOARD_FAB2(SCH_1):M_A_ECC(0)
  U5D1 AC68 DDR0_ECC<0> SKX_EXT_B_BGA1-IC,TBD   I172 @BASEBOARD_FAB2_LIB.BASEBOARD_FAB2(SCH_1):PAGE23
  J4G1  194  CB<1> SCONN288_H44441004_PIP-SCONN,HA     I1 @BASEBOARD_FAB2_LIB.BASEBOARD_FAB2(SCH_1):PAGE43
  J6T1   49  CB<0> SCONN288_H44441003_PIP-SCONN,HA    I13 @BASEBOARD_FAB2_LIB.BASEBOARD_FAB2(SCH_1):PAGE44

M_A_ECC<1> @BASEBOARD_FAB2_LIB.BASEBOARD_FAB2(SCH_1):M_A_ECC(1)
  U5D1 AG68 DDR0_ECC<1> SKX_EXT_B_BGA1-IC,TBD   I172 @BASEBOARD_FAB2_LIB.BASEBOARD_FAB2(SCH_1):PAGE23
  J4G1   49  CB<0> SCONN288_H44441004_PIP-SCONN,HA     I1 @BASEBOARD_FAB2_LIB.BASEBOARD_FAB2(SCH_1):PAGE43
  J6T1  194  CB<1> SCONN288_H44441003_PIP-SCONN,HA    I13 @BASEBOARD_FAB2_LIB.BASEBOARD_FAB2(SCH_1):PAGE44

M_A_ECC<2> @BASEBOARD_FAB2_LIB.BASEBOARD_FAB2(SCH_1):M_A_ECC(2)
  U5D1 AD65 DDR0_ECC<2> SKX_EXT_B_BGA1-IC,TBD   I172 @BASEBOARD_FAB2_LIB.BASEBOARD_FAB2(SCH_1):PAGE23
  J4G1  201  CB<3> SCONN288_H44441004_PIP-SCONN,HA     I1 @BASEBOARD_FAB2_LIB.BASEBOARD_FAB2(SCH_1):PAGE43
  J6T1   56  CB<2> SCONN288_H44441003_PIP-SCONN,HA    I13 @BASEBOARD_FAB2_LIB.BASEBOARD_FAB2(SCH_1):PAGE44

M_A_ECC<3> @BASEBOARD_FAB2_LIB.BASEBOARD_FAB2(SCH_1):M_A_ECC(3)
  U5D1 AF65 DDR0_ECC<3> SKX_EXT_B_BGA1-IC,TBD   I172 @BASEBOARD_FAB2_LIB.BASEBOARD_FAB2(SCH_1):PAGE23
  J4G1   56  CB<2> SCONN288_H44441004_PIP-SCONN,HA     I1 @BASEBOARD_FAB2_LIB.BASEBOARD_FAB2(SCH_1):PAGE43
  J6T1  201  CB<3> SCONN288_H44441003_PIP-SCONN,HA    I13 @BASEBOARD_FAB2_LIB.BASEBOARD_FAB2(SCH_1):PAGE44

M_A_ECC<4> @BASEBOARD_FAB2_LIB.BASEBOARD_FAB2(SCH_1):M_A_ECC(4)
  U5D1 AD69 DDR0_ECC<4> SKX_EXT_B_BGA1-IC,TBD   I172 @BASEBOARD_FAB2_LIB.BASEBOARD_FAB2(SCH_1):PAGE23
  J4G1  192  CB<5> SCONN288_H44441004_PIP-SCONN,HA     I1 @BASEBOARD_FAB2_LIB.BASEBOARD_FAB2(SCH_1):PAGE43
  J6T1   47  CB<4> SCONN288_H44441003_PIP-SCONN,HA    I13 @BASEBOARD_FAB2_LIB.BASEBOARD_FAB2(SCH_1):PAGE44

M_A_ECC<5> @BASEBOARD_FAB2_LIB.BASEBOARD_FAB2(SCH_1):M_A_ECC(5)
  U5D1 AF69 DDR0_ECC<5> SKX_EXT_B_BGA1-IC,TBD   I172 @BASEBOARD_FAB2_LIB.BASEBOARD_FAB2(SCH_1):PAGE23
  J4G1   47  CB<4> SCONN288_H44441004_PIP-SCONN,HA     I1 @BASEBOARD_FAB2_LIB.BASEBOARD_FAB2(SCH_1):PAGE43
  J6T1  192  CB<5> SCONN288_H44441003_PIP-SCONN,HA    I13 @BASEBOARD_FAB2_LIB.BASEBOARD_FAB2(SCH_1):PAGE44

M_A_ECC<6> @BASEBOARD_FAB2_LIB.BASEBOARD_FAB2(SCH_1):M_A_ECC(6)
  U5D1 AC66 DDR0_ECC<6> SKX_EXT_B_BGA1-IC,TBD   I172 @BASEBOARD_FAB2_LIB.BASEBOARD_FAB2(SCH_1):PAGE23
  J4G1  199  CB<7> SCONN288_H44441004_PIP-SCONN,HA     I1 @BASEBOARD_FAB2_LIB.BASEBOARD_FAB2(SCH_1):PAGE43
  J6T1   54  CB<6> SCONN288_H44441003_PIP-SCONN,HA    I13 @BASEBOARD_FAB2_LIB.BASEBOARD_FAB2(SCH_1):PAGE44

M_A_ECC<7> @BASEBOARD_FAB2_LIB.BASEBOARD_FAB2(SCH_1):M_A_ECC(7)
  U5D1 AG66 DDR0_ECC<7> SKX_EXT_B_BGA1-IC,TBD   I172 @BASEBOARD_FAB2_LIB.BASEBOARD_FAB2(SCH_1):PAGE23
  J4G1   54  CB<6> SCONN288_H44441004_PIP-SCONN,HA     I1 @BASEBOARD_FAB2_LIB.BASEBOARD_FAB2(SCH_1):PAGE43
  J6T1  199  CB<7> SCONN288_H44441003_PIP-SCONN,HA    I13 @BASEBOARD_FAB2_LIB.BASEBOARD_FAB2(SCH_1):PAGE44

M_A_MA<0> @BASEBOARD_FAB2_LIB.BASEBOARD_FAB2(SCH_1):M_A_MA(0)
  U5D1  F53 DDR0_MA<0> SKX_EXT_B_BGA1-IC,TBD   I172 @BASEBOARD_FAB2_LIB.BASEBOARD_FAB2(SCH_1):PAGE23
  J4G1   79     A0 SCONN288_H44441004_PIP-SCONN,HA     I1 @BASEBOARD_FAB2_LIB.BASEBOARD_FAB2(SCH_1):PAGE43
  J6T1   79     A0 SCONN288_H44441003_PIP-SCONN,HA    I13 @BASEBOARD_FAB2_LIB.BASEBOARD_FAB2(SCH_1):PAGE44

M_A_MA<10> @BASEBOARD_FAB2_LIB.BASEBOARD_FAB2(SCH_1):M_A_MA(10)
  U5D1  J54 DDR0_MA<10> SKX_EXT_B_BGA1-IC,TBD   I172 @BASEBOARD_FAB2_LIB.BASEBOARD_FAB2(SCH_1):PAGE23
  J4G1  225    A10 SCONN288_H44441004_PIP-SCONN,HA     I1 @BASEBOARD_FAB2_LIB.BASEBOARD_FAB2(SCH_1):PAGE43
  J6T1  225    A10 SCONN288_H44441003_PIP-SCONN,HA    I13 @BASEBOARD_FAB2_LIB.BASEBOARD_FAB2(SCH_1):PAGE44

M_A_MA<11> @BASEBOARD_FAB2_LIB.BASEBOARD_FAB2(SCH_1):M_A_MA(11)
  U5D1  G62 DDR0_MA<11> SKX_EXT_B_BGA1-IC,TBD   I172 @BASEBOARD_FAB2_LIB.BASEBOARD_FAB2(SCH_1):PAGE23
  J4G1  210    A11 SCONN288_H44441004_PIP-SCONN,HA     I1 @BASEBOARD_FAB2_LIB.BASEBOARD_FAB2(SCH_1):PAGE43
  J6T1  210    A11 SCONN288_H44441003_PIP-SCONN,HA    I13 @BASEBOARD_FAB2_LIB.BASEBOARD_FAB2(SCH_1):PAGE44

M_A_MA<12> @BASEBOARD_FAB2_LIB.BASEBOARD_FAB2(SCH_1):M_A_MA(12)
  U5D1  J64 DDR0_MA<12> SKX_EXT_B_BGA1-IC,TBD   I172 @BASEBOARD_FAB2_LIB.BASEBOARD_FAB2(SCH_1):PAGE23
  J4G1   65    A12 SCONN288_H44441004_PIP-SCONN,HA     I1 @BASEBOARD_FAB2_LIB.BASEBOARD_FAB2(SCH_1):PAGE43
  J6T1   65    A12 SCONN288_H44441003_PIP-SCONN,HA    I13 @BASEBOARD_FAB2_LIB.BASEBOARD_FAB2(SCH_1):PAGE44

M_A_MA<13> @BASEBOARD_FAB2_LIB.BASEBOARD_FAB2(SCH_1):M_A_MA(13)
  U5D1  J48 DDR0_MA<13> SKX_EXT_B_BGA1-IC,TBD   I172 @BASEBOARD_FAB2_LIB.BASEBOARD_FAB2(SCH_1):PAGE23
  J4G1  232    A13 SCONN288_H44441004_PIP-SCONN,HA     I1 @BASEBOARD_FAB2_LIB.BASEBOARD_FAB2(SCH_1):PAGE43
  J6T1  232    A13 SCONN288_H44441003_PIP-SCONN,HA    I13 @BASEBOARD_FAB2_LIB.BASEBOARD_FAB2(SCH_1):PAGE44

M_A_MA<14> @BASEBOARD_FAB2_LIB.BASEBOARD_FAB2(SCH_1):M_A_MA(14)
  U5D1  F51 DDR0_MA<14> SKX_EXT_B_BGA1-IC,TBD   I172 @BASEBOARD_FAB2_LIB.BASEBOARD_FAB2(SCH_1):PAGE23
  J4G1  228 A14_WE_N SCONN288_H44441004_PIP-SCONN,HA     I1 @BASEBOARD_FAB2_LIB.BASEBOARD_FAB2(SCH_1):PAGE43
  J6T1  228 A14_WE_N SCONN288_H44441003_PIP-SCONN,HA    I13 @BASEBOARD_FAB2_LIB.BASEBOARD_FAB2(SCH_1):PAGE44

M_A_MA<15> @BASEBOARD_FAB2_LIB.BASEBOARD_FAB2(SCH_1):M_A_MA(15)
  U5D1  K49 DDR0_MA<15> SKX_EXT_B_BGA1-IC,TBD   I172 @BASEBOARD_FAB2_LIB.BASEBOARD_FAB2(SCH_1):PAGE23
  J4G1   86 A15_CAS_N SCONN288_H44441004_PIP-SCONN,HA     I1 @BASEBOARD_FAB2_LIB.BASEBOARD_FAB2(SCH_1):PAGE43
  J6T1   86 A15_CAS_N SCONN288_H44441003_PIP-SCONN,HA    I13 @BASEBOARD_FAB2_LIB.BASEBOARD_FAB2(SCH_1):PAGE44

M_A_MA<16> @BASEBOARD_FAB2_LIB.BASEBOARD_FAB2(SCH_1):M_A_MA(16)
  U5D1  D51 DDR0_MA<16> SKX_EXT_B_BGA1-IC,TBD   I172 @BASEBOARD_FAB2_LIB.BASEBOARD_FAB2(SCH_1):PAGE23
  J4G1   82 A16_RAS_N SCONN288_H44441004_PIP-SCONN,HA     I1 @BASEBOARD_FAB2_LIB.BASEBOARD_FAB2(SCH_1):PAGE43
  J6T1   82 A16_RAS_N SCONN288_H44441003_PIP-SCONN,HA    I13 @BASEBOARD_FAB2_LIB.BASEBOARD_FAB2(SCH_1):PAGE44

M_A_MA<17> @BASEBOARD_FAB2_LIB.BASEBOARD_FAB2(SCH_1):M_A_MA(17)
  U5D1  K47 DDR0_MA<17> SKX_EXT_B_BGA1-IC,TBD   I172 @BASEBOARD_FAB2_LIB.BASEBOARD_FAB2(SCH_1):PAGE23
  J4G1  234    A17 SCONN288_H44441004_PIP-SCONN,HA     I1 @BASEBOARD_FAB2_LIB.BASEBOARD_FAB2(SCH_1):PAGE43
  J6T1  234    A17 SCONN288_H44441003_PIP-SCONN,HA    I13 @BASEBOARD_FAB2_LIB.BASEBOARD_FAB2(SCH_1):PAGE44

M_A_MA<1> @BASEBOARD_FAB2_LIB.BASEBOARD_FAB2(SCH_1):M_A_MA(1)
  U5D1  F57 DDR0_MA<1> SKX_EXT_B_BGA1-IC,TBD   I172 @BASEBOARD_FAB2_LIB.BASEBOARD_FAB2(SCH_1):PAGE23
  J4G1   72     A1 SCONN288_H44441004_PIP-SCONN,HA     I1 @BASEBOARD_FAB2_LIB.BASEBOARD_FAB2(SCH_1):PAGE43
  J6T1   72     A1 SCONN288_H44441003_PIP-SCONN,HA    I13 @BASEBOARD_FAB2_LIB.BASEBOARD_FAB2(SCH_1):PAGE44

M_A_MA<2> @BASEBOARD_FAB2_LIB.BASEBOARD_FAB2(SCH_1):M_A_MA(2)
  U5D1  D57 DDR0_MA<2> SKX_EXT_B_BGA1-IC,TBD   I172 @BASEBOARD_FAB2_LIB.BASEBOARD_FAB2(SCH_1):PAGE23
  J4G1  216     A2 SCONN288_H44441004_PIP-SCONN,HA     I1 @BASEBOARD_FAB2_LIB.BASEBOARD_FAB2(SCH_1):PAGE43
  J6T1  216     A2 SCONN288_H44441003_PIP-SCONN,HA    I13 @BASEBOARD_FAB2_LIB.BASEBOARD_FAB2(SCH_1):PAGE44

M_A_MA<3> @BASEBOARD_FAB2_LIB.BASEBOARD_FAB2(SCH_1):M_A_MA(3)
  U5D1  C58 DDR0_MA<3> SKX_EXT_B_BGA1-IC,TBD   I172 @BASEBOARD_FAB2_LIB.BASEBOARD_FAB2(SCH_1):PAGE23
  J4G1   71     A3 SCONN288_H44441004_PIP-SCONN,HA     I1 @BASEBOARD_FAB2_LIB.BASEBOARD_FAB2(SCH_1):PAGE43
  J6T1   71     A3 SCONN288_H44441003_PIP-SCONN,HA    I13 @BASEBOARD_FAB2_LIB.BASEBOARD_FAB2(SCH_1):PAGE44

M_A_MA<4> @BASEBOARD_FAB2_LIB.BASEBOARD_FAB2(SCH_1):M_A_MA(4)
  U5D1  G58 DDR0_MA<4> SKX_EXT_B_BGA1-IC,TBD   I172 @BASEBOARD_FAB2_LIB.BASEBOARD_FAB2(SCH_1):PAGE23
  J4G1  214     A4 SCONN288_H44441004_PIP-SCONN,HA     I1 @BASEBOARD_FAB2_LIB.BASEBOARD_FAB2(SCH_1):PAGE43
  J6T1  214     A4 SCONN288_H44441003_PIP-SCONN,HA    I13 @BASEBOARD_FAB2_LIB.BASEBOARD_FAB2(SCH_1):PAGE44

M_A_MA<5> @BASEBOARD_FAB2_LIB.BASEBOARD_FAB2(SCH_1):M_A_MA(5)
  U5D1  F59 DDR0_MA<5> SKX_EXT_B_BGA1-IC,TBD   I172 @BASEBOARD_FAB2_LIB.BASEBOARD_FAB2(SCH_1):PAGE23
  J4G1  213     A5 SCONN288_H44441004_PIP-SCONN,HA     I1 @BASEBOARD_FAB2_LIB.BASEBOARD_FAB2(SCH_1):PAGE43
  J6T1  213     A5 SCONN288_H44441003_PIP-SCONN,HA    I13 @BASEBOARD_FAB2_LIB.BASEBOARD_FAB2(SCH_1):PAGE44

M_A_MA<6> @BASEBOARD_FAB2_LIB.BASEBOARD_FAB2(SCH_1):M_A_MA(6)
  U5D1  D59 DDR0_MA<6> SKX_EXT_B_BGA1-IC,TBD   I172 @BASEBOARD_FAB2_LIB.BASEBOARD_FAB2(SCH_1):PAGE23
  J4G1   69     A6 SCONN288_H44441004_PIP-SCONN,HA     I1 @BASEBOARD_FAB2_LIB.BASEBOARD_FAB2(SCH_1):PAGE43
  J6T1   69     A6 SCONN288_H44441003_PIP-SCONN,HA    I13 @BASEBOARD_FAB2_LIB.BASEBOARD_FAB2(SCH_1):PAGE44

M_A_MA<7> @BASEBOARD_FAB2_LIB.BASEBOARD_FAB2(SCH_1):M_A_MA(7)
  U5D1  G60 DDR0_MA<7> SKX_EXT_B_BGA1-IC,TBD   I172 @BASEBOARD_FAB2_LIB.BASEBOARD_FAB2(SCH_1):PAGE23
  J4G1  211     A7 SCONN288_H44441004_PIP-SCONN,HA     I1 @BASEBOARD_FAB2_LIB.BASEBOARD_FAB2(SCH_1):PAGE43
  J6T1  211     A7 SCONN288_H44441003_PIP-SCONN,HA    I13 @BASEBOARD_FAB2_LIB.BASEBOARD_FAB2(SCH_1):PAGE44

M_A_MA<8> @BASEBOARD_FAB2_LIB.BASEBOARD_FAB2(SCH_1):M_A_MA(8)
  U5D1  C60 DDR0_MA<8> SKX_EXT_B_BGA1-IC,TBD   I172 @BASEBOARD_FAB2_LIB.BASEBOARD_FAB2(SCH_1):PAGE23
  J4G1   68     A8 SCONN288_H44441004_PIP-SCONN,HA     I1 @BASEBOARD_FAB2_LIB.BASEBOARD_FAB2(SCH_1):PAGE43
  J6T1   68     A8 SCONN288_H44441003_PIP-SCONN,HA    I13 @BASEBOARD_FAB2_LIB.BASEBOARD_FAB2(SCH_1):PAGE44

M_A_MA<9> @BASEBOARD_FAB2_LIB.BASEBOARD_FAB2(SCH_1):M_A_MA(9)
  U5D1  F61 DDR0_MA<9> SKX_EXT_B_BGA1-IC,TBD   I172 @BASEBOARD_FAB2_LIB.BASEBOARD_FAB2(SCH_1):PAGE23
  J4G1   66     A9 SCONN288_H44441004_PIP-SCONN,HA     I1 @BASEBOARD_FAB2_LIB.BASEBOARD_FAB2(SCH_1):PAGE43
  J6T1   66     A9 SCONN288_H44441003_PIP-SCONN,HA    I13 @BASEBOARD_FAB2_LIB.BASEBOARD_FAB2(SCH_1):PAGE44

M_A_ODT<0> @BASEBOARD_FAB2_LIB.BASEBOARD_FAB2(SCH_1):M_A_ODT(0)
  U5D1  C50 DDR0_ODT<0> SKX_EXT_B_BGA1-IC,TBD   I172 @BASEBOARD_FAB2_LIB.BASEBOARD_FAB2(SCH_1):PAGE23
  J4G1   87 ODT<0> SCONN288_H44441004_PIP-SCONN,HA     I1 @BASEBOARD_FAB2_LIB.BASEBOARD_FAB2(SCH_1):PAGE43

M_A_ODT<1> @BASEBOARD_FAB2_LIB.BASEBOARD_FAB2(SCH_1):M_A_ODT(1)
  U5D1  C48 DDR0_ODT<1> SKX_EXT_B_BGA1-IC,TBD   I172 @BASEBOARD_FAB2_LIB.BASEBOARD_FAB2(SCH_1):PAGE23
  J4G1   91 ODT<1> SCONN288_H44441004_PIP-SCONN,HA     I1 @BASEBOARD_FAB2_LIB.BASEBOARD_FAB2(SCH_1):PAGE43

M_A_ODT<2> @BASEBOARD_FAB2_LIB.BASEBOARD_FAB2(SCH_1):M_A_ODT(2)
  U5D1  G50 DDR0_ODT<2> SKX_EXT_B_BGA1-IC,TBD   I172 @BASEBOARD_FAB2_LIB.BASEBOARD_FAB2(SCH_1):PAGE23
  J6T1   87 ODT<0> SCONN288_H44441003_PIP-SCONN,HA    I13 @BASEBOARD_FAB2_LIB.BASEBOARD_FAB2(SCH_1):PAGE44

M_A_ODT<3> @BASEBOARD_FAB2_LIB.BASEBOARD_FAB2(SCH_1):M_A_ODT(3)
  U5D1  G48 DDR0_ODT<3> SKX_EXT_B_BGA1-IC,TBD   I172 @BASEBOARD_FAB2_LIB.BASEBOARD_FAB2(SCH_1):PAGE23
  J6T1   91 ODT<1> SCONN288_H44441003_PIP-SCONN,HA    I13 @BASEBOARD_FAB2_LIB.BASEBOARD_FAB2(SCH_1):PAGE44

M_A_PAR @BASEBOARD_FAB2_LIB.BASEBOARD_FAB2(SCH_1):M_A_PAR
  U5D1  D53 DDR0_PAR SKX_EXT_B_BGA1-IC,TBD   I172 @BASEBOARD_FAB2_LIB.BASEBOARD_FAB2(SCH_1):PAGE23
  J4G1  222    PAR SCONN288_H44441004_PIP-SCONN,HA     I1 @BASEBOARD_FAB2_LIB.BASEBOARD_FAB2(SCH_1):PAGE43
  J6T1  222    PAR SCONN288_H44441003_PIP-SCONN,HA    I13 @BASEBOARD_FAB2_LIB.BASEBOARD_FAB2(SCH_1):PAGE44

M_A_VREF @BASEBOARD_FAB2_LIB.BASEBOARD_FAB2(SCH_1):M_A_VREF
  J4G1  146 VREFCA SCONN288_H44441004_PIP-SCONN,HA     I1 @BASEBOARD_FAB2_LIB.BASEBOARD_FAB2(SCH_1):PAGE43
 C4F10    1      A CAP_A_0402V-0.01UF,25V,10%,X7RA   I272 @BASEBOARD_FAB2_LIB.BASEBOARD_FAB2(SCH_1):PAGE43
  C6T1    1      A CAP_A_0402V-0.01UF,25V,10%,X7RA     I2 @BASEBOARD_FAB2_LIB.BASEBOARD_FAB2(SCH_1):PAGE44
  J6T1  146 VREFCA SCONN288_H44441003_PIP-SCONN,HA    I13 @BASEBOARD_FAB2_LIB.BASEBOARD_FAB2(SCH_1):PAGE44
  R4F5    1      A RES_0402-1.00K,1%,1/16W,CHIP,GA     I4 @BASEBOARD_FAB2_LIB.BASEBOARD_FAB2(SCH_1):PAGE98
  R4F3    2      B RES_0402-2,1.0%,1/16W,CHIP,G21A     I5 @BASEBOARD_FAB2_LIB.BASEBOARD_FAB2(SCH_1):PAGE98
  R4F4    2      B RES_0402-1.00K,1%,1/16W,CHIP,GA    I36 @BASEBOARD_FAB2_LIB.BASEBOARD_FAB2(SCH_1):PAGE98

M_B_ACT_N @BASEBOARD_FAB2_LIB.BASEBOARD_FAB2(SCH_1):M_B_ACT_N
  U5D1  T63 DDR1_ACT_N SKX_EXT_B_BGA1-IC,TBD   I172 @BASEBOARD_FAB2_LIB.BASEBOARD_FAB2(SCH_1):PAGE24
  J4G2   62  ACT_N SCONN288_H44441004_PIP-SCONN,HA   I111 @BASEBOARD_FAB2_LIB.BASEBOARD_FAB2(SCH_1):PAGE45
  J6U1   62  ACT_N SCONN288_H44441003_PIP-SCONN,HA    I14 @BASEBOARD_FAB2_LIB.BASEBOARD_FAB2(SCH_1):PAGE46

M_B_ALERT_N @BASEBOARD_FAB2_LIB.BASEBOARD_FAB2(SCH_1):M_B_ALERT_N
  U5D1  W62 DDR1_ALERT_N SKX_EXT_B_BGA1-IC,TBD   I172 @BASEBOARD_FAB2_LIB.BASEBOARD_FAB2(SCH_1):PAGE24
  J4G2  208 ALERT_N SCONN288_H44441004_PIP-SCONN,HA   I111 @BASEBOARD_FAB2_LIB.BASEBOARD_FAB2(SCH_1):PAGE45
  J6U1  208 ALERT_N SCONN288_H44441003_PIP-SCONN,HA    I14 @BASEBOARD_FAB2_LIB.BASEBOARD_FAB2(SCH_1):PAGE46

M_B_BA<0> @BASEBOARD_FAB2_LIB.BASEBOARD_FAB2(SCH_1):M_B_BA(0)
  U5D1  T53 DDR1_BA<0> SKX_EXT_B_BGA1-IC,TBD   I172 @BASEBOARD_FAB2_LIB.BASEBOARD_FAB2(SCH_1):PAGE24
  J4G2   81  BA<0> SCONN288_H44441004_PIP-SCONN,HA   I111 @BASEBOARD_FAB2_LIB.BASEBOARD_FAB2(SCH_1):PAGE45
  J6U1   81  BA<0> SCONN288_H44441003_PIP-SCONN,HA    I14 @BASEBOARD_FAB2_LIB.BASEBOARD_FAB2(SCH_1):PAGE46

M_B_BA<1> @BASEBOARD_FAB2_LIB.BASEBOARD_FAB2(SCH_1):M_B_BA(1)
  U5D1  K55 DDR1_BA<1> SKX_EXT_B_BGA1-IC,TBD   I172 @BASEBOARD_FAB2_LIB.BASEBOARD_FAB2(SCH_1):PAGE24
  J4G2  224  BA<1> SCONN288_H44441004_PIP-SCONN,HA   I111 @BASEBOARD_FAB2_LIB.BASEBOARD_FAB2(SCH_1):PAGE45
  J6U1  224  BA<1> SCONN288_H44441003_PIP-SCONN,HA    I14 @BASEBOARD_FAB2_LIB.BASEBOARD_FAB2(SCH_1):PAGE46

M_B_BG<0> @BASEBOARD_FAB2_LIB.BASEBOARD_FAB2(SCH_1):M_B_BG(0)
  U5D1  M61 DDR1_BG<0> SKX_EXT_B_BGA1-IC,TBD   I172 @BASEBOARD_FAB2_LIB.BASEBOARD_FAB2(SCH_1):PAGE24
  J4G2   63  BG<0> SCONN288_H44441004_PIP-SCONN,HA   I111 @BASEBOARD_FAB2_LIB.BASEBOARD_FAB2(SCH_1):PAGE45
  J6U1   63  BG<0> SCONN288_H44441003_PIP-SCONN,HA    I14 @BASEBOARD_FAB2_LIB.BASEBOARD_FAB2(SCH_1):PAGE46

M_B_BG<1> @BASEBOARD_FAB2_LIB.BASEBOARD_FAB2(SCH_1):M_B_BG(1)
  U5D1  N60 DDR1_BG<1> SKX_EXT_B_BGA1-IC,TBD   I172 @BASEBOARD_FAB2_LIB.BASEBOARD_FAB2(SCH_1):PAGE24
  J4G2  207  BG<1> SCONN288_H44441004_PIP-SCONN,HA   I111 @BASEBOARD_FAB2_LIB.BASEBOARD_FAB2(SCH_1):PAGE45
  J6U1  207  BG<1> SCONN288_H44441003_PIP-SCONN,HA    I14 @BASEBOARD_FAB2_LIB.BASEBOARD_FAB2(SCH_1):PAGE46

M_B_C<2> @BASEBOARD_FAB2_LIB.BASEBOARD_FAB2(SCH_1):M_B_C(2)
  U5D1  M47 DDR1_CID<2> SKX_EXT_B_BGA1-IC,TBD   I172 @BASEBOARD_FAB2_LIB.BASEBOARD_FAB2(SCH_1):PAGE24
  J4G2  235   C<2> SCONN288_H44441004_PIP-SCONN,HA   I111 @BASEBOARD_FAB2_LIB.BASEBOARD_FAB2(SCH_1):PAGE45
  J6U1  235   C<2> SCONN288_H44441003_PIP-SCONN,HA    I14 @BASEBOARD_FAB2_LIB.BASEBOARD_FAB2(SCH_1):PAGE46

M_B_CKE<0> @BASEBOARD_FAB2_LIB.BASEBOARD_FAB2(SCH_1):M_B_CKE(0)
  U5D1  N62 DDR1_CKE<0> SKX_EXT_B_BGA1-IC,TBD   I172 @BASEBOARD_FAB2_LIB.BASEBOARD_FAB2(SCH_1):PAGE24
  J4G2   60 CKE<0> SCONN288_H44441004_PIP-SCONN,HA   I111 @BASEBOARD_FAB2_LIB.BASEBOARD_FAB2(SCH_1):PAGE45

M_B_CKE<1> @BASEBOARD_FAB2_LIB.BASEBOARD_FAB2(SCH_1):M_B_CKE(1)
  U5D1  R64 DDR1_CKE<1> SKX_EXT_B_BGA1-IC,TBD   I172 @BASEBOARD_FAB2_LIB.BASEBOARD_FAB2(SCH_1):PAGE24
  J4G2  203 CKE<1> SCONN288_H44441004_PIP-SCONN,HA   I111 @BASEBOARD_FAB2_LIB.BASEBOARD_FAB2(SCH_1):PAGE45

M_B_CKE<2> @BASEBOARD_FAB2_LIB.BASEBOARD_FAB2(SCH_1):M_B_CKE(2)
  U5D1  K63 DDR1_CKE<2> SKX_EXT_B_BGA1-IC,TBD   I172 @BASEBOARD_FAB2_LIB.BASEBOARD_FAB2(SCH_1):PAGE24
  J6U1   60 CKE<0> SCONN288_H44441003_PIP-SCONN,HA    I14 @BASEBOARD_FAB2_LIB.BASEBOARD_FAB2(SCH_1):PAGE46

M_B_CKE<3> @BASEBOARD_FAB2_LIB.BASEBOARD_FAB2(SCH_1):M_B_CKE(3)
  U5D1  L64 DDR1_CKE<3> SKX_EXT_B_BGA1-IC,TBD   I172 @BASEBOARD_FAB2_LIB.BASEBOARD_FAB2(SCH_1):PAGE24
  J6U1  203 CKE<1> SCONN288_H44441003_PIP-SCONN,HA    I14 @BASEBOARD_FAB2_LIB.BASEBOARD_FAB2(SCH_1):PAGE46

M_B_CLK_DN<0> @BASEBOARD_FAB2_LIB.BASEBOARD_FAB2(SCH_1):M_B_CLK_DN(0)
  U5D1  M53 DDR1_CLK_DN<0> SKX_EXT_B_BGA1-IC,TBD   I172 @BASEBOARD_FAB2_LIB.BASEBOARD_FAB2(SCH_1):PAGE24
  J4G2   75   CK0N SCONN288_H44441004_PIP-SCONN,HA   I111 @BASEBOARD_FAB2_LIB.BASEBOARD_FAB2(SCH_1):PAGE45

M_B_CLK_DN<1> @BASEBOARD_FAB2_LIB.BASEBOARD_FAB2(SCH_1):M_B_CLK_DN(1)
  U5D1  R54 DDR1_CLK_DN<1> SKX_EXT_B_BGA1-IC,TBD   I172 @BASEBOARD_FAB2_LIB.BASEBOARD_FAB2(SCH_1):PAGE24
  J4G2  219   CK1N SCONN288_H44441004_PIP-SCONN,HA   I111 @BASEBOARD_FAB2_LIB.BASEBOARD_FAB2(SCH_1):PAGE45

M_B_CLK_DN<2> @BASEBOARD_FAB2_LIB.BASEBOARD_FAB2(SCH_1):M_B_CLK_DN(2)
  U5D1  N56 DDR1_CLK_DN<2> SKX_EXT_B_BGA1-IC,TBD   I172 @BASEBOARD_FAB2_LIB.BASEBOARD_FAB2(SCH_1):PAGE24
  J6U1   75   CK0N SCONN288_H44441003_PIP-SCONN,HA    I14 @BASEBOARD_FAB2_LIB.BASEBOARD_FAB2(SCH_1):PAGE46

M_B_CLK_DN<3> @BASEBOARD_FAB2_LIB.BASEBOARD_FAB2(SCH_1):M_B_CLK_DN(3)
  U5D1  R56 DDR1_CLK_DN<3> SKX_EXT_B_BGA1-IC,TBD   I172 @BASEBOARD_FAB2_LIB.BASEBOARD_FAB2(SCH_1):PAGE24
  J6U1  219   CK1N SCONN288_H44441003_PIP-SCONN,HA    I14 @BASEBOARD_FAB2_LIB.BASEBOARD_FAB2(SCH_1):PAGE46

M_B_CLK_DP<0> @BASEBOARD_FAB2_LIB.BASEBOARD_FAB2(SCH_1):M_B_CLK_DP(0)
  U5D1  N54 DDR1_CLK_DP<0> SKX_EXT_B_BGA1-IC,TBD   I172 @BASEBOARD_FAB2_LIB.BASEBOARD_FAB2(SCH_1):PAGE24
  J4G2   74   CK0P SCONN288_H44441004_PIP-SCONN,HA   I111 @BASEBOARD_FAB2_LIB.BASEBOARD_FAB2(SCH_1):PAGE45

M_B_CLK_DP<1> @BASEBOARD_FAB2_LIB.BASEBOARD_FAB2(SCH_1):M_B_CLK_DP(1)
  U5D1  T55 DDR1_CLK_DP<1> SKX_EXT_B_BGA1-IC,TBD   I172 @BASEBOARD_FAB2_LIB.BASEBOARD_FAB2(SCH_1):PAGE24
  J4G2  218   CK1P SCONN288_H44441004_PIP-SCONN,HA   I111 @BASEBOARD_FAB2_LIB.BASEBOARD_FAB2(SCH_1):PAGE45

M_B_CLK_DP<2> @BASEBOARD_FAB2_LIB.BASEBOARD_FAB2(SCH_1):M_B_CLK_DP(2)
  U5D1  M57 DDR1_CLK_DP<2> SKX_EXT_B_BGA1-IC,TBD   I172 @BASEBOARD_FAB2_LIB.BASEBOARD_FAB2(SCH_1):PAGE24
  J6U1   74   CK0P SCONN288_H44441003_PIP-SCONN,HA    I14 @BASEBOARD_FAB2_LIB.BASEBOARD_FAB2(SCH_1):PAGE46

M_B_CLK_DP<3> @BASEBOARD_FAB2_LIB.BASEBOARD_FAB2(SCH_1):M_B_CLK_DP(3)
  U5D1  T57 DDR1_CLK_DP<3> SKX_EXT_B_BGA1-IC,TBD   I172 @BASEBOARD_FAB2_LIB.BASEBOARD_FAB2(SCH_1):PAGE24
  J6U1  218   CK1P SCONN288_H44441003_PIP-SCONN,HA    I14 @BASEBOARD_FAB2_LIB.BASEBOARD_FAB2(SCH_1):PAGE46

M_B_CPU_VREF @BASEBOARD_FAB2_LIB.BASEBOARD_FAB2(SCH_1):M_B_CPU_VREF
  U5D1 AK63 DDR1_CAVREF SKX_EXT_B_BGA1-IC,TBD   I259 @BASEBOARD_FAB2_LIB.BASEBOARD_FAB2(SCH_1):PAGE21
  R4G1    1      A RES_0402-2,1.0%,1/16W,CHIP,G21A    I42 @BASEBOARD_FAB2_LIB.BASEBOARD_FAB2(SCH_1):PAGE98
  C4G1    1      A CAP_A_0402V-0.01UF,25V,10%,X7RA    I43 @BASEBOARD_FAB2_LIB.BASEBOARD_FAB2(SCH_1):PAGE98

M_B_CS_N<0> @BASEBOARD_FAB2_LIB.BASEBOARD_FAB2(SCH_1):M_B_CS_N(0)
  U5D1  K51 DDR1_CS_N<0> SKX_EXT_B_BGA1-IC,TBD   I172 @BASEBOARD_FAB2_LIB.BASEBOARD_FAB2(SCH_1):PAGE24
  J4G2   84   S0_N SCONN288_H44441004_PIP-SCONN,HA   I111 @BASEBOARD_FAB2_LIB.BASEBOARD_FAB2(SCH_1):PAGE45

M_B_CS_N<1> @BASEBOARD_FAB2_LIB.BASEBOARD_FAB2(SCH_1):M_B_CS_N(1)
  U5D1  R50 DDR1_CS_N<1> SKX_EXT_B_BGA1-IC,TBD   I172 @BASEBOARD_FAB2_LIB.BASEBOARD_FAB2(SCH_1):PAGE24
  J4G2   89   S1_N SCONN288_H44441004_PIP-SCONN,HA   I111 @BASEBOARD_FAB2_LIB.BASEBOARD_FAB2(SCH_1):PAGE45

M_B_CS_N<2> @BASEBOARD_FAB2_LIB.BASEBOARD_FAB2(SCH_1):M_B_CS_N(2)
  U5D1  N46 DDR1_CS_N<2> SKX_EXT_B_BGA1-IC,TBD   I172 @BASEBOARD_FAB2_LIB.BASEBOARD_FAB2(SCH_1):PAGE24
  J4G2   93 S2_N_C<0> SCONN288_H44441004_PIP-SCONN,HA   I111 @BASEBOARD_FAB2_LIB.BASEBOARD_FAB2(SCH_1):PAGE45

M_B_CS_N<3> @BASEBOARD_FAB2_LIB.BASEBOARD_FAB2(SCH_1):M_B_CS_N(3)
  U5D1  V47 DDR1_CS_N<3> SKX_EXT_B_BGA1-IC,TBD   I172 @BASEBOARD_FAB2_LIB.BASEBOARD_FAB2(SCH_1):PAGE24
  J4G2  237 S3_N_C<1> SCONN288_H44441004_PIP-SCONN,HA   I111 @BASEBOARD_FAB2_LIB.BASEBOARD_FAB2(SCH_1):PAGE45

M_B_CS_N<4> @BASEBOARD_FAB2_LIB.BASEBOARD_FAB2(SCH_1):M_B_CS_N(4)
  U5D1  J50 DDR1_CS_N<4> SKX_EXT_B_BGA1-IC,TBD   I172 @BASEBOARD_FAB2_LIB.BASEBOARD_FAB2(SCH_1):PAGE24
  J6U1   84   S0_N SCONN288_H44441003_PIP-SCONN,HA    I14 @BASEBOARD_FAB2_LIB.BASEBOARD_FAB2(SCH_1):PAGE46

M_B_CS_N<5> @BASEBOARD_FAB2_LIB.BASEBOARD_FAB2(SCH_1):M_B_CS_N(5)
  U5D1  T49 DDR1_CS_N<5> SKX_EXT_B_BGA1-IC,TBD   I172 @BASEBOARD_FAB2_LIB.BASEBOARD_FAB2(SCH_1):PAGE24
  J6U1   89   S1_N SCONN288_H44441003_PIP-SCONN,HA    I14 @BASEBOARD_FAB2_LIB.BASEBOARD_FAB2(SCH_1):PAGE46

M_B_CS_N<6> @BASEBOARD_FAB2_LIB.BASEBOARD_FAB2(SCH_1):M_B_CS_N(6)
  U5D1  M45 DDR1_CS_N<6> SKX_EXT_B_BGA1-IC,TBD   I172 @BASEBOARD_FAB2_LIB.BASEBOARD_FAB2(SCH_1):PAGE24
  J6U1   93 S2_N_C<0> SCONN288_H44441003_PIP-SCONN,HA    I14 @BASEBOARD_FAB2_LIB.BASEBOARD_FAB2(SCH_1):PAGE46

M_B_CS_N<7> @BASEBOARD_FAB2_LIB.BASEBOARD_FAB2(SCH_1):M_B_CS_N(7)
  U5D1  R46 DDR1_CS_N<7> SKX_EXT_B_BGA1-IC,TBD   I172 @BASEBOARD_FAB2_LIB.BASEBOARD_FAB2(SCH_1):PAGE24
  J6U1  237 S3_N_C<1> SCONN288_H44441003_PIP-SCONN,HA    I14 @BASEBOARD_FAB2_LIB.BASEBOARD_FAB2(SCH_1):PAGE46

M_B_DQ<0> @BASEBOARD_FAB2_LIB.BASEBOARD_FAB2(SCH_1):M_B_DQ(0)
  U5D1 AV81 DDR1_DQ<0> SKX_EXT_B_BGA1-IC,TBD   I172 @BASEBOARD_FAB2_LIB.BASEBOARD_FAB2(SCH_1):PAGE24
  J4G2  150  DQ<1> SCONN288_H44441004_PIP-SCONN,HA   I111 @BASEBOARD_FAB2_LIB.BASEBOARD_FAB2(SCH_1):PAGE45
  J6U1    5  DQ<0> SCONN288_H44441003_PIP-SCONN,HA    I14 @BASEBOARD_FAB2_LIB.BASEBOARD_FAB2(SCH_1):PAGE46

M_B_DQ<10> @BASEBOARD_FAB2_LIB.BASEBOARD_FAB2(SCH_1):M_B_DQ(10)
  U5D1 AC82 DDR1_DQ<10> SKX_EXT_B_BGA1-IC,TBD   I172 @BASEBOARD_FAB2_LIB.BASEBOARD_FAB2(SCH_1):PAGE24
  J4G2  168 DQ<11> SCONN288_H44441004_PIP-SCONN,HA   I111 @BASEBOARD_FAB2_LIB.BASEBOARD_FAB2(SCH_1):PAGE45
  J6U1   23 DQ<10> SCONN288_H44441003_PIP-SCONN,HA    I14 @BASEBOARD_FAB2_LIB.BASEBOARD_FAB2(SCH_1):PAGE46

M_B_DQ<11> @BASEBOARD_FAB2_LIB.BASEBOARD_FAB2(SCH_1):M_B_DQ(11)
  U5D1 AB81 DDR1_DQ<11> SKX_EXT_B_BGA1-IC,TBD   I172 @BASEBOARD_FAB2_LIB.BASEBOARD_FAB2(SCH_1):PAGE24
  J4G2   23 DQ<10> SCONN288_H44441004_PIP-SCONN,HA   I111 @BASEBOARD_FAB2_LIB.BASEBOARD_FAB2(SCH_1):PAGE45
  J6U1  168 DQ<11> SCONN288_H44441003_PIP-SCONN,HA    I14 @BASEBOARD_FAB2_LIB.BASEBOARD_FAB2(SCH_1):PAGE46

M_B_DQ<12> @BASEBOARD_FAB2_LIB.BASEBOARD_FAB2(SCH_1):M_B_DQ(12)
  U5D1 AJ80 DDR1_DQ<12> SKX_EXT_B_BGA1-IC,TBD   I172 @BASEBOARD_FAB2_LIB.BASEBOARD_FAB2(SCH_1):PAGE24
  J4G2  159 DQ<13> SCONN288_H44441004_PIP-SCONN,HA   I111 @BASEBOARD_FAB2_LIB.BASEBOARD_FAB2(SCH_1):PAGE45
  J6U1   14 DQ<12> SCONN288_H44441003_PIP-SCONN,HA    I14 @BASEBOARD_FAB2_LIB.BASEBOARD_FAB2(SCH_1):PAGE46

M_B_DQ<13> @BASEBOARD_FAB2_LIB.BASEBOARD_FAB2(SCH_1):M_B_DQ(13)
  U5D1 AH79 DDR1_DQ<13> SKX_EXT_B_BGA1-IC,TBD   I172 @BASEBOARD_FAB2_LIB.BASEBOARD_FAB2(SCH_1):PAGE24
  J4G2   14 DQ<12> SCONN288_H44441004_PIP-SCONN,HA   I111 @BASEBOARD_FAB2_LIB.BASEBOARD_FAB2(SCH_1):PAGE45
  J6U1  159 DQ<13> SCONN288_H44441003_PIP-SCONN,HA    I14 @BASEBOARD_FAB2_LIB.BASEBOARD_FAB2(SCH_1):PAGE46

M_B_DQ<14> @BASEBOARD_FAB2_LIB.BASEBOARD_FAB2(SCH_1):M_B_DQ(14)
  U5D1 AE82 DDR1_DQ<14> SKX_EXT_B_BGA1-IC,TBD   I172 @BASEBOARD_FAB2_LIB.BASEBOARD_FAB2(SCH_1):PAGE24
  J4G2  166 DQ<15> SCONN288_H44441004_PIP-SCONN,HA   I111 @BASEBOARD_FAB2_LIB.BASEBOARD_FAB2(SCH_1):PAGE45
  J6U1   21 DQ<14> SCONN288_H44441003_PIP-SCONN,HA    I14 @BASEBOARD_FAB2_LIB.BASEBOARD_FAB2(SCH_1):PAGE46

M_B_DQ<15> @BASEBOARD_FAB2_LIB.BASEBOARD_FAB2(SCH_1):M_B_DQ(15)
  U5D1 AC80 DDR1_DQ<15> SKX_EXT_B_BGA1-IC,TBD   I172 @BASEBOARD_FAB2_LIB.BASEBOARD_FAB2(SCH_1):PAGE24
  J4G2   21 DQ<14> SCONN288_H44441004_PIP-SCONN,HA   I111 @BASEBOARD_FAB2_LIB.BASEBOARD_FAB2(SCH_1):PAGE45
  J6U1  166 DQ<15> SCONN288_H44441003_PIP-SCONN,HA    I14 @BASEBOARD_FAB2_LIB.BASEBOARD_FAB2(SCH_1):PAGE46

M_B_DQ<16> @BASEBOARD_FAB2_LIB.BASEBOARD_FAB2(SCH_1):M_B_DQ(16)
  U5D1  E80 DDR1_DQ<16> SKX_EXT_B_BGA1-IC,TBD   I172 @BASEBOARD_FAB2_LIB.BASEBOARD_FAB2(SCH_1):PAGE24
  J4G2  172 DQ<17> SCONN288_H44441004_PIP-SCONN,HA   I111 @BASEBOARD_FAB2_LIB.BASEBOARD_FAB2(SCH_1):PAGE45
  J6U1   27 DQ<16> SCONN288_H44441003_PIP-SCONN,HA    I14 @BASEBOARD_FAB2_LIB.BASEBOARD_FAB2(SCH_1):PAGE46

M_B_DQ<17> @BASEBOARD_FAB2_LIB.BASEBOARD_FAB2(SCH_1):M_B_DQ(17)
  U5D1  J80 DDR1_DQ<17> SKX_EXT_B_BGA1-IC,TBD   I172 @BASEBOARD_FAB2_LIB.BASEBOARD_FAB2(SCH_1):PAGE24
  J4G2   27 DQ<16> SCONN288_H44441004_PIP-SCONN,HA   I111 @BASEBOARD_FAB2_LIB.BASEBOARD_FAB2(SCH_1):PAGE45
  J6U1  172 DQ<17> SCONN288_H44441003_PIP-SCONN,HA    I14 @BASEBOARD_FAB2_LIB.BASEBOARD_FAB2(SCH_1):PAGE46

M_B_DQ<18> @BASEBOARD_FAB2_LIB.BASEBOARD_FAB2(SCH_1):M_B_DQ(18)
  U5D1  F77 DDR1_DQ<18> SKX_EXT_B_BGA1-IC,TBD   I172 @BASEBOARD_FAB2_LIB.BASEBOARD_FAB2(SCH_1):PAGE24
  J4G2  179 DQ<19> SCONN288_H44441004_PIP-SCONN,HA   I111 @BASEBOARD_FAB2_LIB.BASEBOARD_FAB2(SCH_1):PAGE45
  J6U1   34 DQ<18> SCONN288_H44441003_PIP-SCONN,HA    I14 @BASEBOARD_FAB2_LIB.BASEBOARD_FAB2(SCH_1):PAGE46

M_B_DQ<19> @BASEBOARD_FAB2_LIB.BASEBOARD_FAB2(SCH_1):M_B_DQ(19)
  U5D1  H77 DDR1_DQ<19> SKX_EXT_B_BGA1-IC,TBD   I172 @BASEBOARD_FAB2_LIB.BASEBOARD_FAB2(SCH_1):PAGE24
  J4G2   34 DQ<18> SCONN288_H44441004_PIP-SCONN,HA   I111 @BASEBOARD_FAB2_LIB.BASEBOARD_FAB2(SCH_1):PAGE45
  J6U1  179 DQ<19> SCONN288_H44441003_PIP-SCONN,HA    I14 @BASEBOARD_FAB2_LIB.BASEBOARD_FAB2(SCH_1):PAGE46

M_B_DQ<1> @BASEBOARD_FAB2_LIB.BASEBOARD_FAB2(SCH_1):M_B_DQ(1)
  U5D1 AT79 DDR1_DQ<1> SKX_EXT_B_BGA1-IC,TBD   I172 @BASEBOARD_FAB2_LIB.BASEBOARD_FAB2(SCH_1):PAGE24
  J4G2    5  DQ<0> SCONN288_H44441004_PIP-SCONN,HA   I111 @BASEBOARD_FAB2_LIB.BASEBOARD_FAB2(SCH_1):PAGE45
  J6U1  150  DQ<1> SCONN288_H44441003_PIP-SCONN,HA    I14 @BASEBOARD_FAB2_LIB.BASEBOARD_FAB2(SCH_1):PAGE46

M_B_DQ<20> @BASEBOARD_FAB2_LIB.BASEBOARD_FAB2(SCH_1):M_B_DQ(20)
  U5D1  F81 DDR1_DQ<20> SKX_EXT_B_BGA1-IC,TBD   I172 @BASEBOARD_FAB2_LIB.BASEBOARD_FAB2(SCH_1):PAGE24
  J4G2  170 DQ<21> SCONN288_H44441004_PIP-SCONN,HA   I111 @BASEBOARD_FAB2_LIB.BASEBOARD_FAB2(SCH_1):PAGE45
  J6U1   25 DQ<20> SCONN288_H44441003_PIP-SCONN,HA    I14 @BASEBOARD_FAB2_LIB.BASEBOARD_FAB2(SCH_1):PAGE46

M_B_DQ<21> @BASEBOARD_FAB2_LIB.BASEBOARD_FAB2(SCH_1):M_B_DQ(21)
  U5D1  H81 DDR1_DQ<21> SKX_EXT_B_BGA1-IC,TBD   I172 @BASEBOARD_FAB2_LIB.BASEBOARD_FAB2(SCH_1):PAGE24
  J4G2   25 DQ<20> SCONN288_H44441004_PIP-SCONN,HA   I111 @BASEBOARD_FAB2_LIB.BASEBOARD_FAB2(SCH_1):PAGE45
  J6U1  170 DQ<21> SCONN288_H44441003_PIP-SCONN,HA    I14 @BASEBOARD_FAB2_LIB.BASEBOARD_FAB2(SCH_1):PAGE46

M_B_DQ<22> @BASEBOARD_FAB2_LIB.BASEBOARD_FAB2(SCH_1):M_B_DQ(22)
  U5D1  E78 DDR1_DQ<22> SKX_EXT_B_BGA1-IC,TBD   I172 @BASEBOARD_FAB2_LIB.BASEBOARD_FAB2(SCH_1):PAGE24
  J4G2  177 DQ<23> SCONN288_H44441004_PIP-SCONN,HA   I111 @BASEBOARD_FAB2_LIB.BASEBOARD_FAB2(SCH_1):PAGE45
  J6U1   32 DQ<22> SCONN288_H44441003_PIP-SCONN,HA    I14 @BASEBOARD_FAB2_LIB.BASEBOARD_FAB2(SCH_1):PAGE46

M_B_DQ<23> @BASEBOARD_FAB2_LIB.BASEBOARD_FAB2(SCH_1):M_B_DQ(23)
  U5D1  J78 DDR1_DQ<23> SKX_EXT_B_BGA1-IC,TBD   I172 @BASEBOARD_FAB2_LIB.BASEBOARD_FAB2(SCH_1):PAGE24
  J4G2   32 DQ<22> SCONN288_H44441004_PIP-SCONN,HA   I111 @BASEBOARD_FAB2_LIB.BASEBOARD_FAB2(SCH_1):PAGE45
  J6U1  177 DQ<23> SCONN288_H44441003_PIP-SCONN,HA    I14 @BASEBOARD_FAB2_LIB.BASEBOARD_FAB2(SCH_1):PAGE46

M_B_DQ<24> @BASEBOARD_FAB2_LIB.BASEBOARD_FAB2(SCH_1):M_B_DQ(24)
  U5D1  D75 DDR1_DQ<24> SKX_EXT_B_BGA1-IC,TBD   I172 @BASEBOARD_FAB2_LIB.BASEBOARD_FAB2(SCH_1):PAGE24
  J4G2  183 DQ<25> SCONN288_H44441004_PIP-SCONN,HA   I111 @BASEBOARD_FAB2_LIB.BASEBOARD_FAB2(SCH_1):PAGE45
  J6U1   38 DQ<24> SCONN288_H44441003_PIP-SCONN,HA    I14 @BASEBOARD_FAB2_LIB.BASEBOARD_FAB2(SCH_1):PAGE46

M_B_DQ<25> @BASEBOARD_FAB2_LIB.BASEBOARD_FAB2(SCH_1):M_B_DQ(25)
  U5D1  C74 DDR1_DQ<25> SKX_EXT_B_BGA1-IC,TBD   I172 @BASEBOARD_FAB2_LIB.BASEBOARD_FAB2(SCH_1):PAGE24
  J4G2   38 DQ<24> SCONN288_H44441004_PIP-SCONN,HA   I111 @BASEBOARD_FAB2_LIB.BASEBOARD_FAB2(SCH_1):PAGE45
  J6U1  183 DQ<25> SCONN288_H44441003_PIP-SCONN,HA    I14 @BASEBOARD_FAB2_LIB.BASEBOARD_FAB2(SCH_1):PAGE46

M_B_DQ<26> @BASEBOARD_FAB2_LIB.BASEBOARD_FAB2(SCH_1):M_B_DQ(26)
  U5D1  D71 DDR1_DQ<26> SKX_EXT_B_BGA1-IC,TBD   I172 @BASEBOARD_FAB2_LIB.BASEBOARD_FAB2(SCH_1):PAGE24
  J4G2  190 DQ<27> SCONN288_H44441004_PIP-SCONN,HA   I111 @BASEBOARD_FAB2_LIB.BASEBOARD_FAB2(SCH_1):PAGE45
  J6U1   45 DQ<26> SCONN288_H44441003_PIP-SCONN,HA    I14 @BASEBOARD_FAB2_LIB.BASEBOARD_FAB2(SCH_1):PAGE46

M_B_DQ<27> @BASEBOARD_FAB2_LIB.BASEBOARD_FAB2(SCH_1):M_B_DQ(27)
  U5D1  F71 DDR1_DQ<27> SKX_EXT_B_BGA1-IC,TBD   I172 @BASEBOARD_FAB2_LIB.BASEBOARD_FAB2(SCH_1):PAGE24
  J4G2   45 DQ<26> SCONN288_H44441004_PIP-SCONN,HA   I111 @BASEBOARD_FAB2_LIB.BASEBOARD_FAB2(SCH_1):PAGE45
  J6U1  190 DQ<27> SCONN288_H44441003_PIP-SCONN,HA    I14 @BASEBOARD_FAB2_LIB.BASEBOARD_FAB2(SCH_1):PAGE46

M_B_DQ<28> @BASEBOARD_FAB2_LIB.BASEBOARD_FAB2(SCH_1):M_B_DQ(28)
  U5D1  F75 DDR1_DQ<28> SKX_EXT_B_BGA1-IC,TBD   I172 @BASEBOARD_FAB2_LIB.BASEBOARD_FAB2(SCH_1):PAGE24
  J4G2  181 DQ<29> SCONN288_H44441004_PIP-SCONN,HA   I111 @BASEBOARD_FAB2_LIB.BASEBOARD_FAB2(SCH_1):PAGE45
  J6U1   36 DQ<28> SCONN288_H44441003_PIP-SCONN,HA    I14 @BASEBOARD_FAB2_LIB.BASEBOARD_FAB2(SCH_1):PAGE46

M_B_DQ<29> @BASEBOARD_FAB2_LIB.BASEBOARD_FAB2(SCH_1):M_B_DQ(29)
  U5D1  G74 DDR1_DQ<29> SKX_EXT_B_BGA1-IC,TBD   I172 @BASEBOARD_FAB2_LIB.BASEBOARD_FAB2(SCH_1):PAGE24
  J4G2   36 DQ<28> SCONN288_H44441004_PIP-SCONN,HA   I111 @BASEBOARD_FAB2_LIB.BASEBOARD_FAB2(SCH_1):PAGE45
  J6U1  181 DQ<29> SCONN288_H44441003_PIP-SCONN,HA    I14 @BASEBOARD_FAB2_LIB.BASEBOARD_FAB2(SCH_1):PAGE46

M_B_DQ<2> @BASEBOARD_FAB2_LIB.BASEBOARD_FAB2(SCH_1):M_B_DQ(2)
  U5D1 AN82 DDR1_DQ<2> SKX_EXT_B_BGA1-IC,TBD   I172 @BASEBOARD_FAB2_LIB.BASEBOARD_FAB2(SCH_1):PAGE24
  J4G2  157  DQ<3> SCONN288_H44441004_PIP-SCONN,HA   I111 @BASEBOARD_FAB2_LIB.BASEBOARD_FAB2(SCH_1):PAGE45
  J6U1   12  DQ<2> SCONN288_H44441003_PIP-SCONN,HA    I14 @BASEBOARD_FAB2_LIB.BASEBOARD_FAB2(SCH_1):PAGE46

M_B_DQ<30> @BASEBOARD_FAB2_LIB.BASEBOARD_FAB2(SCH_1):M_B_DQ(30)
  U5D1  C72 DDR1_DQ<30> SKX_EXT_B_BGA1-IC,TBD   I172 @BASEBOARD_FAB2_LIB.BASEBOARD_FAB2(SCH_1):PAGE24
  J4G2  188 DQ<31> SCONN288_H44441004_PIP-SCONN,HA   I111 @BASEBOARD_FAB2_LIB.BASEBOARD_FAB2(SCH_1):PAGE45
  J6U1   43 DQ<30> SCONN288_H44441003_PIP-SCONN,HA    I14 @BASEBOARD_FAB2_LIB.BASEBOARD_FAB2(SCH_1):PAGE46

M_B_DQ<31> @BASEBOARD_FAB2_LIB.BASEBOARD_FAB2(SCH_1):M_B_DQ(31)
  U5D1  G72 DDR1_DQ<31> SKX_EXT_B_BGA1-IC,TBD   I172 @BASEBOARD_FAB2_LIB.BASEBOARD_FAB2(SCH_1):PAGE24
  J4G2   43 DQ<30> SCONN288_H44441004_PIP-SCONN,HA   I111 @BASEBOARD_FAB2_LIB.BASEBOARD_FAB2(SCH_1):PAGE45
  J6U1  188 DQ<31> SCONN288_H44441003_PIP-SCONN,HA    I14 @BASEBOARD_FAB2_LIB.BASEBOARD_FAB2(SCH_1):PAGE46

M_B_DQ<32> @BASEBOARD_FAB2_LIB.BASEBOARD_FAB2(SCH_1):M_B_DQ(32)
  U5D1  K43 DDR1_DQ<32> SKX_EXT_B_BGA1-IC,TBD   I172 @BASEBOARD_FAB2_LIB.BASEBOARD_FAB2(SCH_1):PAGE24
  J4G2  242 DQ<33> SCONN288_H44441004_PIP-SCONN,HA   I111 @BASEBOARD_FAB2_LIB.BASEBOARD_FAB2(SCH_1):PAGE45
  J6U1   97 DQ<32> SCONN288_H44441003_PIP-SCONN,HA    I14 @BASEBOARD_FAB2_LIB.BASEBOARD_FAB2(SCH_1):PAGE46

M_B_DQ<33> @BASEBOARD_FAB2_LIB.BASEBOARD_FAB2(SCH_1):M_B_DQ(33)
  U5D1  H43 DDR1_DQ<33> SKX_EXT_B_BGA1-IC,TBD   I172 @BASEBOARD_FAB2_LIB.BASEBOARD_FAB2(SCH_1):PAGE24
  J4G2   97 DQ<32> SCONN288_H44441004_PIP-SCONN,HA   I111 @BASEBOARD_FAB2_LIB.BASEBOARD_FAB2(SCH_1):PAGE45
  J6U1  242 DQ<33> SCONN288_H44441003_PIP-SCONN,HA    I14 @BASEBOARD_FAB2_LIB.BASEBOARD_FAB2(SCH_1):PAGE46

M_B_DQ<34> @BASEBOARD_FAB2_LIB.BASEBOARD_FAB2(SCH_1):M_B_DQ(34)
  U5D1  L40 DDR1_DQ<34> SKX_EXT_B_BGA1-IC,TBD   I172 @BASEBOARD_FAB2_LIB.BASEBOARD_FAB2(SCH_1):PAGE24
  J4G2  249 DQ<35> SCONN288_H44441004_PIP-SCONN,HA   I111 @BASEBOARD_FAB2_LIB.BASEBOARD_FAB2(SCH_1):PAGE45
  J6U1  104 DQ<34> SCONN288_H44441003_PIP-SCONN,HA    I14 @BASEBOARD_FAB2_LIB.BASEBOARD_FAB2(SCH_1):PAGE46

M_B_DQ<35> @BASEBOARD_FAB2_LIB.BASEBOARD_FAB2(SCH_1):M_B_DQ(35)
  U5D1  N40 DDR1_DQ<35> SKX_EXT_B_BGA1-IC,TBD   I172 @BASEBOARD_FAB2_LIB.BASEBOARD_FAB2(SCH_1):PAGE24
  J4G2  104 DQ<34> SCONN288_H44441004_PIP-SCONN,HA   I111 @BASEBOARD_FAB2_LIB.BASEBOARD_FAB2(SCH_1):PAGE45
  J6U1  249 DQ<35> SCONN288_H44441003_PIP-SCONN,HA    I14 @BASEBOARD_FAB2_LIB.BASEBOARD_FAB2(SCH_1):PAGE46

M_B_DQ<36> @BASEBOARD_FAB2_LIB.BASEBOARD_FAB2(SCH_1):M_B_DQ(36)
  U5D1  P43 DDR1_DQ<36> SKX_EXT_B_BGA1-IC,TBD   I172 @BASEBOARD_FAB2_LIB.BASEBOARD_FAB2(SCH_1):PAGE24
  J4G2  240 DQ<37> SCONN288_H44441004_PIP-SCONN,HA   I111 @BASEBOARD_FAB2_LIB.BASEBOARD_FAB2(SCH_1):PAGE45
  J6U1   95 DQ<36> SCONN288_H44441003_PIP-SCONN,HA    I14 @BASEBOARD_FAB2_LIB.BASEBOARD_FAB2(SCH_1):PAGE46

M_B_DQ<37> @BASEBOARD_FAB2_LIB.BASEBOARD_FAB2(SCH_1):M_B_DQ(37)
  U5D1  T43 DDR1_DQ<37> SKX_EXT_B_BGA1-IC,TBD   I172 @BASEBOARD_FAB2_LIB.BASEBOARD_FAB2(SCH_1):PAGE24
  J4G2   95 DQ<36> SCONN288_H44441004_PIP-SCONN,HA   I111 @BASEBOARD_FAB2_LIB.BASEBOARD_FAB2(SCH_1):PAGE45
  J6U1  240 DQ<37> SCONN288_H44441003_PIP-SCONN,HA    I14 @BASEBOARD_FAB2_LIB.BASEBOARD_FAB2(SCH_1):PAGE46

M_B_DQ<38> @BASEBOARD_FAB2_LIB.BASEBOARD_FAB2(SCH_1):M_B_DQ(38)
  U5D1  K41 DDR1_DQ<38> SKX_EXT_B_BGA1-IC,TBD   I172 @BASEBOARD_FAB2_LIB.BASEBOARD_FAB2(SCH_1):PAGE24
  J4G2  247 DQ<39> SCONN288_H44441004_PIP-SCONN,HA   I111 @BASEBOARD_FAB2_LIB.BASEBOARD_FAB2(SCH_1):PAGE45
  J6U1  102 DQ<38> SCONN288_H44441003_PIP-SCONN,HA    I14 @BASEBOARD_FAB2_LIB.BASEBOARD_FAB2(SCH_1):PAGE46

M_B_DQ<39> @BASEBOARD_FAB2_LIB.BASEBOARD_FAB2(SCH_1):M_B_DQ(39)
  U5D1  P41 DDR1_DQ<39> SKX_EXT_B_BGA1-IC,TBD   I172 @BASEBOARD_FAB2_LIB.BASEBOARD_FAB2(SCH_1):PAGE24
  J4G2  102 DQ<38> SCONN288_H44441004_PIP-SCONN,HA   I111 @BASEBOARD_FAB2_LIB.BASEBOARD_FAB2(SCH_1):PAGE45
  J6U1  247 DQ<39> SCONN288_H44441003_PIP-SCONN,HA    I14 @BASEBOARD_FAB2_LIB.BASEBOARD_FAB2(SCH_1):PAGE46

M_B_DQ<3> @BASEBOARD_FAB2_LIB.BASEBOARD_FAB2(SCH_1):M_B_DQ(3)
  U5D1 AM81 DDR1_DQ<3> SKX_EXT_B_BGA1-IC,TBD   I172 @BASEBOARD_FAB2_LIB.BASEBOARD_FAB2(SCH_1):PAGE24
  J4G2   12  DQ<2> SCONN288_H44441004_PIP-SCONN,HA   I111 @BASEBOARD_FAB2_LIB.BASEBOARD_FAB2(SCH_1):PAGE45
  J6U1  157  DQ<3> SCONN288_H44441003_PIP-SCONN,HA    I14 @BASEBOARD_FAB2_LIB.BASEBOARD_FAB2(SCH_1):PAGE46

M_B_DQ<40> @BASEBOARD_FAB2_LIB.BASEBOARD_FAB2(SCH_1):M_B_DQ(40)
  U5D1  C36 DDR1_DQ<40> SKX_EXT_B_BGA1-IC,TBD   I172 @BASEBOARD_FAB2_LIB.BASEBOARD_FAB2(SCH_1):PAGE24
  J4G2  253 DQ<41> SCONN288_H44441004_PIP-SCONN,HA   I111 @BASEBOARD_FAB2_LIB.BASEBOARD_FAB2(SCH_1):PAGE45
  J6U1  108 DQ<40> SCONN288_H44441003_PIP-SCONN,HA    I14 @BASEBOARD_FAB2_LIB.BASEBOARD_FAB2(SCH_1):PAGE46

M_B_DQ<41> @BASEBOARD_FAB2_LIB.BASEBOARD_FAB2(SCH_1):M_B_DQ(41)
  U5D1  B35 DDR1_DQ<41> SKX_EXT_B_BGA1-IC,TBD   I172 @BASEBOARD_FAB2_LIB.BASEBOARD_FAB2(SCH_1):PAGE24
  J4G2  108 DQ<40> SCONN288_H44441004_PIP-SCONN,HA   I111 @BASEBOARD_FAB2_LIB.BASEBOARD_FAB2(SCH_1):PAGE45
  J6U1  253 DQ<41> SCONN288_H44441003_PIP-SCONN,HA    I14 @BASEBOARD_FAB2_LIB.BASEBOARD_FAB2(SCH_1):PAGE46

M_B_DQ<42> @BASEBOARD_FAB2_LIB.BASEBOARD_FAB2(SCH_1):M_B_DQ(42)
  U5D1  C32 DDR1_DQ<42> SKX_EXT_B_BGA1-IC,TBD   I172 @BASEBOARD_FAB2_LIB.BASEBOARD_FAB2(SCH_1):PAGE24
  J4G2  260 DQ<43> SCONN288_H44441004_PIP-SCONN,HA   I111 @BASEBOARD_FAB2_LIB.BASEBOARD_FAB2(SCH_1):PAGE45
  J6U1  115 DQ<42> SCONN288_H44441003_PIP-SCONN,HA    I14 @BASEBOARD_FAB2_LIB.BASEBOARD_FAB2(SCH_1):PAGE46

M_B_DQ<43> @BASEBOARD_FAB2_LIB.BASEBOARD_FAB2(SCH_1):M_B_DQ(43)
  U5D1  E32 DDR1_DQ<43> SKX_EXT_B_BGA1-IC,TBD   I172 @BASEBOARD_FAB2_LIB.BASEBOARD_FAB2(SCH_1):PAGE24
  J4G2  115 DQ<42> SCONN288_H44441004_PIP-SCONN,HA   I111 @BASEBOARD_FAB2_LIB.BASEBOARD_FAB2(SCH_1):PAGE45
  J6U1  260 DQ<43> SCONN288_H44441003_PIP-SCONN,HA    I14 @BASEBOARD_FAB2_LIB.BASEBOARD_FAB2(SCH_1):PAGE46

M_B_DQ<44> @BASEBOARD_FAB2_LIB.BASEBOARD_FAB2(SCH_1):M_B_DQ(44)
  U5D1  E36 DDR1_DQ<44> SKX_EXT_B_BGA1-IC,TBD   I172 @BASEBOARD_FAB2_LIB.BASEBOARD_FAB2(SCH_1):PAGE24
  J4G2  251 DQ<45> SCONN288_H44441004_PIP-SCONN,HA   I111 @BASEBOARD_FAB2_LIB.BASEBOARD_FAB2(SCH_1):PAGE45
  J6U1  106 DQ<44> SCONN288_H44441003_PIP-SCONN,HA    I14 @BASEBOARD_FAB2_LIB.BASEBOARD_FAB2(SCH_1):PAGE46

M_B_DQ<45> @BASEBOARD_FAB2_LIB.BASEBOARD_FAB2(SCH_1):M_B_DQ(45)
  U5D1  F35 DDR1_DQ<45> SKX_EXT_B_BGA1-IC,TBD   I172 @BASEBOARD_FAB2_LIB.BASEBOARD_FAB2(SCH_1):PAGE24
  J4G2  106 DQ<44> SCONN288_H44441004_PIP-SCONN,HA   I111 @BASEBOARD_FAB2_LIB.BASEBOARD_FAB2(SCH_1):PAGE45
  J6U1  251 DQ<45> SCONN288_H44441003_PIP-SCONN,HA    I14 @BASEBOARD_FAB2_LIB.BASEBOARD_FAB2(SCH_1):PAGE46

M_B_DQ<46> @BASEBOARD_FAB2_LIB.BASEBOARD_FAB2(SCH_1):M_B_DQ(46)
  U5D1  B33 DDR1_DQ<46> SKX_EXT_B_BGA1-IC,TBD   I172 @BASEBOARD_FAB2_LIB.BASEBOARD_FAB2(SCH_1):PAGE24
  J4G2  258 DQ<47> SCONN288_H44441004_PIP-SCONN,HA   I111 @BASEBOARD_FAB2_LIB.BASEBOARD_FAB2(SCH_1):PAGE45
  J6U1  113 DQ<46> SCONN288_H44441003_PIP-SCONN,HA    I14 @BASEBOARD_FAB2_LIB.BASEBOARD_FAB2(SCH_1):PAGE46

M_B_DQ<47> @BASEBOARD_FAB2_LIB.BASEBOARD_FAB2(SCH_1):M_B_DQ(47)
  U5D1  F33 DDR1_DQ<47> SKX_EXT_B_BGA1-IC,TBD   I172 @BASEBOARD_FAB2_LIB.BASEBOARD_FAB2(SCH_1):PAGE24
  J4G2  113 DQ<46> SCONN288_H44441004_PIP-SCONN,HA   I111 @BASEBOARD_FAB2_LIB.BASEBOARD_FAB2(SCH_1):PAGE45
  J6U1  258 DQ<47> SCONN288_H44441003_PIP-SCONN,HA    I14 @BASEBOARD_FAB2_LIB.BASEBOARD_FAB2(SCH_1):PAGE46

M_B_DQ<48> @BASEBOARD_FAB2_LIB.BASEBOARD_FAB2(SCH_1):M_B_DQ(48)
  U5D1  C30 DDR1_DQ<48> SKX_EXT_B_BGA1-IC,TBD   I172 @BASEBOARD_FAB2_LIB.BASEBOARD_FAB2(SCH_1):PAGE24
  J4G2  264 DQ<49> SCONN288_H44441004_PIP-SCONN,HA   I111 @BASEBOARD_FAB2_LIB.BASEBOARD_FAB2(SCH_1):PAGE45
  J6U1  119 DQ<48> SCONN288_H44441003_PIP-SCONN,HA    I14 @BASEBOARD_FAB2_LIB.BASEBOARD_FAB2(SCH_1):PAGE46

M_B_DQ<49> @BASEBOARD_FAB2_LIB.BASEBOARD_FAB2(SCH_1):M_B_DQ(49)
  U5D1  B29 DDR1_DQ<49> SKX_EXT_B_BGA1-IC,TBD   I172 @BASEBOARD_FAB2_LIB.BASEBOARD_FAB2(SCH_1):PAGE24
  J4G2  119 DQ<48> SCONN288_H44441004_PIP-SCONN,HA   I111 @BASEBOARD_FAB2_LIB.BASEBOARD_FAB2(SCH_1):PAGE45
  J6U1  264 DQ<49> SCONN288_H44441003_PIP-SCONN,HA    I14 @BASEBOARD_FAB2_LIB.BASEBOARD_FAB2(SCH_1):PAGE46

M_B_DQ<4> @BASEBOARD_FAB2_LIB.BASEBOARD_FAB2(SCH_1):M_B_DQ(4)
  U5D1 AW80 DDR1_DQ<4> SKX_EXT_B_BGA1-IC,TBD   I172 @BASEBOARD_FAB2_LIB.BASEBOARD_FAB2(SCH_1):PAGE24
  J4G2  148  DQ<5> SCONN288_H44441004_PIP-SCONN,HA   I111 @BASEBOARD_FAB2_LIB.BASEBOARD_FAB2(SCH_1):PAGE45
  J6U1    3  DQ<4> SCONN288_H44441003_PIP-SCONN,HA    I14 @BASEBOARD_FAB2_LIB.BASEBOARD_FAB2(SCH_1):PAGE46

M_B_DQ<50> @BASEBOARD_FAB2_LIB.BASEBOARD_FAB2(SCH_1):M_B_DQ(50)
  U5D1  C26 DDR1_DQ<50> SKX_EXT_B_BGA1-IC,TBD   I172 @BASEBOARD_FAB2_LIB.BASEBOARD_FAB2(SCH_1):PAGE24
  J4G2  271 DQ<51> SCONN288_H44441004_PIP-SCONN,HA   I111 @BASEBOARD_FAB2_LIB.BASEBOARD_FAB2(SCH_1):PAGE45
  J6U1  126 DQ<50> SCONN288_H44441003_PIP-SCONN,HA    I14 @BASEBOARD_FAB2_LIB.BASEBOARD_FAB2(SCH_1):PAGE46

M_B_DQ<51> @BASEBOARD_FAB2_LIB.BASEBOARD_FAB2(SCH_1):M_B_DQ(51)
  U5D1  E26 DDR1_DQ<51> SKX_EXT_B_BGA1-IC,TBD   I172 @BASEBOARD_FAB2_LIB.BASEBOARD_FAB2(SCH_1):PAGE24
  J4G2  126 DQ<50> SCONN288_H44441004_PIP-SCONN,HA   I111 @BASEBOARD_FAB2_LIB.BASEBOARD_FAB2(SCH_1):PAGE45
  J6U1  271 DQ<51> SCONN288_H44441003_PIP-SCONN,HA    I14 @BASEBOARD_FAB2_LIB.BASEBOARD_FAB2(SCH_1):PAGE46

M_B_DQ<52> @BASEBOARD_FAB2_LIB.BASEBOARD_FAB2(SCH_1):M_B_DQ(52)
  U5D1  E30 DDR1_DQ<52> SKX_EXT_B_BGA1-IC,TBD   I172 @BASEBOARD_FAB2_LIB.BASEBOARD_FAB2(SCH_1):PAGE24
  J4G2  262 DQ<53> SCONN288_H44441004_PIP-SCONN,HA   I111 @BASEBOARD_FAB2_LIB.BASEBOARD_FAB2(SCH_1):PAGE45
  J6U1  117 DQ<52> SCONN288_H44441003_PIP-SCONN,HA    I14 @BASEBOARD_FAB2_LIB.BASEBOARD_FAB2(SCH_1):PAGE46

M_B_DQ<53> @BASEBOARD_FAB2_LIB.BASEBOARD_FAB2(SCH_1):M_B_DQ(53)
  U5D1  F29 DDR1_DQ<53> SKX_EXT_B_BGA1-IC,TBD   I172 @BASEBOARD_FAB2_LIB.BASEBOARD_FAB2(SCH_1):PAGE24
  J4G2  117 DQ<52> SCONN288_H44441004_PIP-SCONN,HA   I111 @BASEBOARD_FAB2_LIB.BASEBOARD_FAB2(SCH_1):PAGE45
  J6U1  262 DQ<53> SCONN288_H44441003_PIP-SCONN,HA    I14 @BASEBOARD_FAB2_LIB.BASEBOARD_FAB2(SCH_1):PAGE46

M_B_DQ<54> @BASEBOARD_FAB2_LIB.BASEBOARD_FAB2(SCH_1):M_B_DQ(54)
  U5D1  B27 DDR1_DQ<54> SKX_EXT_B_BGA1-IC,TBD   I172 @BASEBOARD_FAB2_LIB.BASEBOARD_FAB2(SCH_1):PAGE24
  J4G2  269 DQ<55> SCONN288_H44441004_PIP-SCONN,HA   I111 @BASEBOARD_FAB2_LIB.BASEBOARD_FAB2(SCH_1):PAGE45
  J6U1  124 DQ<54> SCONN288_H44441003_PIP-SCONN,HA    I14 @BASEBOARD_FAB2_LIB.BASEBOARD_FAB2(SCH_1):PAGE46

M_B_DQ<55> @BASEBOARD_FAB2_LIB.BASEBOARD_FAB2(SCH_1):M_B_DQ(55)
  U5D1  F27 DDR1_DQ<55> SKX_EXT_B_BGA1-IC,TBD   I172 @BASEBOARD_FAB2_LIB.BASEBOARD_FAB2(SCH_1):PAGE24
  J4G2  124 DQ<54> SCONN288_H44441004_PIP-SCONN,HA   I111 @BASEBOARD_FAB2_LIB.BASEBOARD_FAB2(SCH_1):PAGE45
  J6U1  269 DQ<55> SCONN288_H44441003_PIP-SCONN,HA    I14 @BASEBOARD_FAB2_LIB.BASEBOARD_FAB2(SCH_1):PAGE46

M_B_DQ<56> @BASEBOARD_FAB2_LIB.BASEBOARD_FAB2(SCH_1):M_B_DQ(56)
  U5D1  U28 DDR1_DQ<56> SKX_EXT_B_BGA1-IC,TBD   I172 @BASEBOARD_FAB2_LIB.BASEBOARD_FAB2(SCH_1):PAGE24
  J4G2  275 DQ<57> SCONN288_H44441004_PIP-SCONN,HA   I111 @BASEBOARD_FAB2_LIB.BASEBOARD_FAB2(SCH_1):PAGE45
  J6U1  130 DQ<56> SCONN288_H44441003_PIP-SCONN,HA    I14 @BASEBOARD_FAB2_LIB.BASEBOARD_FAB2(SCH_1):PAGE46

M_B_DQ<57> @BASEBOARD_FAB2_LIB.BASEBOARD_FAB2(SCH_1):M_B_DQ(57)
  U5D1 AA28 DDR1_DQ<57> SKX_EXT_B_BGA1-IC,TBD   I172 @BASEBOARD_FAB2_LIB.BASEBOARD_FAB2(SCH_1):PAGE24
  J4G2  130 DQ<56> SCONN288_H44441004_PIP-SCONN,HA   I111 @BASEBOARD_FAB2_LIB.BASEBOARD_FAB2(SCH_1):PAGE45
  J6U1  275 DQ<57> SCONN288_H44441003_PIP-SCONN,HA    I14 @BASEBOARD_FAB2_LIB.BASEBOARD_FAB2(SCH_1):PAGE46

M_B_DQ<58> @BASEBOARD_FAB2_LIB.BASEBOARD_FAB2(SCH_1):M_B_DQ(58)
  U5D1  V25 DDR1_DQ<58> SKX_EXT_B_BGA1-IC,TBD   I172 @BASEBOARD_FAB2_LIB.BASEBOARD_FAB2(SCH_1):PAGE24
  J4G2  282 DQ<59> SCONN288_H44441004_PIP-SCONN,HA   I111 @BASEBOARD_FAB2_LIB.BASEBOARD_FAB2(SCH_1):PAGE45
  J6U1  137 DQ<58> SCONN288_H44441003_PIP-SCONN,HA    I14 @BASEBOARD_FAB2_LIB.BASEBOARD_FAB2(SCH_1):PAGE46

M_B_DQ<59> @BASEBOARD_FAB2_LIB.BASEBOARD_FAB2(SCH_1):M_B_DQ(59)
  U5D1  Y25 DDR1_DQ<59> SKX_EXT_B_BGA1-IC,TBD   I172 @BASEBOARD_FAB2_LIB.BASEBOARD_FAB2(SCH_1):PAGE24
  J4G2  137 DQ<58> SCONN288_H44441004_PIP-SCONN,HA   I111 @BASEBOARD_FAB2_LIB.BASEBOARD_FAB2(SCH_1):PAGE45
  J6U1  282 DQ<59> SCONN288_H44441003_PIP-SCONN,HA    I14 @BASEBOARD_FAB2_LIB.BASEBOARD_FAB2(SCH_1):PAGE46

M_B_DQ<5> @BASEBOARD_FAB2_LIB.BASEBOARD_FAB2(SCH_1):M_B_DQ(5)
  U5D1 AV79 DDR1_DQ<5> SKX_EXT_B_BGA1-IC,TBD   I172 @BASEBOARD_FAB2_LIB.BASEBOARD_FAB2(SCH_1):PAGE24
  J4G2    3  DQ<4> SCONN288_H44441004_PIP-SCONN,HA   I111 @BASEBOARD_FAB2_LIB.BASEBOARD_FAB2(SCH_1):PAGE45
  J6U1  148  DQ<5> SCONN288_H44441003_PIP-SCONN,HA    I14 @BASEBOARD_FAB2_LIB.BASEBOARD_FAB2(SCH_1):PAGE46

M_B_DQ<60> @BASEBOARD_FAB2_LIB.BASEBOARD_FAB2(SCH_1):M_B_DQ(60)
  U5D1  V29 DDR1_DQ<60> SKX_EXT_B_BGA1-IC,TBD   I172 @BASEBOARD_FAB2_LIB.BASEBOARD_FAB2(SCH_1):PAGE24
  J4G2  273 DQ<61> SCONN288_H44441004_PIP-SCONN,HA   I111 @BASEBOARD_FAB2_LIB.BASEBOARD_FAB2(SCH_1):PAGE45
  J6U1  128 DQ<60> SCONN288_H44441003_PIP-SCONN,HA    I14 @BASEBOARD_FAB2_LIB.BASEBOARD_FAB2(SCH_1):PAGE46

M_B_DQ<61> @BASEBOARD_FAB2_LIB.BASEBOARD_FAB2(SCH_1):M_B_DQ(61)
  U5D1  Y29 DDR1_DQ<61> SKX_EXT_B_BGA1-IC,TBD   I172 @BASEBOARD_FAB2_LIB.BASEBOARD_FAB2(SCH_1):PAGE24
  J4G2  128 DQ<60> SCONN288_H44441004_PIP-SCONN,HA   I111 @BASEBOARD_FAB2_LIB.BASEBOARD_FAB2(SCH_1):PAGE45
  J6U1  273 DQ<61> SCONN288_H44441003_PIP-SCONN,HA    I14 @BASEBOARD_FAB2_LIB.BASEBOARD_FAB2(SCH_1):PAGE46

M_B_DQ<62> @BASEBOARD_FAB2_LIB.BASEBOARD_FAB2(SCH_1):M_B_DQ(62)
  U5D1  U26 DDR1_DQ<62> SKX_EXT_B_BGA1-IC,TBD   I172 @BASEBOARD_FAB2_LIB.BASEBOARD_FAB2(SCH_1):PAGE24
  J4G2  280 DQ<63> SCONN288_H44441004_PIP-SCONN,HA   I111 @BASEBOARD_FAB2_LIB.BASEBOARD_FAB2(SCH_1):PAGE45
  J6U1  135 DQ<62> SCONN288_H44441003_PIP-SCONN,HA    I14 @BASEBOARD_FAB2_LIB.BASEBOARD_FAB2(SCH_1):PAGE46

M_B_DQ<63> @BASEBOARD_FAB2_LIB.BASEBOARD_FAB2(SCH_1):M_B_DQ(63)
  U5D1 AA26 DDR1_DQ<63> SKX_EXT_B_BGA1-IC,TBD   I172 @BASEBOARD_FAB2_LIB.BASEBOARD_FAB2(SCH_1):PAGE24
  J4G2  135 DQ<62> SCONN288_H44441004_PIP-SCONN,HA   I111 @BASEBOARD_FAB2_LIB.BASEBOARD_FAB2(SCH_1):PAGE45
  J6U1  280 DQ<63> SCONN288_H44441003_PIP-SCONN,HA    I14 @BASEBOARD_FAB2_LIB.BASEBOARD_FAB2(SCH_1):PAGE46

M_B_DQ<6> @BASEBOARD_FAB2_LIB.BASEBOARD_FAB2(SCH_1):M_B_DQ(6)
  U5D1 AR82 DDR1_DQ<6> SKX_EXT_B_BGA1-IC,TBD   I172 @BASEBOARD_FAB2_LIB.BASEBOARD_FAB2(SCH_1):PAGE24
  J4G2  155  DQ<7> SCONN288_H44441004_PIP-SCONN,HA   I111 @BASEBOARD_FAB2_LIB.BASEBOARD_FAB2(SCH_1):PAGE45
  J6U1   10  DQ<6> SCONN288_H44441003_PIP-SCONN,HA    I14 @BASEBOARD_FAB2_LIB.BASEBOARD_FAB2(SCH_1):PAGE46

M_B_DQ<7> @BASEBOARD_FAB2_LIB.BASEBOARD_FAB2(SCH_1):M_B_DQ(7)
  U5D1 AN80 DDR1_DQ<7> SKX_EXT_B_BGA1-IC,TBD   I172 @BASEBOARD_FAB2_LIB.BASEBOARD_FAB2(SCH_1):PAGE24
  J4G2   10  DQ<6> SCONN288_H44441004_PIP-SCONN,HA   I111 @BASEBOARD_FAB2_LIB.BASEBOARD_FAB2(SCH_1):PAGE45
  J6U1  155  DQ<7> SCONN288_H44441003_PIP-SCONN,HA    I14 @BASEBOARD_FAB2_LIB.BASEBOARD_FAB2(SCH_1):PAGE46

M_B_DQ<8> @BASEBOARD_FAB2_LIB.BASEBOARD_FAB2(SCH_1):M_B_DQ(8)
  U5D1 AH81 DDR1_DQ<8> SKX_EXT_B_BGA1-IC,TBD   I172 @BASEBOARD_FAB2_LIB.BASEBOARD_FAB2(SCH_1):PAGE24
  J4G2  161  DQ<9> SCONN288_H44441004_PIP-SCONN,HA   I111 @BASEBOARD_FAB2_LIB.BASEBOARD_FAB2(SCH_1):PAGE45
  J6U1   16  DQ<8> SCONN288_H44441003_PIP-SCONN,HA    I14 @BASEBOARD_FAB2_LIB.BASEBOARD_FAB2(SCH_1):PAGE46

M_B_DQ<9> @BASEBOARD_FAB2_LIB.BASEBOARD_FAB2(SCH_1):M_B_DQ(9)
  U5D1 AF79 DDR1_DQ<9> SKX_EXT_B_BGA1-IC,TBD   I172 @BASEBOARD_FAB2_LIB.BASEBOARD_FAB2(SCH_1):PAGE24
  J4G2   16  DQ<8> SCONN288_H44441004_PIP-SCONN,HA   I111 @BASEBOARD_FAB2_LIB.BASEBOARD_FAB2(SCH_1):PAGE45
  J6U1  161  DQ<9> SCONN288_H44441003_PIP-SCONN,HA    I14 @BASEBOARD_FAB2_LIB.BASEBOARD_FAB2(SCH_1):PAGE46

M_B_DQS_DN<0> @BASEBOARD_FAB2_LIB.BASEBOARD_FAB2(SCH_1):M_B_DQS_DN(0)
  U5D1 AP79 DDR1_DQS_DN<0> SKX_EXT_B_BGA1-IC,TBD   I172 @BASEBOARD_FAB2_LIB.BASEBOARD_FAB2(SCH_1):PAGE24
  J4G2  152  DQS0N SCONN288_H44441004_PIP-SCONN,HA    I61 @BASEBOARD_FAB2_LIB.BASEBOARD_FAB2(SCH_1):PAGE45
  J6U1  152  DQS0N SCONN288_H44441003_PIP-SCONN,HA   I112 @BASEBOARD_FAB2_LIB.BASEBOARD_FAB2(SCH_1):PAGE46

M_B_DQS_DN<10> @BASEBOARD_FAB2_LIB.BASEBOARD_FAB2(SCH_1):M_B_DQS_DN(10)
  U5D1 AG82 DDR1_DQS_DN<10> SKX_EXT_B_BGA1-IC,TBD   I172 @BASEBOARD_FAB2_LIB.BASEBOARD_FAB2(SCH_1):PAGE24
  J4G2   19 DQS10N SCONN288_H44441004_PIP-SCONN,HA    I61 @BASEBOARD_FAB2_LIB.BASEBOARD_FAB2(SCH_1):PAGE45
  J6U1   19 DQS10N SCONN288_H44441003_PIP-SCONN,HA   I112 @BASEBOARD_FAB2_LIB.BASEBOARD_FAB2(SCH_1):PAGE46

M_B_DQS_DN<11> @BASEBOARD_FAB2_LIB.BASEBOARD_FAB2(SCH_1):M_B_DQS_DN(11)
  U5D1  D79 DDR1_DQS_DN<11> SKX_EXT_B_BGA1-IC,TBD   I172 @BASEBOARD_FAB2_LIB.BASEBOARD_FAB2(SCH_1):PAGE24
  J4G2   30 DQS11N SCONN288_H44441004_PIP-SCONN,HA    I61 @BASEBOARD_FAB2_LIB.BASEBOARD_FAB2(SCH_1):PAGE45
  J6U1   30 DQS11N SCONN288_H44441003_PIP-SCONN,HA   I112 @BASEBOARD_FAB2_LIB.BASEBOARD_FAB2(SCH_1):PAGE46

M_B_DQS_DN<12> @BASEBOARD_FAB2_LIB.BASEBOARD_FAB2(SCH_1):M_B_DQS_DN(12)
  U5D1  B73 DDR1_DQS_DN<12> SKX_EXT_B_BGA1-IC,TBD   I172 @BASEBOARD_FAB2_LIB.BASEBOARD_FAB2(SCH_1):PAGE24
  J4G2   41 DQS12N SCONN288_H44441004_PIP-SCONN,HA    I61 @BASEBOARD_FAB2_LIB.BASEBOARD_FAB2(SCH_1):PAGE45
  J6U1   41 DQS12N SCONN288_H44441003_PIP-SCONN,HA   I112 @BASEBOARD_FAB2_LIB.BASEBOARD_FAB2(SCH_1):PAGE46

M_B_DQS_DN<13> @BASEBOARD_FAB2_LIB.BASEBOARD_FAB2(SCH_1):M_B_DQS_DN(13)
  U5D1  J42 DDR1_DQS_DN<13> SKX_EXT_B_BGA1-IC,TBD   I172 @BASEBOARD_FAB2_LIB.BASEBOARD_FAB2(SCH_1):PAGE24
  J4G2  100 DQS13N SCONN288_H44441004_PIP-SCONN,HA    I61 @BASEBOARD_FAB2_LIB.BASEBOARD_FAB2(SCH_1):PAGE45
  J6U1  100 DQS13N SCONN288_H44441003_PIP-SCONN,HA   I112 @BASEBOARD_FAB2_LIB.BASEBOARD_FAB2(SCH_1):PAGE46

M_B_DQS_DN<14> @BASEBOARD_FAB2_LIB.BASEBOARD_FAB2(SCH_1):M_B_DQS_DN(14)
  U5D1  A34 DDR1_DQS_DN<14> SKX_EXT_B_BGA1-IC,TBD   I172 @BASEBOARD_FAB2_LIB.BASEBOARD_FAB2(SCH_1):PAGE24
  J4G2  111 DQS14N SCONN288_H44441004_PIP-SCONN,HA    I61 @BASEBOARD_FAB2_LIB.BASEBOARD_FAB2(SCH_1):PAGE45
  J6U1  111 DQS14N SCONN288_H44441003_PIP-SCONN,HA   I112 @BASEBOARD_FAB2_LIB.BASEBOARD_FAB2(SCH_1):PAGE46

M_B_DQS_DN<15> @BASEBOARD_FAB2_LIB.BASEBOARD_FAB2(SCH_1):M_B_DQS_DN(15)
  U5D1  A28 DDR1_DQS_DN<15> SKX_EXT_B_BGA1-IC,TBD   I172 @BASEBOARD_FAB2_LIB.BASEBOARD_FAB2(SCH_1):PAGE24
  J4G2  122 DQS15N SCONN288_H44441004_PIP-SCONN,HA    I61 @BASEBOARD_FAB2_LIB.BASEBOARD_FAB2(SCH_1):PAGE45
  J6U1  122 DQS15N SCONN288_H44441003_PIP-SCONN,HA   I112 @BASEBOARD_FAB2_LIB.BASEBOARD_FAB2(SCH_1):PAGE46

M_B_DQS_DN<16> @BASEBOARD_FAB2_LIB.BASEBOARD_FAB2(SCH_1):M_B_DQS_DN(16)
  U5D1  T27 DDR1_DQS_DN<16> SKX_EXT_B_BGA1-IC,TBD   I172 @BASEBOARD_FAB2_LIB.BASEBOARD_FAB2(SCH_1):PAGE24
  J4G2  133 DQS16N SCONN288_H44441004_PIP-SCONN,HA    I61 @BASEBOARD_FAB2_LIB.BASEBOARD_FAB2(SCH_1):PAGE45
  J6U1  133 DQS16N SCONN288_H44441003_PIP-SCONN,HA   I112 @BASEBOARD_FAB2_LIB.BASEBOARD_FAB2(SCH_1):PAGE46

M_B_DQS_DN<17> @BASEBOARD_FAB2_LIB.BASEBOARD_FAB2(SCH_1):M_B_DQS_DN(17)
  U5D1  G68 DDR1_DQS_DN<17> SKX_EXT_B_BGA1-IC,TBD   I172 @BASEBOARD_FAB2_LIB.BASEBOARD_FAB2(SCH_1):PAGE24
  J4G2   52 DQS17N SCONN288_H44441004_PIP-SCONN,HA    I61 @BASEBOARD_FAB2_LIB.BASEBOARD_FAB2(SCH_1):PAGE45
  J6U1   52 DQS17N SCONN288_H44441003_PIP-SCONN,HA   I112 @BASEBOARD_FAB2_LIB.BASEBOARD_FAB2(SCH_1):PAGE46

M_B_DQS_DN<1> @BASEBOARD_FAB2_LIB.BASEBOARD_FAB2(SCH_1):M_B_DQS_DN(1)
  U5D1 AD79 DDR1_DQS_DN<1> SKX_EXT_B_BGA1-IC,TBD   I172 @BASEBOARD_FAB2_LIB.BASEBOARD_FAB2(SCH_1):PAGE24
  J4G2  163  DQS1N SCONN288_H44441004_PIP-SCONN,HA    I61 @BASEBOARD_FAB2_LIB.BASEBOARD_FAB2(SCH_1):PAGE45
  J6U1  163  DQS1N SCONN288_H44441003_PIP-SCONN,HA   I112 @BASEBOARD_FAB2_LIB.BASEBOARD_FAB2(SCH_1):PAGE46

M_B_DQS_DN<2> @BASEBOARD_FAB2_LIB.BASEBOARD_FAB2(SCH_1):M_B_DQS_DN(2)
  U5D1  K79 DDR1_DQS_DN<2> SKX_EXT_B_BGA1-IC,TBD   I172 @BASEBOARD_FAB2_LIB.BASEBOARD_FAB2(SCH_1):PAGE24
  J4G2  174  DQS2N SCONN288_H44441004_PIP-SCONN,HA    I61 @BASEBOARD_FAB2_LIB.BASEBOARD_FAB2(SCH_1):PAGE45
  J6U1  174  DQS2N SCONN288_H44441003_PIP-SCONN,HA   I112 @BASEBOARD_FAB2_LIB.BASEBOARD_FAB2(SCH_1):PAGE46

M_B_DQS_DN<3> @BASEBOARD_FAB2_LIB.BASEBOARD_FAB2(SCH_1):M_B_DQS_DN(3)
  U5D1  H73 DDR1_DQS_DN<3> SKX_EXT_B_BGA1-IC,TBD   I172 @BASEBOARD_FAB2_LIB.BASEBOARD_FAB2(SCH_1):PAGE24
  J4G2  185  DQS3N SCONN288_H44441004_PIP-SCONN,HA    I61 @BASEBOARD_FAB2_LIB.BASEBOARD_FAB2(SCH_1):PAGE45
  J6U1  185  DQS3N SCONN288_H44441003_PIP-SCONN,HA   I112 @BASEBOARD_FAB2_LIB.BASEBOARD_FAB2(SCH_1):PAGE46

M_B_DQS_DN<4> @BASEBOARD_FAB2_LIB.BASEBOARD_FAB2(SCH_1):M_B_DQS_DN(4)
  U5D1  N42 DDR1_DQS_DN<4> SKX_EXT_B_BGA1-IC,TBD   I172 @BASEBOARD_FAB2_LIB.BASEBOARD_FAB2(SCH_1):PAGE24
  J4G2  244  DQS4N SCONN288_H44441004_PIP-SCONN,HA    I61 @BASEBOARD_FAB2_LIB.BASEBOARD_FAB2(SCH_1):PAGE45
  J6U1  244  DQS4N SCONN288_H44441003_PIP-SCONN,HA   I112 @BASEBOARD_FAB2_LIB.BASEBOARD_FAB2(SCH_1):PAGE46

M_B_DQS_DN<5> @BASEBOARD_FAB2_LIB.BASEBOARD_FAB2(SCH_1):M_B_DQS_DN(5)
  U5D1  G34 DDR1_DQS_DN<5> SKX_EXT_B_BGA1-IC,TBD   I172 @BASEBOARD_FAB2_LIB.BASEBOARD_FAB2(SCH_1):PAGE24
  J4G2  255  DQS5N SCONN288_H44441004_PIP-SCONN,HA    I61 @BASEBOARD_FAB2_LIB.BASEBOARD_FAB2(SCH_1):PAGE45
  J6U1  255  DQS5N SCONN288_H44441003_PIP-SCONN,HA   I112 @BASEBOARD_FAB2_LIB.BASEBOARD_FAB2(SCH_1):PAGE46

M_B_DQS_DN<6> @BASEBOARD_FAB2_LIB.BASEBOARD_FAB2(SCH_1):M_B_DQS_DN(6)
  U5D1  G28 DDR1_DQS_DN<6> SKX_EXT_B_BGA1-IC,TBD   I172 @BASEBOARD_FAB2_LIB.BASEBOARD_FAB2(SCH_1):PAGE24
  J4G2  266  DQS6N SCONN288_H44441004_PIP-SCONN,HA    I61 @BASEBOARD_FAB2_LIB.BASEBOARD_FAB2(SCH_1):PAGE45
  J6U1  266  DQS6N SCONN288_H44441003_PIP-SCONN,HA   I112 @BASEBOARD_FAB2_LIB.BASEBOARD_FAB2(SCH_1):PAGE46

M_B_DQS_DN<7> @BASEBOARD_FAB2_LIB.BASEBOARD_FAB2(SCH_1):M_B_DQS_DN(7)
  U5D1 AB27 DDR1_DQS_DN<7> SKX_EXT_B_BGA1-IC,TBD   I172 @BASEBOARD_FAB2_LIB.BASEBOARD_FAB2(SCH_1):PAGE24
  J4G2  277  DQS7N SCONN288_H44441004_PIP-SCONN,HA    I61 @BASEBOARD_FAB2_LIB.BASEBOARD_FAB2(SCH_1):PAGE45
  J6U1  277  DQS7N SCONN288_H44441003_PIP-SCONN,HA   I112 @BASEBOARD_FAB2_LIB.BASEBOARD_FAB2(SCH_1):PAGE46

M_B_DQS_DN<8> @BASEBOARD_FAB2_LIB.BASEBOARD_FAB2(SCH_1):M_B_DQS_DN(8)
  U5D1  N68 DDR1_DQS_DN<8> SKX_EXT_B_BGA1-IC,TBD   I172 @BASEBOARD_FAB2_LIB.BASEBOARD_FAB2(SCH_1):PAGE24
  J4G2  196  DQS8N SCONN288_H44441004_PIP-SCONN,HA    I61 @BASEBOARD_FAB2_LIB.BASEBOARD_FAB2(SCH_1):PAGE45
  J6U1  196  DQS8N SCONN288_H44441003_PIP-SCONN,HA   I112 @BASEBOARD_FAB2_LIB.BASEBOARD_FAB2(SCH_1):PAGE46

M_B_DQS_DN<9> @BASEBOARD_FAB2_LIB.BASEBOARD_FAB2(SCH_1):M_B_DQS_DN(9)
  U5D1 AU82 DDR1_DQS_DN<9> SKX_EXT_B_BGA1-IC,TBD   I172 @BASEBOARD_FAB2_LIB.BASEBOARD_FAB2(SCH_1):PAGE24
  J4G2    8  DQS9N SCONN288_H44441004_PIP-SCONN,HA    I61 @BASEBOARD_FAB2_LIB.BASEBOARD_FAB2(SCH_1):PAGE45
  J6U1    8  DQS9N SCONN288_H44441003_PIP-SCONN,HA   I112 @BASEBOARD_FAB2_LIB.BASEBOARD_FAB2(SCH_1):PAGE46

M_B_DQS_DP<0> @BASEBOARD_FAB2_LIB.BASEBOARD_FAB2(SCH_1):M_B_DQS_DP(0)
  U5D1 AR80 DDR1_DQS_DP<0> SKX_EXT_B_BGA1-IC,TBD   I172 @BASEBOARD_FAB2_LIB.BASEBOARD_FAB2(SCH_1):PAGE24
  J4G2  153  DQS0P SCONN288_H44441004_PIP-SCONN,HA    I61 @BASEBOARD_FAB2_LIB.BASEBOARD_FAB2(SCH_1):PAGE45
  J6U1  153  DQS0P SCONN288_H44441003_PIP-SCONN,HA   I112 @BASEBOARD_FAB2_LIB.BASEBOARD_FAB2(SCH_1):PAGE46

M_B_DQS_DP<10> @BASEBOARD_FAB2_LIB.BASEBOARD_FAB2(SCH_1):M_B_DQS_DP(10)
  U5D1 AF81 DDR1_DQS_DP<10> SKX_EXT_B_BGA1-IC,TBD   I172 @BASEBOARD_FAB2_LIB.BASEBOARD_FAB2(SCH_1):PAGE24
  J4G2   18 DQS10P SCONN288_H44441004_PIP-SCONN,HA    I61 @BASEBOARD_FAB2_LIB.BASEBOARD_FAB2(SCH_1):PAGE45
  J6U1   18 DQS10P SCONN288_H44441003_PIP-SCONN,HA   I112 @BASEBOARD_FAB2_LIB.BASEBOARD_FAB2(SCH_1):PAGE46

M_B_DQS_DP<11> @BASEBOARD_FAB2_LIB.BASEBOARD_FAB2(SCH_1):M_B_DQS_DP(11)
  U5D1  F79 DDR1_DQS_DP<11> SKX_EXT_B_BGA1-IC,TBD   I172 @BASEBOARD_FAB2_LIB.BASEBOARD_FAB2(SCH_1):PAGE24
  J4G2   29 DQS11P SCONN288_H44441004_PIP-SCONN,HA    I61 @BASEBOARD_FAB2_LIB.BASEBOARD_FAB2(SCH_1):PAGE45
  J6U1   29 DQS11P SCONN288_H44441003_PIP-SCONN,HA   I112 @BASEBOARD_FAB2_LIB.BASEBOARD_FAB2(SCH_1):PAGE46

M_B_DQS_DP<12> @BASEBOARD_FAB2_LIB.BASEBOARD_FAB2(SCH_1):M_B_DQS_DP(12)
  U5D1  D73 DDR1_DQS_DP<12> SKX_EXT_B_BGA1-IC,TBD   I172 @BASEBOARD_FAB2_LIB.BASEBOARD_FAB2(SCH_1):PAGE24
  J4G2   40 DQS12P SCONN288_H44441004_PIP-SCONN,HA    I61 @BASEBOARD_FAB2_LIB.BASEBOARD_FAB2(SCH_1):PAGE45
  J6U1   40 DQS12P SCONN288_H44441003_PIP-SCONN,HA   I112 @BASEBOARD_FAB2_LIB.BASEBOARD_FAB2(SCH_1):PAGE46

M_B_DQS_DP<13> @BASEBOARD_FAB2_LIB.BASEBOARD_FAB2(SCH_1):M_B_DQS_DP(13)
  U5D1  L42 DDR1_DQS_DP<13> SKX_EXT_B_BGA1-IC,TBD   I172 @BASEBOARD_FAB2_LIB.BASEBOARD_FAB2(SCH_1):PAGE24
  J4G2   99 DQS13P SCONN288_H44441004_PIP-SCONN,HA    I61 @BASEBOARD_FAB2_LIB.BASEBOARD_FAB2(SCH_1):PAGE45
  J6U1   99 DQS13P SCONN288_H44441003_PIP-SCONN,HA   I112 @BASEBOARD_FAB2_LIB.BASEBOARD_FAB2(SCH_1):PAGE46

M_B_DQS_DP<14> @BASEBOARD_FAB2_LIB.BASEBOARD_FAB2(SCH_1):M_B_DQS_DP(14)
  U5D1  C34 DDR1_DQS_DP<14> SKX_EXT_B_BGA1-IC,TBD   I172 @BASEBOARD_FAB2_LIB.BASEBOARD_FAB2(SCH_1):PAGE24
  J4G2  110 DQS14P SCONN288_H44441004_PIP-SCONN,HA    I61 @BASEBOARD_FAB2_LIB.BASEBOARD_FAB2(SCH_1):PAGE45
  J6U1  110 DQS14P SCONN288_H44441003_PIP-SCONN,HA   I112 @BASEBOARD_FAB2_LIB.BASEBOARD_FAB2(SCH_1):PAGE46

M_B_DQS_DP<15> @BASEBOARD_FAB2_LIB.BASEBOARD_FAB2(SCH_1):M_B_DQS_DP(15)
  U5D1  C28 DDR1_DQS_DP<15> SKX_EXT_B_BGA1-IC,TBD   I172 @BASEBOARD_FAB2_LIB.BASEBOARD_FAB2(SCH_1):PAGE24
  J4G2  121 DQS15P SCONN288_H44441004_PIP-SCONN,HA    I61 @BASEBOARD_FAB2_LIB.BASEBOARD_FAB2(SCH_1):PAGE45
  J6U1  121 DQS15P SCONN288_H44441003_PIP-SCONN,HA   I112 @BASEBOARD_FAB2_LIB.BASEBOARD_FAB2(SCH_1):PAGE46

M_B_DQS_DP<16> @BASEBOARD_FAB2_LIB.BASEBOARD_FAB2(SCH_1):M_B_DQS_DP(16)
  U5D1  V27 DDR1_DQS_DP<16> SKX_EXT_B_BGA1-IC,TBD   I172 @BASEBOARD_FAB2_LIB.BASEBOARD_FAB2(SCH_1):PAGE24
  J4G2  132 DQS16P SCONN288_H44441004_PIP-SCONN,HA    I61 @BASEBOARD_FAB2_LIB.BASEBOARD_FAB2(SCH_1):PAGE45
  J6U1  132 DQS16P SCONN288_H44441003_PIP-SCONN,HA   I112 @BASEBOARD_FAB2_LIB.BASEBOARD_FAB2(SCH_1):PAGE46

M_B_DQS_DP<17> @BASEBOARD_FAB2_LIB.BASEBOARD_FAB2(SCH_1):M_B_DQS_DP(17)
  U5D1  J68 DDR1_DQS_DP<17> SKX_EXT_B_BGA1-IC,TBD   I172 @BASEBOARD_FAB2_LIB.BASEBOARD_FAB2(SCH_1):PAGE24
  J4G2   51 DQS17P SCONN288_H44441004_PIP-SCONN,HA    I61 @BASEBOARD_FAB2_LIB.BASEBOARD_FAB2(SCH_1):PAGE45
  J6U1   51 DQS17P SCONN288_H44441003_PIP-SCONN,HA   I112 @BASEBOARD_FAB2_LIB.BASEBOARD_FAB2(SCH_1):PAGE46

M_B_DQS_DP<1> @BASEBOARD_FAB2_LIB.BASEBOARD_FAB2(SCH_1):M_B_DQS_DP(1)
  U5D1 AE80 DDR1_DQS_DP<1> SKX_EXT_B_BGA1-IC,TBD   I172 @BASEBOARD_FAB2_LIB.BASEBOARD_FAB2(SCH_1):PAGE24
  J4G2  164  DQS1P SCONN288_H44441004_PIP-SCONN,HA    I61 @BASEBOARD_FAB2_LIB.BASEBOARD_FAB2(SCH_1):PAGE45
  J6U1  164  DQS1P SCONN288_H44441003_PIP-SCONN,HA   I112 @BASEBOARD_FAB2_LIB.BASEBOARD_FAB2(SCH_1):PAGE46

M_B_DQS_DP<2> @BASEBOARD_FAB2_LIB.BASEBOARD_FAB2(SCH_1):M_B_DQS_DP(2)
  U5D1  H79 DDR1_DQS_DP<2> SKX_EXT_B_BGA1-IC,TBD   I172 @BASEBOARD_FAB2_LIB.BASEBOARD_FAB2(SCH_1):PAGE24
  J4G2  175  DQS2P SCONN288_H44441004_PIP-SCONN,HA    I61 @BASEBOARD_FAB2_LIB.BASEBOARD_FAB2(SCH_1):PAGE45
  J6U1  175  DQS2P SCONN288_H44441003_PIP-SCONN,HA   I112 @BASEBOARD_FAB2_LIB.BASEBOARD_FAB2(SCH_1):PAGE46

M_B_DQS_DP<3> @BASEBOARD_FAB2_LIB.BASEBOARD_FAB2(SCH_1):M_B_DQS_DP(3)
  U5D1  F73 DDR1_DQS_DP<3> SKX_EXT_B_BGA1-IC,TBD   I172 @BASEBOARD_FAB2_LIB.BASEBOARD_FAB2(SCH_1):PAGE24
  J4G2  186  DQS3P SCONN288_H44441004_PIP-SCONN,HA    I61 @BASEBOARD_FAB2_LIB.BASEBOARD_FAB2(SCH_1):PAGE45
  J6U1  186  DQS3P SCONN288_H44441003_PIP-SCONN,HA   I112 @BASEBOARD_FAB2_LIB.BASEBOARD_FAB2(SCH_1):PAGE46

M_B_DQS_DP<4> @BASEBOARD_FAB2_LIB.BASEBOARD_FAB2(SCH_1):M_B_DQS_DP(4)
  U5D1  R42 DDR1_DQS_DP<4> SKX_EXT_B_BGA1-IC,TBD   I172 @BASEBOARD_FAB2_LIB.BASEBOARD_FAB2(SCH_1):PAGE24
  J4G2  245  DQS4P SCONN288_H44441004_PIP-SCONN,HA    I61 @BASEBOARD_FAB2_LIB.BASEBOARD_FAB2(SCH_1):PAGE45
  J6U1  245  DQS4P SCONN288_H44441003_PIP-SCONN,HA   I112 @BASEBOARD_FAB2_LIB.BASEBOARD_FAB2(SCH_1):PAGE46

M_B_DQS_DP<5> @BASEBOARD_FAB2_LIB.BASEBOARD_FAB2(SCH_1):M_B_DQS_DP(5)
  U5D1  E34 DDR1_DQS_DP<5> SKX_EXT_B_BGA1-IC,TBD   I172 @BASEBOARD_FAB2_LIB.BASEBOARD_FAB2(SCH_1):PAGE24
  J4G2  256  DQS5P SCONN288_H44441004_PIP-SCONN,HA    I61 @BASEBOARD_FAB2_LIB.BASEBOARD_FAB2(SCH_1):PAGE45
  J6U1  256  DQS5P SCONN288_H44441003_PIP-SCONN,HA   I112 @BASEBOARD_FAB2_LIB.BASEBOARD_FAB2(SCH_1):PAGE46

M_B_DQS_DP<6> @BASEBOARD_FAB2_LIB.BASEBOARD_FAB2(SCH_1):M_B_DQS_DP(6)
  U5D1  E28 DDR1_DQS_DP<6> SKX_EXT_B_BGA1-IC,TBD   I172 @BASEBOARD_FAB2_LIB.BASEBOARD_FAB2(SCH_1):PAGE24
  J4G2  267  DQS6P SCONN288_H44441004_PIP-SCONN,HA    I61 @BASEBOARD_FAB2_LIB.BASEBOARD_FAB2(SCH_1):PAGE45
  J6U1  267  DQS6P SCONN288_H44441003_PIP-SCONN,HA   I112 @BASEBOARD_FAB2_LIB.BASEBOARD_FAB2(SCH_1):PAGE46

M_B_DQS_DP<7> @BASEBOARD_FAB2_LIB.BASEBOARD_FAB2(SCH_1):M_B_DQS_DP(7)
  U5D1  Y27 DDR1_DQS_DP<7> SKX_EXT_B_BGA1-IC,TBD   I172 @BASEBOARD_FAB2_LIB.BASEBOARD_FAB2(SCH_1):PAGE24
  J4G2  278  DQS7P SCONN288_H44441004_PIP-SCONN,HA    I61 @BASEBOARD_FAB2_LIB.BASEBOARD_FAB2(SCH_1):PAGE45
  J6U1  278  DQS7P SCONN288_H44441003_PIP-SCONN,HA   I112 @BASEBOARD_FAB2_LIB.BASEBOARD_FAB2(SCH_1):PAGE46

M_B_DQS_DP<8> @BASEBOARD_FAB2_LIB.BASEBOARD_FAB2(SCH_1):M_B_DQS_DP(8)
  U5D1  L68 DDR1_DQS_DP<8> SKX_EXT_B_BGA1-IC,TBD   I172 @BASEBOARD_FAB2_LIB.BASEBOARD_FAB2(SCH_1):PAGE24
  J4G2  197  DQS8P SCONN288_H44441004_PIP-SCONN,HA    I61 @BASEBOARD_FAB2_LIB.BASEBOARD_FAB2(SCH_1):PAGE45
  J6U1  197  DQS8P SCONN288_H44441003_PIP-SCONN,HA   I112 @BASEBOARD_FAB2_LIB.BASEBOARD_FAB2(SCH_1):PAGE46

M_B_DQS_DP<9> @BASEBOARD_FAB2_LIB.BASEBOARD_FAB2(SCH_1):M_B_DQS_DP(9)
  U5D1 AT81 DDR1_DQS_DP<9> SKX_EXT_B_BGA1-IC,TBD   I172 @BASEBOARD_FAB2_LIB.BASEBOARD_FAB2(SCH_1):PAGE24
  J4G2    7  DQS9P SCONN288_H44441004_PIP-SCONN,HA    I61 @BASEBOARD_FAB2_LIB.BASEBOARD_FAB2(SCH_1):PAGE45
  J6U1    7  DQS9P SCONN288_H44441003_PIP-SCONN,HA   I112 @BASEBOARD_FAB2_LIB.BASEBOARD_FAB2(SCH_1):PAGE46

M_B_ECC<0> @BASEBOARD_FAB2_LIB.BASEBOARD_FAB2(SCH_1):M_B_ECC(0)
  U5D1  J70 DDR1_ECC<0> SKX_EXT_B_BGA1-IC,TBD   I172 @BASEBOARD_FAB2_LIB.BASEBOARD_FAB2(SCH_1):PAGE24
  J4G2  194  CB<1> SCONN288_H44441004_PIP-SCONN,HA   I111 @BASEBOARD_FAB2_LIB.BASEBOARD_FAB2(SCH_1):PAGE45
  J6U1   49  CB<0> SCONN288_H44441003_PIP-SCONN,HA    I14 @BASEBOARD_FAB2_LIB.BASEBOARD_FAB2(SCH_1):PAGE46

M_B_ECC<1> @BASEBOARD_FAB2_LIB.BASEBOARD_FAB2(SCH_1):M_B_ECC(1)
  U5D1  H69 DDR1_ECC<1> SKX_EXT_B_BGA1-IC,TBD   I172 @BASEBOARD_FAB2_LIB.BASEBOARD_FAB2(SCH_1):PAGE24
  J4G2   49  CB<0> SCONN288_H44441004_PIP-SCONN,HA   I111 @BASEBOARD_FAB2_LIB.BASEBOARD_FAB2(SCH_1):PAGE45
  J6U1  194  CB<1> SCONN288_H44441003_PIP-SCONN,HA    I14 @BASEBOARD_FAB2_LIB.BASEBOARD_FAB2(SCH_1):PAGE46

M_B_ECC<2> @BASEBOARD_FAB2_LIB.BASEBOARD_FAB2(SCH_1):M_B_ECC(2)
  U5D1  J66 DDR1_ECC<2> SKX_EXT_B_BGA1-IC,TBD   I172 @BASEBOARD_FAB2_LIB.BASEBOARD_FAB2(SCH_1):PAGE24
  J4G2  201  CB<3> SCONN288_H44441004_PIP-SCONN,HA   I111 @BASEBOARD_FAB2_LIB.BASEBOARD_FAB2(SCH_1):PAGE45
  J6U1   56  CB<2> SCONN288_H44441003_PIP-SCONN,HA    I14 @BASEBOARD_FAB2_LIB.BASEBOARD_FAB2(SCH_1):PAGE46

M_B_ECC<3> @BASEBOARD_FAB2_LIB.BASEBOARD_FAB2(SCH_1):M_B_ECC(3)
  U5D1  L66 DDR1_ECC<3> SKX_EXT_B_BGA1-IC,TBD   I172 @BASEBOARD_FAB2_LIB.BASEBOARD_FAB2(SCH_1):PAGE24
  J4G2   56  CB<2> SCONN288_H44441004_PIP-SCONN,HA   I111 @BASEBOARD_FAB2_LIB.BASEBOARD_FAB2(SCH_1):PAGE45
  J6U1  201  CB<3> SCONN288_H44441003_PIP-SCONN,HA    I14 @BASEBOARD_FAB2_LIB.BASEBOARD_FAB2(SCH_1):PAGE46

M_B_ECC<4> @BASEBOARD_FAB2_LIB.BASEBOARD_FAB2(SCH_1):M_B_ECC(4)
  U5D1  L70 DDR1_ECC<4> SKX_EXT_B_BGA1-IC,TBD   I172 @BASEBOARD_FAB2_LIB.BASEBOARD_FAB2(SCH_1):PAGE24
  J4G2  192  CB<5> SCONN288_H44441004_PIP-SCONN,HA   I111 @BASEBOARD_FAB2_LIB.BASEBOARD_FAB2(SCH_1):PAGE45
  J6U1   47  CB<4> SCONN288_H44441003_PIP-SCONN,HA    I14 @BASEBOARD_FAB2_LIB.BASEBOARD_FAB2(SCH_1):PAGE46

M_B_ECC<5> @BASEBOARD_FAB2_LIB.BASEBOARD_FAB2(SCH_1):M_B_ECC(5)
  U5D1  M69 DDR1_ECC<5> SKX_EXT_B_BGA1-IC,TBD   I172 @BASEBOARD_FAB2_LIB.BASEBOARD_FAB2(SCH_1):PAGE24
  J4G2   47  CB<4> SCONN288_H44441004_PIP-SCONN,HA   I111 @BASEBOARD_FAB2_LIB.BASEBOARD_FAB2(SCH_1):PAGE45
  J6U1  192  CB<5> SCONN288_H44441003_PIP-SCONN,HA    I14 @BASEBOARD_FAB2_LIB.BASEBOARD_FAB2(SCH_1):PAGE46

M_B_ECC<6> @BASEBOARD_FAB2_LIB.BASEBOARD_FAB2(SCH_1):M_B_ECC(6)
  U5D1  H67 DDR1_ECC<6> SKX_EXT_B_BGA1-IC,TBD   I172 @BASEBOARD_FAB2_LIB.BASEBOARD_FAB2(SCH_1):PAGE24
  J4G2  199  CB<7> SCONN288_H44441004_PIP-SCONN,HA   I111 @BASEBOARD_FAB2_LIB.BASEBOARD_FAB2(SCH_1):PAGE45
  J6U1   54  CB<6> SCONN288_H44441003_PIP-SCONN,HA    I14 @BASEBOARD_FAB2_LIB.BASEBOARD_FAB2(SCH_1):PAGE46

M_B_ECC<7> @BASEBOARD_FAB2_LIB.BASEBOARD_FAB2(SCH_1):M_B_ECC(7)
  U5D1  M67 DDR1_ECC<7> SKX_EXT_B_BGA1-IC,TBD   I172 @BASEBOARD_FAB2_LIB.BASEBOARD_FAB2(SCH_1):PAGE24
  J4G2   54  CB<6> SCONN288_H44441004_PIP-SCONN,HA   I111 @BASEBOARD_FAB2_LIB.BASEBOARD_FAB2(SCH_1):PAGE45
  J6U1  199  CB<7> SCONN288_H44441003_PIP-SCONN,HA    I14 @BASEBOARD_FAB2_LIB.BASEBOARD_FAB2(SCH_1):PAGE46

M_B_MA<0> @BASEBOARD_FAB2_LIB.BASEBOARD_FAB2(SCH_1):M_B_MA(0)
  U5D1  J52 DDR1_MA<0> SKX_EXT_B_BGA1-IC,TBD   I172 @BASEBOARD_FAB2_LIB.BASEBOARD_FAB2(SCH_1):PAGE24
  J4G2   79     A0 SCONN288_H44441004_PIP-SCONN,HA   I111 @BASEBOARD_FAB2_LIB.BASEBOARD_FAB2(SCH_1):PAGE45
  J6U1   79     A0 SCONN288_H44441003_PIP-SCONN,HA    I14 @BASEBOARD_FAB2_LIB.BASEBOARD_FAB2(SCH_1):PAGE46

M_B_MA<10> @BASEBOARD_FAB2_LIB.BASEBOARD_FAB2(SCH_1):M_B_MA(10)
  U5D1  M55 DDR1_MA<10> SKX_EXT_B_BGA1-IC,TBD   I172 @BASEBOARD_FAB2_LIB.BASEBOARD_FAB2(SCH_1):PAGE24
  J4G2  225    A10 SCONN288_H44441004_PIP-SCONN,HA   I111 @BASEBOARD_FAB2_LIB.BASEBOARD_FAB2(SCH_1):PAGE45
  J6U1  225    A10 SCONN288_H44441003_PIP-SCONN,HA    I14 @BASEBOARD_FAB2_LIB.BASEBOARD_FAB2(SCH_1):PAGE46

M_B_MA<11> @BASEBOARD_FAB2_LIB.BASEBOARD_FAB2(SCH_1):M_B_MA(11)
  U5D1  R60 DDR1_MA<11> SKX_EXT_B_BGA1-IC,TBD   I172 @BASEBOARD_FAB2_LIB.BASEBOARD_FAB2(SCH_1):PAGE24
  J4G2  210    A11 SCONN288_H44441004_PIP-SCONN,HA   I111 @BASEBOARD_FAB2_LIB.BASEBOARD_FAB2(SCH_1):PAGE45
  J6U1  210    A11 SCONN288_H44441003_PIP-SCONN,HA    I14 @BASEBOARD_FAB2_LIB.BASEBOARD_FAB2(SCH_1):PAGE46

M_B_MA<12> @BASEBOARD_FAB2_LIB.BASEBOARD_FAB2(SCH_1):M_B_MA(12)
  U5D1  T61 DDR1_MA<12> SKX_EXT_B_BGA1-IC,TBD   I172 @BASEBOARD_FAB2_LIB.BASEBOARD_FAB2(SCH_1):PAGE24
  J4G2   65    A12 SCONN288_H44441004_PIP-SCONN,HA   I111 @BASEBOARD_FAB2_LIB.BASEBOARD_FAB2(SCH_1):PAGE45
  J6U1   65    A12 SCONN288_H44441003_PIP-SCONN,HA    I14 @BASEBOARD_FAB2_LIB.BASEBOARD_FAB2(SCH_1):PAGE46

M_B_MA<13> @BASEBOARD_FAB2_LIB.BASEBOARD_FAB2(SCH_1):M_B_MA(13)
  U5D1  M51 DDR1_MA<13> SKX_EXT_B_BGA1-IC,TBD   I172 @BASEBOARD_FAB2_LIB.BASEBOARD_FAB2(SCH_1):PAGE24
  J4G2  232    A13 SCONN288_H44441004_PIP-SCONN,HA   I111 @BASEBOARD_FAB2_LIB.BASEBOARD_FAB2(SCH_1):PAGE45
  J6U1  232    A13 SCONN288_H44441003_PIP-SCONN,HA    I14 @BASEBOARD_FAB2_LIB.BASEBOARD_FAB2(SCH_1):PAGE46

M_B_MA<14> @BASEBOARD_FAB2_LIB.BASEBOARD_FAB2(SCH_1):M_B_MA(14)
  U5D1  T51 DDR1_MA<14> SKX_EXT_B_BGA1-IC,TBD   I172 @BASEBOARD_FAB2_LIB.BASEBOARD_FAB2(SCH_1):PAGE24
  J4G2  228 A14_WE_N SCONN288_H44441004_PIP-SCONN,HA   I111 @BASEBOARD_FAB2_LIB.BASEBOARD_FAB2(SCH_1):PAGE45
  J6U1  228 A14_WE_N SCONN288_H44441003_PIP-SCONN,HA    I14 @BASEBOARD_FAB2_LIB.BASEBOARD_FAB2(SCH_1):PAGE46

M_B_MA<15> @BASEBOARD_FAB2_LIB.BASEBOARD_FAB2(SCH_1):M_B_MA(15)
  U5D1  N52 DDR1_MA<15> SKX_EXT_B_BGA1-IC,TBD   I172 @BASEBOARD_FAB2_LIB.BASEBOARD_FAB2(SCH_1):PAGE24
  J4G2   86 A15_CAS_N SCONN288_H44441004_PIP-SCONN,HA   I111 @BASEBOARD_FAB2_LIB.BASEBOARD_FAB2(SCH_1):PAGE45
  J6U1   86 A15_CAS_N SCONN288_H44441003_PIP-SCONN,HA    I14 @BASEBOARD_FAB2_LIB.BASEBOARD_FAB2(SCH_1):PAGE46

M_B_MA<16> @BASEBOARD_FAB2_LIB.BASEBOARD_FAB2(SCH_1):M_B_MA(16)
  U5D1  R52 DDR1_MA<16> SKX_EXT_B_BGA1-IC,TBD   I172 @BASEBOARD_FAB2_LIB.BASEBOARD_FAB2(SCH_1):PAGE24
  J4G2   82 A16_RAS_N SCONN288_H44441004_PIP-SCONN,HA   I111 @BASEBOARD_FAB2_LIB.BASEBOARD_FAB2(SCH_1):PAGE45
  J6U1   82 A16_RAS_N SCONN288_H44441003_PIP-SCONN,HA    I14 @BASEBOARD_FAB2_LIB.BASEBOARD_FAB2(SCH_1):PAGE46

M_B_MA<17> @BASEBOARD_FAB2_LIB.BASEBOARD_FAB2(SCH_1):M_B_MA(17)
  U5D1  N48 DDR1_MA<17> SKX_EXT_B_BGA1-IC,TBD   I172 @BASEBOARD_FAB2_LIB.BASEBOARD_FAB2(SCH_1):PAGE24
  J4G2  234    A17 SCONN288_H44441004_PIP-SCONN,HA   I111 @BASEBOARD_FAB2_LIB.BASEBOARD_FAB2(SCH_1):PAGE45
  J6U1  234    A17 SCONN288_H44441003_PIP-SCONN,HA    I14 @BASEBOARD_FAB2_LIB.BASEBOARD_FAB2(SCH_1):PAGE46

M_B_MA<1> @BASEBOARD_FAB2_LIB.BASEBOARD_FAB2(SCH_1):M_B_MA(1)
  U5D1  J58 DDR1_MA<1> SKX_EXT_B_BGA1-IC,TBD   I172 @BASEBOARD_FAB2_LIB.BASEBOARD_FAB2(SCH_1):PAGE24
  J4G2   72     A1 SCONN288_H44441004_PIP-SCONN,HA   I111 @BASEBOARD_FAB2_LIB.BASEBOARD_FAB2(SCH_1):PAGE45
  J6U1   72     A1 SCONN288_H44441003_PIP-SCONN,HA    I14 @BASEBOARD_FAB2_LIB.BASEBOARD_FAB2(SCH_1):PAGE46

M_B_MA<2> @BASEBOARD_FAB2_LIB.BASEBOARD_FAB2(SCH_1):M_B_MA(2)
  U5D1  K57 DDR1_MA<2> SKX_EXT_B_BGA1-IC,TBD   I172 @BASEBOARD_FAB2_LIB.BASEBOARD_FAB2(SCH_1):PAGE24
  J4G2  216     A2 SCONN288_H44441004_PIP-SCONN,HA   I111 @BASEBOARD_FAB2_LIB.BASEBOARD_FAB2(SCH_1):PAGE45
  J6U1  216     A2 SCONN288_H44441003_PIP-SCONN,HA    I14 @BASEBOARD_FAB2_LIB.BASEBOARD_FAB2(SCH_1):PAGE46

M_B_MA<3> @BASEBOARD_FAB2_LIB.BASEBOARD_FAB2(SCH_1):M_B_MA(3)
  U5D1  N58 DDR1_MA<3> SKX_EXT_B_BGA1-IC,TBD   I172 @BASEBOARD_FAB2_LIB.BASEBOARD_FAB2(SCH_1):PAGE24
  J4G2   71     A3 SCONN288_H44441004_PIP-SCONN,HA   I111 @BASEBOARD_FAB2_LIB.BASEBOARD_FAB2(SCH_1):PAGE45
  J6U1   71     A3 SCONN288_H44441003_PIP-SCONN,HA    I14 @BASEBOARD_FAB2_LIB.BASEBOARD_FAB2(SCH_1):PAGE46

M_B_MA<4> @BASEBOARD_FAB2_LIB.BASEBOARD_FAB2(SCH_1):M_B_MA(4)
  U5D1  M59 DDR1_MA<4> SKX_EXT_B_BGA1-IC,TBD   I172 @BASEBOARD_FAB2_LIB.BASEBOARD_FAB2(SCH_1):PAGE24
  J4G2  214     A4 SCONN288_H44441004_PIP-SCONN,HA   I111 @BASEBOARD_FAB2_LIB.BASEBOARD_FAB2(SCH_1):PAGE45
  J6U1  214     A4 SCONN288_H44441003_PIP-SCONN,HA    I14 @BASEBOARD_FAB2_LIB.BASEBOARD_FAB2(SCH_1):PAGE46

M_B_MA<5> @BASEBOARD_FAB2_LIB.BASEBOARD_FAB2(SCH_1):M_B_MA(5)
  U5D1  R58 DDR1_MA<5> SKX_EXT_B_BGA1-IC,TBD   I172 @BASEBOARD_FAB2_LIB.BASEBOARD_FAB2(SCH_1):PAGE24
  J4G2  213     A5 SCONN288_H44441004_PIP-SCONN,HA   I111 @BASEBOARD_FAB2_LIB.BASEBOARD_FAB2(SCH_1):PAGE45
  J6U1  213     A5 SCONN288_H44441003_PIP-SCONN,HA    I14 @BASEBOARD_FAB2_LIB.BASEBOARD_FAB2(SCH_1):PAGE46

M_B_MA<6> @BASEBOARD_FAB2_LIB.BASEBOARD_FAB2(SCH_1):M_B_MA(6)
  U5D1  T59 DDR1_MA<6> SKX_EXT_B_BGA1-IC,TBD   I172 @BASEBOARD_FAB2_LIB.BASEBOARD_FAB2(SCH_1):PAGE24
  J4G2   69     A6 SCONN288_H44441004_PIP-SCONN,HA   I111 @BASEBOARD_FAB2_LIB.BASEBOARD_FAB2(SCH_1):PAGE45
  J6U1   69     A6 SCONN288_H44441003_PIP-SCONN,HA    I14 @BASEBOARD_FAB2_LIB.BASEBOARD_FAB2(SCH_1):PAGE46

M_B_MA<7> @BASEBOARD_FAB2_LIB.BASEBOARD_FAB2(SCH_1):M_B_MA(7)
  U5D1  V61 DDR1_MA<7> SKX_EXT_B_BGA1-IC,TBD   I172 @BASEBOARD_FAB2_LIB.BASEBOARD_FAB2(SCH_1):PAGE24
  J4G2  211     A7 SCONN288_H44441004_PIP-SCONN,HA   I111 @BASEBOARD_FAB2_LIB.BASEBOARD_FAB2(SCH_1):PAGE45
  J6U1  211     A7 SCONN288_H44441003_PIP-SCONN,HA    I14 @BASEBOARD_FAB2_LIB.BASEBOARD_FAB2(SCH_1):PAGE46

M_B_MA<8> @BASEBOARD_FAB2_LIB.BASEBOARD_FAB2(SCH_1):M_B_MA(8)
  U5D1  W60 DDR1_MA<8> SKX_EXT_B_BGA1-IC,TBD   I172 @BASEBOARD_FAB2_LIB.BASEBOARD_FAB2(SCH_1):PAGE24
  J4G2   68     A8 SCONN288_H44441004_PIP-SCONN,HA   I111 @BASEBOARD_FAB2_LIB.BASEBOARD_FAB2(SCH_1):PAGE45
  J6U1   68     A8 SCONN288_H44441003_PIP-SCONN,HA    I14 @BASEBOARD_FAB2_LIB.BASEBOARD_FAB2(SCH_1):PAGE46

M_B_MA<9> @BASEBOARD_FAB2_LIB.BASEBOARD_FAB2(SCH_1):M_B_MA(9)
  U5D1  K59 DDR1_MA<9> SKX_EXT_B_BGA1-IC,TBD   I172 @BASEBOARD_FAB2_LIB.BASEBOARD_FAB2(SCH_1):PAGE24
  J4G2   66     A9 SCONN288_H44441004_PIP-SCONN,HA   I111 @BASEBOARD_FAB2_LIB.BASEBOARD_FAB2(SCH_1):PAGE45
  J6U1   66     A9 SCONN288_H44441003_PIP-SCONN,HA    I14 @BASEBOARD_FAB2_LIB.BASEBOARD_FAB2(SCH_1):PAGE46

M_B_ODT<0> @BASEBOARD_FAB2_LIB.BASEBOARD_FAB2(SCH_1):M_B_ODT(0)
  U5D1  N50 DDR1_ODT<0> SKX_EXT_B_BGA1-IC,TBD   I172 @BASEBOARD_FAB2_LIB.BASEBOARD_FAB2(SCH_1):PAGE24
  J4G2   87 ODT<0> SCONN288_H44441004_PIP-SCONN,HA   I111 @BASEBOARD_FAB2_LIB.BASEBOARD_FAB2(SCH_1):PAGE45

M_B_ODT<1> @BASEBOARD_FAB2_LIB.BASEBOARD_FAB2(SCH_1):M_B_ODT(1)
  U5D1  R48 DDR1_ODT<1> SKX_EXT_B_BGA1-IC,TBD   I172 @BASEBOARD_FAB2_LIB.BASEBOARD_FAB2(SCH_1):PAGE24
  J4G2   91 ODT<1> SCONN288_H44441004_PIP-SCONN,HA   I111 @BASEBOARD_FAB2_LIB.BASEBOARD_FAB2(SCH_1):PAGE45

M_B_ODT<2> @BASEBOARD_FAB2_LIB.BASEBOARD_FAB2(SCH_1):M_B_ODT(2)
  U5D1  M49 DDR1_ODT<2> SKX_EXT_B_BGA1-IC,TBD   I172 @BASEBOARD_FAB2_LIB.BASEBOARD_FAB2(SCH_1):PAGE24
  J6U1   87 ODT<0> SCONN288_H44441003_PIP-SCONN,HA    I14 @BASEBOARD_FAB2_LIB.BASEBOARD_FAB2(SCH_1):PAGE46

M_B_ODT<3> @BASEBOARD_FAB2_LIB.BASEBOARD_FAB2(SCH_1):M_B_ODT(3)
  U5D1  T47 DDR1_ODT<3> SKX_EXT_B_BGA1-IC,TBD   I172 @BASEBOARD_FAB2_LIB.BASEBOARD_FAB2(SCH_1):PAGE24
  J6U1   91 ODT<1> SCONN288_H44441003_PIP-SCONN,HA    I14 @BASEBOARD_FAB2_LIB.BASEBOARD_FAB2(SCH_1):PAGE46

M_B_PAR @BASEBOARD_FAB2_LIB.BASEBOARD_FAB2(SCH_1):M_B_PAR
  U5D1  K53 DDR1_PAR SKX_EXT_B_BGA1-IC,TBD   I172 @BASEBOARD_FAB2_LIB.BASEBOARD_FAB2(SCH_1):PAGE24
  J4G2  222    PAR SCONN288_H44441004_PIP-SCONN,HA   I111 @BASEBOARD_FAB2_LIB.BASEBOARD_FAB2(SCH_1):PAGE45
  J6U1  222    PAR SCONN288_H44441003_PIP-SCONN,HA    I14 @BASEBOARD_FAB2_LIB.BASEBOARD_FAB2(SCH_1):PAGE46

M_B_VREF @BASEBOARD_FAB2_LIB.BASEBOARD_FAB2(SCH_1):M_B_VREF
  J4G2  146 VREFCA SCONN288_H44441004_PIP-SCONN,HA   I111 @BASEBOARD_FAB2_LIB.BASEBOARD_FAB2(SCH_1):PAGE45
  C4G3    1      A CAP_A_0402V-0.01UF,25V,10%,X7RA   I179 @BASEBOARD_FAB2_LIB.BASEBOARD_FAB2(SCH_1):PAGE45
  C6U9    1      A CAP_A_0402V-0.01UF,25V,10%,X7RA     I5 @BASEBOARD_FAB2_LIB.BASEBOARD_FAB2(SCH_1):PAGE46
  J6U1  146 VREFCA SCONN288_H44441003_PIP-SCONN,HA    I14 @BASEBOARD_FAB2_LIB.BASEBOARD_FAB2(SCH_1):PAGE46
  R4G2    2      B RES_0402-1.00K,1%,1/16W,CHIP,GA    I38 @BASEBOARD_FAB2_LIB.BASEBOARD_FAB2(SCH_1):PAGE98
  R4G3    1      A RES_0402-1.00K,1%,1/16W,CHIP,GA    I40 @BASEBOARD_FAB2_LIB.BASEBOARD_FAB2(SCH_1):PAGE98
  R4G1    2      B RES_0402-2,1.0%,1/16W,CHIP,G21A    I42 @BASEBOARD_FAB2_LIB.BASEBOARD_FAB2(SCH_1):PAGE98

M_C_ACT_N @BASEBOARD_FAB2_LIB.BASEBOARD_FAB2(SCH_1):M_C_ACT_N
  U5D1 AB61 DDR2_ACT_N SKX_EXT_B_BGA1-IC,TBD   I172 @BASEBOARD_FAB2_LIB.BASEBOARD_FAB2(SCH_1):PAGE25
  J4G3   62  ACT_N SCONN288_H44441004_PIP-SCONN,HA   I111 @BASEBOARD_FAB2_LIB.BASEBOARD_FAB2(SCH_1):PAGE47
  J6U2   62  ACT_N SCONN288_H44441003_PIP-SCONN,HA   I111 @BASEBOARD_FAB2_LIB.BASEBOARD_FAB2(SCH_1):PAGE48

M_C_ALERT_N @BASEBOARD_FAB2_LIB.BASEBOARD_FAB2(SCH_1):M_C_ALERT_N
  U5D1 AD61 DDR2_ALERT_N SKX_EXT_B_BGA1-IC,TBD   I172 @BASEBOARD_FAB2_LIB.BASEBOARD_FAB2(SCH_1):PAGE25
  J4G3  208 ALERT_N SCONN288_H44441004_PIP-SCONN,HA   I111 @BASEBOARD_FAB2_LIB.BASEBOARD_FAB2(SCH_1):PAGE47
  J6U2  208 ALERT_N SCONN288_H44441003_PIP-SCONN,HA   I111 @BASEBOARD_FAB2_LIB.BASEBOARD_FAB2(SCH_1):PAGE48

M_C_BA<0> @BASEBOARD_FAB2_LIB.BASEBOARD_FAB2(SCH_1):M_C_BA(0)
  U5D1  W52 DDR2_BA<0> SKX_EXT_B_BGA1-IC,TBD   I172 @BASEBOARD_FAB2_LIB.BASEBOARD_FAB2(SCH_1):PAGE25
  J4G3   81  BA<0> SCONN288_H44441004_PIP-SCONN,HA   I111 @BASEBOARD_FAB2_LIB.BASEBOARD_FAB2(SCH_1):PAGE47
  J6U2   81  BA<0> SCONN288_H44441003_PIP-SCONN,HA   I111 @BASEBOARD_FAB2_LIB.BASEBOARD_FAB2(SCH_1):PAGE48

M_C_BA<1> @BASEBOARD_FAB2_LIB.BASEBOARD_FAB2(SCH_1):M_C_BA(1)
  U5D1 AE56 DDR2_BA<1> SKX_EXT_B_BGA1-IC,TBD   I172 @BASEBOARD_FAB2_LIB.BASEBOARD_FAB2(SCH_1):PAGE25
  J4G3  224  BA<1> SCONN288_H44441004_PIP-SCONN,HA   I111 @BASEBOARD_FAB2_LIB.BASEBOARD_FAB2(SCH_1):PAGE47
  J6U2  224  BA<1> SCONN288_H44441003_PIP-SCONN,HA   I111 @BASEBOARD_FAB2_LIB.BASEBOARD_FAB2(SCH_1):PAGE48

M_C_BG<0> @BASEBOARD_FAB2_LIB.BASEBOARD_FAB2(SCH_1):M_C_BG(0)
  U5D1 AA60 DDR2_BG<0> SKX_EXT_B_BGA1-IC,TBD   I172 @BASEBOARD_FAB2_LIB.BASEBOARD_FAB2(SCH_1):PAGE25
  J4G3   63  BG<0> SCONN288_H44441004_PIP-SCONN,HA   I111 @BASEBOARD_FAB2_LIB.BASEBOARD_FAB2(SCH_1):PAGE47
  J6U2   63  BG<0> SCONN288_H44441003_PIP-SCONN,HA   I111 @BASEBOARD_FAB2_LIB.BASEBOARD_FAB2(SCH_1):PAGE48

M_C_BG<1> @BASEBOARD_FAB2_LIB.BASEBOARD_FAB2(SCH_1):M_C_BG(1)
  U5D1 AE62 DDR2_BG<1> SKX_EXT_B_BGA1-IC,TBD   I172 @BASEBOARD_FAB2_LIB.BASEBOARD_FAB2(SCH_1):PAGE25
  J4G3  207  BG<1> SCONN288_H44441004_PIP-SCONN,HA   I111 @BASEBOARD_FAB2_LIB.BASEBOARD_FAB2(SCH_1):PAGE47
  J6U2  207  BG<1> SCONN288_H44441003_PIP-SCONN,HA   I111 @BASEBOARD_FAB2_LIB.BASEBOARD_FAB2(SCH_1):PAGE48

M_C_C<2> @BASEBOARD_FAB2_LIB.BASEBOARD_FAB2(SCH_1):M_C_C(2)
  U5D1 AB45 DDR2_CID<2> SKX_EXT_B_BGA1-IC,TBD   I172 @BASEBOARD_FAB2_LIB.BASEBOARD_FAB2(SCH_1):PAGE25
  J4G3  235   C<2> SCONN288_H44441004_PIP-SCONN,HA   I111 @BASEBOARD_FAB2_LIB.BASEBOARD_FAB2(SCH_1):PAGE47
  J6U2  235   C<2> SCONN288_H44441003_PIP-SCONN,HA   I111 @BASEBOARD_FAB2_LIB.BASEBOARD_FAB2(SCH_1):PAGE48

M_C_CKE<0> @BASEBOARD_FAB2_LIB.BASEBOARD_FAB2(SCH_1):M_C_CKE(0)
  U5D1 AA62 DDR2_CKE<0> SKX_EXT_B_BGA1-IC,TBD   I172 @BASEBOARD_FAB2_LIB.BASEBOARD_FAB2(SCH_1):PAGE25
  J4G3   60 CKE<0> SCONN288_H44441004_PIP-SCONN,HA   I111 @BASEBOARD_FAB2_LIB.BASEBOARD_FAB2(SCH_1):PAGE47

M_C_CKE<1> @BASEBOARD_FAB2_LIB.BASEBOARD_FAB2(SCH_1):M_C_CKE(1)
  U5D1 AD63 DDR2_CKE<1> SKX_EXT_B_BGA1-IC,TBD   I172 @BASEBOARD_FAB2_LIB.BASEBOARD_FAB2(SCH_1):PAGE25
  J4G3  203 CKE<1> SCONN288_H44441004_PIP-SCONN,HA   I111 @BASEBOARD_FAB2_LIB.BASEBOARD_FAB2(SCH_1):PAGE47

M_C_CKE<2> @BASEBOARD_FAB2_LIB.BASEBOARD_FAB2(SCH_1):M_C_CKE(2)
  U5D1  V63 DDR2_CKE<2> SKX_EXT_B_BGA1-IC,TBD   I172 @BASEBOARD_FAB2_LIB.BASEBOARD_FAB2(SCH_1):PAGE25
  J6U2   60 CKE<0> SCONN288_H44441003_PIP-SCONN,HA   I111 @BASEBOARD_FAB2_LIB.BASEBOARD_FAB2(SCH_1):PAGE48

M_C_CKE<3> @BASEBOARD_FAB2_LIB.BASEBOARD_FAB2(SCH_1):M_C_CKE(3)
  U5D1 AB63 DDR2_CKE<3> SKX_EXT_B_BGA1-IC,TBD   I172 @BASEBOARD_FAB2_LIB.BASEBOARD_FAB2(SCH_1):PAGE25
  J6U2  203 CKE<1> SCONN288_H44441003_PIP-SCONN,HA   I111 @BASEBOARD_FAB2_LIB.BASEBOARD_FAB2(SCH_1):PAGE48

M_C_CLK_DN<0> @BASEBOARD_FAB2_LIB.BASEBOARD_FAB2(SCH_1):M_C_CLK_DN(0)
  U5D1 AA54 DDR2_CLK_DN<0> SKX_EXT_B_BGA1-IC,TBD   I172 @BASEBOARD_FAB2_LIB.BASEBOARD_FAB2(SCH_1):PAGE25
  J4G3   75   CK0N SCONN288_H44441004_PIP-SCONN,HA   I111 @BASEBOARD_FAB2_LIB.BASEBOARD_FAB2(SCH_1):PAGE47

M_C_CLK_DN<1> @BASEBOARD_FAB2_LIB.BASEBOARD_FAB2(SCH_1):M_C_CLK_DN(1)
  U5D1  W54 DDR2_CLK_DN<1> SKX_EXT_B_BGA1-IC,TBD   I172 @BASEBOARD_FAB2_LIB.BASEBOARD_FAB2(SCH_1):PAGE25
  J4G3  219   CK1N SCONN288_H44441004_PIP-SCONN,HA   I111 @BASEBOARD_FAB2_LIB.BASEBOARD_FAB2(SCH_1):PAGE47

M_C_CLK_DN<2> @BASEBOARD_FAB2_LIB.BASEBOARD_FAB2(SCH_1):M_C_CLK_DN(2)
  U5D1 AA56 DDR2_CLK_DN<2> SKX_EXT_B_BGA1-IC,TBD   I172 @BASEBOARD_FAB2_LIB.BASEBOARD_FAB2(SCH_1):PAGE25
  J6U2   75   CK0N SCONN288_H44441003_PIP-SCONN,HA   I111 @BASEBOARD_FAB2_LIB.BASEBOARD_FAB2(SCH_1):PAGE48

M_C_CLK_DN<3> @BASEBOARD_FAB2_LIB.BASEBOARD_FAB2(SCH_1):M_C_CLK_DN(3)
  U5D1  W56 DDR2_CLK_DN<3> SKX_EXT_B_BGA1-IC,TBD   I172 @BASEBOARD_FAB2_LIB.BASEBOARD_FAB2(SCH_1):PAGE25
  J6U2  219   CK1N SCONN288_H44441003_PIP-SCONN,HA   I111 @BASEBOARD_FAB2_LIB.BASEBOARD_FAB2(SCH_1):PAGE48

M_C_CLK_DP<0> @BASEBOARD_FAB2_LIB.BASEBOARD_FAB2(SCH_1):M_C_CLK_DP(0)
  U5D1 AB55 DDR2_CLK_DP<0> SKX_EXT_B_BGA1-IC,TBD   I172 @BASEBOARD_FAB2_LIB.BASEBOARD_FAB2(SCH_1):PAGE25
  J4G3   74   CK0P SCONN288_H44441004_PIP-SCONN,HA   I111 @BASEBOARD_FAB2_LIB.BASEBOARD_FAB2(SCH_1):PAGE47

M_C_CLK_DP<1> @BASEBOARD_FAB2_LIB.BASEBOARD_FAB2(SCH_1):M_C_CLK_DP(1)
  U5D1  V55 DDR2_CLK_DP<1> SKX_EXT_B_BGA1-IC,TBD   I172 @BASEBOARD_FAB2_LIB.BASEBOARD_FAB2(SCH_1):PAGE25
  J4G3  218   CK1P SCONN288_H44441004_PIP-SCONN,HA   I111 @BASEBOARD_FAB2_LIB.BASEBOARD_FAB2(SCH_1):PAGE47

M_C_CLK_DP<2> @BASEBOARD_FAB2_LIB.BASEBOARD_FAB2(SCH_1):M_C_CLK_DP(2)
  U5D1 AB57 DDR2_CLK_DP<2> SKX_EXT_B_BGA1-IC,TBD   I172 @BASEBOARD_FAB2_LIB.BASEBOARD_FAB2(SCH_1):PAGE25
  J6U2   74   CK0P SCONN288_H44441003_PIP-SCONN,HA   I111 @BASEBOARD_FAB2_LIB.BASEBOARD_FAB2(SCH_1):PAGE48

M_C_CLK_DP<3> @BASEBOARD_FAB2_LIB.BASEBOARD_FAB2(SCH_1):M_C_CLK_DP(3)
  U5D1  V57 DDR2_CLK_DP<3> SKX_EXT_B_BGA1-IC,TBD   I172 @BASEBOARD_FAB2_LIB.BASEBOARD_FAB2(SCH_1):PAGE25
  J6U2  218   CK1P SCONN288_H44441003_PIP-SCONN,HA   I111 @BASEBOARD_FAB2_LIB.BASEBOARD_FAB2(SCH_1):PAGE48

M_C_CPU_VREF @BASEBOARD_FAB2_LIB.BASEBOARD_FAB2(SCH_1):M_C_CPU_VREF
  U5D1 AH63 DDR2_CAVREF SKX_EXT_B_BGA1-IC,TBD   I259 @BASEBOARD_FAB2_LIB.BASEBOARD_FAB2(SCH_1):PAGE21
 R4G20    1      A RES_0402-2,1.0%,1/16W,CHIP,G21A    I50 @BASEBOARD_FAB2_LIB.BASEBOARD_FAB2(SCH_1):PAGE98
 C4G17    1      A CAP_A_0402V-0.01UF,25V,10%,X7RA    I51 @BASEBOARD_FAB2_LIB.BASEBOARD_FAB2(SCH_1):PAGE98

M_C_CS_N<0> @BASEBOARD_FAB2_LIB.BASEBOARD_FAB2(SCH_1):M_C_CS_N(0)
  U5D1  V51 DDR2_CS_N<0> SKX_EXT_B_BGA1-IC,TBD   I172 @BASEBOARD_FAB2_LIB.BASEBOARD_FAB2(SCH_1):PAGE25
  J4G3   84   S0_N SCONN288_H44441004_PIP-SCONN,HA   I111 @BASEBOARD_FAB2_LIB.BASEBOARD_FAB2(SCH_1):PAGE47

M_C_CS_N<1> @BASEBOARD_FAB2_LIB.BASEBOARD_FAB2(SCH_1):M_C_CS_N(1)
  U5D1 AB49 DDR2_CS_N<1> SKX_EXT_B_BGA1-IC,TBD   I172 @BASEBOARD_FAB2_LIB.BASEBOARD_FAB2(SCH_1):PAGE25
  J4G3   89   S1_N SCONN288_H44441004_PIP-SCONN,HA   I111 @BASEBOARD_FAB2_LIB.BASEBOARD_FAB2(SCH_1):PAGE47

M_C_CS_N<2> @BASEBOARD_FAB2_LIB.BASEBOARD_FAB2(SCH_1):M_C_CS_N(2)
  U5D1  W46 DDR2_CS_N<2> SKX_EXT_B_BGA1-IC,TBD   I172 @BASEBOARD_FAB2_LIB.BASEBOARD_FAB2(SCH_1):PAGE25
  J4G3   93 S2_N_C<0> SCONN288_H44441004_PIP-SCONN,HA   I111 @BASEBOARD_FAB2_LIB.BASEBOARD_FAB2(SCH_1):PAGE47

M_C_CS_N<3> @BASEBOARD_FAB2_LIB.BASEBOARD_FAB2(SCH_1):M_C_CS_N(3)
  U5D1 AA46 DDR2_CS_N<3> SKX_EXT_B_BGA1-IC,TBD   I172 @BASEBOARD_FAB2_LIB.BASEBOARD_FAB2(SCH_1):PAGE25
  J4G3  237 S3_N_C<1> SCONN288_H44441004_PIP-SCONN,HA   I111 @BASEBOARD_FAB2_LIB.BASEBOARD_FAB2(SCH_1):PAGE47

M_C_CS_N<4> @BASEBOARD_FAB2_LIB.BASEBOARD_FAB2(SCH_1):M_C_CS_N(4)
  U5D1 AB51 DDR2_CS_N<4> SKX_EXT_B_BGA1-IC,TBD   I172 @BASEBOARD_FAB2_LIB.BASEBOARD_FAB2(SCH_1):PAGE25
  J6U2   84   S0_N SCONN288_H44441003_PIP-SCONN,HA   I111 @BASEBOARD_FAB2_LIB.BASEBOARD_FAB2(SCH_1):PAGE48

M_C_CS_N<5> @BASEBOARD_FAB2_LIB.BASEBOARD_FAB2(SCH_1):M_C_CS_N(5)
  U5D1  W48 DDR2_CS_N<5> SKX_EXT_B_BGA1-IC,TBD   I172 @BASEBOARD_FAB2_LIB.BASEBOARD_FAB2(SCH_1):PAGE25
  J6U2   89   S1_N SCONN288_H44441003_PIP-SCONN,HA   I111 @BASEBOARD_FAB2_LIB.BASEBOARD_FAB2(SCH_1):PAGE48

M_C_CS_N<6> @BASEBOARD_FAB2_LIB.BASEBOARD_FAB2(SCH_1):M_C_CS_N(6)
  U5D1  T45 DDR2_CS_N<6> SKX_EXT_B_BGA1-IC,TBD   I172 @BASEBOARD_FAB2_LIB.BASEBOARD_FAB2(SCH_1):PAGE25
  J6U2   93 S2_N_C<0> SCONN288_H44441003_PIP-SCONN,HA   I111 @BASEBOARD_FAB2_LIB.BASEBOARD_FAB2(SCH_1):PAGE48

M_C_CS_N<7> @BASEBOARD_FAB2_LIB.BASEBOARD_FAB2(SCH_1):M_C_CS_N(7)
  U5D1  V45 DDR2_CS_N<7> SKX_EXT_B_BGA1-IC,TBD   I172 @BASEBOARD_FAB2_LIB.BASEBOARD_FAB2(SCH_1):PAGE25
  J6U2  237 S3_N_C<1> SCONN288_H44441003_PIP-SCONN,HA   I111 @BASEBOARD_FAB2_LIB.BASEBOARD_FAB2(SCH_1):PAGE48

M_C_DQ<0> @BASEBOARD_FAB2_LIB.BASEBOARD_FAB2(SCH_1):M_C_DQ(0)
  U5D1 AR76 DDR2_DQ<0> SKX_EXT_B_BGA1-IC,TBD   I172 @BASEBOARD_FAB2_LIB.BASEBOARD_FAB2(SCH_1):PAGE25
  J4G3  150  DQ<1> SCONN288_H44441004_PIP-SCONN,HA   I111 @BASEBOARD_FAB2_LIB.BASEBOARD_FAB2(SCH_1):PAGE47
  J6U2    5  DQ<0> SCONN288_H44441003_PIP-SCONN,HA   I111 @BASEBOARD_FAB2_LIB.BASEBOARD_FAB2(SCH_1):PAGE48

M_C_DQ<10> @BASEBOARD_FAB2_LIB.BASEBOARD_FAB2(SCH_1):M_C_DQ(10)
  U5D1  Y77 DDR2_DQ<10> SKX_EXT_B_BGA1-IC,TBD   I172 @BASEBOARD_FAB2_LIB.BASEBOARD_FAB2(SCH_1):PAGE25
  J4G3  168 DQ<11> SCONN288_H44441004_PIP-SCONN,HA   I111 @BASEBOARD_FAB2_LIB.BASEBOARD_FAB2(SCH_1):PAGE47
  J6U2   23 DQ<10> SCONN288_H44441003_PIP-SCONN,HA   I111 @BASEBOARD_FAB2_LIB.BASEBOARD_FAB2(SCH_1):PAGE48

M_C_DQ<11> @BASEBOARD_FAB2_LIB.BASEBOARD_FAB2(SCH_1):M_C_DQ(11)
  U5D1  W76 DDR2_DQ<11> SKX_EXT_B_BGA1-IC,TBD   I172 @BASEBOARD_FAB2_LIB.BASEBOARD_FAB2(SCH_1):PAGE25
  J4G3   23 DQ<10> SCONN288_H44441004_PIP-SCONN,HA   I111 @BASEBOARD_FAB2_LIB.BASEBOARD_FAB2(SCH_1):PAGE47
  J6U2  168 DQ<11> SCONN288_H44441003_PIP-SCONN,HA   I111 @BASEBOARD_FAB2_LIB.BASEBOARD_FAB2(SCH_1):PAGE48

M_C_DQ<12> @BASEBOARD_FAB2_LIB.BASEBOARD_FAB2(SCH_1):M_C_DQ(12)
  U5D1 AF75 DDR2_DQ<12> SKX_EXT_B_BGA1-IC,TBD   I172 @BASEBOARD_FAB2_LIB.BASEBOARD_FAB2(SCH_1):PAGE25
  J4G3  159 DQ<13> SCONN288_H44441004_PIP-SCONN,HA   I111 @BASEBOARD_FAB2_LIB.BASEBOARD_FAB2(SCH_1):PAGE47
  J6U2   14 DQ<12> SCONN288_H44441003_PIP-SCONN,HA   I111 @BASEBOARD_FAB2_LIB.BASEBOARD_FAB2(SCH_1):PAGE48

M_C_DQ<13> @BASEBOARD_FAB2_LIB.BASEBOARD_FAB2(SCH_1):M_C_DQ(13)
  U5D1 AE74 DDR2_DQ<13> SKX_EXT_B_BGA1-IC,TBD   I172 @BASEBOARD_FAB2_LIB.BASEBOARD_FAB2(SCH_1):PAGE25
  J4G3   14 DQ<12> SCONN288_H44441004_PIP-SCONN,HA   I111 @BASEBOARD_FAB2_LIB.BASEBOARD_FAB2(SCH_1):PAGE47
  J6U2  159 DQ<13> SCONN288_H44441003_PIP-SCONN,HA   I111 @BASEBOARD_FAB2_LIB.BASEBOARD_FAB2(SCH_1):PAGE48

M_C_DQ<14> @BASEBOARD_FAB2_LIB.BASEBOARD_FAB2(SCH_1):M_C_DQ(14)
  U5D1 AB77 DDR2_DQ<14> SKX_EXT_B_BGA1-IC,TBD   I172 @BASEBOARD_FAB2_LIB.BASEBOARD_FAB2(SCH_1):PAGE25
  J4G3  166 DQ<15> SCONN288_H44441004_PIP-SCONN,HA   I111 @BASEBOARD_FAB2_LIB.BASEBOARD_FAB2(SCH_1):PAGE47
  J6U2   21 DQ<14> SCONN288_H44441003_PIP-SCONN,HA   I111 @BASEBOARD_FAB2_LIB.BASEBOARD_FAB2(SCH_1):PAGE48

M_C_DQ<15> @BASEBOARD_FAB2_LIB.BASEBOARD_FAB2(SCH_1):M_C_DQ(15)
  U5D1  Y75 DDR2_DQ<15> SKX_EXT_B_BGA1-IC,TBD   I172 @BASEBOARD_FAB2_LIB.BASEBOARD_FAB2(SCH_1):PAGE25
  J4G3   21 DQ<14> SCONN288_H44441004_PIP-SCONN,HA   I111 @BASEBOARD_FAB2_LIB.BASEBOARD_FAB2(SCH_1):PAGE47
  J6U2  166 DQ<15> SCONN288_H44441003_PIP-SCONN,HA   I111 @BASEBOARD_FAB2_LIB.BASEBOARD_FAB2(SCH_1):PAGE48

M_C_DQ<16> @BASEBOARD_FAB2_LIB.BASEBOARD_FAB2(SCH_1):M_C_DQ(16)
  U5D1  W72 DDR2_DQ<16> SKX_EXT_B_BGA1-IC,TBD   I172 @BASEBOARD_FAB2_LIB.BASEBOARD_FAB2(SCH_1):PAGE25
  J4G3  172 DQ<17> SCONN288_H44441004_PIP-SCONN,HA   I111 @BASEBOARD_FAB2_LIB.BASEBOARD_FAB2(SCH_1):PAGE47
  J6U2   27 DQ<16> SCONN288_H44441003_PIP-SCONN,HA   I111 @BASEBOARD_FAB2_LIB.BASEBOARD_FAB2(SCH_1):PAGE48

M_C_DQ<17> @BASEBOARD_FAB2_LIB.BASEBOARD_FAB2(SCH_1):M_C_DQ(17)
  U5D1 AA70 DDR2_DQ<17> SKX_EXT_B_BGA1-IC,TBD   I172 @BASEBOARD_FAB2_LIB.BASEBOARD_FAB2(SCH_1):PAGE25
  J4G3   27 DQ<16> SCONN288_H44441004_PIP-SCONN,HA   I111 @BASEBOARD_FAB2_LIB.BASEBOARD_FAB2(SCH_1):PAGE47
  J6U2  172 DQ<17> SCONN288_H44441003_PIP-SCONN,HA   I111 @BASEBOARD_FAB2_LIB.BASEBOARD_FAB2(SCH_1):PAGE48

M_C_DQ<18> @BASEBOARD_FAB2_LIB.BASEBOARD_FAB2(SCH_1):M_C_DQ(18)
  U5D1  R70 DDR2_DQ<18> SKX_EXT_B_BGA1-IC,TBD   I172 @BASEBOARD_FAB2_LIB.BASEBOARD_FAB2(SCH_1):PAGE25
  J4G3  179 DQ<19> SCONN288_H44441004_PIP-SCONN,HA   I111 @BASEBOARD_FAB2_LIB.BASEBOARD_FAB2(SCH_1):PAGE47
  J6U2   34 DQ<18> SCONN288_H44441003_PIP-SCONN,HA   I111 @BASEBOARD_FAB2_LIB.BASEBOARD_FAB2(SCH_1):PAGE48

M_C_DQ<19> @BASEBOARD_FAB2_LIB.BASEBOARD_FAB2(SCH_1):M_C_DQ(19)
  U5D1  T69 DDR2_DQ<19> SKX_EXT_B_BGA1-IC,TBD   I172 @BASEBOARD_FAB2_LIB.BASEBOARD_FAB2(SCH_1):PAGE25
  J4G3   34 DQ<18> SCONN288_H44441004_PIP-SCONN,HA   I111 @BASEBOARD_FAB2_LIB.BASEBOARD_FAB2(SCH_1):PAGE47
  J6U2  179 DQ<19> SCONN288_H44441003_PIP-SCONN,HA   I111 @BASEBOARD_FAB2_LIB.BASEBOARD_FAB2(SCH_1):PAGE48

M_C_DQ<1> @BASEBOARD_FAB2_LIB.BASEBOARD_FAB2(SCH_1):M_C_DQ(1)
  U5D1 AN74 DDR2_DQ<1> SKX_EXT_B_BGA1-IC,TBD   I172 @BASEBOARD_FAB2_LIB.BASEBOARD_FAB2(SCH_1):PAGE25
  J4G3    5  DQ<0> SCONN288_H44441004_PIP-SCONN,HA   I111 @BASEBOARD_FAB2_LIB.BASEBOARD_FAB2(SCH_1):PAGE47
  J6U2  150  DQ<1> SCONN288_H44441003_PIP-SCONN,HA   I111 @BASEBOARD_FAB2_LIB.BASEBOARD_FAB2(SCH_1):PAGE48

M_C_DQ<20> @BASEBOARD_FAB2_LIB.BASEBOARD_FAB2(SCH_1):M_C_DQ(20)
  U5D1 AA72 DDR2_DQ<20> SKX_EXT_B_BGA1-IC,TBD   I172 @BASEBOARD_FAB2_LIB.BASEBOARD_FAB2(SCH_1):PAGE25
  J4G3  170 DQ<21> SCONN288_H44441004_PIP-SCONN,HA   I111 @BASEBOARD_FAB2_LIB.BASEBOARD_FAB2(SCH_1):PAGE47
  J6U2   25 DQ<20> SCONN288_H44441003_PIP-SCONN,HA   I111 @BASEBOARD_FAB2_LIB.BASEBOARD_FAB2(SCH_1):PAGE48

M_C_DQ<21> @BASEBOARD_FAB2_LIB.BASEBOARD_FAB2(SCH_1):M_C_DQ(21)
  U5D1 AB71 DDR2_DQ<21> SKX_EXT_B_BGA1-IC,TBD   I172 @BASEBOARD_FAB2_LIB.BASEBOARD_FAB2(SCH_1):PAGE25
  J4G3   25 DQ<20> SCONN288_H44441004_PIP-SCONN,HA   I111 @BASEBOARD_FAB2_LIB.BASEBOARD_FAB2(SCH_1):PAGE47
  J6U2  170 DQ<21> SCONN288_H44441003_PIP-SCONN,HA   I111 @BASEBOARD_FAB2_LIB.BASEBOARD_FAB2(SCH_1):PAGE48

M_C_DQ<22> @BASEBOARD_FAB2_LIB.BASEBOARD_FAB2(SCH_1):M_C_DQ(22)
  U5D1  T71 DDR2_DQ<22> SKX_EXT_B_BGA1-IC,TBD   I172 @BASEBOARD_FAB2_LIB.BASEBOARD_FAB2(SCH_1):PAGE25
  J4G3  177 DQ<23> SCONN288_H44441004_PIP-SCONN,HA   I111 @BASEBOARD_FAB2_LIB.BASEBOARD_FAB2(SCH_1):PAGE47
  J6U2   32 DQ<22> SCONN288_H44441003_PIP-SCONN,HA   I111 @BASEBOARD_FAB2_LIB.BASEBOARD_FAB2(SCH_1):PAGE48

M_C_DQ<23> @BASEBOARD_FAB2_LIB.BASEBOARD_FAB2(SCH_1):M_C_DQ(23)
  U5D1  V69 DDR2_DQ<23> SKX_EXT_B_BGA1-IC,TBD   I172 @BASEBOARD_FAB2_LIB.BASEBOARD_FAB2(SCH_1):PAGE25
  J4G3   32 DQ<22> SCONN288_H44441004_PIP-SCONN,HA   I111 @BASEBOARD_FAB2_LIB.BASEBOARD_FAB2(SCH_1):PAGE47
  J6U2  177 DQ<23> SCONN288_H44441003_PIP-SCONN,HA   I111 @BASEBOARD_FAB2_LIB.BASEBOARD_FAB2(SCH_1):PAGE48

M_C_DQ<24> @BASEBOARD_FAB2_LIB.BASEBOARD_FAB2(SCH_1):M_C_DQ(24)
  U5D1 AM67 DDR2_DQ<24> SKX_EXT_B_BGA1-IC,TBD   I172 @BASEBOARD_FAB2_LIB.BASEBOARD_FAB2(SCH_1):PAGE25
  J4G3  183 DQ<25> SCONN288_H44441004_PIP-SCONN,HA   I111 @BASEBOARD_FAB2_LIB.BASEBOARD_FAB2(SCH_1):PAGE47
  J6U2   38 DQ<24> SCONN288_H44441003_PIP-SCONN,HA   I111 @BASEBOARD_FAB2_LIB.BASEBOARD_FAB2(SCH_1):PAGE48

M_C_DQ<25> @BASEBOARD_FAB2_LIB.BASEBOARD_FAB2(SCH_1):M_C_DQ(25)
  U5D1 AT67 DDR2_DQ<25> SKX_EXT_B_BGA1-IC,TBD   I172 @BASEBOARD_FAB2_LIB.BASEBOARD_FAB2(SCH_1):PAGE25
  J4G3   38 DQ<24> SCONN288_H44441004_PIP-SCONN,HA   I111 @BASEBOARD_FAB2_LIB.BASEBOARD_FAB2(SCH_1):PAGE47
  J6U2  183 DQ<25> SCONN288_H44441003_PIP-SCONN,HA   I111 @BASEBOARD_FAB2_LIB.BASEBOARD_FAB2(SCH_1):PAGE48

M_C_DQ<26> @BASEBOARD_FAB2_LIB.BASEBOARD_FAB2(SCH_1):M_C_DQ(26)
  U5D1 AN64 DDR2_DQ<26> SKX_EXT_B_BGA1-IC,TBD   I172 @BASEBOARD_FAB2_LIB.BASEBOARD_FAB2(SCH_1):PAGE25
  J4G3  190 DQ<27> SCONN288_H44441004_PIP-SCONN,HA   I111 @BASEBOARD_FAB2_LIB.BASEBOARD_FAB2(SCH_1):PAGE47
  J6U2   45 DQ<26> SCONN288_H44441003_PIP-SCONN,HA   I111 @BASEBOARD_FAB2_LIB.BASEBOARD_FAB2(SCH_1):PAGE48

M_C_DQ<27> @BASEBOARD_FAB2_LIB.BASEBOARD_FAB2(SCH_1):M_C_DQ(27)
  U5D1 AR64 DDR2_DQ<27> SKX_EXT_B_BGA1-IC,TBD   I172 @BASEBOARD_FAB2_LIB.BASEBOARD_FAB2(SCH_1):PAGE25
  J4G3   45 DQ<26> SCONN288_H44441004_PIP-SCONN,HA   I111 @BASEBOARD_FAB2_LIB.BASEBOARD_FAB2(SCH_1):PAGE47
  J6U2  190 DQ<27> SCONN288_H44441003_PIP-SCONN,HA   I111 @BASEBOARD_FAB2_LIB.BASEBOARD_FAB2(SCH_1):PAGE48

M_C_DQ<28> @BASEBOARD_FAB2_LIB.BASEBOARD_FAB2(SCH_1):M_C_DQ(28)
  U5D1 AN68 DDR2_DQ<28> SKX_EXT_B_BGA1-IC,TBD   I172 @BASEBOARD_FAB2_LIB.BASEBOARD_FAB2(SCH_1):PAGE25
  J4G3  181 DQ<29> SCONN288_H44441004_PIP-SCONN,HA   I111 @BASEBOARD_FAB2_LIB.BASEBOARD_FAB2(SCH_1):PAGE47
  J6U2   36 DQ<28> SCONN288_H44441003_PIP-SCONN,HA   I111 @BASEBOARD_FAB2_LIB.BASEBOARD_FAB2(SCH_1):PAGE48

M_C_DQ<29> @BASEBOARD_FAB2_LIB.BASEBOARD_FAB2(SCH_1):M_C_DQ(29)
  U5D1 AR68 DDR2_DQ<29> SKX_EXT_B_BGA1-IC,TBD   I172 @BASEBOARD_FAB2_LIB.BASEBOARD_FAB2(SCH_1):PAGE25
  J4G3   36 DQ<28> SCONN288_H44441004_PIP-SCONN,HA   I111 @BASEBOARD_FAB2_LIB.BASEBOARD_FAB2(SCH_1):PAGE47
  J6U2  181 DQ<29> SCONN288_H44441003_PIP-SCONN,HA   I111 @BASEBOARD_FAB2_LIB.BASEBOARD_FAB2(SCH_1):PAGE48

M_C_DQ<2> @BASEBOARD_FAB2_LIB.BASEBOARD_FAB2(SCH_1):M_C_DQ(2)
  U5D1 AK77 DDR2_DQ<2> SKX_EXT_B_BGA1-IC,TBD   I172 @BASEBOARD_FAB2_LIB.BASEBOARD_FAB2(SCH_1):PAGE25
  J4G3  157  DQ<3> SCONN288_H44441004_PIP-SCONN,HA   I111 @BASEBOARD_FAB2_LIB.BASEBOARD_FAB2(SCH_1):PAGE47
  J6U2   12  DQ<2> SCONN288_H44441003_PIP-SCONN,HA   I111 @BASEBOARD_FAB2_LIB.BASEBOARD_FAB2(SCH_1):PAGE48

M_C_DQ<30> @BASEBOARD_FAB2_LIB.BASEBOARD_FAB2(SCH_1):M_C_DQ(30)
  U5D1 AM65 DDR2_DQ<30> SKX_EXT_B_BGA1-IC,TBD   I172 @BASEBOARD_FAB2_LIB.BASEBOARD_FAB2(SCH_1):PAGE25
  J4G3  188 DQ<31> SCONN288_H44441004_PIP-SCONN,HA   I111 @BASEBOARD_FAB2_LIB.BASEBOARD_FAB2(SCH_1):PAGE47
  J6U2   43 DQ<30> SCONN288_H44441003_PIP-SCONN,HA   I111 @BASEBOARD_FAB2_LIB.BASEBOARD_FAB2(SCH_1):PAGE48

M_C_DQ<31> @BASEBOARD_FAB2_LIB.BASEBOARD_FAB2(SCH_1):M_C_DQ(31)
  U5D1 AT65 DDR2_DQ<31> SKX_EXT_B_BGA1-IC,TBD   I172 @BASEBOARD_FAB2_LIB.BASEBOARD_FAB2(SCH_1):PAGE25
  J4G3   43 DQ<30> SCONN288_H44441004_PIP-SCONN,HA   I111 @BASEBOARD_FAB2_LIB.BASEBOARD_FAB2(SCH_1):PAGE47
  J6U2  188 DQ<31> SCONN288_H44441003_PIP-SCONN,HA   I111 @BASEBOARD_FAB2_LIB.BASEBOARD_FAB2(SCH_1):PAGE48

M_C_DQ<32> @BASEBOARD_FAB2_LIB.BASEBOARD_FAB2(SCH_1):M_C_DQ(32)
  U5D1  U40 DDR2_DQ<32> SKX_EXT_B_BGA1-IC,TBD   I172 @BASEBOARD_FAB2_LIB.BASEBOARD_FAB2(SCH_1):PAGE25
  J4G3  242 DQ<33> SCONN288_H44441004_PIP-SCONN,HA   I111 @BASEBOARD_FAB2_LIB.BASEBOARD_FAB2(SCH_1):PAGE47
  J6U2   97 DQ<32> SCONN288_H44441003_PIP-SCONN,HA   I111 @BASEBOARD_FAB2_LIB.BASEBOARD_FAB2(SCH_1):PAGE48

M_C_DQ<33> @BASEBOARD_FAB2_LIB.BASEBOARD_FAB2(SCH_1):M_C_DQ(33)
  U5D1 AA40 DDR2_DQ<33> SKX_EXT_B_BGA1-IC,TBD   I172 @BASEBOARD_FAB2_LIB.BASEBOARD_FAB2(SCH_1):PAGE25
  J4G3   97 DQ<32> SCONN288_H44441004_PIP-SCONN,HA   I111 @BASEBOARD_FAB2_LIB.BASEBOARD_FAB2(SCH_1):PAGE47
  J6U2  242 DQ<33> SCONN288_H44441003_PIP-SCONN,HA   I111 @BASEBOARD_FAB2_LIB.BASEBOARD_FAB2(SCH_1):PAGE48

M_C_DQ<34> @BASEBOARD_FAB2_LIB.BASEBOARD_FAB2(SCH_1):M_C_DQ(34)
  U5D1  V37 DDR2_DQ<34> SKX_EXT_B_BGA1-IC,TBD   I172 @BASEBOARD_FAB2_LIB.BASEBOARD_FAB2(SCH_1):PAGE25
  J4G3  249 DQ<35> SCONN288_H44441004_PIP-SCONN,HA   I111 @BASEBOARD_FAB2_LIB.BASEBOARD_FAB2(SCH_1):PAGE47
  J6U2  104 DQ<34> SCONN288_H44441003_PIP-SCONN,HA   I111 @BASEBOARD_FAB2_LIB.BASEBOARD_FAB2(SCH_1):PAGE48

M_C_DQ<35> @BASEBOARD_FAB2_LIB.BASEBOARD_FAB2(SCH_1):M_C_DQ(35)
  U5D1  Y37 DDR2_DQ<35> SKX_EXT_B_BGA1-IC,TBD   I172 @BASEBOARD_FAB2_LIB.BASEBOARD_FAB2(SCH_1):PAGE25
  J4G3  104 DQ<34> SCONN288_H44441004_PIP-SCONN,HA   I111 @BASEBOARD_FAB2_LIB.BASEBOARD_FAB2(SCH_1):PAGE47
  J6U2  249 DQ<35> SCONN288_H44441003_PIP-SCONN,HA   I111 @BASEBOARD_FAB2_LIB.BASEBOARD_FAB2(SCH_1):PAGE48

M_C_DQ<36> @BASEBOARD_FAB2_LIB.BASEBOARD_FAB2(SCH_1):M_C_DQ(36)
  U5D1  V41 DDR2_DQ<36> SKX_EXT_B_BGA1-IC,TBD   I172 @BASEBOARD_FAB2_LIB.BASEBOARD_FAB2(SCH_1):PAGE25
  J4G3  240 DQ<37> SCONN288_H44441004_PIP-SCONN,HA   I111 @BASEBOARD_FAB2_LIB.BASEBOARD_FAB2(SCH_1):PAGE47
  J6U2   95 DQ<36> SCONN288_H44441003_PIP-SCONN,HA   I111 @BASEBOARD_FAB2_LIB.BASEBOARD_FAB2(SCH_1):PAGE48

M_C_DQ<37> @BASEBOARD_FAB2_LIB.BASEBOARD_FAB2(SCH_1):M_C_DQ(37)
  U5D1  Y41 DDR2_DQ<37> SKX_EXT_B_BGA1-IC,TBD   I172 @BASEBOARD_FAB2_LIB.BASEBOARD_FAB2(SCH_1):PAGE25
  J4G3   95 DQ<36> SCONN288_H44441004_PIP-SCONN,HA   I111 @BASEBOARD_FAB2_LIB.BASEBOARD_FAB2(SCH_1):PAGE47
  J6U2  240 DQ<37> SCONN288_H44441003_PIP-SCONN,HA   I111 @BASEBOARD_FAB2_LIB.BASEBOARD_FAB2(SCH_1):PAGE48

M_C_DQ<38> @BASEBOARD_FAB2_LIB.BASEBOARD_FAB2(SCH_1):M_C_DQ(38)
  U5D1  U38 DDR2_DQ<38> SKX_EXT_B_BGA1-IC,TBD   I172 @BASEBOARD_FAB2_LIB.BASEBOARD_FAB2(SCH_1):PAGE25
  J4G3  247 DQ<39> SCONN288_H44441004_PIP-SCONN,HA   I111 @BASEBOARD_FAB2_LIB.BASEBOARD_FAB2(SCH_1):PAGE47
  J6U2  102 DQ<38> SCONN288_H44441003_PIP-SCONN,HA   I111 @BASEBOARD_FAB2_LIB.BASEBOARD_FAB2(SCH_1):PAGE48

M_C_DQ<39> @BASEBOARD_FAB2_LIB.BASEBOARD_FAB2(SCH_1):M_C_DQ(39)
  U5D1 AA38 DDR2_DQ<39> SKX_EXT_B_BGA1-IC,TBD   I172 @BASEBOARD_FAB2_LIB.BASEBOARD_FAB2(SCH_1):PAGE25
  J4G3  102 DQ<38> SCONN288_H44441004_PIP-SCONN,HA   I111 @BASEBOARD_FAB2_LIB.BASEBOARD_FAB2(SCH_1):PAGE47
  J6U2  247 DQ<39> SCONN288_H44441003_PIP-SCONN,HA   I111 @BASEBOARD_FAB2_LIB.BASEBOARD_FAB2(SCH_1):PAGE48

M_C_DQ<3> @BASEBOARD_FAB2_LIB.BASEBOARD_FAB2(SCH_1):M_C_DQ(3)
  U5D1 AJ76 DDR2_DQ<3> SKX_EXT_B_BGA1-IC,TBD   I172 @BASEBOARD_FAB2_LIB.BASEBOARD_FAB2(SCH_1):PAGE25
  J4G3   12  DQ<2> SCONN288_H44441004_PIP-SCONN,HA   I111 @BASEBOARD_FAB2_LIB.BASEBOARD_FAB2(SCH_1):PAGE47
  J6U2  157  DQ<3> SCONN288_H44441003_PIP-SCONN,HA   I111 @BASEBOARD_FAB2_LIB.BASEBOARD_FAB2(SCH_1):PAGE48

M_C_DQ<40> @BASEBOARD_FAB2_LIB.BASEBOARD_FAB2(SCH_1):M_C_DQ(40)
  U5D1  U34 DDR2_DQ<40> SKX_EXT_B_BGA1-IC,TBD   I172 @BASEBOARD_FAB2_LIB.BASEBOARD_FAB2(SCH_1):PAGE25
  J4G3  253 DQ<41> SCONN288_H44441004_PIP-SCONN,HA   I111 @BASEBOARD_FAB2_LIB.BASEBOARD_FAB2(SCH_1):PAGE47
  J6U2  108 DQ<40> SCONN288_H44441003_PIP-SCONN,HA   I111 @BASEBOARD_FAB2_LIB.BASEBOARD_FAB2(SCH_1):PAGE48

M_C_DQ<41> @BASEBOARD_FAB2_LIB.BASEBOARD_FAB2(SCH_1):M_C_DQ(41)
  U5D1 AA34 DDR2_DQ<41> SKX_EXT_B_BGA1-IC,TBD   I172 @BASEBOARD_FAB2_LIB.BASEBOARD_FAB2(SCH_1):PAGE25
  J4G3  108 DQ<40> SCONN288_H44441004_PIP-SCONN,HA   I111 @BASEBOARD_FAB2_LIB.BASEBOARD_FAB2(SCH_1):PAGE47
  J6U2  253 DQ<41> SCONN288_H44441003_PIP-SCONN,HA   I111 @BASEBOARD_FAB2_LIB.BASEBOARD_FAB2(SCH_1):PAGE48

M_C_DQ<42> @BASEBOARD_FAB2_LIB.BASEBOARD_FAB2(SCH_1):M_C_DQ(42)
  U5D1  V31 DDR2_DQ<42> SKX_EXT_B_BGA1-IC,TBD   I172 @BASEBOARD_FAB2_LIB.BASEBOARD_FAB2(SCH_1):PAGE25
  J4G3  260 DQ<43> SCONN288_H44441004_PIP-SCONN,HA   I111 @BASEBOARD_FAB2_LIB.BASEBOARD_FAB2(SCH_1):PAGE47
  J6U2  115 DQ<42> SCONN288_H44441003_PIP-SCONN,HA   I111 @BASEBOARD_FAB2_LIB.BASEBOARD_FAB2(SCH_1):PAGE48

M_C_DQ<43> @BASEBOARD_FAB2_LIB.BASEBOARD_FAB2(SCH_1):M_C_DQ(43)
  U5D1  Y31 DDR2_DQ<43> SKX_EXT_B_BGA1-IC,TBD   I172 @BASEBOARD_FAB2_LIB.BASEBOARD_FAB2(SCH_1):PAGE25
  J4G3  115 DQ<42> SCONN288_H44441004_PIP-SCONN,HA   I111 @BASEBOARD_FAB2_LIB.BASEBOARD_FAB2(SCH_1):PAGE47
  J6U2  260 DQ<43> SCONN288_H44441003_PIP-SCONN,HA   I111 @BASEBOARD_FAB2_LIB.BASEBOARD_FAB2(SCH_1):PAGE48

M_C_DQ<44> @BASEBOARD_FAB2_LIB.BASEBOARD_FAB2(SCH_1):M_C_DQ(44)
  U5D1  V35 DDR2_DQ<44> SKX_EXT_B_BGA1-IC,TBD   I172 @BASEBOARD_FAB2_LIB.BASEBOARD_FAB2(SCH_1):PAGE25
  J4G3  251 DQ<45> SCONN288_H44441004_PIP-SCONN,HA   I111 @BASEBOARD_FAB2_LIB.BASEBOARD_FAB2(SCH_1):PAGE47
  J6U2  106 DQ<44> SCONN288_H44441003_PIP-SCONN,HA   I111 @BASEBOARD_FAB2_LIB.BASEBOARD_FAB2(SCH_1):PAGE48

M_C_DQ<45> @BASEBOARD_FAB2_LIB.BASEBOARD_FAB2(SCH_1):M_C_DQ(45)
  U5D1  Y35 DDR2_DQ<45> SKX_EXT_B_BGA1-IC,TBD   I172 @BASEBOARD_FAB2_LIB.BASEBOARD_FAB2(SCH_1):PAGE25
  J4G3  106 DQ<44> SCONN288_H44441004_PIP-SCONN,HA   I111 @BASEBOARD_FAB2_LIB.BASEBOARD_FAB2(SCH_1):PAGE47
  J6U2  251 DQ<45> SCONN288_H44441003_PIP-SCONN,HA   I111 @BASEBOARD_FAB2_LIB.BASEBOARD_FAB2(SCH_1):PAGE48

M_C_DQ<46> @BASEBOARD_FAB2_LIB.BASEBOARD_FAB2(SCH_1):M_C_DQ(46)
  U5D1  U32 DDR2_DQ<46> SKX_EXT_B_BGA1-IC,TBD   I172 @BASEBOARD_FAB2_LIB.BASEBOARD_FAB2(SCH_1):PAGE25
  J4G3  258 DQ<47> SCONN288_H44441004_PIP-SCONN,HA   I111 @BASEBOARD_FAB2_LIB.BASEBOARD_FAB2(SCH_1):PAGE47
  J6U2  113 DQ<46> SCONN288_H44441003_PIP-SCONN,HA   I111 @BASEBOARD_FAB2_LIB.BASEBOARD_FAB2(SCH_1):PAGE48

M_C_DQ<47> @BASEBOARD_FAB2_LIB.BASEBOARD_FAB2(SCH_1):M_C_DQ(47)
  U5D1 AA32 DDR2_DQ<47> SKX_EXT_B_BGA1-IC,TBD   I172 @BASEBOARD_FAB2_LIB.BASEBOARD_FAB2(SCH_1):PAGE25
  J4G3  113 DQ<46> SCONN288_H44441004_PIP-SCONN,HA   I111 @BASEBOARD_FAB2_LIB.BASEBOARD_FAB2(SCH_1):PAGE47
  J6U2  258 DQ<47> SCONN288_H44441003_PIP-SCONN,HA   I111 @BASEBOARD_FAB2_LIB.BASEBOARD_FAB2(SCH_1):PAGE48

M_C_DQ<48> @BASEBOARD_FAB2_LIB.BASEBOARD_FAB2(SCH_1):M_C_DQ(48)
  U5D1 AD31 DDR2_DQ<48> SKX_EXT_B_BGA1-IC,TBD   I172 @BASEBOARD_FAB2_LIB.BASEBOARD_FAB2(SCH_1):PAGE25
  J4G3  264 DQ<49> SCONN288_H44441004_PIP-SCONN,HA   I111 @BASEBOARD_FAB2_LIB.BASEBOARD_FAB2(SCH_1):PAGE47
  J6U2  119 DQ<48> SCONN288_H44441003_PIP-SCONN,HA   I111 @BASEBOARD_FAB2_LIB.BASEBOARD_FAB2(SCH_1):PAGE48

M_C_DQ<49> @BASEBOARD_FAB2_LIB.BASEBOARD_FAB2(SCH_1):M_C_DQ(49)
  U5D1 AH31 DDR2_DQ<49> SKX_EXT_B_BGA1-IC,TBD   I172 @BASEBOARD_FAB2_LIB.BASEBOARD_FAB2(SCH_1):PAGE25
  J4G3  119 DQ<48> SCONN288_H44441004_PIP-SCONN,HA   I111 @BASEBOARD_FAB2_LIB.BASEBOARD_FAB2(SCH_1):PAGE47
  J6U2  264 DQ<49> SCONN288_H44441003_PIP-SCONN,HA   I111 @BASEBOARD_FAB2_LIB.BASEBOARD_FAB2(SCH_1):PAGE48

M_C_DQ<4> @BASEBOARD_FAB2_LIB.BASEBOARD_FAB2(SCH_1):M_C_DQ(4)
  U5D1 AT75 DDR2_DQ<4> SKX_EXT_B_BGA1-IC,TBD   I172 @BASEBOARD_FAB2_LIB.BASEBOARD_FAB2(SCH_1):PAGE25
  J4G3  148  DQ<5> SCONN288_H44441004_PIP-SCONN,HA   I111 @BASEBOARD_FAB2_LIB.BASEBOARD_FAB2(SCH_1):PAGE47
  J6U2    3  DQ<4> SCONN288_H44441003_PIP-SCONN,HA   I111 @BASEBOARD_FAB2_LIB.BASEBOARD_FAB2(SCH_1):PAGE48

M_C_DQ<50> @BASEBOARD_FAB2_LIB.BASEBOARD_FAB2(SCH_1):M_C_DQ(50)
  U5D1 AE28 DDR2_DQ<50> SKX_EXT_B_BGA1-IC,TBD   I172 @BASEBOARD_FAB2_LIB.BASEBOARD_FAB2(SCH_1):PAGE25
  J4G3  271 DQ<51> SCONN288_H44441004_PIP-SCONN,HA   I111 @BASEBOARD_FAB2_LIB.BASEBOARD_FAB2(SCH_1):PAGE47
  J6U2  126 DQ<50> SCONN288_H44441003_PIP-SCONN,HA   I111 @BASEBOARD_FAB2_LIB.BASEBOARD_FAB2(SCH_1):PAGE48

M_C_DQ<51> @BASEBOARD_FAB2_LIB.BASEBOARD_FAB2(SCH_1):M_C_DQ(51)
  U5D1 AG28 DDR2_DQ<51> SKX_EXT_B_BGA1-IC,TBD   I172 @BASEBOARD_FAB2_LIB.BASEBOARD_FAB2(SCH_1):PAGE25
  J4G3  126 DQ<50> SCONN288_H44441004_PIP-SCONN,HA   I111 @BASEBOARD_FAB2_LIB.BASEBOARD_FAB2(SCH_1):PAGE47
  J6U2  271 DQ<51> SCONN288_H44441003_PIP-SCONN,HA   I111 @BASEBOARD_FAB2_LIB.BASEBOARD_FAB2(SCH_1):PAGE48

M_C_DQ<52> @BASEBOARD_FAB2_LIB.BASEBOARD_FAB2(SCH_1):M_C_DQ(52)
  U5D1 AE32 DDR2_DQ<52> SKX_EXT_B_BGA1-IC,TBD   I172 @BASEBOARD_FAB2_LIB.BASEBOARD_FAB2(SCH_1):PAGE25
  J4G3  262 DQ<53> SCONN288_H44441004_PIP-SCONN,HA   I111 @BASEBOARD_FAB2_LIB.BASEBOARD_FAB2(SCH_1):PAGE47
  J6U2  117 DQ<52> SCONN288_H44441003_PIP-SCONN,HA   I111 @BASEBOARD_FAB2_LIB.BASEBOARD_FAB2(SCH_1):PAGE48

M_C_DQ<53> @BASEBOARD_FAB2_LIB.BASEBOARD_FAB2(SCH_1):M_C_DQ(53)
  U5D1 AG32 DDR2_DQ<53> SKX_EXT_B_BGA1-IC,TBD   I172 @BASEBOARD_FAB2_LIB.BASEBOARD_FAB2(SCH_1):PAGE25
  J4G3  117 DQ<52> SCONN288_H44441004_PIP-SCONN,HA   I111 @BASEBOARD_FAB2_LIB.BASEBOARD_FAB2(SCH_1):PAGE47
  J6U2  262 DQ<53> SCONN288_H44441003_PIP-SCONN,HA   I111 @BASEBOARD_FAB2_LIB.BASEBOARD_FAB2(SCH_1):PAGE48

M_C_DQ<54> @BASEBOARD_FAB2_LIB.BASEBOARD_FAB2(SCH_1):M_C_DQ(54)
  U5D1 AD29 DDR2_DQ<54> SKX_EXT_B_BGA1-IC,TBD   I172 @BASEBOARD_FAB2_LIB.BASEBOARD_FAB2(SCH_1):PAGE25
  J4G3  269 DQ<55> SCONN288_H44441004_PIP-SCONN,HA   I111 @BASEBOARD_FAB2_LIB.BASEBOARD_FAB2(SCH_1):PAGE47
  J6U2  124 DQ<54> SCONN288_H44441003_PIP-SCONN,HA   I111 @BASEBOARD_FAB2_LIB.BASEBOARD_FAB2(SCH_1):PAGE48

M_C_DQ<55> @BASEBOARD_FAB2_LIB.BASEBOARD_FAB2(SCH_1):M_C_DQ(55)
  U5D1 AH29 DDR2_DQ<55> SKX_EXT_B_BGA1-IC,TBD   I172 @BASEBOARD_FAB2_LIB.BASEBOARD_FAB2(SCH_1):PAGE25
  J4G3  124 DQ<54> SCONN288_H44441004_PIP-SCONN,HA   I111 @BASEBOARD_FAB2_LIB.BASEBOARD_FAB2(SCH_1):PAGE47
  J6U2  269 DQ<55> SCONN288_H44441003_PIP-SCONN,HA   I111 @BASEBOARD_FAB2_LIB.BASEBOARD_FAB2(SCH_1):PAGE48

M_C_DQ<56> @BASEBOARD_FAB2_LIB.BASEBOARD_FAB2(SCH_1):M_C_DQ(56)
  U5D1 AD25 DDR2_DQ<56> SKX_EXT_B_BGA1-IC,TBD   I172 @BASEBOARD_FAB2_LIB.BASEBOARD_FAB2(SCH_1):PAGE25
  J4G3  275 DQ<57> SCONN288_H44441004_PIP-SCONN,HA   I111 @BASEBOARD_FAB2_LIB.BASEBOARD_FAB2(SCH_1):PAGE47
  J6U2  130 DQ<56> SCONN288_H44441003_PIP-SCONN,HA   I111 @BASEBOARD_FAB2_LIB.BASEBOARD_FAB2(SCH_1):PAGE48

M_C_DQ<57> @BASEBOARD_FAB2_LIB.BASEBOARD_FAB2(SCH_1):M_C_DQ(57)
  U5D1 AH25 DDR2_DQ<57> SKX_EXT_B_BGA1-IC,TBD   I172 @BASEBOARD_FAB2_LIB.BASEBOARD_FAB2(SCH_1):PAGE25
  J4G3  130 DQ<56> SCONN288_H44441004_PIP-SCONN,HA   I111 @BASEBOARD_FAB2_LIB.BASEBOARD_FAB2(SCH_1):PAGE47
  J6U2  275 DQ<57> SCONN288_H44441003_PIP-SCONN,HA   I111 @BASEBOARD_FAB2_LIB.BASEBOARD_FAB2(SCH_1):PAGE48

M_C_DQ<58> @BASEBOARD_FAB2_LIB.BASEBOARD_FAB2(SCH_1):M_C_DQ(58)
  U5D1 AE22 DDR2_DQ<58> SKX_EXT_B_BGA1-IC,TBD   I172 @BASEBOARD_FAB2_LIB.BASEBOARD_FAB2(SCH_1):PAGE25
  J4G3  282 DQ<59> SCONN288_H44441004_PIP-SCONN,HA   I111 @BASEBOARD_FAB2_LIB.BASEBOARD_FAB2(SCH_1):PAGE47
  J6U2  137 DQ<58> SCONN288_H44441003_PIP-SCONN,HA   I111 @BASEBOARD_FAB2_LIB.BASEBOARD_FAB2(SCH_1):PAGE48

M_C_DQ<59> @BASEBOARD_FAB2_LIB.BASEBOARD_FAB2(SCH_1):M_C_DQ(59)
  U5D1 AG22 DDR2_DQ<59> SKX_EXT_B_BGA1-IC,TBD   I172 @BASEBOARD_FAB2_LIB.BASEBOARD_FAB2(SCH_1):PAGE25
  J4G3  137 DQ<58> SCONN288_H44441004_PIP-SCONN,HA   I111 @BASEBOARD_FAB2_LIB.BASEBOARD_FAB2(SCH_1):PAGE47
  J6U2  282 DQ<59> SCONN288_H44441003_PIP-SCONN,HA   I111 @BASEBOARD_FAB2_LIB.BASEBOARD_FAB2(SCH_1):PAGE48

M_C_DQ<5> @BASEBOARD_FAB2_LIB.BASEBOARD_FAB2(SCH_1):M_C_DQ(5)
  U5D1 AR74 DDR2_DQ<5> SKX_EXT_B_BGA1-IC,TBD   I172 @BASEBOARD_FAB2_LIB.BASEBOARD_FAB2(SCH_1):PAGE25
  J4G3    3  DQ<4> SCONN288_H44441004_PIP-SCONN,HA   I111 @BASEBOARD_FAB2_LIB.BASEBOARD_FAB2(SCH_1):PAGE47
  J6U2  148  DQ<5> SCONN288_H44441003_PIP-SCONN,HA   I111 @BASEBOARD_FAB2_LIB.BASEBOARD_FAB2(SCH_1):PAGE48

M_C_DQ<60> @BASEBOARD_FAB2_LIB.BASEBOARD_FAB2(SCH_1):M_C_DQ(60)
  U5D1 AE26 DDR2_DQ<60> SKX_EXT_B_BGA1-IC,TBD   I172 @BASEBOARD_FAB2_LIB.BASEBOARD_FAB2(SCH_1):PAGE25
  J4G3  273 DQ<61> SCONN288_H44441004_PIP-SCONN,HA   I111 @BASEBOARD_FAB2_LIB.BASEBOARD_FAB2(SCH_1):PAGE47
  J6U2  128 DQ<60> SCONN288_H44441003_PIP-SCONN,HA   I111 @BASEBOARD_FAB2_LIB.BASEBOARD_FAB2(SCH_1):PAGE48

M_C_DQ<61> @BASEBOARD_FAB2_LIB.BASEBOARD_FAB2(SCH_1):M_C_DQ(61)
  U5D1 AG26 DDR2_DQ<61> SKX_EXT_B_BGA1-IC,TBD   I172 @BASEBOARD_FAB2_LIB.BASEBOARD_FAB2(SCH_1):PAGE25
  J4G3  128 DQ<60> SCONN288_H44441004_PIP-SCONN,HA   I111 @BASEBOARD_FAB2_LIB.BASEBOARD_FAB2(SCH_1):PAGE47
  J6U2  273 DQ<61> SCONN288_H44441003_PIP-SCONN,HA   I111 @BASEBOARD_FAB2_LIB.BASEBOARD_FAB2(SCH_1):PAGE48

M_C_DQ<62> @BASEBOARD_FAB2_LIB.BASEBOARD_FAB2(SCH_1):M_C_DQ(62)
  U5D1 AD23 DDR2_DQ<62> SKX_EXT_B_BGA1-IC,TBD   I172 @BASEBOARD_FAB2_LIB.BASEBOARD_FAB2(SCH_1):PAGE25
  J4G3  280 DQ<63> SCONN288_H44441004_PIP-SCONN,HA   I111 @BASEBOARD_FAB2_LIB.BASEBOARD_FAB2(SCH_1):PAGE47
  J6U2  135 DQ<62> SCONN288_H44441003_PIP-SCONN,HA   I111 @BASEBOARD_FAB2_LIB.BASEBOARD_FAB2(SCH_1):PAGE48

M_C_DQ<63> @BASEBOARD_FAB2_LIB.BASEBOARD_FAB2(SCH_1):M_C_DQ(63)
  U5D1 AH23 DDR2_DQ<63> SKX_EXT_B_BGA1-IC,TBD   I172 @BASEBOARD_FAB2_LIB.BASEBOARD_FAB2(SCH_1):PAGE25
  J4G3  135 DQ<62> SCONN288_H44441004_PIP-SCONN,HA   I111 @BASEBOARD_FAB2_LIB.BASEBOARD_FAB2(SCH_1):PAGE47
  J6U2  280 DQ<63> SCONN288_H44441003_PIP-SCONN,HA   I111 @BASEBOARD_FAB2_LIB.BASEBOARD_FAB2(SCH_1):PAGE48

M_C_DQ<6> @BASEBOARD_FAB2_LIB.BASEBOARD_FAB2(SCH_1):M_C_DQ(6)
  U5D1 AM77 DDR2_DQ<6> SKX_EXT_B_BGA1-IC,TBD   I172 @BASEBOARD_FAB2_LIB.BASEBOARD_FAB2(SCH_1):PAGE25
  J4G3  155  DQ<7> SCONN288_H44441004_PIP-SCONN,HA   I111 @BASEBOARD_FAB2_LIB.BASEBOARD_FAB2(SCH_1):PAGE47
  J6U2   10  DQ<6> SCONN288_H44441003_PIP-SCONN,HA   I111 @BASEBOARD_FAB2_LIB.BASEBOARD_FAB2(SCH_1):PAGE48

M_C_DQ<7> @BASEBOARD_FAB2_LIB.BASEBOARD_FAB2(SCH_1):M_C_DQ(7)
  U5D1 AK75 DDR2_DQ<7> SKX_EXT_B_BGA1-IC,TBD   I172 @BASEBOARD_FAB2_LIB.BASEBOARD_FAB2(SCH_1):PAGE25
  J4G3   10  DQ<6> SCONN288_H44441004_PIP-SCONN,HA   I111 @BASEBOARD_FAB2_LIB.BASEBOARD_FAB2(SCH_1):PAGE47
  J6U2  155  DQ<7> SCONN288_H44441003_PIP-SCONN,HA   I111 @BASEBOARD_FAB2_LIB.BASEBOARD_FAB2(SCH_1):PAGE48

M_C_DQ<8> @BASEBOARD_FAB2_LIB.BASEBOARD_FAB2(SCH_1):M_C_DQ(8)
  U5D1 AE76 DDR2_DQ<8> SKX_EXT_B_BGA1-IC,TBD   I172 @BASEBOARD_FAB2_LIB.BASEBOARD_FAB2(SCH_1):PAGE25
  J4G3  161  DQ<9> SCONN288_H44441004_PIP-SCONN,HA   I111 @BASEBOARD_FAB2_LIB.BASEBOARD_FAB2(SCH_1):PAGE47
  J6U2   16  DQ<8> SCONN288_H44441003_PIP-SCONN,HA   I111 @BASEBOARD_FAB2_LIB.BASEBOARD_FAB2(SCH_1):PAGE48

M_C_DQ<9> @BASEBOARD_FAB2_LIB.BASEBOARD_FAB2(SCH_1):M_C_DQ(9)
  U5D1 AC74 DDR2_DQ<9> SKX_EXT_B_BGA1-IC,TBD   I172 @BASEBOARD_FAB2_LIB.BASEBOARD_FAB2(SCH_1):PAGE25
  J4G3   16  DQ<8> SCONN288_H44441004_PIP-SCONN,HA   I111 @BASEBOARD_FAB2_LIB.BASEBOARD_FAB2(SCH_1):PAGE47
  J6U2  161  DQ<9> SCONN288_H44441003_PIP-SCONN,HA   I111 @BASEBOARD_FAB2_LIB.BASEBOARD_FAB2(SCH_1):PAGE48

M_C_DQS_DN<0> @BASEBOARD_FAB2_LIB.BASEBOARD_FAB2(SCH_1):M_C_DQS_DN(0)
  U5D1 AL74 DDR2_DQS_DN<0> SKX_EXT_B_BGA1-IC,TBD   I172 @BASEBOARD_FAB2_LIB.BASEBOARD_FAB2(SCH_1):PAGE25
  J4G3  152  DQS0N SCONN288_H44441004_PIP-SCONN,HA    I61 @BASEBOARD_FAB2_LIB.BASEBOARD_FAB2(SCH_1):PAGE47
  J6U2  152  DQS0N SCONN288_H44441003_PIP-SCONN,HA    I61 @BASEBOARD_FAB2_LIB.BASEBOARD_FAB2(SCH_1):PAGE48

M_C_DQS_DN<10> @BASEBOARD_FAB2_LIB.BASEBOARD_FAB2(SCH_1):M_C_DQS_DN(10)
  U5D1 AD77 DDR2_DQS_DN<10> SKX_EXT_B_BGA1-IC,TBD   I172 @BASEBOARD_FAB2_LIB.BASEBOARD_FAB2(SCH_1):PAGE25
  J4G3   19 DQS10N SCONN288_H44441004_PIP-SCONN,HA    I61 @BASEBOARD_FAB2_LIB.BASEBOARD_FAB2(SCH_1):PAGE47
  J6U2   19 DQS10N SCONN288_H44441003_PIP-SCONN,HA    I61 @BASEBOARD_FAB2_LIB.BASEBOARD_FAB2(SCH_1):PAGE48

M_C_DQS_DN<11> @BASEBOARD_FAB2_LIB.BASEBOARD_FAB2(SCH_1):M_C_DQS_DN(11)
  U5D1  U72 DDR2_DQS_DN<11> SKX_EXT_B_BGA1-IC,TBD   I172 @BASEBOARD_FAB2_LIB.BASEBOARD_FAB2(SCH_1):PAGE25
  J4G3   30 DQS11N SCONN288_H44441004_PIP-SCONN,HA    I61 @BASEBOARD_FAB2_LIB.BASEBOARD_FAB2(SCH_1):PAGE47
  J6U2   30 DQS11N SCONN288_H44441003_PIP-SCONN,HA    I61 @BASEBOARD_FAB2_LIB.BASEBOARD_FAB2(SCH_1):PAGE48

M_C_DQS_DN<12> @BASEBOARD_FAB2_LIB.BASEBOARD_FAB2(SCH_1):M_C_DQS_DN(12)
  U5D1 AL66 DDR2_DQS_DN<12> SKX_EXT_B_BGA1-IC,TBD   I172 @BASEBOARD_FAB2_LIB.BASEBOARD_FAB2(SCH_1):PAGE25
  J4G3   41 DQS12N SCONN288_H44441004_PIP-SCONN,HA    I61 @BASEBOARD_FAB2_LIB.BASEBOARD_FAB2(SCH_1):PAGE47
  J6U2   41 DQS12N SCONN288_H44441003_PIP-SCONN,HA    I61 @BASEBOARD_FAB2_LIB.BASEBOARD_FAB2(SCH_1):PAGE48

M_C_DQS_DN<13> @BASEBOARD_FAB2_LIB.BASEBOARD_FAB2(SCH_1):M_C_DQS_DN(13)
  U5D1  T39 DDR2_DQS_DN<13> SKX_EXT_B_BGA1-IC,TBD   I172 @BASEBOARD_FAB2_LIB.BASEBOARD_FAB2(SCH_1):PAGE25
  J4G3  100 DQS13N SCONN288_H44441004_PIP-SCONN,HA    I61 @BASEBOARD_FAB2_LIB.BASEBOARD_FAB2(SCH_1):PAGE47
  J6U2  100 DQS13N SCONN288_H44441003_PIP-SCONN,HA    I61 @BASEBOARD_FAB2_LIB.BASEBOARD_FAB2(SCH_1):PAGE48

M_C_DQS_DN<14> @BASEBOARD_FAB2_LIB.BASEBOARD_FAB2(SCH_1):M_C_DQS_DN(14)
  U5D1  T33 DDR2_DQS_DN<14> SKX_EXT_B_BGA1-IC,TBD   I172 @BASEBOARD_FAB2_LIB.BASEBOARD_FAB2(SCH_1):PAGE25
  J4G3  111 DQS14N SCONN288_H44441004_PIP-SCONN,HA    I61 @BASEBOARD_FAB2_LIB.BASEBOARD_FAB2(SCH_1):PAGE47
  J6U2  111 DQS14N SCONN288_H44441003_PIP-SCONN,HA    I61 @BASEBOARD_FAB2_LIB.BASEBOARD_FAB2(SCH_1):PAGE48

M_C_DQS_DN<15> @BASEBOARD_FAB2_LIB.BASEBOARD_FAB2(SCH_1):M_C_DQS_DN(15)
  U5D1 AC30 DDR2_DQS_DN<15> SKX_EXT_B_BGA1-IC,TBD   I172 @BASEBOARD_FAB2_LIB.BASEBOARD_FAB2(SCH_1):PAGE25
  J4G3  122 DQS15N SCONN288_H44441004_PIP-SCONN,HA    I61 @BASEBOARD_FAB2_LIB.BASEBOARD_FAB2(SCH_1):PAGE47
  J6U2  122 DQS15N SCONN288_H44441003_PIP-SCONN,HA    I61 @BASEBOARD_FAB2_LIB.BASEBOARD_FAB2(SCH_1):PAGE48

M_C_DQS_DN<16> @BASEBOARD_FAB2_LIB.BASEBOARD_FAB2(SCH_1):M_C_DQS_DN(16)
  U5D1 AC24 DDR2_DQS_DN<16> SKX_EXT_B_BGA1-IC,TBD   I172 @BASEBOARD_FAB2_LIB.BASEBOARD_FAB2(SCH_1):PAGE25
  J4G3  133 DQS16N SCONN288_H44441004_PIP-SCONN,HA    I61 @BASEBOARD_FAB2_LIB.BASEBOARD_FAB2(SCH_1):PAGE47
  J6U2  133 DQS16N SCONN288_H44441003_PIP-SCONN,HA    I61 @BASEBOARD_FAB2_LIB.BASEBOARD_FAB2(SCH_1):PAGE48

M_C_DQS_DN<17> @BASEBOARD_FAB2_LIB.BASEBOARD_FAB2(SCH_1):M_C_DQS_DN(17)
  U5D1 AT71 DDR2_DQS_DN<17> SKX_EXT_B_BGA1-IC,TBD   I172 @BASEBOARD_FAB2_LIB.BASEBOARD_FAB2(SCH_1):PAGE25
  J4G3   52 DQS17N SCONN288_H44441004_PIP-SCONN,HA    I61 @BASEBOARD_FAB2_LIB.BASEBOARD_FAB2(SCH_1):PAGE47
  J6U2   52 DQS17N SCONN288_H44441003_PIP-SCONN,HA    I61 @BASEBOARD_FAB2_LIB.BASEBOARD_FAB2(SCH_1):PAGE48

M_C_DQS_DN<1> @BASEBOARD_FAB2_LIB.BASEBOARD_FAB2(SCH_1):M_C_DQS_DN(1)
  U5D1 AA74 DDR2_DQS_DN<1> SKX_EXT_B_BGA1-IC,TBD   I172 @BASEBOARD_FAB2_LIB.BASEBOARD_FAB2(SCH_1):PAGE25
  J4G3  163  DQS1N SCONN288_H44441004_PIP-SCONN,HA    I61 @BASEBOARD_FAB2_LIB.BASEBOARD_FAB2(SCH_1):PAGE47
  J6U2  163  DQS1N SCONN288_H44441003_PIP-SCONN,HA    I61 @BASEBOARD_FAB2_LIB.BASEBOARD_FAB2(SCH_1):PAGE48

M_C_DQS_DN<2> @BASEBOARD_FAB2_LIB.BASEBOARD_FAB2(SCH_1):M_C_DQS_DN(2)
  U5D1  Y69 DDR2_DQS_DN<2> SKX_EXT_B_BGA1-IC,TBD   I172 @BASEBOARD_FAB2_LIB.BASEBOARD_FAB2(SCH_1):PAGE25
  J4G3  174  DQS2N SCONN288_H44441004_PIP-SCONN,HA    I61 @BASEBOARD_FAB2_LIB.BASEBOARD_FAB2(SCH_1):PAGE47
  J6U2  174  DQS2N SCONN288_H44441003_PIP-SCONN,HA    I61 @BASEBOARD_FAB2_LIB.BASEBOARD_FAB2(SCH_1):PAGE48

M_C_DQS_DN<3> @BASEBOARD_FAB2_LIB.BASEBOARD_FAB2(SCH_1):M_C_DQS_DN(3)
  U5D1 AU66 DDR2_DQS_DN<3> SKX_EXT_B_BGA1-IC,TBD   I172 @BASEBOARD_FAB2_LIB.BASEBOARD_FAB2(SCH_1):PAGE25
  J4G3  185  DQS3N SCONN288_H44441004_PIP-SCONN,HA    I61 @BASEBOARD_FAB2_LIB.BASEBOARD_FAB2(SCH_1):PAGE47
  J6U2  185  DQS3N SCONN288_H44441003_PIP-SCONN,HA    I61 @BASEBOARD_FAB2_LIB.BASEBOARD_FAB2(SCH_1):PAGE48

M_C_DQS_DN<4> @BASEBOARD_FAB2_LIB.BASEBOARD_FAB2(SCH_1):M_C_DQS_DN(4)
  U5D1 AB39 DDR2_DQS_DN<4> SKX_EXT_B_BGA1-IC,TBD   I172 @BASEBOARD_FAB2_LIB.BASEBOARD_FAB2(SCH_1):PAGE25
  J4G3  244  DQS4N SCONN288_H44441004_PIP-SCONN,HA    I61 @BASEBOARD_FAB2_LIB.BASEBOARD_FAB2(SCH_1):PAGE47
  J6U2  244  DQS4N SCONN288_H44441003_PIP-SCONN,HA    I61 @BASEBOARD_FAB2_LIB.BASEBOARD_FAB2(SCH_1):PAGE48

M_C_DQS_DN<5> @BASEBOARD_FAB2_LIB.BASEBOARD_FAB2(SCH_1):M_C_DQS_DN(5)
  U5D1 AB33 DDR2_DQS_DN<5> SKX_EXT_B_BGA1-IC,TBD   I172 @BASEBOARD_FAB2_LIB.BASEBOARD_FAB2(SCH_1):PAGE25
  J4G3  255  DQS5N SCONN288_H44441004_PIP-SCONN,HA    I61 @BASEBOARD_FAB2_LIB.BASEBOARD_FAB2(SCH_1):PAGE47
  J6U2  255  DQS5N SCONN288_H44441003_PIP-SCONN,HA    I61 @BASEBOARD_FAB2_LIB.BASEBOARD_FAB2(SCH_1):PAGE48

M_C_DQS_DN<6> @BASEBOARD_FAB2_LIB.BASEBOARD_FAB2(SCH_1):M_C_DQS_DN(6)
  U5D1 AJ30 DDR2_DQS_DN<6> SKX_EXT_B_BGA1-IC,TBD   I172 @BASEBOARD_FAB2_LIB.BASEBOARD_FAB2(SCH_1):PAGE25
  J4G3  266  DQS6N SCONN288_H44441004_PIP-SCONN,HA    I61 @BASEBOARD_FAB2_LIB.BASEBOARD_FAB2(SCH_1):PAGE47
  J6U2  266  DQS6N SCONN288_H44441003_PIP-SCONN,HA    I61 @BASEBOARD_FAB2_LIB.BASEBOARD_FAB2(SCH_1):PAGE48

M_C_DQS_DN<7> @BASEBOARD_FAB2_LIB.BASEBOARD_FAB2(SCH_1):M_C_DQS_DN(7)
  U5D1 AJ24 DDR2_DQS_DN<7> SKX_EXT_B_BGA1-IC,TBD   I172 @BASEBOARD_FAB2_LIB.BASEBOARD_FAB2(SCH_1):PAGE25
  J4G3  277  DQS7N SCONN288_H44441004_PIP-SCONN,HA    I61 @BASEBOARD_FAB2_LIB.BASEBOARD_FAB2(SCH_1):PAGE47
  J6U2  277  DQS7N SCONN288_H44441003_PIP-SCONN,HA    I61 @BASEBOARD_FAB2_LIB.BASEBOARD_FAB2(SCH_1):PAGE48

M_C_DQS_DN<8> @BASEBOARD_FAB2_LIB.BASEBOARD_FAB2(SCH_1):M_C_DQS_DN(8)
  U5D1 BB71 DDR2_DQS_DN<8> SKX_EXT_B_BGA1-IC,TBD   I172 @BASEBOARD_FAB2_LIB.BASEBOARD_FAB2(SCH_1):PAGE25
  J4G3  196  DQS8N SCONN288_H44441004_PIP-SCONN,HA    I61 @BASEBOARD_FAB2_LIB.BASEBOARD_FAB2(SCH_1):PAGE47
  J6U2  196  DQS8N SCONN288_H44441003_PIP-SCONN,HA    I61 @BASEBOARD_FAB2_LIB.BASEBOARD_FAB2(SCH_1):PAGE48

M_C_DQS_DN<9> @BASEBOARD_FAB2_LIB.BASEBOARD_FAB2(SCH_1):M_C_DQS_DN(9)
  U5D1 AP77 DDR2_DQS_DN<9> SKX_EXT_B_BGA1-IC,TBD   I172 @BASEBOARD_FAB2_LIB.BASEBOARD_FAB2(SCH_1):PAGE25
  J4G3    8  DQS9N SCONN288_H44441004_PIP-SCONN,HA    I61 @BASEBOARD_FAB2_LIB.BASEBOARD_FAB2(SCH_1):PAGE47
  J6U2    8  DQS9N SCONN288_H44441003_PIP-SCONN,HA    I61 @BASEBOARD_FAB2_LIB.BASEBOARD_FAB2(SCH_1):PAGE48

M_C_DQS_DP<0> @BASEBOARD_FAB2_LIB.BASEBOARD_FAB2(SCH_1):M_C_DQS_DP(0)
  U5D1 AM75 DDR2_DQS_DP<0> SKX_EXT_B_BGA1-IC,TBD   I172 @BASEBOARD_FAB2_LIB.BASEBOARD_FAB2(SCH_1):PAGE25
  J4G3  153  DQS0P SCONN288_H44441004_PIP-SCONN,HA    I61 @BASEBOARD_FAB2_LIB.BASEBOARD_FAB2(SCH_1):PAGE47
  J6U2  153  DQS0P SCONN288_H44441003_PIP-SCONN,HA    I61 @BASEBOARD_FAB2_LIB.BASEBOARD_FAB2(SCH_1):PAGE48

M_C_DQS_DP<10> @BASEBOARD_FAB2_LIB.BASEBOARD_FAB2(SCH_1):M_C_DQS_DP(10)
  U5D1 AC76 DDR2_DQS_DP<10> SKX_EXT_B_BGA1-IC,TBD   I172 @BASEBOARD_FAB2_LIB.BASEBOARD_FAB2(SCH_1):PAGE25
  J4G3   18 DQS10P SCONN288_H44441004_PIP-SCONN,HA    I61 @BASEBOARD_FAB2_LIB.BASEBOARD_FAB2(SCH_1):PAGE47
  J6U2   18 DQS10P SCONN288_H44441003_PIP-SCONN,HA    I61 @BASEBOARD_FAB2_LIB.BASEBOARD_FAB2(SCH_1):PAGE48

M_C_DQS_DP<11> @BASEBOARD_FAB2_LIB.BASEBOARD_FAB2(SCH_1):M_C_DQS_DP(11)
  U5D1  V71 DDR2_DQS_DP<11> SKX_EXT_B_BGA1-IC,TBD   I172 @BASEBOARD_FAB2_LIB.BASEBOARD_FAB2(SCH_1):PAGE25
  J4G3   29 DQS11P SCONN288_H44441004_PIP-SCONN,HA    I61 @BASEBOARD_FAB2_LIB.BASEBOARD_FAB2(SCH_1):PAGE47
  J6U2   29 DQS11P SCONN288_H44441003_PIP-SCONN,HA    I61 @BASEBOARD_FAB2_LIB.BASEBOARD_FAB2(SCH_1):PAGE48

M_C_DQS_DP<12> @BASEBOARD_FAB2_LIB.BASEBOARD_FAB2(SCH_1):M_C_DQS_DP(12)
  U5D1 AN66 DDR2_DQS_DP<12> SKX_EXT_B_BGA1-IC,TBD   I172 @BASEBOARD_FAB2_LIB.BASEBOARD_FAB2(SCH_1):PAGE25
  J4G3   40 DQS12P SCONN288_H44441004_PIP-SCONN,HA    I61 @BASEBOARD_FAB2_LIB.BASEBOARD_FAB2(SCH_1):PAGE47
  J6U2   40 DQS12P SCONN288_H44441003_PIP-SCONN,HA    I61 @BASEBOARD_FAB2_LIB.BASEBOARD_FAB2(SCH_1):PAGE48

M_C_DQS_DP<13> @BASEBOARD_FAB2_LIB.BASEBOARD_FAB2(SCH_1):M_C_DQS_DP(13)
  U5D1  V39 DDR2_DQS_DP<13> SKX_EXT_B_BGA1-IC,TBD   I172 @BASEBOARD_FAB2_LIB.BASEBOARD_FAB2(SCH_1):PAGE25
  J4G3   99 DQS13P SCONN288_H44441004_PIP-SCONN,HA    I61 @BASEBOARD_FAB2_LIB.BASEBOARD_FAB2(SCH_1):PAGE47
  J6U2   99 DQS13P SCONN288_H44441003_PIP-SCONN,HA    I61 @BASEBOARD_FAB2_LIB.BASEBOARD_FAB2(SCH_1):PAGE48

M_C_DQS_DP<14> @BASEBOARD_FAB2_LIB.BASEBOARD_FAB2(SCH_1):M_C_DQS_DP(14)
  U5D1  V33 DDR2_DQS_DP<14> SKX_EXT_B_BGA1-IC,TBD   I172 @BASEBOARD_FAB2_LIB.BASEBOARD_FAB2(SCH_1):PAGE25
  J4G3  110 DQS14P SCONN288_H44441004_PIP-SCONN,HA    I61 @BASEBOARD_FAB2_LIB.BASEBOARD_FAB2(SCH_1):PAGE47
  J6U2  110 DQS14P SCONN288_H44441003_PIP-SCONN,HA    I61 @BASEBOARD_FAB2_LIB.BASEBOARD_FAB2(SCH_1):PAGE48

M_C_DQS_DP<15> @BASEBOARD_FAB2_LIB.BASEBOARD_FAB2(SCH_1):M_C_DQS_DP(15)
  U5D1 AE30 DDR2_DQS_DP<15> SKX_EXT_B_BGA1-IC,TBD   I172 @BASEBOARD_FAB2_LIB.BASEBOARD_FAB2(SCH_1):PAGE25
  J4G3  121 DQS15P SCONN288_H44441004_PIP-SCONN,HA    I61 @BASEBOARD_FAB2_LIB.BASEBOARD_FAB2(SCH_1):PAGE47
  J6U2  121 DQS15P SCONN288_H44441003_PIP-SCONN,HA    I61 @BASEBOARD_FAB2_LIB.BASEBOARD_FAB2(SCH_1):PAGE48

M_C_DQS_DP<16> @BASEBOARD_FAB2_LIB.BASEBOARD_FAB2(SCH_1):M_C_DQS_DP(16)
  U5D1 AE24 DDR2_DQS_DP<16> SKX_EXT_B_BGA1-IC,TBD   I172 @BASEBOARD_FAB2_LIB.BASEBOARD_FAB2(SCH_1):PAGE25
  J4G3  132 DQS16P SCONN288_H44441004_PIP-SCONN,HA    I61 @BASEBOARD_FAB2_LIB.BASEBOARD_FAB2(SCH_1):PAGE47
  J6U2  132 DQS16P SCONN288_H44441003_PIP-SCONN,HA    I61 @BASEBOARD_FAB2_LIB.BASEBOARD_FAB2(SCH_1):PAGE48

M_C_DQS_DP<17> @BASEBOARD_FAB2_LIB.BASEBOARD_FAB2(SCH_1):M_C_DQS_DP(17)
  U5D1 AV71 DDR2_DQS_DP<17> SKX_EXT_B_BGA1-IC,TBD   I172 @BASEBOARD_FAB2_LIB.BASEBOARD_FAB2(SCH_1):PAGE25
  J4G3   51 DQS17P SCONN288_H44441004_PIP-SCONN,HA    I61 @BASEBOARD_FAB2_LIB.BASEBOARD_FAB2(SCH_1):PAGE47
  J6U2   51 DQS17P SCONN288_H44441003_PIP-SCONN,HA    I61 @BASEBOARD_FAB2_LIB.BASEBOARD_FAB2(SCH_1):PAGE48

M_C_DQS_DP<1> @BASEBOARD_FAB2_LIB.BASEBOARD_FAB2(SCH_1):M_C_DQS_DP(1)
  U5D1 AB75 DDR2_DQS_DP<1> SKX_EXT_B_BGA1-IC,TBD   I172 @BASEBOARD_FAB2_LIB.BASEBOARD_FAB2(SCH_1):PAGE25
  J4G3  164  DQS1P SCONN288_H44441004_PIP-SCONN,HA    I61 @BASEBOARD_FAB2_LIB.BASEBOARD_FAB2(SCH_1):PAGE47
  J6U2  164  DQS1P SCONN288_H44441003_PIP-SCONN,HA    I61 @BASEBOARD_FAB2_LIB.BASEBOARD_FAB2(SCH_1):PAGE48

M_C_DQS_DP<2> @BASEBOARD_FAB2_LIB.BASEBOARD_FAB2(SCH_1):M_C_DQS_DP(2)
  U5D1  W70 DDR2_DQS_DP<2> SKX_EXT_B_BGA1-IC,TBD   I172 @BASEBOARD_FAB2_LIB.BASEBOARD_FAB2(SCH_1):PAGE25
  J4G3  175  DQS2P SCONN288_H44441004_PIP-SCONN,HA    I61 @BASEBOARD_FAB2_LIB.BASEBOARD_FAB2(SCH_1):PAGE47
  J6U2  175  DQS2P SCONN288_H44441003_PIP-SCONN,HA    I61 @BASEBOARD_FAB2_LIB.BASEBOARD_FAB2(SCH_1):PAGE48

M_C_DQS_DP<3> @BASEBOARD_FAB2_LIB.BASEBOARD_FAB2(SCH_1):M_C_DQS_DP(3)
  U5D1 AR66 DDR2_DQS_DP<3> SKX_EXT_B_BGA1-IC,TBD   I172 @BASEBOARD_FAB2_LIB.BASEBOARD_FAB2(SCH_1):PAGE25
  J4G3  186  DQS3P SCONN288_H44441004_PIP-SCONN,HA    I61 @BASEBOARD_FAB2_LIB.BASEBOARD_FAB2(SCH_1):PAGE47
  J6U2  186  DQS3P SCONN288_H44441003_PIP-SCONN,HA    I61 @BASEBOARD_FAB2_LIB.BASEBOARD_FAB2(SCH_1):PAGE48

M_C_DQS_DP<4> @BASEBOARD_FAB2_LIB.BASEBOARD_FAB2(SCH_1):M_C_DQS_DP(4)
  U5D1  Y39 DDR2_DQS_DP<4> SKX_EXT_B_BGA1-IC,TBD   I172 @BASEBOARD_FAB2_LIB.BASEBOARD_FAB2(SCH_1):PAGE25
  J4G3  245  DQS4P SCONN288_H44441004_PIP-SCONN,HA    I61 @BASEBOARD_FAB2_LIB.BASEBOARD_FAB2(SCH_1):PAGE47
  J6U2  245  DQS4P SCONN288_H44441003_PIP-SCONN,HA    I61 @BASEBOARD_FAB2_LIB.BASEBOARD_FAB2(SCH_1):PAGE48

M_C_DQS_DP<5> @BASEBOARD_FAB2_LIB.BASEBOARD_FAB2(SCH_1):M_C_DQS_DP(5)
  U5D1  Y33 DDR2_DQS_DP<5> SKX_EXT_B_BGA1-IC,TBD   I172 @BASEBOARD_FAB2_LIB.BASEBOARD_FAB2(SCH_1):PAGE25
  J4G3  256  DQS5P SCONN288_H44441004_PIP-SCONN,HA    I61 @BASEBOARD_FAB2_LIB.BASEBOARD_FAB2(SCH_1):PAGE47
  J6U2  256  DQS5P SCONN288_H44441003_PIP-SCONN,HA    I61 @BASEBOARD_FAB2_LIB.BASEBOARD_FAB2(SCH_1):PAGE48

M_C_DQS_DP<6> @BASEBOARD_FAB2_LIB.BASEBOARD_FAB2(SCH_1):M_C_DQS_DP(6)
  U5D1 AG30 DDR2_DQS_DP<6> SKX_EXT_B_BGA1-IC,TBD   I172 @BASEBOARD_FAB2_LIB.BASEBOARD_FAB2(SCH_1):PAGE25
  J4G3  267  DQS6P SCONN288_H44441004_PIP-SCONN,HA    I61 @BASEBOARD_FAB2_LIB.BASEBOARD_FAB2(SCH_1):PAGE47
  J6U2  267  DQS6P SCONN288_H44441003_PIP-SCONN,HA    I61 @BASEBOARD_FAB2_LIB.BASEBOARD_FAB2(SCH_1):PAGE48

M_C_DQS_DP<7> @BASEBOARD_FAB2_LIB.BASEBOARD_FAB2(SCH_1):M_C_DQS_DP(7)
  U5D1 AG24 DDR2_DQS_DP<7> SKX_EXT_B_BGA1-IC,TBD   I172 @BASEBOARD_FAB2_LIB.BASEBOARD_FAB2(SCH_1):PAGE25
  J4G3  278  DQS7P SCONN288_H44441004_PIP-SCONN,HA    I61 @BASEBOARD_FAB2_LIB.BASEBOARD_FAB2(SCH_1):PAGE47
  J6U2  278  DQS7P SCONN288_H44441003_PIP-SCONN,HA    I61 @BASEBOARD_FAB2_LIB.BASEBOARD_FAB2(SCH_1):PAGE48

M_C_DQS_DP<8> @BASEBOARD_FAB2_LIB.BASEBOARD_FAB2(SCH_1):M_C_DQS_DP(8)
  U5D1 AY71 DDR2_DQS_DP<8> SKX_EXT_B_BGA1-IC,TBD   I172 @BASEBOARD_FAB2_LIB.BASEBOARD_FAB2(SCH_1):PAGE25
  J4G3  197  DQS8P SCONN288_H44441004_PIP-SCONN,HA    I61 @BASEBOARD_FAB2_LIB.BASEBOARD_FAB2(SCH_1):PAGE47
  J6U2  197  DQS8P SCONN288_H44441003_PIP-SCONN,HA    I61 @BASEBOARD_FAB2_LIB.BASEBOARD_FAB2(SCH_1):PAGE48

M_C_DQS_DP<9> @BASEBOARD_FAB2_LIB.BASEBOARD_FAB2(SCH_1):M_C_DQS_DP(9)
  U5D1 AN76 DDR2_DQS_DP<9> SKX_EXT_B_BGA1-IC,TBD   I172 @BASEBOARD_FAB2_LIB.BASEBOARD_FAB2(SCH_1):PAGE25
  J4G3    7  DQS9P SCONN288_H44441004_PIP-SCONN,HA    I61 @BASEBOARD_FAB2_LIB.BASEBOARD_FAB2(SCH_1):PAGE47
  J6U2    7  DQS9P SCONN288_H44441003_PIP-SCONN,HA    I61 @BASEBOARD_FAB2_LIB.BASEBOARD_FAB2(SCH_1):PAGE48

M_C_ECC<0> @BASEBOARD_FAB2_LIB.BASEBOARD_FAB2(SCH_1):M_C_ECC(0)
  U5D1 AU72 DDR2_ECC<0> SKX_EXT_B_BGA1-IC,TBD   I172 @BASEBOARD_FAB2_LIB.BASEBOARD_FAB2(SCH_1):PAGE25
  J4G3  194  CB<1> SCONN288_H44441004_PIP-SCONN,HA   I111 @BASEBOARD_FAB2_LIB.BASEBOARD_FAB2(SCH_1):PAGE47
  J6U2   49  CB<0> SCONN288_H44441003_PIP-SCONN,HA   I111 @BASEBOARD_FAB2_LIB.BASEBOARD_FAB2(SCH_1):PAGE48

M_C_ECC<1> @BASEBOARD_FAB2_LIB.BASEBOARD_FAB2(SCH_1):M_C_ECC(1)
  U5D1 BA72 DDR2_ECC<1> SKX_EXT_B_BGA1-IC,TBD   I172 @BASEBOARD_FAB2_LIB.BASEBOARD_FAB2(SCH_1):PAGE25
  J4G3   49  CB<0> SCONN288_H44441004_PIP-SCONN,HA   I111 @BASEBOARD_FAB2_LIB.BASEBOARD_FAB2(SCH_1):PAGE47
  J6U2  194  CB<1> SCONN288_H44441003_PIP-SCONN,HA   I111 @BASEBOARD_FAB2_LIB.BASEBOARD_FAB2(SCH_1):PAGE48

M_C_ECC<2> @BASEBOARD_FAB2_LIB.BASEBOARD_FAB2(SCH_1):M_C_ECC(2)
  U5D1 AV69 DDR2_ECC<2> SKX_EXT_B_BGA1-IC,TBD   I172 @BASEBOARD_FAB2_LIB.BASEBOARD_FAB2(SCH_1):PAGE25
  J4G3  201  CB<3> SCONN288_H44441004_PIP-SCONN,HA   I111 @BASEBOARD_FAB2_LIB.BASEBOARD_FAB2(SCH_1):PAGE47
  J6U2   56  CB<2> SCONN288_H44441003_PIP-SCONN,HA   I111 @BASEBOARD_FAB2_LIB.BASEBOARD_FAB2(SCH_1):PAGE48

M_C_ECC<3> @BASEBOARD_FAB2_LIB.BASEBOARD_FAB2(SCH_1):M_C_ECC(3)
  U5D1 AY69 DDR2_ECC<3> SKX_EXT_B_BGA1-IC,TBD   I172 @BASEBOARD_FAB2_LIB.BASEBOARD_FAB2(SCH_1):PAGE25
  J4G3   56  CB<2> SCONN288_H44441004_PIP-SCONN,HA   I111 @BASEBOARD_FAB2_LIB.BASEBOARD_FAB2(SCH_1):PAGE47
  J6U2  201  CB<3> SCONN288_H44441003_PIP-SCONN,HA   I111 @BASEBOARD_FAB2_LIB.BASEBOARD_FAB2(SCH_1):PAGE48

M_C_ECC<4> @BASEBOARD_FAB2_LIB.BASEBOARD_FAB2(SCH_1):M_C_ECC(4)
  U5D1 AV73 DDR2_ECC<4> SKX_EXT_B_BGA1-IC,TBD   I172 @BASEBOARD_FAB2_LIB.BASEBOARD_FAB2(SCH_1):PAGE25
  J4G3  192  CB<5> SCONN288_H44441004_PIP-SCONN,HA   I111 @BASEBOARD_FAB2_LIB.BASEBOARD_FAB2(SCH_1):PAGE47
  J6U2   47  CB<4> SCONN288_H44441003_PIP-SCONN,HA   I111 @BASEBOARD_FAB2_LIB.BASEBOARD_FAB2(SCH_1):PAGE48

M_C_ECC<5> @BASEBOARD_FAB2_LIB.BASEBOARD_FAB2(SCH_1):M_C_ECC(5)
  U5D1 AY73 DDR2_ECC<5> SKX_EXT_B_BGA1-IC,TBD   I172 @BASEBOARD_FAB2_LIB.BASEBOARD_FAB2(SCH_1):PAGE25
  J4G3   47  CB<4> SCONN288_H44441004_PIP-SCONN,HA   I111 @BASEBOARD_FAB2_LIB.BASEBOARD_FAB2(SCH_1):PAGE47
  J6U2  192  CB<5> SCONN288_H44441003_PIP-SCONN,HA   I111 @BASEBOARD_FAB2_LIB.BASEBOARD_FAB2(SCH_1):PAGE48

M_C_ECC<6> @BASEBOARD_FAB2_LIB.BASEBOARD_FAB2(SCH_1):M_C_ECC(6)
  U5D1 AU70 DDR2_ECC<6> SKX_EXT_B_BGA1-IC,TBD   I172 @BASEBOARD_FAB2_LIB.BASEBOARD_FAB2(SCH_1):PAGE25
  J4G3  199  CB<7> SCONN288_H44441004_PIP-SCONN,HA   I111 @BASEBOARD_FAB2_LIB.BASEBOARD_FAB2(SCH_1):PAGE47
  J6U2   54  CB<6> SCONN288_H44441003_PIP-SCONN,HA   I111 @BASEBOARD_FAB2_LIB.BASEBOARD_FAB2(SCH_1):PAGE48

M_C_ECC<7> @BASEBOARD_FAB2_LIB.BASEBOARD_FAB2(SCH_1):M_C_ECC(7)
  U5D1 BA70 DDR2_ECC<7> SKX_EXT_B_BGA1-IC,TBD   I172 @BASEBOARD_FAB2_LIB.BASEBOARD_FAB2(SCH_1):PAGE25
  J4G3   54  CB<6> SCONN288_H44441004_PIP-SCONN,HA   I111 @BASEBOARD_FAB2_LIB.BASEBOARD_FAB2(SCH_1):PAGE47
  J6U2  199  CB<7> SCONN288_H44441003_PIP-SCONN,HA   I111 @BASEBOARD_FAB2_LIB.BASEBOARD_FAB2(SCH_1):PAGE48

M_C_MA<0> @BASEBOARD_FAB2_LIB.BASEBOARD_FAB2(SCH_1):M_C_MA(0)
  U5D1 AB53 DDR2_MA<0> SKX_EXT_B_BGA1-IC,TBD   I172 @BASEBOARD_FAB2_LIB.BASEBOARD_FAB2(SCH_1):PAGE25
  J4G3   79     A0 SCONN288_H44441004_PIP-SCONN,HA   I111 @BASEBOARD_FAB2_LIB.BASEBOARD_FAB2(SCH_1):PAGE47
  J6U2   79     A0 SCONN288_H44441003_PIP-SCONN,HA   I111 @BASEBOARD_FAB2_LIB.BASEBOARD_FAB2(SCH_1):PAGE48

M_C_MA<10> @BASEBOARD_FAB2_LIB.BASEBOARD_FAB2(SCH_1):M_C_MA(10)
  U5D1 AD55 DDR2_MA<10> SKX_EXT_B_BGA1-IC,TBD   I172 @BASEBOARD_FAB2_LIB.BASEBOARD_FAB2(SCH_1):PAGE25
  J4G3  225    A10 SCONN288_H44441004_PIP-SCONN,HA   I111 @BASEBOARD_FAB2_LIB.BASEBOARD_FAB2(SCH_1):PAGE47
  J6U2  225    A10 SCONN288_H44441003_PIP-SCONN,HA   I111 @BASEBOARD_FAB2_LIB.BASEBOARD_FAB2(SCH_1):PAGE48

M_C_MA<11> @BASEBOARD_FAB2_LIB.BASEBOARD_FAB2(SCH_1):M_C_MA(11)
  U5D1 AG60 DDR2_MA<11> SKX_EXT_B_BGA1-IC,TBD   I172 @BASEBOARD_FAB2_LIB.BASEBOARD_FAB2(SCH_1):PAGE25
  J4G3  210    A11 SCONN288_H44441004_PIP-SCONN,HA   I111 @BASEBOARD_FAB2_LIB.BASEBOARD_FAB2(SCH_1):PAGE47
  J6U2  210    A11 SCONN288_H44441003_PIP-SCONN,HA   I111 @BASEBOARD_FAB2_LIB.BASEBOARD_FAB2(SCH_1):PAGE48

M_C_MA<12> @BASEBOARD_FAB2_LIB.BASEBOARD_FAB2(SCH_1):M_C_MA(12)
  U5D1 AG62 DDR2_MA<12> SKX_EXT_B_BGA1-IC,TBD   I172 @BASEBOARD_FAB2_LIB.BASEBOARD_FAB2(SCH_1):PAGE25
  J4G3   65    A12 SCONN288_H44441004_PIP-SCONN,HA   I111 @BASEBOARD_FAB2_LIB.BASEBOARD_FAB2(SCH_1):PAGE47
  J6U2   65    A12 SCONN288_H44441003_PIP-SCONN,HA   I111 @BASEBOARD_FAB2_LIB.BASEBOARD_FAB2(SCH_1):PAGE48

M_C_MA<13> @BASEBOARD_FAB2_LIB.BASEBOARD_FAB2(SCH_1):M_C_MA(13)
  U5D1 AD53 DDR2_MA<13> SKX_EXT_B_BGA1-IC,TBD   I172 @BASEBOARD_FAB2_LIB.BASEBOARD_FAB2(SCH_1):PAGE25
  J4G3  232    A13 SCONN288_H44441004_PIP-SCONN,HA   I111 @BASEBOARD_FAB2_LIB.BASEBOARD_FAB2(SCH_1):PAGE47
  J6U2  232    A13 SCONN288_H44441003_PIP-SCONN,HA   I111 @BASEBOARD_FAB2_LIB.BASEBOARD_FAB2(SCH_1):PAGE48

M_C_MA<14> @BASEBOARD_FAB2_LIB.BASEBOARD_FAB2(SCH_1):M_C_MA(14)
  U5D1  W50 DDR2_MA<14> SKX_EXT_B_BGA1-IC,TBD   I172 @BASEBOARD_FAB2_LIB.BASEBOARD_FAB2(SCH_1):PAGE25
  J4G3  228 A14_WE_N SCONN288_H44441004_PIP-SCONN,HA   I111 @BASEBOARD_FAB2_LIB.BASEBOARD_FAB2(SCH_1):PAGE47
  J6U2  228 A14_WE_N SCONN288_H44441003_PIP-SCONN,HA   I111 @BASEBOARD_FAB2_LIB.BASEBOARD_FAB2(SCH_1):PAGE48

M_C_MA<15> @BASEBOARD_FAB2_LIB.BASEBOARD_FAB2(SCH_1):M_C_MA(15)
  U5D1 AE54 DDR2_MA<15> SKX_EXT_B_BGA1-IC,TBD   I172 @BASEBOARD_FAB2_LIB.BASEBOARD_FAB2(SCH_1):PAGE25
  J4G3   86 A15_CAS_N SCONN288_H44441004_PIP-SCONN,HA   I111 @BASEBOARD_FAB2_LIB.BASEBOARD_FAB2(SCH_1):PAGE47
  J6U2   86 A15_CAS_N SCONN288_H44441003_PIP-SCONN,HA   I111 @BASEBOARD_FAB2_LIB.BASEBOARD_FAB2(SCH_1):PAGE48

M_C_MA<16> @BASEBOARD_FAB2_LIB.BASEBOARD_FAB2(SCH_1):M_C_MA(16)
  U5D1 AA52 DDR2_MA<16> SKX_EXT_B_BGA1-IC,TBD   I172 @BASEBOARD_FAB2_LIB.BASEBOARD_FAB2(SCH_1):PAGE25
  J4G3   82 A16_RAS_N SCONN288_H44441004_PIP-SCONN,HA   I111 @BASEBOARD_FAB2_LIB.BASEBOARD_FAB2(SCH_1):PAGE47
  J6U2   82 A16_RAS_N SCONN288_H44441003_PIP-SCONN,HA   I111 @BASEBOARD_FAB2_LIB.BASEBOARD_FAB2(SCH_1):PAGE48

M_C_MA<17> @BASEBOARD_FAB2_LIB.BASEBOARD_FAB2(SCH_1):M_C_MA(17)
  U5D1 AC46 DDR2_MA<17> SKX_EXT_B_BGA1-IC,TBD   I172 @BASEBOARD_FAB2_LIB.BASEBOARD_FAB2(SCH_1):PAGE25
  J4G3  234    A17 SCONN288_H44441004_PIP-SCONN,HA   I111 @BASEBOARD_FAB2_LIB.BASEBOARD_FAB2(SCH_1):PAGE47
  J6U2  234    A17 SCONN288_H44441003_PIP-SCONN,HA   I111 @BASEBOARD_FAB2_LIB.BASEBOARD_FAB2(SCH_1):PAGE48

M_C_MA<1> @BASEBOARD_FAB2_LIB.BASEBOARD_FAB2(SCH_1):M_C_MA(1)
  U5D1 AE58 DDR2_MA<1> SKX_EXT_B_BGA1-IC,TBD   I172 @BASEBOARD_FAB2_LIB.BASEBOARD_FAB2(SCH_1):PAGE25
  J4G3   72     A1 SCONN288_H44441004_PIP-SCONN,HA   I111 @BASEBOARD_FAB2_LIB.BASEBOARD_FAB2(SCH_1):PAGE47
  J6U2   72     A1 SCONN288_H44441003_PIP-SCONN,HA   I111 @BASEBOARD_FAB2_LIB.BASEBOARD_FAB2(SCH_1):PAGE48

M_C_MA<2> @BASEBOARD_FAB2_LIB.BASEBOARD_FAB2(SCH_1):M_C_MA(2)
  U5D1 AD57 DDR2_MA<2> SKX_EXT_B_BGA1-IC,TBD   I172 @BASEBOARD_FAB2_LIB.BASEBOARD_FAB2(SCH_1):PAGE25
  J4G3  216     A2 SCONN288_H44441004_PIP-SCONN,HA   I111 @BASEBOARD_FAB2_LIB.BASEBOARD_FAB2(SCH_1):PAGE47
  J6U2  216     A2 SCONN288_H44441003_PIP-SCONN,HA   I111 @BASEBOARD_FAB2_LIB.BASEBOARD_FAB2(SCH_1):PAGE48

M_C_MA<3> @BASEBOARD_FAB2_LIB.BASEBOARD_FAB2(SCH_1):M_C_MA(3)
  U5D1  W58 DDR2_MA<3> SKX_EXT_B_BGA1-IC,TBD   I172 @BASEBOARD_FAB2_LIB.BASEBOARD_FAB2(SCH_1):PAGE25
  J4G3   71     A3 SCONN288_H44441004_PIP-SCONN,HA   I111 @BASEBOARD_FAB2_LIB.BASEBOARD_FAB2(SCH_1):PAGE47
  J6U2   71     A3 SCONN288_H44441003_PIP-SCONN,HA   I111 @BASEBOARD_FAB2_LIB.BASEBOARD_FAB2(SCH_1):PAGE48

M_C_MA<4> @BASEBOARD_FAB2_LIB.BASEBOARD_FAB2(SCH_1):M_C_MA(4)
  U5D1 AA58 DDR2_MA<4> SKX_EXT_B_BGA1-IC,TBD   I172 @BASEBOARD_FAB2_LIB.BASEBOARD_FAB2(SCH_1):PAGE25
  J4G3  214     A4 SCONN288_H44441004_PIP-SCONN,HA   I111 @BASEBOARD_FAB2_LIB.BASEBOARD_FAB2(SCH_1):PAGE47
  J6U2  214     A4 SCONN288_H44441003_PIP-SCONN,HA   I111 @BASEBOARD_FAB2_LIB.BASEBOARD_FAB2(SCH_1):PAGE48

M_C_MA<5> @BASEBOARD_FAB2_LIB.BASEBOARD_FAB2(SCH_1):M_C_MA(5)
  U5D1  V59 DDR2_MA<5> SKX_EXT_B_BGA1-IC,TBD   I172 @BASEBOARD_FAB2_LIB.BASEBOARD_FAB2(SCH_1):PAGE25
  J4G3  213     A5 SCONN288_H44441004_PIP-SCONN,HA   I111 @BASEBOARD_FAB2_LIB.BASEBOARD_FAB2(SCH_1):PAGE47
  J6U2  213     A5 SCONN288_H44441003_PIP-SCONN,HA   I111 @BASEBOARD_FAB2_LIB.BASEBOARD_FAB2(SCH_1):PAGE48

M_C_MA<6> @BASEBOARD_FAB2_LIB.BASEBOARD_FAB2(SCH_1):M_C_MA(6)
  U5D1 AB59 DDR2_MA<6> SKX_EXT_B_BGA1-IC,TBD   I172 @BASEBOARD_FAB2_LIB.BASEBOARD_FAB2(SCH_1):PAGE25
  J4G3   69     A6 SCONN288_H44441004_PIP-SCONN,HA   I111 @BASEBOARD_FAB2_LIB.BASEBOARD_FAB2(SCH_1):PAGE47
  J6U2   69     A6 SCONN288_H44441003_PIP-SCONN,HA   I111 @BASEBOARD_FAB2_LIB.BASEBOARD_FAB2(SCH_1):PAGE48

M_C_MA<7> @BASEBOARD_FAB2_LIB.BASEBOARD_FAB2(SCH_1):M_C_MA(7)
  U5D1 AE60 DDR2_MA<7> SKX_EXT_B_BGA1-IC,TBD   I172 @BASEBOARD_FAB2_LIB.BASEBOARD_FAB2(SCH_1):PAGE25
  J4G3  211     A7 SCONN288_H44441004_PIP-SCONN,HA   I111 @BASEBOARD_FAB2_LIB.BASEBOARD_FAB2(SCH_1):PAGE47
  J6U2  211     A7 SCONN288_H44441003_PIP-SCONN,HA   I111 @BASEBOARD_FAB2_LIB.BASEBOARD_FAB2(SCH_1):PAGE48

M_C_MA<8> @BASEBOARD_FAB2_LIB.BASEBOARD_FAB2(SCH_1):M_C_MA(8)
  U5D1 AD59 DDR2_MA<8> SKX_EXT_B_BGA1-IC,TBD   I172 @BASEBOARD_FAB2_LIB.BASEBOARD_FAB2(SCH_1):PAGE25
  J4G3   68     A8 SCONN288_H44441004_PIP-SCONN,HA   I111 @BASEBOARD_FAB2_LIB.BASEBOARD_FAB2(SCH_1):PAGE47
  J6U2   68     A8 SCONN288_H44441003_PIP-SCONN,HA   I111 @BASEBOARD_FAB2_LIB.BASEBOARD_FAB2(SCH_1):PAGE48

M_C_MA<9> @BASEBOARD_FAB2_LIB.BASEBOARD_FAB2(SCH_1):M_C_MA(9)
  U5D1 AG58 DDR2_MA<9> SKX_EXT_B_BGA1-IC,TBD   I172 @BASEBOARD_FAB2_LIB.BASEBOARD_FAB2(SCH_1):PAGE25
  J4G3   66     A9 SCONN288_H44441004_PIP-SCONN,HA   I111 @BASEBOARD_FAB2_LIB.BASEBOARD_FAB2(SCH_1):PAGE47
  J6U2   66     A9 SCONN288_H44441003_PIP-SCONN,HA   I111 @BASEBOARD_FAB2_LIB.BASEBOARD_FAB2(SCH_1):PAGE48

M_C_ODT<0> @BASEBOARD_FAB2_LIB.BASEBOARD_FAB2(SCH_1):M_C_ODT(0)
  U5D1 AA50 DDR2_ODT<0> SKX_EXT_B_BGA1-IC,TBD   I172 @BASEBOARD_FAB2_LIB.BASEBOARD_FAB2(SCH_1):PAGE25
  J4G3   87 ODT<0> SCONN288_H44441004_PIP-SCONN,HA   I111 @BASEBOARD_FAB2_LIB.BASEBOARD_FAB2(SCH_1):PAGE47

M_C_ODT<1> @BASEBOARD_FAB2_LIB.BASEBOARD_FAB2(SCH_1):M_C_ODT(1)
  U5D1 AA48 DDR2_ODT<1> SKX_EXT_B_BGA1-IC,TBD   I172 @BASEBOARD_FAB2_LIB.BASEBOARD_FAB2(SCH_1):PAGE25
  J4G3   91 ODT<1> SCONN288_H44441004_PIP-SCONN,HA   I111 @BASEBOARD_FAB2_LIB.BASEBOARD_FAB2(SCH_1):PAGE47

M_C_ODT<2> @BASEBOARD_FAB2_LIB.BASEBOARD_FAB2(SCH_1):M_C_ODT(2)
  U5D1  V49 DDR2_ODT<2> SKX_EXT_B_BGA1-IC,TBD   I172 @BASEBOARD_FAB2_LIB.BASEBOARD_FAB2(SCH_1):PAGE25
  J6U2   87 ODT<0> SCONN288_H44441003_PIP-SCONN,HA   I111 @BASEBOARD_FAB2_LIB.BASEBOARD_FAB2(SCH_1):PAGE48

M_C_ODT<3> @BASEBOARD_FAB2_LIB.BASEBOARD_FAB2(SCH_1):M_C_ODT(3)
  U5D1 AB47 DDR2_ODT<3> SKX_EXT_B_BGA1-IC,TBD   I172 @BASEBOARD_FAB2_LIB.BASEBOARD_FAB2(SCH_1):PAGE25
  J6U2   91 ODT<1> SCONN288_H44441003_PIP-SCONN,HA   I111 @BASEBOARD_FAB2_LIB.BASEBOARD_FAB2(SCH_1):PAGE48

M_C_PAR @BASEBOARD_FAB2_LIB.BASEBOARD_FAB2(SCH_1):M_C_PAR
  U5D1  V53 DDR2_PAR SKX_EXT_B_BGA1-IC,TBD   I172 @BASEBOARD_FAB2_LIB.BASEBOARD_FAB2(SCH_1):PAGE25
  J4G3  222    PAR SCONN288_H44441004_PIP-SCONN,HA   I111 @BASEBOARD_FAB2_LIB.BASEBOARD_FAB2(SCH_1):PAGE47
  J6U2  222    PAR SCONN288_H44441003_PIP-SCONN,HA   I111 @BASEBOARD_FAB2_LIB.BASEBOARD_FAB2(SCH_1):PAGE48

M_C_VREF @BASEBOARD_FAB2_LIB.BASEBOARD_FAB2(SCH_1):M_C_VREF
  J4G3  146 VREFCA SCONN288_H44441004_PIP-SCONN,HA   I111 @BASEBOARD_FAB2_LIB.BASEBOARD_FAB2(SCH_1):PAGE47
 C4G19    1      A CAP_A_0402V-0.01UF,25V,10%,X7RA   I188 @BASEBOARD_FAB2_LIB.BASEBOARD_FAB2(SCH_1):PAGE47
  J6U2  146 VREFCA SCONN288_H44441003_PIP-SCONN,HA   I111 @BASEBOARD_FAB2_LIB.BASEBOARD_FAB2(SCH_1):PAGE48
 C6U17    1      A CAP_A_0402V-0.01UF,25V,10%,X7RA   I176 @BASEBOARD_FAB2_LIB.BASEBOARD_FAB2(SCH_1):PAGE48
 R4G21    2      B RES_0402-1.00K,1%,1/16W,CHIP,GA    I46 @BASEBOARD_FAB2_LIB.BASEBOARD_FAB2(SCH_1):PAGE98
 R4G22    1      A RES_0402-1.00K,1%,1/16W,CHIP,GA    I48 @BASEBOARD_FAB2_LIB.BASEBOARD_FAB2(SCH_1):PAGE98
 R4G20    2      B RES_0402-2,1.0%,1/16W,CHIP,G21A    I50 @BASEBOARD_FAB2_LIB.BASEBOARD_FAB2(SCH_1):PAGE98

M_DEF_RST_N @BASEBOARD_FAB2_LIB.BASEBOARD_FAB2(SCH_1):M_DEF_RST_N
  U5D1 DV63 DDR345_RESET_N SKX_EXT_B_BGA1-IC,TBD   I259 @BASEBOARD_FAB2_LIB.BASEBOARD_FAB2(SCH_1):PAGE21
  J4B1   58 RESET_N SCONN288_H44441004_PIP-SCONN,HA   I111 @BASEBOARD_FAB2_LIB.BASEBOARD_FAB2(SCH_1):PAGE49
  J6M1   58 RESET_N SCONN288_H44441003_PIP-SCONN,HA   I158 @BASEBOARD_FAB2_LIB.BASEBOARD_FAB2(SCH_1):PAGE50
  J4A2   58 RESET_N SCONN288_H44441004_PIP-SCONN,HA   I111 @BASEBOARD_FAB2_LIB.BASEBOARD_FAB2(SCH_1):PAGE51
  J6L2   58 RESET_N SCONN288_H44441003_PIP-SCONN,HA    I12 @BASEBOARD_FAB2_LIB.BASEBOARD_FAB2(SCH_1):PAGE52
  J4A1   58 RESET_N SCONN288_H44441004_PIP-SCONN,HA   I111 @BASEBOARD_FAB2_LIB.BASEBOARD_FAB2(SCH_1):PAGE53
  J6L1   58 RESET_N SCONN288_H44441003_PIP-SCONN,HA   I111 @BASEBOARD_FAB2_LIB.BASEBOARD_FAB2(SCH_1):PAGE54

M_D_ACT_N @BASEBOARD_FAB2_LIB.BASEBOARD_FAB2(SCH_1):M_D_ACT_N
  U5D1 DW60 DDR3_ACT_N SKX_EXT_B_BGA1-IC,TBD   I172 @BASEBOARD_FAB2_LIB.BASEBOARD_FAB2(SCH_1):PAGE26
  J4B1   62  ACT_N SCONN288_H44441004_PIP-SCONN,HA   I111 @BASEBOARD_FAB2_LIB.BASEBOARD_FAB2(SCH_1):PAGE49
  J6M1   62  ACT_N SCONN288_H44441003_PIP-SCONN,HA   I158 @BASEBOARD_FAB2_LIB.BASEBOARD_FAB2(SCH_1):PAGE50

M_D_ALERT_N @BASEBOARD_FAB2_LIB.BASEBOARD_FAB2(SCH_1):M_D_ALERT_N
  U5D1 ED63 DDR3_ALERT_N SKX_EXT_B_BGA1-IC,TBD   I172 @BASEBOARD_FAB2_LIB.BASEBOARD_FAB2(SCH_1):PAGE26
  J4B1  208 ALERT_N SCONN288_H44441004_PIP-SCONN,HA   I111 @BASEBOARD_FAB2_LIB.BASEBOARD_FAB2(SCH_1):PAGE49
  J6M1  208 ALERT_N SCONN288_H44441003_PIP-SCONN,HA   I158 @BASEBOARD_FAB2_LIB.BASEBOARD_FAB2(SCH_1):PAGE50

M_D_BA<0> @BASEBOARD_FAB2_LIB.BASEBOARD_FAB2(SCH_1):M_D_BA(0)
  U5D1 EE52 DDR3_BA<0> SKX_EXT_B_BGA1-IC,TBD   I172 @BASEBOARD_FAB2_LIB.BASEBOARD_FAB2(SCH_1):PAGE26
  J4B1   81  BA<0> SCONN288_H44441004_PIP-SCONN,HA   I111 @BASEBOARD_FAB2_LIB.BASEBOARD_FAB2(SCH_1):PAGE49
  J6M1   81  BA<0> SCONN288_H44441003_PIP-SCONN,HA   I158 @BASEBOARD_FAB2_LIB.BASEBOARD_FAB2(SCH_1):PAGE50

M_D_BA<1> @BASEBOARD_FAB2_LIB.BASEBOARD_FAB2(SCH_1):M_D_BA(1)
  U5D1 EA54 DDR3_BA<1> SKX_EXT_B_BGA1-IC,TBD   I172 @BASEBOARD_FAB2_LIB.BASEBOARD_FAB2(SCH_1):PAGE26
  J4B1  224  BA<1> SCONN288_H44441004_PIP-SCONN,HA   I111 @BASEBOARD_FAB2_LIB.BASEBOARD_FAB2(SCH_1):PAGE49
  J6M1  224  BA<1> SCONN288_H44441003_PIP-SCONN,HA   I158 @BASEBOARD_FAB2_LIB.BASEBOARD_FAB2(SCH_1):PAGE50

M_D_BG<0> @BASEBOARD_FAB2_LIB.BASEBOARD_FAB2(SCH_1):M_D_BG(0)
  U5D1 ED61 DDR3_BG<0> SKX_EXT_B_BGA1-IC,TBD   I172 @BASEBOARD_FAB2_LIB.BASEBOARD_FAB2(SCH_1):PAGE26
  J4B1   63  BG<0> SCONN288_H44441004_PIP-SCONN,HA   I111 @BASEBOARD_FAB2_LIB.BASEBOARD_FAB2(SCH_1):PAGE49
  J6M1   63  BG<0> SCONN288_H44441003_PIP-SCONN,HA   I158 @BASEBOARD_FAB2_LIB.BASEBOARD_FAB2(SCH_1):PAGE50

M_D_BG<1> @BASEBOARD_FAB2_LIB.BASEBOARD_FAB2(SCH_1):M_D_BG(1)
  U5D1 DW62 DDR3_BG<1> SKX_EXT_B_BGA1-IC,TBD   I172 @BASEBOARD_FAB2_LIB.BASEBOARD_FAB2(SCH_1):PAGE26
  J4B1  207  BG<1> SCONN288_H44441004_PIP-SCONN,HA   I111 @BASEBOARD_FAB2_LIB.BASEBOARD_FAB2(SCH_1):PAGE49
  J6M1  207  BG<1> SCONN288_H44441003_PIP-SCONN,HA   I158 @BASEBOARD_FAB2_LIB.BASEBOARD_FAB2(SCH_1):PAGE50

M_D_C<2> @BASEBOARD_FAB2_LIB.BASEBOARD_FAB2(SCH_1):M_D_C(2)
  U5D1 DV47 DDR3_CID<2> SKX_EXT_B_BGA1-IC,TBD   I172 @BASEBOARD_FAB2_LIB.BASEBOARD_FAB2(SCH_1):PAGE26
  J4B1  235   C<2> SCONN288_H44441004_PIP-SCONN,HA   I111 @BASEBOARD_FAB2_LIB.BASEBOARD_FAB2(SCH_1):PAGE49
  J6M1  235   C<2> SCONN288_H44441003_PIP-SCONN,HA   I158 @BASEBOARD_FAB2_LIB.BASEBOARD_FAB2(SCH_1):PAGE50

M_D_CKE<0> @BASEBOARD_FAB2_LIB.BASEBOARD_FAB2(SCH_1):M_D_CKE(0)
  U5D1 EE62 DDR3_CKE<0> SKX_EXT_B_BGA1-IC,TBD   I172 @BASEBOARD_FAB2_LIB.BASEBOARD_FAB2(SCH_1):PAGE26
  J4B1   60 CKE<0> SCONN288_H44441004_PIP-SCONN,HA   I111 @BASEBOARD_FAB2_LIB.BASEBOARD_FAB2(SCH_1):PAGE49

M_D_CKE<1> @BASEBOARD_FAB2_LIB.BASEBOARD_FAB2(SCH_1):M_D_CKE(1)
  U5D1 EF63 DDR3_CKE<1> SKX_EXT_B_BGA1-IC,TBD   I172 @BASEBOARD_FAB2_LIB.BASEBOARD_FAB2(SCH_1):PAGE26
  J4B1  203 CKE<1> SCONN288_H44441004_PIP-SCONN,HA   I111 @BASEBOARD_FAB2_LIB.BASEBOARD_FAB2(SCH_1):PAGE49

M_D_CKE<2> @BASEBOARD_FAB2_LIB.BASEBOARD_FAB2(SCH_1):M_D_CKE(2)
  U5D1 EA62 DDR3_CKE<2> SKX_EXT_B_BGA1-IC,TBD   I172 @BASEBOARD_FAB2_LIB.BASEBOARD_FAB2(SCH_1):PAGE26
  J6M1   60 CKE<0> SCONN288_H44441003_PIP-SCONN,HA   I158 @BASEBOARD_FAB2_LIB.BASEBOARD_FAB2(SCH_1):PAGE50

M_D_CKE<3> @BASEBOARD_FAB2_LIB.BASEBOARD_FAB2(SCH_1):M_D_CKE(3)
  U5D1 EB63 DDR3_CKE<3> SKX_EXT_B_BGA1-IC,TBD   I172 @BASEBOARD_FAB2_LIB.BASEBOARD_FAB2(SCH_1):PAGE26
  J6M1  203 CKE<1> SCONN288_H44441003_PIP-SCONN,HA   I158 @BASEBOARD_FAB2_LIB.BASEBOARD_FAB2(SCH_1):PAGE50

M_D_CLK_DN<0> @BASEBOARD_FAB2_LIB.BASEBOARD_FAB2(SCH_1):M_D_CLK_DN(0)
  U5D1 ED55 DDR3_CLK_DN<0> SKX_EXT_B_BGA1-IC,TBD   I172 @BASEBOARD_FAB2_LIB.BASEBOARD_FAB2(SCH_1):PAGE26
  J4B1   75   CK0N SCONN288_H44441004_PIP-SCONN,HA   I111 @BASEBOARD_FAB2_LIB.BASEBOARD_FAB2(SCH_1):PAGE49

M_D_CLK_DN<1> @BASEBOARD_FAB2_LIB.BASEBOARD_FAB2(SCH_1):M_D_CLK_DN(1)
  U5D1 EF55 DDR3_CLK_DN<1> SKX_EXT_B_BGA1-IC,TBD   I172 @BASEBOARD_FAB2_LIB.BASEBOARD_FAB2(SCH_1):PAGE26
  J4B1  219   CK1N SCONN288_H44441004_PIP-SCONN,HA   I111 @BASEBOARD_FAB2_LIB.BASEBOARD_FAB2(SCH_1):PAGE49

M_D_CLK_DN<2> @BASEBOARD_FAB2_LIB.BASEBOARD_FAB2(SCH_1):M_D_CLK_DN(2)
  U5D1 DW56 DDR3_CLK_DN<2> SKX_EXT_B_BGA1-IC,TBD   I172 @BASEBOARD_FAB2_LIB.BASEBOARD_FAB2(SCH_1):PAGE26
  J6M1   75   CK0N SCONN288_H44441003_PIP-SCONN,HA   I158 @BASEBOARD_FAB2_LIB.BASEBOARD_FAB2(SCH_1):PAGE50

M_D_CLK_DN<3> @BASEBOARD_FAB2_LIB.BASEBOARD_FAB2(SCH_1):M_D_CLK_DN(3)
  U5D1 EF57 DDR3_CLK_DN<3> SKX_EXT_B_BGA1-IC,TBD   I172 @BASEBOARD_FAB2_LIB.BASEBOARD_FAB2(SCH_1):PAGE26
  J6M1  219   CK1N SCONN288_H44441003_PIP-SCONN,HA   I158 @BASEBOARD_FAB2_LIB.BASEBOARD_FAB2(SCH_1):PAGE50

M_D_CLK_DP<0> @BASEBOARD_FAB2_LIB.BASEBOARD_FAB2(SCH_1):M_D_CLK_DP(0)
  U5D1 EB55 DDR3_CLK_DP<0> SKX_EXT_B_BGA1-IC,TBD   I172 @BASEBOARD_FAB2_LIB.BASEBOARD_FAB2(SCH_1):PAGE26
  J4B1   74   CK0P SCONN288_H44441004_PIP-SCONN,HA   I111 @BASEBOARD_FAB2_LIB.BASEBOARD_FAB2(SCH_1):PAGE49

M_D_CLK_DP<1> @BASEBOARD_FAB2_LIB.BASEBOARD_FAB2(SCH_1):M_D_CLK_DP(1)
  U5D1 EE54 DDR3_CLK_DP<1> SKX_EXT_B_BGA1-IC,TBD   I172 @BASEBOARD_FAB2_LIB.BASEBOARD_FAB2(SCH_1):PAGE26
  J4B1  218   CK1P SCONN288_H44441004_PIP-SCONN,HA   I111 @BASEBOARD_FAB2_LIB.BASEBOARD_FAB2(SCH_1):PAGE49

M_D_CLK_DP<2> @BASEBOARD_FAB2_LIB.BASEBOARD_FAB2(SCH_1):M_D_CLK_DP(2)
  U5D1 EA56 DDR3_CLK_DP<2> SKX_EXT_B_BGA1-IC,TBD   I172 @BASEBOARD_FAB2_LIB.BASEBOARD_FAB2(SCH_1):PAGE26
  J6M1   74   CK0P SCONN288_H44441003_PIP-SCONN,HA   I158 @BASEBOARD_FAB2_LIB.BASEBOARD_FAB2(SCH_1):PAGE50

M_D_CLK_DP<3> @BASEBOARD_FAB2_LIB.BASEBOARD_FAB2(SCH_1):M_D_CLK_DP(3)
  U5D1 EE56 DDR3_CLK_DP<3> SKX_EXT_B_BGA1-IC,TBD   I172 @BASEBOARD_FAB2_LIB.BASEBOARD_FAB2(SCH_1):PAGE26
  J6M1  218   CK1P SCONN288_H44441003_PIP-SCONN,HA   I158 @BASEBOARD_FAB2_LIB.BASEBOARD_FAB2(SCH_1):PAGE50

M_D_CPU_VREF @BASEBOARD_FAB2_LIB.BASEBOARD_FAB2(SCH_1):M_D_CPU_VREF
  U5D1 CP61 DDR3_CAVREF SKX_EXT_B_BGA1-IC,TBD   I259 @BASEBOARD_FAB2_LIB.BASEBOARD_FAB2(SCH_1):PAGE21
  R6M2    1      A RES_0402-2,1.0%,1/16W,CHIP,G21A    I14 @BASEBOARD_FAB2_LIB.BASEBOARD_FAB2(SCH_1):PAGE98
  C6M2    1      A CAP_A_0402V-0.01UF,25V,10%,X7RA    I33 @BASEBOARD_FAB2_LIB.BASEBOARD_FAB2(SCH_1):PAGE98

M_D_CS_N<0> @BASEBOARD_FAB2_LIB.BASEBOARD_FAB2(SCH_1):M_D_CS_N(0)
  U5D1 EF51 DDR3_CS_N<0> SKX_EXT_B_BGA1-IC,TBD   I172 @BASEBOARD_FAB2_LIB.BASEBOARD_FAB2(SCH_1):PAGE26
  J4B1   84   S0_N SCONN288_H44441004_PIP-SCONN,HA   I111 @BASEBOARD_FAB2_LIB.BASEBOARD_FAB2(SCH_1):PAGE49

M_D_CS_N<1> @BASEBOARD_FAB2_LIB.BASEBOARD_FAB2(SCH_1):M_D_CS_N(1)
  U5D1 ED49 DDR3_CS_N<1> SKX_EXT_B_BGA1-IC,TBD   I172 @BASEBOARD_FAB2_LIB.BASEBOARD_FAB2(SCH_1):PAGE26
  J4B1   89   S1_N SCONN288_H44441004_PIP-SCONN,HA   I111 @BASEBOARD_FAB2_LIB.BASEBOARD_FAB2(SCH_1):PAGE49

M_D_CS_N<2> @BASEBOARD_FAB2_LIB.BASEBOARD_FAB2(SCH_1):M_D_CS_N(2)
  U5D1 ED47 DDR3_CS_N<2> SKX_EXT_B_BGA1-IC,TBD   I172 @BASEBOARD_FAB2_LIB.BASEBOARD_FAB2(SCH_1):PAGE26
  J4B1   93 S2_N_C<0> SCONN288_H44441004_PIP-SCONN,HA   I111 @BASEBOARD_FAB2_LIB.BASEBOARD_FAB2(SCH_1):PAGE49

M_D_CS_N<3> @BASEBOARD_FAB2_LIB.BASEBOARD_FAB2(SCH_1):M_D_CS_N(3)
  U5D1 EB47 DDR3_CS_N<3> SKX_EXT_B_BGA1-IC,TBD   I172 @BASEBOARD_FAB2_LIB.BASEBOARD_FAB2(SCH_1):PAGE26
  J4B1  237 S3_N_C<1> SCONN288_H44441004_PIP-SCONN,HA   I111 @BASEBOARD_FAB2_LIB.BASEBOARD_FAB2(SCH_1):PAGE49

M_D_CS_N<4> @BASEBOARD_FAB2_LIB.BASEBOARD_FAB2(SCH_1):M_D_CS_N(4)
  U5D1 EB51 DDR3_CS_N<4> SKX_EXT_B_BGA1-IC,TBD   I172 @BASEBOARD_FAB2_LIB.BASEBOARD_FAB2(SCH_1):PAGE26
  J6M1   84   S0_N SCONN288_H44441003_PIP-SCONN,HA   I158 @BASEBOARD_FAB2_LIB.BASEBOARD_FAB2(SCH_1):PAGE50

M_D_CS_N<5> @BASEBOARD_FAB2_LIB.BASEBOARD_FAB2(SCH_1):M_D_CS_N(5)
  U5D1 EB49 DDR3_CS_N<5> SKX_EXT_B_BGA1-IC,TBD   I172 @BASEBOARD_FAB2_LIB.BASEBOARD_FAB2(SCH_1):PAGE26
  J6M1   89   S1_N SCONN288_H44441003_PIP-SCONN,HA   I158 @BASEBOARD_FAB2_LIB.BASEBOARD_FAB2(SCH_1):PAGE50

M_D_CS_N<6> @BASEBOARD_FAB2_LIB.BASEBOARD_FAB2(SCH_1):M_D_CS_N(6)
  U5D1 DV45 DDR3_CS_N<6> SKX_EXT_B_BGA1-IC,TBD   I172 @BASEBOARD_FAB2_LIB.BASEBOARD_FAB2(SCH_1):PAGE26
  J6M1   93 S2_N_C<0> SCONN288_H44441003_PIP-SCONN,HA   I158 @BASEBOARD_FAB2_LIB.BASEBOARD_FAB2(SCH_1):PAGE50

M_D_CS_N<7> @BASEBOARD_FAB2_LIB.BASEBOARD_FAB2(SCH_1):M_D_CS_N(7)
  U5D1 EB45 DDR3_CS_N<7> SKX_EXT_B_BGA1-IC,TBD   I172 @BASEBOARD_FAB2_LIB.BASEBOARD_FAB2(SCH_1):PAGE26
  J6M1  237 S3_N_C<1> SCONN288_H44441003_PIP-SCONN,HA   I158 @BASEBOARD_FAB2_LIB.BASEBOARD_FAB2(SCH_1):PAGE50

M_D_DQ<0> @BASEBOARD_FAB2_LIB.BASEBOARD_FAB2(SCH_1):M_D_DQ(0)
  U5D1 CN84 DDR3_DQ<0> SKX_EXT_B_BGA1-IC,TBD   I172 @BASEBOARD_FAB2_LIB.BASEBOARD_FAB2(SCH_1):PAGE26
  J4B1  150  DQ<1> SCONN288_H44441004_PIP-SCONN,HA   I111 @BASEBOARD_FAB2_LIB.BASEBOARD_FAB2(SCH_1):PAGE49
  J6M1    5  DQ<0> SCONN288_H44441003_PIP-SCONN,HA   I158 @BASEBOARD_FAB2_LIB.BASEBOARD_FAB2(SCH_1):PAGE50

M_D_DQ<10> @BASEBOARD_FAB2_LIB.BASEBOARD_FAB2(SCH_1):M_D_DQ(10)
  U5D1 DV83 DDR3_DQ<10> SKX_EXT_B_BGA1-IC,TBD   I172 @BASEBOARD_FAB2_LIB.BASEBOARD_FAB2(SCH_1):PAGE26
  J4B1  168 DQ<11> SCONN288_H44441004_PIP-SCONN,HA   I111 @BASEBOARD_FAB2_LIB.BASEBOARD_FAB2(SCH_1):PAGE49
  J6M1   23 DQ<10> SCONN288_H44441003_PIP-SCONN,HA   I158 @BASEBOARD_FAB2_LIB.BASEBOARD_FAB2(SCH_1):PAGE50

M_D_DQ<11> @BASEBOARD_FAB2_LIB.BASEBOARD_FAB2(SCH_1):M_D_DQ(11)
  U5D1 DY83 DDR3_DQ<11> SKX_EXT_B_BGA1-IC,TBD   I172 @BASEBOARD_FAB2_LIB.BASEBOARD_FAB2(SCH_1):PAGE26
  J4B1   23 DQ<10> SCONN288_H44441004_PIP-SCONN,HA   I111 @BASEBOARD_FAB2_LIB.BASEBOARD_FAB2(SCH_1):PAGE49
  J6M1  168 DQ<11> SCONN288_H44441003_PIP-SCONN,HA   I158 @BASEBOARD_FAB2_LIB.BASEBOARD_FAB2(SCH_1):PAGE50

M_D_DQ<12> @BASEBOARD_FAB2_LIB.BASEBOARD_FAB2(SCH_1):M_D_DQ(12)
  U5D1 DD85 DDR3_DQ<12> SKX_EXT_B_BGA1-IC,TBD   I172 @BASEBOARD_FAB2_LIB.BASEBOARD_FAB2(SCH_1):PAGE26
  J4B1  159 DQ<13> SCONN288_H44441004_PIP-SCONN,HA   I111 @BASEBOARD_FAB2_LIB.BASEBOARD_FAB2(SCH_1):PAGE49
  J6M1   14 DQ<12> SCONN288_H44441003_PIP-SCONN,HA   I158 @BASEBOARD_FAB2_LIB.BASEBOARD_FAB2(SCH_1):PAGE50

M_D_DQ<13> @BASEBOARD_FAB2_LIB.BASEBOARD_FAB2(SCH_1):M_D_DQ(13)
  U5D1 DE84 DDR3_DQ<13> SKX_EXT_B_BGA1-IC,TBD   I172 @BASEBOARD_FAB2_LIB.BASEBOARD_FAB2(SCH_1):PAGE26
  J4B1   14 DQ<12> SCONN288_H44441004_PIP-SCONN,HA   I111 @BASEBOARD_FAB2_LIB.BASEBOARD_FAB2(SCH_1):PAGE49
  J6M1  159 DQ<13> SCONN288_H44441003_PIP-SCONN,HA   I158 @BASEBOARD_FAB2_LIB.BASEBOARD_FAB2(SCH_1):PAGE50

M_D_DQ<14> @BASEBOARD_FAB2_LIB.BASEBOARD_FAB2(SCH_1):M_D_DQ(14)
  U5D1 DR84 DDR3_DQ<14> SKX_EXT_B_BGA1-IC,TBD   I172 @BASEBOARD_FAB2_LIB.BASEBOARD_FAB2(SCH_1):PAGE26
  J4B1  166 DQ<15> SCONN288_H44441004_PIP-SCONN,HA   I111 @BASEBOARD_FAB2_LIB.BASEBOARD_FAB2(SCH_1):PAGE49
  J6M1   21 DQ<14> SCONN288_H44441003_PIP-SCONN,HA   I158 @BASEBOARD_FAB2_LIB.BASEBOARD_FAB2(SCH_1):PAGE50

M_D_DQ<15> @BASEBOARD_FAB2_LIB.BASEBOARD_FAB2(SCH_1):M_D_DQ(15)
  U5D1 DV85 DDR3_DQ<15> SKX_EXT_B_BGA1-IC,TBD   I172 @BASEBOARD_FAB2_LIB.BASEBOARD_FAB2(SCH_1):PAGE26
  J4B1   21 DQ<14> SCONN288_H44441004_PIP-SCONN,HA   I111 @BASEBOARD_FAB2_LIB.BASEBOARD_FAB2(SCH_1):PAGE49
  J6M1  166 DQ<15> SCONN288_H44441003_PIP-SCONN,HA   I158 @BASEBOARD_FAB2_LIB.BASEBOARD_FAB2(SCH_1):PAGE50

M_D_DQ<16> @BASEBOARD_FAB2_LIB.BASEBOARD_FAB2(SCH_1):M_D_DQ(16)
  U5D1 DM79 DDR3_DQ<16> SKX_EXT_B_BGA1-IC,TBD   I172 @BASEBOARD_FAB2_LIB.BASEBOARD_FAB2(SCH_1):PAGE26
  J4B1  172 DQ<17> SCONN288_H44441004_PIP-SCONN,HA   I111 @BASEBOARD_FAB2_LIB.BASEBOARD_FAB2(SCH_1):PAGE49
  J6M1   27 DQ<16> SCONN288_H44441003_PIP-SCONN,HA   I158 @BASEBOARD_FAB2_LIB.BASEBOARD_FAB2(SCH_1):PAGE50

M_D_DQ<17> @BASEBOARD_FAB2_LIB.BASEBOARD_FAB2(SCH_1):M_D_DQ(17)
  U5D1 DK81 DDR3_DQ<17> SKX_EXT_B_BGA1-IC,TBD   I172 @BASEBOARD_FAB2_LIB.BASEBOARD_FAB2(SCH_1):PAGE26
  J4B1   27 DQ<16> SCONN288_H44441004_PIP-SCONN,HA   I111 @BASEBOARD_FAB2_LIB.BASEBOARD_FAB2(SCH_1):PAGE49
  J6M1  172 DQ<17> SCONN288_H44441003_PIP-SCONN,HA   I158 @BASEBOARD_FAB2_LIB.BASEBOARD_FAB2(SCH_1):PAGE50

M_D_DQ<18> @BASEBOARD_FAB2_LIB.BASEBOARD_FAB2(SCH_1):M_D_DQ(18)
  U5D1 DT81 DDR3_DQ<18> SKX_EXT_B_BGA1-IC,TBD   I172 @BASEBOARD_FAB2_LIB.BASEBOARD_FAB2(SCH_1):PAGE26
  J4B1  179 DQ<19> SCONN288_H44441004_PIP-SCONN,HA   I111 @BASEBOARD_FAB2_LIB.BASEBOARD_FAB2(SCH_1):PAGE49
  J6M1   34 DQ<18> SCONN288_H44441003_PIP-SCONN,HA   I158 @BASEBOARD_FAB2_LIB.BASEBOARD_FAB2(SCH_1):PAGE50

M_D_DQ<19> @BASEBOARD_FAB2_LIB.BASEBOARD_FAB2(SCH_1):M_D_DQ(19)
  U5D1 DR82 DDR3_DQ<19> SKX_EXT_B_BGA1-IC,TBD   I172 @BASEBOARD_FAB2_LIB.BASEBOARD_FAB2(SCH_1):PAGE26
  J4B1   34 DQ<18> SCONN288_H44441004_PIP-SCONN,HA   I111 @BASEBOARD_FAB2_LIB.BASEBOARD_FAB2(SCH_1):PAGE49
  J6M1  179 DQ<19> SCONN288_H44441003_PIP-SCONN,HA   I158 @BASEBOARD_FAB2_LIB.BASEBOARD_FAB2(SCH_1):PAGE50

M_D_DQ<1> @BASEBOARD_FAB2_LIB.BASEBOARD_FAB2(SCH_1):M_D_DQ(1)
  U5D1 CN86 DDR3_DQ<1> SKX_EXT_B_BGA1-IC,TBD   I172 @BASEBOARD_FAB2_LIB.BASEBOARD_FAB2(SCH_1):PAGE26
  J4B1    5  DQ<0> SCONN288_H44441004_PIP-SCONN,HA   I111 @BASEBOARD_FAB2_LIB.BASEBOARD_FAB2(SCH_1):PAGE49
  J6M1  150  DQ<1> SCONN288_H44441003_PIP-SCONN,HA   I158 @BASEBOARD_FAB2_LIB.BASEBOARD_FAB2(SCH_1):PAGE50

M_D_DQ<20> @BASEBOARD_FAB2_LIB.BASEBOARD_FAB2(SCH_1):M_D_DQ(20)
  U5D1 DK79 DDR3_DQ<20> SKX_EXT_B_BGA1-IC,TBD   I172 @BASEBOARD_FAB2_LIB.BASEBOARD_FAB2(SCH_1):PAGE26
  J4B1  170 DQ<21> SCONN288_H44441004_PIP-SCONN,HA   I111 @BASEBOARD_FAB2_LIB.BASEBOARD_FAB2(SCH_1):PAGE49
  J6M1   25 DQ<20> SCONN288_H44441003_PIP-SCONN,HA   I158 @BASEBOARD_FAB2_LIB.BASEBOARD_FAB2(SCH_1):PAGE50

M_D_DQ<21> @BASEBOARD_FAB2_LIB.BASEBOARD_FAB2(SCH_1):M_D_DQ(21)
  U5D1 DJ80 DDR3_DQ<21> SKX_EXT_B_BGA1-IC,TBD   I172 @BASEBOARD_FAB2_LIB.BASEBOARD_FAB2(SCH_1):PAGE26
  J4B1   25 DQ<20> SCONN288_H44441004_PIP-SCONN,HA   I111 @BASEBOARD_FAB2_LIB.BASEBOARD_FAB2(SCH_1):PAGE49
  J6M1  170 DQ<21> SCONN288_H44441003_PIP-SCONN,HA   I158 @BASEBOARD_FAB2_LIB.BASEBOARD_FAB2(SCH_1):PAGE50

M_D_DQ<22> @BASEBOARD_FAB2_LIB.BASEBOARD_FAB2(SCH_1):M_D_DQ(22)
  U5D1 DR80 DDR3_DQ<22> SKX_EXT_B_BGA1-IC,TBD   I172 @BASEBOARD_FAB2_LIB.BASEBOARD_FAB2(SCH_1):PAGE26
  J4B1  177 DQ<23> SCONN288_H44441004_PIP-SCONN,HA   I111 @BASEBOARD_FAB2_LIB.BASEBOARD_FAB2(SCH_1):PAGE49
  J6M1   32 DQ<22> SCONN288_H44441003_PIP-SCONN,HA   I158 @BASEBOARD_FAB2_LIB.BASEBOARD_FAB2(SCH_1):PAGE50

M_D_DQ<23> @BASEBOARD_FAB2_LIB.BASEBOARD_FAB2(SCH_1):M_D_DQ(23)
  U5D1 DN82 DDR3_DQ<23> SKX_EXT_B_BGA1-IC,TBD   I172 @BASEBOARD_FAB2_LIB.BASEBOARD_FAB2(SCH_1):PAGE26
  J4B1   32 DQ<22> SCONN288_H44441004_PIP-SCONN,HA   I111 @BASEBOARD_FAB2_LIB.BASEBOARD_FAB2(SCH_1):PAGE49
  J6M1  177 DQ<23> SCONN288_H44441003_PIP-SCONN,HA   I158 @BASEBOARD_FAB2_LIB.BASEBOARD_FAB2(SCH_1):PAGE50

M_D_DQ<24> @BASEBOARD_FAB2_LIB.BASEBOARD_FAB2(SCH_1):M_D_DQ(24)
  U5D1 DN76 DDR3_DQ<24> SKX_EXT_B_BGA1-IC,TBD   I172 @BASEBOARD_FAB2_LIB.BASEBOARD_FAB2(SCH_1):PAGE26
  J4B1  183 DQ<25> SCONN288_H44441004_PIP-SCONN,HA   I111 @BASEBOARD_FAB2_LIB.BASEBOARD_FAB2(SCH_1):PAGE49
  J6M1   38 DQ<24> SCONN288_H44441003_PIP-SCONN,HA   I158 @BASEBOARD_FAB2_LIB.BASEBOARD_FAB2(SCH_1):PAGE50

M_D_DQ<25> @BASEBOARD_FAB2_LIB.BASEBOARD_FAB2(SCH_1):M_D_DQ(25)
  U5D1 DU76 DDR3_DQ<25> SKX_EXT_B_BGA1-IC,TBD   I172 @BASEBOARD_FAB2_LIB.BASEBOARD_FAB2(SCH_1):PAGE26
  J4B1   38 DQ<24> SCONN288_H44441004_PIP-SCONN,HA   I111 @BASEBOARD_FAB2_LIB.BASEBOARD_FAB2(SCH_1):PAGE49
  J6M1  183 DQ<25> SCONN288_H44441003_PIP-SCONN,HA   I158 @BASEBOARD_FAB2_LIB.BASEBOARD_FAB2(SCH_1):PAGE50

M_D_DQ<26> @BASEBOARD_FAB2_LIB.BASEBOARD_FAB2(SCH_1):M_D_DQ(26)
  U5D1 DP73 DDR3_DQ<26> SKX_EXT_B_BGA1-IC,TBD   I172 @BASEBOARD_FAB2_LIB.BASEBOARD_FAB2(SCH_1):PAGE26
  J4B1  190 DQ<27> SCONN288_H44441004_PIP-SCONN,HA   I111 @BASEBOARD_FAB2_LIB.BASEBOARD_FAB2(SCH_1):PAGE49
  J6M1   45 DQ<26> SCONN288_H44441003_PIP-SCONN,HA   I158 @BASEBOARD_FAB2_LIB.BASEBOARD_FAB2(SCH_1):PAGE50

M_D_DQ<27> @BASEBOARD_FAB2_LIB.BASEBOARD_FAB2(SCH_1):M_D_DQ(27)
  U5D1 DT73 DDR3_DQ<27> SKX_EXT_B_BGA1-IC,TBD   I172 @BASEBOARD_FAB2_LIB.BASEBOARD_FAB2(SCH_1):PAGE26
  J4B1   45 DQ<26> SCONN288_H44441004_PIP-SCONN,HA   I111 @BASEBOARD_FAB2_LIB.BASEBOARD_FAB2(SCH_1):PAGE49
  J6M1  190 DQ<27> SCONN288_H44441003_PIP-SCONN,HA   I158 @BASEBOARD_FAB2_LIB.BASEBOARD_FAB2(SCH_1):PAGE50

M_D_DQ<28> @BASEBOARD_FAB2_LIB.BASEBOARD_FAB2(SCH_1):M_D_DQ(28)
  U5D1 DP77 DDR3_DQ<28> SKX_EXT_B_BGA1-IC,TBD   I172 @BASEBOARD_FAB2_LIB.BASEBOARD_FAB2(SCH_1):PAGE26
  J4B1  181 DQ<29> SCONN288_H44441004_PIP-SCONN,HA   I111 @BASEBOARD_FAB2_LIB.BASEBOARD_FAB2(SCH_1):PAGE49
  J6M1   36 DQ<28> SCONN288_H44441003_PIP-SCONN,HA   I158 @BASEBOARD_FAB2_LIB.BASEBOARD_FAB2(SCH_1):PAGE50

M_D_DQ<29> @BASEBOARD_FAB2_LIB.BASEBOARD_FAB2(SCH_1):M_D_DQ(29)
  U5D1 DT77 DDR3_DQ<29> SKX_EXT_B_BGA1-IC,TBD   I172 @BASEBOARD_FAB2_LIB.BASEBOARD_FAB2(SCH_1):PAGE26
  J4B1   36 DQ<28> SCONN288_H44441004_PIP-SCONN,HA   I111 @BASEBOARD_FAB2_LIB.BASEBOARD_FAB2(SCH_1):PAGE49
  J6M1  181 DQ<29> SCONN288_H44441003_PIP-SCONN,HA   I158 @BASEBOARD_FAB2_LIB.BASEBOARD_FAB2(SCH_1):PAGE50

M_D_DQ<2> @BASEBOARD_FAB2_LIB.BASEBOARD_FAB2(SCH_1):M_D_DQ(2)
  U5D1 DA86 DDR3_DQ<2> SKX_EXT_B_BGA1-IC,TBD   I172 @BASEBOARD_FAB2_LIB.BASEBOARD_FAB2(SCH_1):PAGE26
  J4B1  157  DQ<3> SCONN288_H44441004_PIP-SCONN,HA   I111 @BASEBOARD_FAB2_LIB.BASEBOARD_FAB2(SCH_1):PAGE49
  J6M1   12  DQ<2> SCONN288_H44441003_PIP-SCONN,HA   I158 @BASEBOARD_FAB2_LIB.BASEBOARD_FAB2(SCH_1):PAGE50

M_D_DQ<30> @BASEBOARD_FAB2_LIB.BASEBOARD_FAB2(SCH_1):M_D_DQ(30)
  U5D1 DN74 DDR3_DQ<30> SKX_EXT_B_BGA1-IC,TBD   I172 @BASEBOARD_FAB2_LIB.BASEBOARD_FAB2(SCH_1):PAGE26
  J4B1  188 DQ<31> SCONN288_H44441004_PIP-SCONN,HA   I111 @BASEBOARD_FAB2_LIB.BASEBOARD_FAB2(SCH_1):PAGE49
  J6M1   43 DQ<30> SCONN288_H44441003_PIP-SCONN,HA   I158 @BASEBOARD_FAB2_LIB.BASEBOARD_FAB2(SCH_1):PAGE50

M_D_DQ<31> @BASEBOARD_FAB2_LIB.BASEBOARD_FAB2(SCH_1):M_D_DQ(31)
  U5D1 DU74 DDR3_DQ<31> SKX_EXT_B_BGA1-IC,TBD   I172 @BASEBOARD_FAB2_LIB.BASEBOARD_FAB2(SCH_1):PAGE26
  J4B1   43 DQ<30> SCONN288_H44441004_PIP-SCONN,HA   I111 @BASEBOARD_FAB2_LIB.BASEBOARD_FAB2(SCH_1):PAGE49
  J6M1  188 DQ<31> SCONN288_H44441003_PIP-SCONN,HA   I158 @BASEBOARD_FAB2_LIB.BASEBOARD_FAB2(SCH_1):PAGE50

M_D_DQ<32> @BASEBOARD_FAB2_LIB.BASEBOARD_FAB2(SCH_1):M_D_DQ(32)
  U5D1 EC40 DDR3_DQ<32> SKX_EXT_B_BGA1-IC,TBD   I172 @BASEBOARD_FAB2_LIB.BASEBOARD_FAB2(SCH_1):PAGE26
  J4B1  242 DQ<33> SCONN288_H44441004_PIP-SCONN,HA   I111 @BASEBOARD_FAB2_LIB.BASEBOARD_FAB2(SCH_1):PAGE49
  J6M1   97 DQ<32> SCONN288_H44441003_PIP-SCONN,HA   I158 @BASEBOARD_FAB2_LIB.BASEBOARD_FAB2(SCH_1):PAGE50

M_D_DQ<33> @BASEBOARD_FAB2_LIB.BASEBOARD_FAB2(SCH_1):M_D_DQ(33)
  U5D1 ED39 DDR3_DQ<33> SKX_EXT_B_BGA1-IC,TBD   I172 @BASEBOARD_FAB2_LIB.BASEBOARD_FAB2(SCH_1):PAGE26
  J4B1   97 DQ<32> SCONN288_H44441004_PIP-SCONN,HA   I111 @BASEBOARD_FAB2_LIB.BASEBOARD_FAB2(SCH_1):PAGE49
  J6M1  242 DQ<33> SCONN288_H44441003_PIP-SCONN,HA   I158 @BASEBOARD_FAB2_LIB.BASEBOARD_FAB2(SCH_1):PAGE50

M_D_DQ<34> @BASEBOARD_FAB2_LIB.BASEBOARD_FAB2(SCH_1):M_D_DQ(34)
  U5D1 EA36 DDR3_DQ<34> SKX_EXT_B_BGA1-IC,TBD   I172 @BASEBOARD_FAB2_LIB.BASEBOARD_FAB2(SCH_1):PAGE26
  J4B1  249 DQ<35> SCONN288_H44441004_PIP-SCONN,HA   I111 @BASEBOARD_FAB2_LIB.BASEBOARD_FAB2(SCH_1):PAGE49
  J6M1  104 DQ<34> SCONN288_H44441003_PIP-SCONN,HA   I158 @BASEBOARD_FAB2_LIB.BASEBOARD_FAB2(SCH_1):PAGE50

M_D_DQ<35> @BASEBOARD_FAB2_LIB.BASEBOARD_FAB2(SCH_1):M_D_DQ(35)
  U5D1 EC36 DDR3_DQ<35> SKX_EXT_B_BGA1-IC,TBD   I172 @BASEBOARD_FAB2_LIB.BASEBOARD_FAB2(SCH_1):PAGE26
  J4B1  104 DQ<34> SCONN288_H44441004_PIP-SCONN,HA   I111 @BASEBOARD_FAB2_LIB.BASEBOARD_FAB2(SCH_1):PAGE49
  J6M1  249 DQ<35> SCONN288_H44441003_PIP-SCONN,HA   I158 @BASEBOARD_FAB2_LIB.BASEBOARD_FAB2(SCH_1):PAGE50

M_D_DQ<36> @BASEBOARD_FAB2_LIB.BASEBOARD_FAB2(SCH_1):M_D_DQ(36)
  U5D1 DY39 DDR3_DQ<36> SKX_EXT_B_BGA1-IC,TBD   I172 @BASEBOARD_FAB2_LIB.BASEBOARD_FAB2(SCH_1):PAGE26
  J4B1  240 DQ<37> SCONN288_H44441004_PIP-SCONN,HA   I111 @BASEBOARD_FAB2_LIB.BASEBOARD_FAB2(SCH_1):PAGE49
  J6M1   95 DQ<36> SCONN288_H44441003_PIP-SCONN,HA   I158 @BASEBOARD_FAB2_LIB.BASEBOARD_FAB2(SCH_1):PAGE50

M_D_DQ<37> @BASEBOARD_FAB2_LIB.BASEBOARD_FAB2(SCH_1):M_D_DQ(37)
  U5D1 EA40 DDR3_DQ<37> SKX_EXT_B_BGA1-IC,TBD   I172 @BASEBOARD_FAB2_LIB.BASEBOARD_FAB2(SCH_1):PAGE26
  J4B1   95 DQ<36> SCONN288_H44441004_PIP-SCONN,HA   I111 @BASEBOARD_FAB2_LIB.BASEBOARD_FAB2(SCH_1):PAGE49
  J6M1  240 DQ<37> SCONN288_H44441003_PIP-SCONN,HA   I158 @BASEBOARD_FAB2_LIB.BASEBOARD_FAB2(SCH_1):PAGE50

M_D_DQ<38> @BASEBOARD_FAB2_LIB.BASEBOARD_FAB2(SCH_1):M_D_DQ(38)
  U5D1 DY37 DDR3_DQ<38> SKX_EXT_B_BGA1-IC,TBD   I172 @BASEBOARD_FAB2_LIB.BASEBOARD_FAB2(SCH_1):PAGE26
  J4B1  247 DQ<39> SCONN288_H44441004_PIP-SCONN,HA   I111 @BASEBOARD_FAB2_LIB.BASEBOARD_FAB2(SCH_1):PAGE49
  J6M1  102 DQ<38> SCONN288_H44441003_PIP-SCONN,HA   I158 @BASEBOARD_FAB2_LIB.BASEBOARD_FAB2(SCH_1):PAGE50

M_D_DQ<39> @BASEBOARD_FAB2_LIB.BASEBOARD_FAB2(SCH_1):M_D_DQ(39)
  U5D1 ED37 DDR3_DQ<39> SKX_EXT_B_BGA1-IC,TBD   I172 @BASEBOARD_FAB2_LIB.BASEBOARD_FAB2(SCH_1):PAGE26
  J4B1  102 DQ<38> SCONN288_H44441004_PIP-SCONN,HA   I111 @BASEBOARD_FAB2_LIB.BASEBOARD_FAB2(SCH_1):PAGE49
  J6M1  247 DQ<39> SCONN288_H44441003_PIP-SCONN,HA   I158 @BASEBOARD_FAB2_LIB.BASEBOARD_FAB2(SCH_1):PAGE50

M_D_DQ<3> @BASEBOARD_FAB2_LIB.BASEBOARD_FAB2(SCH_1):M_D_DQ(3)
  U5D1 DA84 DDR3_DQ<3> SKX_EXT_B_BGA1-IC,TBD   I172 @BASEBOARD_FAB2_LIB.BASEBOARD_FAB2(SCH_1):PAGE26
  J4B1   12  DQ<2> SCONN288_H44441004_PIP-SCONN,HA   I111 @BASEBOARD_FAB2_LIB.BASEBOARD_FAB2(SCH_1):PAGE49
  J6M1  157  DQ<3> SCONN288_H44441003_PIP-SCONN,HA   I158 @BASEBOARD_FAB2_LIB.BASEBOARD_FAB2(SCH_1):PAGE50

M_D_DQ<40> @BASEBOARD_FAB2_LIB.BASEBOARD_FAB2(SCH_1):M_D_DQ(40)
  U5D1 DN36 DDR3_DQ<40> SKX_EXT_B_BGA1-IC,TBD   I172 @BASEBOARD_FAB2_LIB.BASEBOARD_FAB2(SCH_1):PAGE26
  J4B1  253 DQ<41> SCONN288_H44441004_PIP-SCONN,HA   I111 @BASEBOARD_FAB2_LIB.BASEBOARD_FAB2(SCH_1):PAGE49
  J6M1  108 DQ<40> SCONN288_H44441003_PIP-SCONN,HA   I158 @BASEBOARD_FAB2_LIB.BASEBOARD_FAB2(SCH_1):PAGE50

M_D_DQ<41> @BASEBOARD_FAB2_LIB.BASEBOARD_FAB2(SCH_1):M_D_DQ(41)
  U5D1 DU36 DDR3_DQ<41> SKX_EXT_B_BGA1-IC,TBD   I172 @BASEBOARD_FAB2_LIB.BASEBOARD_FAB2(SCH_1):PAGE26
  J4B1  108 DQ<40> SCONN288_H44441004_PIP-SCONN,HA   I111 @BASEBOARD_FAB2_LIB.BASEBOARD_FAB2(SCH_1):PAGE49
  J6M1  253 DQ<41> SCONN288_H44441003_PIP-SCONN,HA   I158 @BASEBOARD_FAB2_LIB.BASEBOARD_FAB2(SCH_1):PAGE50

M_D_DQ<42> @BASEBOARD_FAB2_LIB.BASEBOARD_FAB2(SCH_1):M_D_DQ(42)
  U5D1 DP33 DDR3_DQ<42> SKX_EXT_B_BGA1-IC,TBD   I172 @BASEBOARD_FAB2_LIB.BASEBOARD_FAB2(SCH_1):PAGE26
  J4B1  260 DQ<43> SCONN288_H44441004_PIP-SCONN,HA   I111 @BASEBOARD_FAB2_LIB.BASEBOARD_FAB2(SCH_1):PAGE49
  J6M1  115 DQ<42> SCONN288_H44441003_PIP-SCONN,HA   I158 @BASEBOARD_FAB2_LIB.BASEBOARD_FAB2(SCH_1):PAGE50

M_D_DQ<43> @BASEBOARD_FAB2_LIB.BASEBOARD_FAB2(SCH_1):M_D_DQ(43)
  U5D1 DT33 DDR3_DQ<43> SKX_EXT_B_BGA1-IC,TBD   I172 @BASEBOARD_FAB2_LIB.BASEBOARD_FAB2(SCH_1):PAGE26
  J4B1  115 DQ<42> SCONN288_H44441004_PIP-SCONN,HA   I111 @BASEBOARD_FAB2_LIB.BASEBOARD_FAB2(SCH_1):PAGE49
  J6M1  260 DQ<43> SCONN288_H44441003_PIP-SCONN,HA   I158 @BASEBOARD_FAB2_LIB.BASEBOARD_FAB2(SCH_1):PAGE50

M_D_DQ<44> @BASEBOARD_FAB2_LIB.BASEBOARD_FAB2(SCH_1):M_D_DQ(44)
  U5D1 DP37 DDR3_DQ<44> SKX_EXT_B_BGA1-IC,TBD   I172 @BASEBOARD_FAB2_LIB.BASEBOARD_FAB2(SCH_1):PAGE26
  J4B1  251 DQ<45> SCONN288_H44441004_PIP-SCONN,HA   I111 @BASEBOARD_FAB2_LIB.BASEBOARD_FAB2(SCH_1):PAGE49
  J6M1  106 DQ<44> SCONN288_H44441003_PIP-SCONN,HA   I158 @BASEBOARD_FAB2_LIB.BASEBOARD_FAB2(SCH_1):PAGE50

M_D_DQ<45> @BASEBOARD_FAB2_LIB.BASEBOARD_FAB2(SCH_1):M_D_DQ(45)
  U5D1 DT37 DDR3_DQ<45> SKX_EXT_B_BGA1-IC,TBD   I172 @BASEBOARD_FAB2_LIB.BASEBOARD_FAB2(SCH_1):PAGE26
  J4B1  106 DQ<44> SCONN288_H44441004_PIP-SCONN,HA   I111 @BASEBOARD_FAB2_LIB.BASEBOARD_FAB2(SCH_1):PAGE49
  J6M1  251 DQ<45> SCONN288_H44441003_PIP-SCONN,HA   I158 @BASEBOARD_FAB2_LIB.BASEBOARD_FAB2(SCH_1):PAGE50

M_D_DQ<46> @BASEBOARD_FAB2_LIB.BASEBOARD_FAB2(SCH_1):M_D_DQ(46)
  U5D1 DN34 DDR3_DQ<46> SKX_EXT_B_BGA1-IC,TBD   I172 @BASEBOARD_FAB2_LIB.BASEBOARD_FAB2(SCH_1):PAGE26
  J4B1  258 DQ<47> SCONN288_H44441004_PIP-SCONN,HA   I111 @BASEBOARD_FAB2_LIB.BASEBOARD_FAB2(SCH_1):PAGE49
  J6M1  113 DQ<46> SCONN288_H44441003_PIP-SCONN,HA   I158 @BASEBOARD_FAB2_LIB.BASEBOARD_FAB2(SCH_1):PAGE50

M_D_DQ<47> @BASEBOARD_FAB2_LIB.BASEBOARD_FAB2(SCH_1):M_D_DQ(47)
  U5D1 DU34 DDR3_DQ<47> SKX_EXT_B_BGA1-IC,TBD   I172 @BASEBOARD_FAB2_LIB.BASEBOARD_FAB2(SCH_1):PAGE26
  J4B1  113 DQ<46> SCONN288_H44441004_PIP-SCONN,HA   I111 @BASEBOARD_FAB2_LIB.BASEBOARD_FAB2(SCH_1):PAGE49
  J6M1  258 DQ<47> SCONN288_H44441003_PIP-SCONN,HA   I158 @BASEBOARD_FAB2_LIB.BASEBOARD_FAB2(SCH_1):PAGE50

M_D_DQ<48> @BASEBOARD_FAB2_LIB.BASEBOARD_FAB2(SCH_1):M_D_DQ(48)
  U5D1 DN30 DDR3_DQ<48> SKX_EXT_B_BGA1-IC,TBD   I172 @BASEBOARD_FAB2_LIB.BASEBOARD_FAB2(SCH_1):PAGE26
  J4B1  264 DQ<49> SCONN288_H44441004_PIP-SCONN,HA   I111 @BASEBOARD_FAB2_LIB.BASEBOARD_FAB2(SCH_1):PAGE49
  J6M1  119 DQ<48> SCONN288_H44441003_PIP-SCONN,HA   I158 @BASEBOARD_FAB2_LIB.BASEBOARD_FAB2(SCH_1):PAGE50

M_D_DQ<49> @BASEBOARD_FAB2_LIB.BASEBOARD_FAB2(SCH_1):M_D_DQ(49)
  U5D1 DU30 DDR3_DQ<49> SKX_EXT_B_BGA1-IC,TBD   I172 @BASEBOARD_FAB2_LIB.BASEBOARD_FAB2(SCH_1):PAGE26
  J4B1  119 DQ<48> SCONN288_H44441004_PIP-SCONN,HA   I111 @BASEBOARD_FAB2_LIB.BASEBOARD_FAB2(SCH_1):PAGE49
  J6M1  264 DQ<49> SCONN288_H44441003_PIP-SCONN,HA   I158 @BASEBOARD_FAB2_LIB.BASEBOARD_FAB2(SCH_1):PAGE50

M_D_DQ<4> @BASEBOARD_FAB2_LIB.BASEBOARD_FAB2(SCH_1):M_D_DQ(4)
  U5D1 CL84 DDR3_DQ<4> SKX_EXT_B_BGA1-IC,TBD   I172 @BASEBOARD_FAB2_LIB.BASEBOARD_FAB2(SCH_1):PAGE26
  J4B1  148  DQ<5> SCONN288_H44441004_PIP-SCONN,HA   I111 @BASEBOARD_FAB2_LIB.BASEBOARD_FAB2(SCH_1):PAGE49
  J6M1    3  DQ<4> SCONN288_H44441003_PIP-SCONN,HA   I158 @BASEBOARD_FAB2_LIB.BASEBOARD_FAB2(SCH_1):PAGE50

M_D_DQ<50> @BASEBOARD_FAB2_LIB.BASEBOARD_FAB2(SCH_1):M_D_DQ(50)
  U5D1 DP27 DDR3_DQ<50> SKX_EXT_B_BGA1-IC,TBD   I172 @BASEBOARD_FAB2_LIB.BASEBOARD_FAB2(SCH_1):PAGE26
  J4B1  271 DQ<51> SCONN288_H44441004_PIP-SCONN,HA   I111 @BASEBOARD_FAB2_LIB.BASEBOARD_FAB2(SCH_1):PAGE49
  J6M1  126 DQ<50> SCONN288_H44441003_PIP-SCONN,HA   I158 @BASEBOARD_FAB2_LIB.BASEBOARD_FAB2(SCH_1):PAGE50

M_D_DQ<51> @BASEBOARD_FAB2_LIB.BASEBOARD_FAB2(SCH_1):M_D_DQ(51)
  U5D1 DT27 DDR3_DQ<51> SKX_EXT_B_BGA1-IC,TBD   I172 @BASEBOARD_FAB2_LIB.BASEBOARD_FAB2(SCH_1):PAGE26
  J4B1  126 DQ<50> SCONN288_H44441004_PIP-SCONN,HA   I111 @BASEBOARD_FAB2_LIB.BASEBOARD_FAB2(SCH_1):PAGE49
  J6M1  271 DQ<51> SCONN288_H44441003_PIP-SCONN,HA   I158 @BASEBOARD_FAB2_LIB.BASEBOARD_FAB2(SCH_1):PAGE50

M_D_DQ<52> @BASEBOARD_FAB2_LIB.BASEBOARD_FAB2(SCH_1):M_D_DQ(52)
  U5D1 DP31 DDR3_DQ<52> SKX_EXT_B_BGA1-IC,TBD   I172 @BASEBOARD_FAB2_LIB.BASEBOARD_FAB2(SCH_1):PAGE26
  J4B1  262 DQ<53> SCONN288_H44441004_PIP-SCONN,HA   I111 @BASEBOARD_FAB2_LIB.BASEBOARD_FAB2(SCH_1):PAGE49
  J6M1  117 DQ<52> SCONN288_H44441003_PIP-SCONN,HA   I158 @BASEBOARD_FAB2_LIB.BASEBOARD_FAB2(SCH_1):PAGE50

M_D_DQ<53> @BASEBOARD_FAB2_LIB.BASEBOARD_FAB2(SCH_1):M_D_DQ(53)
  U5D1 DT31 DDR3_DQ<53> SKX_EXT_B_BGA1-IC,TBD   I172 @BASEBOARD_FAB2_LIB.BASEBOARD_FAB2(SCH_1):PAGE26
  J4B1  117 DQ<52> SCONN288_H44441004_PIP-SCONN,HA   I111 @BASEBOARD_FAB2_LIB.BASEBOARD_FAB2(SCH_1):PAGE49
  J6M1  262 DQ<53> SCONN288_H44441003_PIP-SCONN,HA   I158 @BASEBOARD_FAB2_LIB.BASEBOARD_FAB2(SCH_1):PAGE50

M_D_DQ<54> @BASEBOARD_FAB2_LIB.BASEBOARD_FAB2(SCH_1):M_D_DQ(54)
  U5D1 DN28 DDR3_DQ<54> SKX_EXT_B_BGA1-IC,TBD   I172 @BASEBOARD_FAB2_LIB.BASEBOARD_FAB2(SCH_1):PAGE26
  J4B1  269 DQ<55> SCONN288_H44441004_PIP-SCONN,HA   I111 @BASEBOARD_FAB2_LIB.BASEBOARD_FAB2(SCH_1):PAGE49
  J6M1  124 DQ<54> SCONN288_H44441003_PIP-SCONN,HA   I158 @BASEBOARD_FAB2_LIB.BASEBOARD_FAB2(SCH_1):PAGE50

M_D_DQ<55> @BASEBOARD_FAB2_LIB.BASEBOARD_FAB2(SCH_1):M_D_DQ(55)
  U5D1 DU28 DDR3_DQ<55> SKX_EXT_B_BGA1-IC,TBD   I172 @BASEBOARD_FAB2_LIB.BASEBOARD_FAB2(SCH_1):PAGE26
  J4B1  124 DQ<54> SCONN288_H44441004_PIP-SCONN,HA   I111 @BASEBOARD_FAB2_LIB.BASEBOARD_FAB2(SCH_1):PAGE49
  J6M1  269 DQ<55> SCONN288_H44441003_PIP-SCONN,HA   I158 @BASEBOARD_FAB2_LIB.BASEBOARD_FAB2(SCH_1):PAGE50

M_D_DQ<56> @BASEBOARD_FAB2_LIB.BASEBOARD_FAB2(SCH_1):M_D_DQ(56)
  U5D1 DN24 DDR3_DQ<56> SKX_EXT_B_BGA1-IC,TBD   I172 @BASEBOARD_FAB2_LIB.BASEBOARD_FAB2(SCH_1):PAGE26
  J4B1  275 DQ<57> SCONN288_H44441004_PIP-SCONN,HA   I111 @BASEBOARD_FAB2_LIB.BASEBOARD_FAB2(SCH_1):PAGE49
  J6M1  130 DQ<56> SCONN288_H44441003_PIP-SCONN,HA   I158 @BASEBOARD_FAB2_LIB.BASEBOARD_FAB2(SCH_1):PAGE50

M_D_DQ<57> @BASEBOARD_FAB2_LIB.BASEBOARD_FAB2(SCH_1):M_D_DQ(57)
  U5D1 DU24 DDR3_DQ<57> SKX_EXT_B_BGA1-IC,TBD   I172 @BASEBOARD_FAB2_LIB.BASEBOARD_FAB2(SCH_1):PAGE26
  J4B1  130 DQ<56> SCONN288_H44441004_PIP-SCONN,HA   I111 @BASEBOARD_FAB2_LIB.BASEBOARD_FAB2(SCH_1):PAGE49
  J6M1  275 DQ<57> SCONN288_H44441003_PIP-SCONN,HA   I158 @BASEBOARD_FAB2_LIB.BASEBOARD_FAB2(SCH_1):PAGE50

M_D_DQ<58> @BASEBOARD_FAB2_LIB.BASEBOARD_FAB2(SCH_1):M_D_DQ(58)
  U5D1 DY21 DDR3_DQ<58> SKX_EXT_B_BGA1-IC,TBD   I172 @BASEBOARD_FAB2_LIB.BASEBOARD_FAB2(SCH_1):PAGE26
  J4B1  282 DQ<59> SCONN288_H44441004_PIP-SCONN,HA   I111 @BASEBOARD_FAB2_LIB.BASEBOARD_FAB2(SCH_1):PAGE49
  J6M1  137 DQ<58> SCONN288_H44441003_PIP-SCONN,HA   I158 @BASEBOARD_FAB2_LIB.BASEBOARD_FAB2(SCH_1):PAGE50

M_D_DQ<59> @BASEBOARD_FAB2_LIB.BASEBOARD_FAB2(SCH_1):M_D_DQ(59)
  U5D1 EB21 DDR3_DQ<59> SKX_EXT_B_BGA1-IC,TBD   I172 @BASEBOARD_FAB2_LIB.BASEBOARD_FAB2(SCH_1):PAGE26
  J4B1  137 DQ<58> SCONN288_H44441004_PIP-SCONN,HA   I111 @BASEBOARD_FAB2_LIB.BASEBOARD_FAB2(SCH_1):PAGE49
  J6M1  282 DQ<59> SCONN288_H44441003_PIP-SCONN,HA   I158 @BASEBOARD_FAB2_LIB.BASEBOARD_FAB2(SCH_1):PAGE50

M_D_DQ<5> @BASEBOARD_FAB2_LIB.BASEBOARD_FAB2(SCH_1):M_D_DQ(5)
  U5D1 CL86 DDR3_DQ<5> SKX_EXT_B_BGA1-IC,TBD   I172 @BASEBOARD_FAB2_LIB.BASEBOARD_FAB2(SCH_1):PAGE26
  J4B1    3  DQ<4> SCONN288_H44441004_PIP-SCONN,HA   I111 @BASEBOARD_FAB2_LIB.BASEBOARD_FAB2(SCH_1):PAGE49
  J6M1  148  DQ<5> SCONN288_H44441003_PIP-SCONN,HA   I158 @BASEBOARD_FAB2_LIB.BASEBOARD_FAB2(SCH_1):PAGE50

M_D_DQ<60> @BASEBOARD_FAB2_LIB.BASEBOARD_FAB2(SCH_1):M_D_DQ(60)
  U5D1 DP25 DDR3_DQ<60> SKX_EXT_B_BGA1-IC,TBD   I172 @BASEBOARD_FAB2_LIB.BASEBOARD_FAB2(SCH_1):PAGE26
  J4B1  273 DQ<61> SCONN288_H44441004_PIP-SCONN,HA   I111 @BASEBOARD_FAB2_LIB.BASEBOARD_FAB2(SCH_1):PAGE49
  J6M1  128 DQ<60> SCONN288_H44441003_PIP-SCONN,HA   I158 @BASEBOARD_FAB2_LIB.BASEBOARD_FAB2(SCH_1):PAGE50

M_D_DQ<61> @BASEBOARD_FAB2_LIB.BASEBOARD_FAB2(SCH_1):M_D_DQ(61)
  U5D1 DT25 DDR3_DQ<61> SKX_EXT_B_BGA1-IC,TBD   I172 @BASEBOARD_FAB2_LIB.BASEBOARD_FAB2(SCH_1):PAGE26
  J4B1  128 DQ<60> SCONN288_H44441004_PIP-SCONN,HA   I111 @BASEBOARD_FAB2_LIB.BASEBOARD_FAB2(SCH_1):PAGE49
  J6M1  273 DQ<61> SCONN288_H44441003_PIP-SCONN,HA   I158 @BASEBOARD_FAB2_LIB.BASEBOARD_FAB2(SCH_1):PAGE50

M_D_DQ<62> @BASEBOARD_FAB2_LIB.BASEBOARD_FAB2(SCH_1):M_D_DQ(62)
  U5D1 EC22 DDR3_DQ<62> SKX_EXT_B_BGA1-IC,TBD   I172 @BASEBOARD_FAB2_LIB.BASEBOARD_FAB2(SCH_1):PAGE26
  J4B1  280 DQ<63> SCONN288_H44441004_PIP-SCONN,HA   I111 @BASEBOARD_FAB2_LIB.BASEBOARD_FAB2(SCH_1):PAGE49
  J6M1  135 DQ<62> SCONN288_H44441003_PIP-SCONN,HA   I158 @BASEBOARD_FAB2_LIB.BASEBOARD_FAB2(SCH_1):PAGE50

M_D_DQ<63> @BASEBOARD_FAB2_LIB.BASEBOARD_FAB2(SCH_1):M_D_DQ(63)
  U5D1 DW22 DDR3_DQ<63> SKX_EXT_B_BGA1-IC,TBD   I172 @BASEBOARD_FAB2_LIB.BASEBOARD_FAB2(SCH_1):PAGE26
  J4B1  135 DQ<62> SCONN288_H44441004_PIP-SCONN,HA   I111 @BASEBOARD_FAB2_LIB.BASEBOARD_FAB2(SCH_1):PAGE49
  J6M1  280 DQ<63> SCONN288_H44441003_PIP-SCONN,HA   I158 @BASEBOARD_FAB2_LIB.BASEBOARD_FAB2(SCH_1):PAGE50

M_D_DQ<6> @BASEBOARD_FAB2_LIB.BASEBOARD_FAB2(SCH_1):M_D_DQ(6)
  U5D1 CW86 DDR3_DQ<6> SKX_EXT_B_BGA1-IC,TBD   I172 @BASEBOARD_FAB2_LIB.BASEBOARD_FAB2(SCH_1):PAGE26
  J4B1  155  DQ<7> SCONN288_H44441004_PIP-SCONN,HA   I111 @BASEBOARD_FAB2_LIB.BASEBOARD_FAB2(SCH_1):PAGE49
  J6M1   10  DQ<6> SCONN288_H44441003_PIP-SCONN,HA   I158 @BASEBOARD_FAB2_LIB.BASEBOARD_FAB2(SCH_1):PAGE50

M_D_DQ<7> @BASEBOARD_FAB2_LIB.BASEBOARD_FAB2(SCH_1):M_D_DQ(7)
  U5D1 CW84 DDR3_DQ<7> SKX_EXT_B_BGA1-IC,TBD   I172 @BASEBOARD_FAB2_LIB.BASEBOARD_FAB2(SCH_1):PAGE26
  J4B1   10  DQ<6> SCONN288_H44441004_PIP-SCONN,HA   I111 @BASEBOARD_FAB2_LIB.BASEBOARD_FAB2(SCH_1):PAGE49
  J6M1  155  DQ<7> SCONN288_H44441003_PIP-SCONN,HA   I158 @BASEBOARD_FAB2_LIB.BASEBOARD_FAB2(SCH_1):PAGE50

M_D_DQ<8> @BASEBOARD_FAB2_LIB.BASEBOARD_FAB2(SCH_1):M_D_DQ(8)
  U5D1 DG84 DDR3_DQ<8> SKX_EXT_B_BGA1-IC,TBD   I172 @BASEBOARD_FAB2_LIB.BASEBOARD_FAB2(SCH_1):PAGE26
  J4B1  161  DQ<9> SCONN288_H44441004_PIP-SCONN,HA   I111 @BASEBOARD_FAB2_LIB.BASEBOARD_FAB2(SCH_1):PAGE49
  J6M1   16  DQ<8> SCONN288_H44441003_PIP-SCONN,HA   I158 @BASEBOARD_FAB2_LIB.BASEBOARD_FAB2(SCH_1):PAGE50

M_D_DQ<9> @BASEBOARD_FAB2_LIB.BASEBOARD_FAB2(SCH_1):M_D_DQ(9)
  U5D1 DH85 DDR3_DQ<9> SKX_EXT_B_BGA1-IC,TBD   I172 @BASEBOARD_FAB2_LIB.BASEBOARD_FAB2(SCH_1):PAGE26
  J4B1   16  DQ<8> SCONN288_H44441004_PIP-SCONN,HA   I111 @BASEBOARD_FAB2_LIB.BASEBOARD_FAB2(SCH_1):PAGE49
  J6M1  161  DQ<9> SCONN288_H44441003_PIP-SCONN,HA   I158 @BASEBOARD_FAB2_LIB.BASEBOARD_FAB2(SCH_1):PAGE50

M_D_DQS_DN<0> @BASEBOARD_FAB2_LIB.BASEBOARD_FAB2(SCH_1):M_D_DQS_DN(0)
  U5D1 CU84 DDR3_DQS_DN<0> SKX_EXT_B_BGA1-IC,TBD   I172 @BASEBOARD_FAB2_LIB.BASEBOARD_FAB2(SCH_1):PAGE26
  J4B1  152  DQS0N SCONN288_H44441004_PIP-SCONN,HA    I66 @BASEBOARD_FAB2_LIB.BASEBOARD_FAB2(SCH_1):PAGE49
  J6M1  152  DQS0N SCONN288_H44441003_PIP-SCONN,HA    I46 @BASEBOARD_FAB2_LIB.BASEBOARD_FAB2(SCH_1):PAGE50

M_D_DQS_DN<10> @BASEBOARD_FAB2_LIB.BASEBOARD_FAB2(SCH_1):M_D_DQS_DN(10)
  U5D1 DM85 DDR3_DQS_DN<10> SKX_EXT_B_BGA1-IC,TBD   I172 @BASEBOARD_FAB2_LIB.BASEBOARD_FAB2(SCH_1):PAGE26
  J4B1   19 DQS10N SCONN288_H44441004_PIP-SCONN,HA    I66 @BASEBOARD_FAB2_LIB.BASEBOARD_FAB2(SCH_1):PAGE49
  J6M1   19 DQS10N SCONN288_H44441003_PIP-SCONN,HA    I46 @BASEBOARD_FAB2_LIB.BASEBOARD_FAB2(SCH_1):PAGE50

M_D_DQS_DN<11> @BASEBOARD_FAB2_LIB.BASEBOARD_FAB2(SCH_1):M_D_DQS_DN(11)
  U5D1 DN80 DDR3_DQS_DN<11> SKX_EXT_B_BGA1-IC,TBD   I172 @BASEBOARD_FAB2_LIB.BASEBOARD_FAB2(SCH_1):PAGE26
  J4B1   30 DQS11N SCONN288_H44441004_PIP-SCONN,HA    I66 @BASEBOARD_FAB2_LIB.BASEBOARD_FAB2(SCH_1):PAGE49
  J6M1   30 DQS11N SCONN288_H44441003_PIP-SCONN,HA    I46 @BASEBOARD_FAB2_LIB.BASEBOARD_FAB2(SCH_1):PAGE50

M_D_DQS_DN<12> @BASEBOARD_FAB2_LIB.BASEBOARD_FAB2(SCH_1):M_D_DQS_DN(12)
  U5D1 DP75 DDR3_DQS_DN<12> SKX_EXT_B_BGA1-IC,TBD   I172 @BASEBOARD_FAB2_LIB.BASEBOARD_FAB2(SCH_1):PAGE26
  J4B1   41 DQS12N SCONN288_H44441004_PIP-SCONN,HA    I66 @BASEBOARD_FAB2_LIB.BASEBOARD_FAB2(SCH_1):PAGE49
  J6M1   41 DQS12N SCONN288_H44441003_PIP-SCONN,HA    I46 @BASEBOARD_FAB2_LIB.BASEBOARD_FAB2(SCH_1):PAGE50

M_D_DQS_DN<13> @BASEBOARD_FAB2_LIB.BASEBOARD_FAB2(SCH_1):M_D_DQS_DN(13)
  U5D1 EA38 DDR3_DQS_DN<13> SKX_EXT_B_BGA1-IC,TBD   I172 @BASEBOARD_FAB2_LIB.BASEBOARD_FAB2(SCH_1):PAGE26
  J4B1  100 DQS13N SCONN288_H44441004_PIP-SCONN,HA    I66 @BASEBOARD_FAB2_LIB.BASEBOARD_FAB2(SCH_1):PAGE49
  J6M1  100 DQS13N SCONN288_H44441003_PIP-SCONN,HA    I46 @BASEBOARD_FAB2_LIB.BASEBOARD_FAB2(SCH_1):PAGE50

M_D_DQS_DN<14> @BASEBOARD_FAB2_LIB.BASEBOARD_FAB2(SCH_1):M_D_DQS_DN(14)
  U5D1 DP35 DDR3_DQS_DN<14> SKX_EXT_B_BGA1-IC,TBD   I172 @BASEBOARD_FAB2_LIB.BASEBOARD_FAB2(SCH_1):PAGE26
  J4B1  111 DQS14N SCONN288_H44441004_PIP-SCONN,HA    I66 @BASEBOARD_FAB2_LIB.BASEBOARD_FAB2(SCH_1):PAGE49
  J6M1  111 DQS14N SCONN288_H44441003_PIP-SCONN,HA    I46 @BASEBOARD_FAB2_LIB.BASEBOARD_FAB2(SCH_1):PAGE50

M_D_DQS_DN<15> @BASEBOARD_FAB2_LIB.BASEBOARD_FAB2(SCH_1):M_D_DQS_DN(15)
  U5D1 DM29 DDR3_DQS_DN<15> SKX_EXT_B_BGA1-IC,TBD   I172 @BASEBOARD_FAB2_LIB.BASEBOARD_FAB2(SCH_1):PAGE26
  J4B1  122 DQS15N SCONN288_H44441004_PIP-SCONN,HA    I66 @BASEBOARD_FAB2_LIB.BASEBOARD_FAB2(SCH_1):PAGE49
  J6M1  122 DQS15N SCONN288_H44441003_PIP-SCONN,HA    I46 @BASEBOARD_FAB2_LIB.BASEBOARD_FAB2(SCH_1):PAGE50

M_D_DQS_DN<16> @BASEBOARD_FAB2_LIB.BASEBOARD_FAB2(SCH_1):M_D_DQS_DN(16)
  U5D1 DM23 DDR3_DQS_DN<16> SKX_EXT_B_BGA1-IC,TBD   I172 @BASEBOARD_FAB2_LIB.BASEBOARD_FAB2(SCH_1):PAGE26
  J4B1  133 DQS16N SCONN288_H44441004_PIP-SCONN,HA    I66 @BASEBOARD_FAB2_LIB.BASEBOARD_FAB2(SCH_1):PAGE49
  J6M1  133 DQS16N SCONN288_H44441003_PIP-SCONN,HA    I46 @BASEBOARD_FAB2_LIB.BASEBOARD_FAB2(SCH_1):PAGE50

M_D_DQS_DN<17> @BASEBOARD_FAB2_LIB.BASEBOARD_FAB2(SCH_1):M_D_DQS_DN(17)
  U5D1 DB67 DDR3_DQS_DN<17> SKX_EXT_B_BGA1-IC,TBD   I172 @BASEBOARD_FAB2_LIB.BASEBOARD_FAB2(SCH_1):PAGE26
  J4B1   52 DQS17N SCONN288_H44441004_PIP-SCONN,HA    I66 @BASEBOARD_FAB2_LIB.BASEBOARD_FAB2(SCH_1):PAGE49
  J6M1   52 DQS17N SCONN288_H44441003_PIP-SCONN,HA    I46 @BASEBOARD_FAB2_LIB.BASEBOARD_FAB2(SCH_1):PAGE50

M_D_DQS_DN<1> @BASEBOARD_FAB2_LIB.BASEBOARD_FAB2(SCH_1):M_D_DQS_DN(1)
  U5D1 DN84 DDR3_DQS_DN<1> SKX_EXT_B_BGA1-IC,TBD   I172 @BASEBOARD_FAB2_LIB.BASEBOARD_FAB2(SCH_1):PAGE26
  J4B1  163  DQS1N SCONN288_H44441004_PIP-SCONN,HA    I66 @BASEBOARD_FAB2_LIB.BASEBOARD_FAB2(SCH_1):PAGE49
  J6M1  163  DQS1N SCONN288_H44441003_PIP-SCONN,HA    I46 @BASEBOARD_FAB2_LIB.BASEBOARD_FAB2(SCH_1):PAGE50

M_D_DQS_DN<2> @BASEBOARD_FAB2_LIB.BASEBOARD_FAB2(SCH_1):M_D_DQS_DN(2)
  U5D1 DL82 DDR3_DQS_DN<2> SKX_EXT_B_BGA1-IC,TBD   I172 @BASEBOARD_FAB2_LIB.BASEBOARD_FAB2(SCH_1):PAGE26
  J4B1  174  DQS2N SCONN288_H44441004_PIP-SCONN,HA    I66 @BASEBOARD_FAB2_LIB.BASEBOARD_FAB2(SCH_1):PAGE49
  J6M1  174  DQS2N SCONN288_H44441003_PIP-SCONN,HA    I46 @BASEBOARD_FAB2_LIB.BASEBOARD_FAB2(SCH_1):PAGE50

M_D_DQS_DN<3> @BASEBOARD_FAB2_LIB.BASEBOARD_FAB2(SCH_1):M_D_DQS_DN(3)
  U5D1 DV75 DDR3_DQS_DN<3> SKX_EXT_B_BGA1-IC,TBD   I172 @BASEBOARD_FAB2_LIB.BASEBOARD_FAB2(SCH_1):PAGE26
  J4B1  185  DQS3N SCONN288_H44441004_PIP-SCONN,HA    I66 @BASEBOARD_FAB2_LIB.BASEBOARD_FAB2(SCH_1):PAGE49
  J6M1  185  DQS3N SCONN288_H44441003_PIP-SCONN,HA    I46 @BASEBOARD_FAB2_LIB.BASEBOARD_FAB2(SCH_1):PAGE50

M_D_DQS_DN<4> @BASEBOARD_FAB2_LIB.BASEBOARD_FAB2(SCH_1):M_D_DQS_DN(4)
  U5D1 EE38 DDR3_DQS_DN<4> SKX_EXT_B_BGA1-IC,TBD   I172 @BASEBOARD_FAB2_LIB.BASEBOARD_FAB2(SCH_1):PAGE26
  J4B1  244  DQS4N SCONN288_H44441004_PIP-SCONN,HA    I66 @BASEBOARD_FAB2_LIB.BASEBOARD_FAB2(SCH_1):PAGE49
  J6M1  244  DQS4N SCONN288_H44441003_PIP-SCONN,HA    I46 @BASEBOARD_FAB2_LIB.BASEBOARD_FAB2(SCH_1):PAGE50

M_D_DQS_DN<5> @BASEBOARD_FAB2_LIB.BASEBOARD_FAB2(SCH_1):M_D_DQS_DN(5)
  U5D1 DV35 DDR3_DQS_DN<5> SKX_EXT_B_BGA1-IC,TBD   I172 @BASEBOARD_FAB2_LIB.BASEBOARD_FAB2(SCH_1):PAGE26
  J4B1  255  DQS5N SCONN288_H44441004_PIP-SCONN,HA    I66 @BASEBOARD_FAB2_LIB.BASEBOARD_FAB2(SCH_1):PAGE49
  J6M1  255  DQS5N SCONN288_H44441003_PIP-SCONN,HA    I46 @BASEBOARD_FAB2_LIB.BASEBOARD_FAB2(SCH_1):PAGE50

M_D_DQS_DN<6> @BASEBOARD_FAB2_LIB.BASEBOARD_FAB2(SCH_1):M_D_DQS_DN(6)
  U5D1 DV29 DDR3_DQS_DN<6> SKX_EXT_B_BGA1-IC,TBD   I172 @BASEBOARD_FAB2_LIB.BASEBOARD_FAB2(SCH_1):PAGE26
  J4B1  266  DQS6N SCONN288_H44441004_PIP-SCONN,HA    I66 @BASEBOARD_FAB2_LIB.BASEBOARD_FAB2(SCH_1):PAGE49
  J6M1  266  DQS6N SCONN288_H44441003_PIP-SCONN,HA    I46 @BASEBOARD_FAB2_LIB.BASEBOARD_FAB2(SCH_1):PAGE50

M_D_DQS_DN<7> @BASEBOARD_FAB2_LIB.BASEBOARD_FAB2(SCH_1):M_D_DQS_DN(7)
  U5D1 DV23 DDR3_DQS_DN<7> SKX_EXT_B_BGA1-IC,TBD   I172 @BASEBOARD_FAB2_LIB.BASEBOARD_FAB2(SCH_1):PAGE26
  J4B1  277  DQS7N SCONN288_H44441004_PIP-SCONN,HA    I66 @BASEBOARD_FAB2_LIB.BASEBOARD_FAB2(SCH_1):PAGE49
  J6M1  277  DQS7N SCONN288_H44441003_PIP-SCONN,HA    I46 @BASEBOARD_FAB2_LIB.BASEBOARD_FAB2(SCH_1):PAGE50

M_D_DQS_DN<8> @BASEBOARD_FAB2_LIB.BASEBOARD_FAB2(SCH_1):M_D_DQS_DN(8)
  U5D1 DF67 DDR3_DQS_DN<8> SKX_EXT_B_BGA1-IC,TBD   I172 @BASEBOARD_FAB2_LIB.BASEBOARD_FAB2(SCH_1):PAGE26
  J4B1  196  DQS8N SCONN288_H44441004_PIP-SCONN,HA    I66 @BASEBOARD_FAB2_LIB.BASEBOARD_FAB2(SCH_1):PAGE49
  J6M1  196  DQS8N SCONN288_H44441003_PIP-SCONN,HA    I46 @BASEBOARD_FAB2_LIB.BASEBOARD_FAB2(SCH_1):PAGE50

M_D_DQS_DN<9> @BASEBOARD_FAB2_LIB.BASEBOARD_FAB2(SCH_1):M_D_DQS_DN(9)
  U5D1 CR84 DDR3_DQS_DN<9> SKX_EXT_B_BGA1-IC,TBD   I172 @BASEBOARD_FAB2_LIB.BASEBOARD_FAB2(SCH_1):PAGE26
  J4B1    8  DQS9N SCONN288_H44441004_PIP-SCONN,HA    I66 @BASEBOARD_FAB2_LIB.BASEBOARD_FAB2(SCH_1):PAGE49
  J6M1    8  DQS9N SCONN288_H44441003_PIP-SCONN,HA    I46 @BASEBOARD_FAB2_LIB.BASEBOARD_FAB2(SCH_1):PAGE50

M_D_DQS_DP<0> @BASEBOARD_FAB2_LIB.BASEBOARD_FAB2(SCH_1):M_D_DQS_DP(0)
  U5D1 CV85 DDR3_DQS_DP<0> SKX_EXT_B_BGA1-IC,TBD   I172 @BASEBOARD_FAB2_LIB.BASEBOARD_FAB2(SCH_1):PAGE26
  J4B1  153  DQS0P SCONN288_H44441004_PIP-SCONN,HA    I66 @BASEBOARD_FAB2_LIB.BASEBOARD_FAB2(SCH_1):PAGE49
  J6M1  153  DQS0P SCONN288_H44441003_PIP-SCONN,HA    I46 @BASEBOARD_FAB2_LIB.BASEBOARD_FAB2(SCH_1):PAGE50

M_D_DQS_DP<10> @BASEBOARD_FAB2_LIB.BASEBOARD_FAB2(SCH_1):M_D_DQS_DP(10)
  U5D1 DL84 DDR3_DQS_DP<10> SKX_EXT_B_BGA1-IC,TBD   I172 @BASEBOARD_FAB2_LIB.BASEBOARD_FAB2(SCH_1):PAGE26
  J4B1   18 DQS10P SCONN288_H44441004_PIP-SCONN,HA    I66 @BASEBOARD_FAB2_LIB.BASEBOARD_FAB2(SCH_1):PAGE49
  J6M1   18 DQS10P SCONN288_H44441003_PIP-SCONN,HA    I46 @BASEBOARD_FAB2_LIB.BASEBOARD_FAB2(SCH_1):PAGE50

M_D_DQS_DP<11> @BASEBOARD_FAB2_LIB.BASEBOARD_FAB2(SCH_1):M_D_DQS_DP(11)
  U5D1 DP79 DDR3_DQS_DP<11> SKX_EXT_B_BGA1-IC,TBD   I172 @BASEBOARD_FAB2_LIB.BASEBOARD_FAB2(SCH_1):PAGE26
  J4B1   29 DQS11P SCONN288_H44441004_PIP-SCONN,HA    I66 @BASEBOARD_FAB2_LIB.BASEBOARD_FAB2(SCH_1):PAGE49
  J6M1   29 DQS11P SCONN288_H44441003_PIP-SCONN,HA    I46 @BASEBOARD_FAB2_LIB.BASEBOARD_FAB2(SCH_1):PAGE50

M_D_DQS_DP<12> @BASEBOARD_FAB2_LIB.BASEBOARD_FAB2(SCH_1):M_D_DQS_DP(12)
  U5D1 DM75 DDR3_DQS_DP<12> SKX_EXT_B_BGA1-IC,TBD   I172 @BASEBOARD_FAB2_LIB.BASEBOARD_FAB2(SCH_1):PAGE26
  J4B1   40 DQS12P SCONN288_H44441004_PIP-SCONN,HA    I66 @BASEBOARD_FAB2_LIB.BASEBOARD_FAB2(SCH_1):PAGE49
  J6M1   40 DQS12P SCONN288_H44441003_PIP-SCONN,HA    I46 @BASEBOARD_FAB2_LIB.BASEBOARD_FAB2(SCH_1):PAGE50

M_D_DQS_DP<13> @BASEBOARD_FAB2_LIB.BASEBOARD_FAB2(SCH_1):M_D_DQS_DP(13)
  U5D1 DW38 DDR3_DQS_DP<13> SKX_EXT_B_BGA1-IC,TBD   I172 @BASEBOARD_FAB2_LIB.BASEBOARD_FAB2(SCH_1):PAGE26
  J4B1   99 DQS13P SCONN288_H44441004_PIP-SCONN,HA    I66 @BASEBOARD_FAB2_LIB.BASEBOARD_FAB2(SCH_1):PAGE49
  J6M1   99 DQS13P SCONN288_H44441003_PIP-SCONN,HA    I46 @BASEBOARD_FAB2_LIB.BASEBOARD_FAB2(SCH_1):PAGE50

M_D_DQS_DP<14> @BASEBOARD_FAB2_LIB.BASEBOARD_FAB2(SCH_1):M_D_DQS_DP(14)
  U5D1 DM35 DDR3_DQS_DP<14> SKX_EXT_B_BGA1-IC,TBD   I172 @BASEBOARD_FAB2_LIB.BASEBOARD_FAB2(SCH_1):PAGE26
  J4B1  110 DQS14P SCONN288_H44441004_PIP-SCONN,HA    I66 @BASEBOARD_FAB2_LIB.BASEBOARD_FAB2(SCH_1):PAGE49
  J6M1  110 DQS14P SCONN288_H44441003_PIP-SCONN,HA    I46 @BASEBOARD_FAB2_LIB.BASEBOARD_FAB2(SCH_1):PAGE50

M_D_DQS_DP<15> @BASEBOARD_FAB2_LIB.BASEBOARD_FAB2(SCH_1):M_D_DQS_DP(15)
  U5D1 DP29 DDR3_DQS_DP<15> SKX_EXT_B_BGA1-IC,TBD   I172 @BASEBOARD_FAB2_LIB.BASEBOARD_FAB2(SCH_1):PAGE26
  J4B1  121 DQS15P SCONN288_H44441004_PIP-SCONN,HA    I66 @BASEBOARD_FAB2_LIB.BASEBOARD_FAB2(SCH_1):PAGE49
  J6M1  121 DQS15P SCONN288_H44441003_PIP-SCONN,HA    I46 @BASEBOARD_FAB2_LIB.BASEBOARD_FAB2(SCH_1):PAGE50

M_D_DQS_DP<16> @BASEBOARD_FAB2_LIB.BASEBOARD_FAB2(SCH_1):M_D_DQS_DP(16)
  U5D1 DP23 DDR3_DQS_DP<16> SKX_EXT_B_BGA1-IC,TBD   I172 @BASEBOARD_FAB2_LIB.BASEBOARD_FAB2(SCH_1):PAGE26
  J4B1  132 DQS16P SCONN288_H44441004_PIP-SCONN,HA    I66 @BASEBOARD_FAB2_LIB.BASEBOARD_FAB2(SCH_1):PAGE49
  J6M1  132 DQS16P SCONN288_H44441003_PIP-SCONN,HA    I46 @BASEBOARD_FAB2_LIB.BASEBOARD_FAB2(SCH_1):PAGE50

M_D_DQS_DP<17> @BASEBOARD_FAB2_LIB.BASEBOARD_FAB2(SCH_1):M_D_DQS_DP(17)
  U5D1 CY67 DDR3_DQS_DP<17> SKX_EXT_B_BGA1-IC,TBD   I172 @BASEBOARD_FAB2_LIB.BASEBOARD_FAB2(SCH_1):PAGE26
  J4B1   51 DQS17P SCONN288_H44441004_PIP-SCONN,HA    I66 @BASEBOARD_FAB2_LIB.BASEBOARD_FAB2(SCH_1):PAGE49
  J6M1   51 DQS17P SCONN288_H44441003_PIP-SCONN,HA    I46 @BASEBOARD_FAB2_LIB.BASEBOARD_FAB2(SCH_1):PAGE50

M_D_DQS_DP<1> @BASEBOARD_FAB2_LIB.BASEBOARD_FAB2(SCH_1):M_D_DQS_DP(1)
  U5D1 DP85 DDR3_DQS_DP<1> SKX_EXT_B_BGA1-IC,TBD   I172 @BASEBOARD_FAB2_LIB.BASEBOARD_FAB2(SCH_1):PAGE26
  J4B1  164  DQS1P SCONN288_H44441004_PIP-SCONN,HA    I66 @BASEBOARD_FAB2_LIB.BASEBOARD_FAB2(SCH_1):PAGE49
  J6M1  164  DQS1P SCONN288_H44441003_PIP-SCONN,HA    I46 @BASEBOARD_FAB2_LIB.BASEBOARD_FAB2(SCH_1):PAGE50

M_D_DQS_DP<2> @BASEBOARD_FAB2_LIB.BASEBOARD_FAB2(SCH_1):M_D_DQS_DP(2)
  U5D1 DM81 DDR3_DQS_DP<2> SKX_EXT_B_BGA1-IC,TBD   I172 @BASEBOARD_FAB2_LIB.BASEBOARD_FAB2(SCH_1):PAGE26
  J4B1  175  DQS2P SCONN288_H44441004_PIP-SCONN,HA    I66 @BASEBOARD_FAB2_LIB.BASEBOARD_FAB2(SCH_1):PAGE49
  J6M1  175  DQS2P SCONN288_H44441003_PIP-SCONN,HA    I46 @BASEBOARD_FAB2_LIB.BASEBOARD_FAB2(SCH_1):PAGE50

M_D_DQS_DP<3> @BASEBOARD_FAB2_LIB.BASEBOARD_FAB2(SCH_1):M_D_DQS_DP(3)
  U5D1 DT75 DDR3_DQS_DP<3> SKX_EXT_B_BGA1-IC,TBD   I172 @BASEBOARD_FAB2_LIB.BASEBOARD_FAB2(SCH_1):PAGE26
  J4B1  186  DQS3P SCONN288_H44441004_PIP-SCONN,HA    I66 @BASEBOARD_FAB2_LIB.BASEBOARD_FAB2(SCH_1):PAGE49
  J6M1  186  DQS3P SCONN288_H44441003_PIP-SCONN,HA    I46 @BASEBOARD_FAB2_LIB.BASEBOARD_FAB2(SCH_1):PAGE50

M_D_DQS_DP<4> @BASEBOARD_FAB2_LIB.BASEBOARD_FAB2(SCH_1):M_D_DQS_DP(4)
  U5D1 EC38 DDR3_DQS_DP<4> SKX_EXT_B_BGA1-IC,TBD   I172 @BASEBOARD_FAB2_LIB.BASEBOARD_FAB2(SCH_1):PAGE26
  J4B1  245  DQS4P SCONN288_H44441004_PIP-SCONN,HA    I66 @BASEBOARD_FAB2_LIB.BASEBOARD_FAB2(SCH_1):PAGE49
  J6M1  245  DQS4P SCONN288_H44441003_PIP-SCONN,HA    I46 @BASEBOARD_FAB2_LIB.BASEBOARD_FAB2(SCH_1):PAGE50

M_D_DQS_DP<5> @BASEBOARD_FAB2_LIB.BASEBOARD_FAB2(SCH_1):M_D_DQS_DP(5)
  U5D1 DT35 DDR3_DQS_DP<5> SKX_EXT_B_BGA1-IC,TBD   I172 @BASEBOARD_FAB2_LIB.BASEBOARD_FAB2(SCH_1):PAGE26
  J4B1  256  DQS5P SCONN288_H44441004_PIP-SCONN,HA    I66 @BASEBOARD_FAB2_LIB.BASEBOARD_FAB2(SCH_1):PAGE49
  J6M1  256  DQS5P SCONN288_H44441003_PIP-SCONN,HA    I46 @BASEBOARD_FAB2_LIB.BASEBOARD_FAB2(SCH_1):PAGE50

M_D_DQS_DP<6> @BASEBOARD_FAB2_LIB.BASEBOARD_FAB2(SCH_1):M_D_DQS_DP(6)
  U5D1 DT29 DDR3_DQS_DP<6> SKX_EXT_B_BGA1-IC,TBD   I172 @BASEBOARD_FAB2_LIB.BASEBOARD_FAB2(SCH_1):PAGE26
  J4B1  267  DQS6P SCONN288_H44441004_PIP-SCONN,HA    I66 @BASEBOARD_FAB2_LIB.BASEBOARD_FAB2(SCH_1):PAGE49
  J6M1  267  DQS6P SCONN288_H44441003_PIP-SCONN,HA    I46 @BASEBOARD_FAB2_LIB.BASEBOARD_FAB2(SCH_1):PAGE50

M_D_DQS_DP<7> @BASEBOARD_FAB2_LIB.BASEBOARD_FAB2(SCH_1):M_D_DQS_DP(7)
  U5D1 DT23 DDR3_DQS_DP<7> SKX_EXT_B_BGA1-IC,TBD   I172 @BASEBOARD_FAB2_LIB.BASEBOARD_FAB2(SCH_1):PAGE26
  J4B1  278  DQS7P SCONN288_H44441004_PIP-SCONN,HA    I66 @BASEBOARD_FAB2_LIB.BASEBOARD_FAB2(SCH_1):PAGE49
  J6M1  278  DQS7P SCONN288_H44441003_PIP-SCONN,HA    I46 @BASEBOARD_FAB2_LIB.BASEBOARD_FAB2(SCH_1):PAGE50

M_D_DQS_DP<8> @BASEBOARD_FAB2_LIB.BASEBOARD_FAB2(SCH_1):M_D_DQS_DP(8)
  U5D1 DD67 DDR3_DQS_DP<8> SKX_EXT_B_BGA1-IC,TBD   I172 @BASEBOARD_FAB2_LIB.BASEBOARD_FAB2(SCH_1):PAGE26
  J4B1  197  DQS8P SCONN288_H44441004_PIP-SCONN,HA    I66 @BASEBOARD_FAB2_LIB.BASEBOARD_FAB2(SCH_1):PAGE49
  J6M1  197  DQS8P SCONN288_H44441003_PIP-SCONN,HA    I46 @BASEBOARD_FAB2_LIB.BASEBOARD_FAB2(SCH_1):PAGE50

M_D_DQS_DP<9> @BASEBOARD_FAB2_LIB.BASEBOARD_FAB2(SCH_1):M_D_DQS_DP(9)
  U5D1 CP85 DDR3_DQS_DP<9> SKX_EXT_B_BGA1-IC,TBD   I172 @BASEBOARD_FAB2_LIB.BASEBOARD_FAB2(SCH_1):PAGE26
  J4B1    7  DQS9P SCONN288_H44441004_PIP-SCONN,HA    I66 @BASEBOARD_FAB2_LIB.BASEBOARD_FAB2(SCH_1):PAGE49
  J6M1    7  DQS9P SCONN288_H44441003_PIP-SCONN,HA    I46 @BASEBOARD_FAB2_LIB.BASEBOARD_FAB2(SCH_1):PAGE50

M_D_ECC<0> @BASEBOARD_FAB2_LIB.BASEBOARD_FAB2(SCH_1):M_D_ECC(0)
  U5D1 DA68 DDR3_ECC<0> SKX_EXT_B_BGA1-IC,TBD   I172 @BASEBOARD_FAB2_LIB.BASEBOARD_FAB2(SCH_1):PAGE26
  J4B1  194  CB<1> SCONN288_H44441004_PIP-SCONN,HA   I111 @BASEBOARD_FAB2_LIB.BASEBOARD_FAB2(SCH_1):PAGE49
  J6M1   49  CB<0> SCONN288_H44441003_PIP-SCONN,HA   I158 @BASEBOARD_FAB2_LIB.BASEBOARD_FAB2(SCH_1):PAGE50

M_D_ECC<1> @BASEBOARD_FAB2_LIB.BASEBOARD_FAB2(SCH_1):M_D_ECC(1)
  U5D1 DE68 DDR3_ECC<1> SKX_EXT_B_BGA1-IC,TBD   I172 @BASEBOARD_FAB2_LIB.BASEBOARD_FAB2(SCH_1):PAGE26
  J4B1   49  CB<0> SCONN288_H44441004_PIP-SCONN,HA   I111 @BASEBOARD_FAB2_LIB.BASEBOARD_FAB2(SCH_1):PAGE49
  J6M1  194  CB<1> SCONN288_H44441003_PIP-SCONN,HA   I158 @BASEBOARD_FAB2_LIB.BASEBOARD_FAB2(SCH_1):PAGE50

M_D_ECC<2> @BASEBOARD_FAB2_LIB.BASEBOARD_FAB2(SCH_1):M_D_ECC(2)
  U5D1 DB65 DDR3_ECC<2> SKX_EXT_B_BGA1-IC,TBD   I172 @BASEBOARD_FAB2_LIB.BASEBOARD_FAB2(SCH_1):PAGE26
  J4B1  201  CB<3> SCONN288_H44441004_PIP-SCONN,HA   I111 @BASEBOARD_FAB2_LIB.BASEBOARD_FAB2(SCH_1):PAGE49
  J6M1   56  CB<2> SCONN288_H44441003_PIP-SCONN,HA   I158 @BASEBOARD_FAB2_LIB.BASEBOARD_FAB2(SCH_1):PAGE50

M_D_ECC<3> @BASEBOARD_FAB2_LIB.BASEBOARD_FAB2(SCH_1):M_D_ECC(3)
  U5D1 DD65 DDR3_ECC<3> SKX_EXT_B_BGA1-IC,TBD   I172 @BASEBOARD_FAB2_LIB.BASEBOARD_FAB2(SCH_1):PAGE26
  J4B1   56  CB<2> SCONN288_H44441004_PIP-SCONN,HA   I111 @BASEBOARD_FAB2_LIB.BASEBOARD_FAB2(SCH_1):PAGE49
  J6M1  201  CB<3> SCONN288_H44441003_PIP-SCONN,HA   I158 @BASEBOARD_FAB2_LIB.BASEBOARD_FAB2(SCH_1):PAGE50

M_D_ECC<4> @BASEBOARD_FAB2_LIB.BASEBOARD_FAB2(SCH_1):M_D_ECC(4)
  U5D1 DB69 DDR3_ECC<4> SKX_EXT_B_BGA1-IC,TBD   I172 @BASEBOARD_FAB2_LIB.BASEBOARD_FAB2(SCH_1):PAGE26
  J4B1  192  CB<5> SCONN288_H44441004_PIP-SCONN,HA   I111 @BASEBOARD_FAB2_LIB.BASEBOARD_FAB2(SCH_1):PAGE49
  J6M1   47  CB<4> SCONN288_H44441003_PIP-SCONN,HA   I158 @BASEBOARD_FAB2_LIB.BASEBOARD_FAB2(SCH_1):PAGE50

M_D_ECC<5> @BASEBOARD_FAB2_LIB.BASEBOARD_FAB2(SCH_1):M_D_ECC(5)
  U5D1 DD69 DDR3_ECC<5> SKX_EXT_B_BGA1-IC,TBD   I172 @BASEBOARD_FAB2_LIB.BASEBOARD_FAB2(SCH_1):PAGE26
  J4B1   47  CB<4> SCONN288_H44441004_PIP-SCONN,HA   I111 @BASEBOARD_FAB2_LIB.BASEBOARD_FAB2(SCH_1):PAGE49
  J6M1  192  CB<5> SCONN288_H44441003_PIP-SCONN,HA   I158 @BASEBOARD_FAB2_LIB.BASEBOARD_FAB2(SCH_1):PAGE50

M_D_ECC<6> @BASEBOARD_FAB2_LIB.BASEBOARD_FAB2(SCH_1):M_D_ECC(6)
  U5D1 DA66 DDR3_ECC<6> SKX_EXT_B_BGA1-IC,TBD   I172 @BASEBOARD_FAB2_LIB.BASEBOARD_FAB2(SCH_1):PAGE26
  J4B1  199  CB<7> SCONN288_H44441004_PIP-SCONN,HA   I111 @BASEBOARD_FAB2_LIB.BASEBOARD_FAB2(SCH_1):PAGE49
  J6M1   54  CB<6> SCONN288_H44441003_PIP-SCONN,HA   I158 @BASEBOARD_FAB2_LIB.BASEBOARD_FAB2(SCH_1):PAGE50

M_D_ECC<7> @BASEBOARD_FAB2_LIB.BASEBOARD_FAB2(SCH_1):M_D_ECC(7)
  U5D1 DE66 DDR3_ECC<7> SKX_EXT_B_BGA1-IC,TBD   I172 @BASEBOARD_FAB2_LIB.BASEBOARD_FAB2(SCH_1):PAGE26
  J4B1   54  CB<6> SCONN288_H44441004_PIP-SCONN,HA   I111 @BASEBOARD_FAB2_LIB.BASEBOARD_FAB2(SCH_1):PAGE49
  J6M1  199  CB<7> SCONN288_H44441003_PIP-SCONN,HA   I158 @BASEBOARD_FAB2_LIB.BASEBOARD_FAB2(SCH_1):PAGE50

M_D_MA<0> @BASEBOARD_FAB2_LIB.BASEBOARD_FAB2(SCH_1):M_D_MA(0)
  U5D1 EB53 DDR3_MA<0> SKX_EXT_B_BGA1-IC,TBD   I172 @BASEBOARD_FAB2_LIB.BASEBOARD_FAB2(SCH_1):PAGE26
  J4B1   79     A0 SCONN288_H44441004_PIP-SCONN,HA   I111 @BASEBOARD_FAB2_LIB.BASEBOARD_FAB2(SCH_1):PAGE49
  J6M1   79     A0 SCONN288_H44441003_PIP-SCONN,HA   I158 @BASEBOARD_FAB2_LIB.BASEBOARD_FAB2(SCH_1):PAGE50

M_D_MA<10> @BASEBOARD_FAB2_LIB.BASEBOARD_FAB2(SCH_1):M_D_MA(10)
  U5D1 DW54 DDR3_MA<10> SKX_EXT_B_BGA1-IC,TBD   I172 @BASEBOARD_FAB2_LIB.BASEBOARD_FAB2(SCH_1):PAGE26
  J4B1  225    A10 SCONN288_H44441004_PIP-SCONN,HA   I111 @BASEBOARD_FAB2_LIB.BASEBOARD_FAB2(SCH_1):PAGE49
  J6M1  225    A10 SCONN288_H44441003_PIP-SCONN,HA   I158 @BASEBOARD_FAB2_LIB.BASEBOARD_FAB2(SCH_1):PAGE50

M_D_MA<11> @BASEBOARD_FAB2_LIB.BASEBOARD_FAB2(SCH_1):M_D_MA(11)
  U5D1 EB61 DDR3_MA<11> SKX_EXT_B_BGA1-IC,TBD   I172 @BASEBOARD_FAB2_LIB.BASEBOARD_FAB2(SCH_1):PAGE26
  J4B1  210    A11 SCONN288_H44441004_PIP-SCONN,HA   I111 @BASEBOARD_FAB2_LIB.BASEBOARD_FAB2(SCH_1):PAGE49
  J6M1  210    A11 SCONN288_H44441003_PIP-SCONN,HA   I158 @BASEBOARD_FAB2_LIB.BASEBOARD_FAB2(SCH_1):PAGE50

M_D_MA<12> @BASEBOARD_FAB2_LIB.BASEBOARD_FAB2(SCH_1):M_D_MA(12)
  U5D1 DT63 DDR3_MA<12> SKX_EXT_B_BGA1-IC,TBD   I172 @BASEBOARD_FAB2_LIB.BASEBOARD_FAB2(SCH_1):PAGE26
  J4B1   65    A12 SCONN288_H44441004_PIP-SCONN,HA   I111 @BASEBOARD_FAB2_LIB.BASEBOARD_FAB2(SCH_1):PAGE49
  J6M1   65    A12 SCONN288_H44441003_PIP-SCONN,HA   I158 @BASEBOARD_FAB2_LIB.BASEBOARD_FAB2(SCH_1):PAGE50

M_D_MA<13> @BASEBOARD_FAB2_LIB.BASEBOARD_FAB2(SCH_1):M_D_MA(13)
  U5D1 DW48 DDR3_MA<13> SKX_EXT_B_BGA1-IC,TBD   I172 @BASEBOARD_FAB2_LIB.BASEBOARD_FAB2(SCH_1):PAGE26
  J4B1  232    A13 SCONN288_H44441004_PIP-SCONN,HA   I111 @BASEBOARD_FAB2_LIB.BASEBOARD_FAB2(SCH_1):PAGE49
  J6M1  232    A13 SCONN288_H44441003_PIP-SCONN,HA   I158 @BASEBOARD_FAB2_LIB.BASEBOARD_FAB2(SCH_1):PAGE50

M_D_MA<14> @BASEBOARD_FAB2_LIB.BASEBOARD_FAB2(SCH_1):M_D_MA(14)
  U5D1 ED51 DDR3_MA<14> SKX_EXT_B_BGA1-IC,TBD   I172 @BASEBOARD_FAB2_LIB.BASEBOARD_FAB2(SCH_1):PAGE26
  J4B1  228 A14_WE_N SCONN288_H44441004_PIP-SCONN,HA   I111 @BASEBOARD_FAB2_LIB.BASEBOARD_FAB2(SCH_1):PAGE49
  J6M1  228 A14_WE_N SCONN288_H44441003_PIP-SCONN,HA   I158 @BASEBOARD_FAB2_LIB.BASEBOARD_FAB2(SCH_1):PAGE50

M_D_MA<15> @BASEBOARD_FAB2_LIB.BASEBOARD_FAB2(SCH_1):M_D_MA(15)
  U5D1 DV49 DDR3_MA<15> SKX_EXT_B_BGA1-IC,TBD   I172 @BASEBOARD_FAB2_LIB.BASEBOARD_FAB2(SCH_1):PAGE26
  J4B1   86 A15_CAS_N SCONN288_H44441004_PIP-SCONN,HA   I111 @BASEBOARD_FAB2_LIB.BASEBOARD_FAB2(SCH_1):PAGE49
  J6M1   86 A15_CAS_N SCONN288_H44441003_PIP-SCONN,HA   I158 @BASEBOARD_FAB2_LIB.BASEBOARD_FAB2(SCH_1):PAGE50

M_D_MA<16> @BASEBOARD_FAB2_LIB.BASEBOARD_FAB2(SCH_1):M_D_MA(16)
  U5D1 EA52 DDR3_MA<16> SKX_EXT_B_BGA1-IC,TBD   I172 @BASEBOARD_FAB2_LIB.BASEBOARD_FAB2(SCH_1):PAGE26
  J4B1   82 A16_RAS_N SCONN288_H44441004_PIP-SCONN,HA   I111 @BASEBOARD_FAB2_LIB.BASEBOARD_FAB2(SCH_1):PAGE49
  J6M1   82 A16_RAS_N SCONN288_H44441003_PIP-SCONN,HA   I158 @BASEBOARD_FAB2_LIB.BASEBOARD_FAB2(SCH_1):PAGE50

M_D_MA<17> @BASEBOARD_FAB2_LIB.BASEBOARD_FAB2(SCH_1):M_D_MA(17)
  U5D1 EA46 DDR3_MA<17> SKX_EXT_B_BGA1-IC,TBD   I172 @BASEBOARD_FAB2_LIB.BASEBOARD_FAB2(SCH_1):PAGE26
  J4B1  234    A17 SCONN288_H44441004_PIP-SCONN,HA   I111 @BASEBOARD_FAB2_LIB.BASEBOARD_FAB2(SCH_1):PAGE49
  J6M1  234    A17 SCONN288_H44441003_PIP-SCONN,HA   I158 @BASEBOARD_FAB2_LIB.BASEBOARD_FAB2(SCH_1):PAGE50

M_D_MA<1> @BASEBOARD_FAB2_LIB.BASEBOARD_FAB2(SCH_1):M_D_MA(1)
  U5D1 ED57 DDR3_MA<1> SKX_EXT_B_BGA1-IC,TBD   I172 @BASEBOARD_FAB2_LIB.BASEBOARD_FAB2(SCH_1):PAGE26
  J4B1   72     A1 SCONN288_H44441004_PIP-SCONN,HA   I111 @BASEBOARD_FAB2_LIB.BASEBOARD_FAB2(SCH_1):PAGE49
  J6M1   72     A1 SCONN288_H44441003_PIP-SCONN,HA   I158 @BASEBOARD_FAB2_LIB.BASEBOARD_FAB2(SCH_1):PAGE50

M_D_MA<2> @BASEBOARD_FAB2_LIB.BASEBOARD_FAB2(SCH_1):M_D_MA(2)
  U5D1 EE58 DDR3_MA<2> SKX_EXT_B_BGA1-IC,TBD   I172 @BASEBOARD_FAB2_LIB.BASEBOARD_FAB2(SCH_1):PAGE26
  J4B1  216     A2 SCONN288_H44441004_PIP-SCONN,HA   I111 @BASEBOARD_FAB2_LIB.BASEBOARD_FAB2(SCH_1):PAGE49
  J6M1  216     A2 SCONN288_H44441003_PIP-SCONN,HA   I158 @BASEBOARD_FAB2_LIB.BASEBOARD_FAB2(SCH_1):PAGE50

M_D_MA<3> @BASEBOARD_FAB2_LIB.BASEBOARD_FAB2(SCH_1):M_D_MA(3)
  U5D1 EB57 DDR3_MA<3> SKX_EXT_B_BGA1-IC,TBD   I172 @BASEBOARD_FAB2_LIB.BASEBOARD_FAB2(SCH_1):PAGE26
  J4B1   71     A3 SCONN288_H44441004_PIP-SCONN,HA   I111 @BASEBOARD_FAB2_LIB.BASEBOARD_FAB2(SCH_1):PAGE49
  J6M1   71     A3 SCONN288_H44441003_PIP-SCONN,HA   I158 @BASEBOARD_FAB2_LIB.BASEBOARD_FAB2(SCH_1):PAGE50

M_D_MA<4> @BASEBOARD_FAB2_LIB.BASEBOARD_FAB2(SCH_1):M_D_MA(4)
  U5D1 ED59 DDR3_MA<4> SKX_EXT_B_BGA1-IC,TBD   I172 @BASEBOARD_FAB2_LIB.BASEBOARD_FAB2(SCH_1):PAGE26
  J4B1  214     A4 SCONN288_H44441004_PIP-SCONN,HA   I111 @BASEBOARD_FAB2_LIB.BASEBOARD_FAB2(SCH_1):PAGE49
  J6M1  214     A4 SCONN288_H44441003_PIP-SCONN,HA   I158 @BASEBOARD_FAB2_LIB.BASEBOARD_FAB2(SCH_1):PAGE50

M_D_MA<5> @BASEBOARD_FAB2_LIB.BASEBOARD_FAB2(SCH_1):M_D_MA(5)
  U5D1 EA58 DDR3_MA<5> SKX_EXT_B_BGA1-IC,TBD   I172 @BASEBOARD_FAB2_LIB.BASEBOARD_FAB2(SCH_1):PAGE26
  J4B1  213     A5 SCONN288_H44441004_PIP-SCONN,HA   I111 @BASEBOARD_FAB2_LIB.BASEBOARD_FAB2(SCH_1):PAGE49
  J6M1  213     A5 SCONN288_H44441003_PIP-SCONN,HA   I158 @BASEBOARD_FAB2_LIB.BASEBOARD_FAB2(SCH_1):PAGE50

M_D_MA<6> @BASEBOARD_FAB2_LIB.BASEBOARD_FAB2(SCH_1):M_D_MA(6)
  U5D1 EE60 DDR3_MA<6> SKX_EXT_B_BGA1-IC,TBD   I172 @BASEBOARD_FAB2_LIB.BASEBOARD_FAB2(SCH_1):PAGE26
  J4B1   69     A6 SCONN288_H44441004_PIP-SCONN,HA   I111 @BASEBOARD_FAB2_LIB.BASEBOARD_FAB2(SCH_1):PAGE49
  J6M1   69     A6 SCONN288_H44441003_PIP-SCONN,HA   I158 @BASEBOARD_FAB2_LIB.BASEBOARD_FAB2(SCH_1):PAGE50

M_D_MA<7> @BASEBOARD_FAB2_LIB.BASEBOARD_FAB2(SCH_1):M_D_MA(7)
  U5D1 EA60 DDR3_MA<7> SKX_EXT_B_BGA1-IC,TBD   I172 @BASEBOARD_FAB2_LIB.BASEBOARD_FAB2(SCH_1):PAGE26
  J4B1  211     A7 SCONN288_H44441004_PIP-SCONN,HA   I111 @BASEBOARD_FAB2_LIB.BASEBOARD_FAB2(SCH_1):PAGE49
  J6M1  211     A7 SCONN288_H44441003_PIP-SCONN,HA   I158 @BASEBOARD_FAB2_LIB.BASEBOARD_FAB2(SCH_1):PAGE50

M_D_MA<8> @BASEBOARD_FAB2_LIB.BASEBOARD_FAB2(SCH_1):M_D_MA(8)
  U5D1 EB59 DDR3_MA<8> SKX_EXT_B_BGA1-IC,TBD   I172 @BASEBOARD_FAB2_LIB.BASEBOARD_FAB2(SCH_1):PAGE26
  J4B1   68     A8 SCONN288_H44441004_PIP-SCONN,HA   I111 @BASEBOARD_FAB2_LIB.BASEBOARD_FAB2(SCH_1):PAGE49
  J6M1   68     A8 SCONN288_H44441003_PIP-SCONN,HA   I158 @BASEBOARD_FAB2_LIB.BASEBOARD_FAB2(SCH_1):PAGE50

M_D_MA<9> @BASEBOARD_FAB2_LIB.BASEBOARD_FAB2(SCH_1):M_D_MA(9)
  U5D1 EF61 DDR3_MA<9> SKX_EXT_B_BGA1-IC,TBD   I172 @BASEBOARD_FAB2_LIB.BASEBOARD_FAB2(SCH_1):PAGE26
  J4B1   66     A9 SCONN288_H44441004_PIP-SCONN,HA   I111 @BASEBOARD_FAB2_LIB.BASEBOARD_FAB2(SCH_1):PAGE49
  J6M1   66     A9 SCONN288_H44441003_PIP-SCONN,HA   I158 @BASEBOARD_FAB2_LIB.BASEBOARD_FAB2(SCH_1):PAGE50

M_D_ODT<0> @BASEBOARD_FAB2_LIB.BASEBOARD_FAB2(SCH_1):M_D_ODT(0)
  U5D1 EE50 DDR3_ODT<0> SKX_EXT_B_BGA1-IC,TBD   I172 @BASEBOARD_FAB2_LIB.BASEBOARD_FAB2(SCH_1):PAGE26
  J4B1   87 ODT<0> SCONN288_H44441004_PIP-SCONN,HA   I111 @BASEBOARD_FAB2_LIB.BASEBOARD_FAB2(SCH_1):PAGE49

M_D_ODT<1> @BASEBOARD_FAB2_LIB.BASEBOARD_FAB2(SCH_1):M_D_ODT(1)
  U5D1 EE48 DDR3_ODT<1> SKX_EXT_B_BGA1-IC,TBD   I172 @BASEBOARD_FAB2_LIB.BASEBOARD_FAB2(SCH_1):PAGE26
  J4B1   91 ODT<1> SCONN288_H44441004_PIP-SCONN,HA   I111 @BASEBOARD_FAB2_LIB.BASEBOARD_FAB2(SCH_1):PAGE49

M_D_ODT<2> @BASEBOARD_FAB2_LIB.BASEBOARD_FAB2(SCH_1):M_D_ODT(2)
  U5D1 EA50 DDR3_ODT<2> SKX_EXT_B_BGA1-IC,TBD   I172 @BASEBOARD_FAB2_LIB.BASEBOARD_FAB2(SCH_1):PAGE26
  J6M1   87 ODT<0> SCONN288_H44441003_PIP-SCONN,HA   I158 @BASEBOARD_FAB2_LIB.BASEBOARD_FAB2(SCH_1):PAGE50

M_D_ODT<3> @BASEBOARD_FAB2_LIB.BASEBOARD_FAB2(SCH_1):M_D_ODT(3)
  U5D1 EA48 DDR3_ODT<3> SKX_EXT_B_BGA1-IC,TBD   I172 @BASEBOARD_FAB2_LIB.BASEBOARD_FAB2(SCH_1):PAGE26
  J6M1   91 ODT<1> SCONN288_H44441003_PIP-SCONN,HA   I158 @BASEBOARD_FAB2_LIB.BASEBOARD_FAB2(SCH_1):PAGE50

M_D_PAR @BASEBOARD_FAB2_LIB.BASEBOARD_FAB2(SCH_1):M_D_PAR
  U5D1 ED53 DDR3_PAR SKX_EXT_B_BGA1-IC,TBD   I172 @BASEBOARD_FAB2_LIB.BASEBOARD_FAB2(SCH_1):PAGE26
  J4B1  222    PAR SCONN288_H44441004_PIP-SCONN,HA   I111 @BASEBOARD_FAB2_LIB.BASEBOARD_FAB2(SCH_1):PAGE49
  J6M1  222    PAR SCONN288_H44441003_PIP-SCONN,HA   I158 @BASEBOARD_FAB2_LIB.BASEBOARD_FAB2(SCH_1):PAGE50

M_D_VREF @BASEBOARD_FAB2_LIB.BASEBOARD_FAB2(SCH_1):M_D_VREF
  J4B1  146 VREFCA SCONN288_H44441004_PIP-SCONN,HA   I111 @BASEBOARD_FAB2_LIB.BASEBOARD_FAB2(SCH_1):PAGE49
 C4B12    1      A CAP_A_0402V-0.01UF,25V,10%,X7RA   I179 @BASEBOARD_FAB2_LIB.BASEBOARD_FAB2(SCH_1):PAGE49
  J6M1  146 VREFCA SCONN288_H44441003_PIP-SCONN,HA   I158 @BASEBOARD_FAB2_LIB.BASEBOARD_FAB2(SCH_1):PAGE50
  C6M1    1      A CAP_A_0402V-0.01UF,25V,10%,X7RA   I177 @BASEBOARD_FAB2_LIB.BASEBOARD_FAB2(SCH_1):PAGE50
  R6M1    2      B RES_0402-1.00K,1%,1/16W,CHIP,GA     I9 @BASEBOARD_FAB2_LIB.BASEBOARD_FAB2(SCH_1):PAGE98
 R6L16    1      A RES_0402-1.00K,1%,1/16W,CHIP,GA    I12 @BASEBOARD_FAB2_LIB.BASEBOARD_FAB2(SCH_1):PAGE98
  R6M2    2      B RES_0402-2,1.0%,1/16W,CHIP,G21A    I14 @BASEBOARD_FAB2_LIB.BASEBOARD_FAB2(SCH_1):PAGE98

M_E_ACT_N @BASEBOARD_FAB2_LIB.BASEBOARD_FAB2(SCH_1):M_E_ACT_N
  U5D1 DR62 DDR4_ACT_N SKX_EXT_B_BGA1-IC,TBD   I172 @BASEBOARD_FAB2_LIB.BASEBOARD_FAB2(SCH_1):PAGE27
  J4A2   62  ACT_N SCONN288_H44441004_PIP-SCONN,HA   I111 @BASEBOARD_FAB2_LIB.BASEBOARD_FAB2(SCH_1):PAGE51
  J6L2   62  ACT_N SCONN288_H44441003_PIP-SCONN,HA    I12 @BASEBOARD_FAB2_LIB.BASEBOARD_FAB2(SCH_1):PAGE52

M_E_ALERT_N @BASEBOARD_FAB2_LIB.BASEBOARD_FAB2(SCH_1):M_E_ALERT_N
  U5D1 DT61 DDR4_ALERT_N SKX_EXT_B_BGA1-IC,TBD   I172 @BASEBOARD_FAB2_LIB.BASEBOARD_FAB2(SCH_1):PAGE27
  J4A2  208 ALERT_N SCONN288_H44441004_PIP-SCONN,HA   I111 @BASEBOARD_FAB2_LIB.BASEBOARD_FAB2(SCH_1):PAGE51
  J6L2  208 ALERT_N SCONN288_H44441003_PIP-SCONN,HA    I12 @BASEBOARD_FAB2_LIB.BASEBOARD_FAB2(SCH_1):PAGE52

M_E_BA<0> @BASEBOARD_FAB2_LIB.BASEBOARD_FAB2(SCH_1):M_E_BA(0)
  U5D1 DM53 DDR4_BA<0> SKX_EXT_B_BGA1-IC,TBD   I172 @BASEBOARD_FAB2_LIB.BASEBOARD_FAB2(SCH_1):PAGE27
  J4A2   81  BA<0> SCONN288_H44441004_PIP-SCONN,HA   I111 @BASEBOARD_FAB2_LIB.BASEBOARD_FAB2(SCH_1):PAGE51
  J6L2   81  BA<0> SCONN288_H44441003_PIP-SCONN,HA    I12 @BASEBOARD_FAB2_LIB.BASEBOARD_FAB2(SCH_1):PAGE52

M_E_BA<1> @BASEBOARD_FAB2_LIB.BASEBOARD_FAB2(SCH_1):M_E_BA(1)
  U5D1 DV55 DDR4_BA<1> SKX_EXT_B_BGA1-IC,TBD   I172 @BASEBOARD_FAB2_LIB.BASEBOARD_FAB2(SCH_1):PAGE27
  J4A2  224  BA<1> SCONN288_H44441004_PIP-SCONN,HA   I111 @BASEBOARD_FAB2_LIB.BASEBOARD_FAB2(SCH_1):PAGE51
  J6L2  224  BA<1> SCONN288_H44441003_PIP-SCONN,HA    I12 @BASEBOARD_FAB2_LIB.BASEBOARD_FAB2(SCH_1):PAGE52

M_E_BG<0> @BASEBOARD_FAB2_LIB.BASEBOARD_FAB2(SCH_1):M_E_BG(0)
  U5D1 DJ62 DDR4_BG<0> SKX_EXT_B_BGA1-IC,TBD   I172 @BASEBOARD_FAB2_LIB.BASEBOARD_FAB2(SCH_1):PAGE27
  J4A2   63  BG<0> SCONN288_H44441004_PIP-SCONN,HA   I111 @BASEBOARD_FAB2_LIB.BASEBOARD_FAB2(SCH_1):PAGE51
  J6L2   63  BG<0> SCONN288_H44441003_PIP-SCONN,HA    I12 @BASEBOARD_FAB2_LIB.BASEBOARD_FAB2(SCH_1):PAGE52

M_E_BG<1> @BASEBOARD_FAB2_LIB.BASEBOARD_FAB2(SCH_1):M_E_BG(1)
  U5D1 DM61 DDR4_BG<1> SKX_EXT_B_BGA1-IC,TBD   I172 @BASEBOARD_FAB2_LIB.BASEBOARD_FAB2(SCH_1):PAGE27
  J4A2  207  BG<1> SCONN288_H44441004_PIP-SCONN,HA   I111 @BASEBOARD_FAB2_LIB.BASEBOARD_FAB2(SCH_1):PAGE51
  J6L2  207  BG<1> SCONN288_H44441003_PIP-SCONN,HA    I12 @BASEBOARD_FAB2_LIB.BASEBOARD_FAB2(SCH_1):PAGE52

M_E_C<2> @BASEBOARD_FAB2_LIB.BASEBOARD_FAB2(SCH_1):M_E_C(2)
  U5D1 DT47 DDR4_CID<2> SKX_EXT_B_BGA1-IC,TBD   I172 @BASEBOARD_FAB2_LIB.BASEBOARD_FAB2(SCH_1):PAGE27
  J4A2  235   C<2> SCONN288_H44441004_PIP-SCONN,HA   I111 @BASEBOARD_FAB2_LIB.BASEBOARD_FAB2(SCH_1):PAGE51
  J6L2  235   C<2> SCONN288_H44441003_PIP-SCONN,HA    I12 @BASEBOARD_FAB2_LIB.BASEBOARD_FAB2(SCH_1):PAGE52

M_E_CKE<0> @BASEBOARD_FAB2_LIB.BASEBOARD_FAB2(SCH_1):M_E_CKE(0)
  U5D1 DM63 DDR4_CKE<0> SKX_EXT_B_BGA1-IC,TBD   I172 @BASEBOARD_FAB2_LIB.BASEBOARD_FAB2(SCH_1):PAGE27
  J4A2   60 CKE<0> SCONN288_H44441004_PIP-SCONN,HA   I111 @BASEBOARD_FAB2_LIB.BASEBOARD_FAB2(SCH_1):PAGE51

M_E_CKE<1> @BASEBOARD_FAB2_LIB.BASEBOARD_FAB2(SCH_1):M_E_CKE(1)
  U5D1 DN64 DDR4_CKE<1> SKX_EXT_B_BGA1-IC,TBD   I172 @BASEBOARD_FAB2_LIB.BASEBOARD_FAB2(SCH_1):PAGE27
  J4A2  203 CKE<1> SCONN288_H44441004_PIP-SCONN,HA   I111 @BASEBOARD_FAB2_LIB.BASEBOARD_FAB2(SCH_1):PAGE51

M_E_CKE<2> @BASEBOARD_FAB2_LIB.BASEBOARD_FAB2(SCH_1):M_E_CKE(2)
  U5D1 DL64 DDR4_CKE<2> SKX_EXT_B_BGA1-IC,TBD   I172 @BASEBOARD_FAB2_LIB.BASEBOARD_FAB2(SCH_1):PAGE27
  J6L2   60 CKE<0> SCONN288_H44441003_PIP-SCONN,HA    I12 @BASEBOARD_FAB2_LIB.BASEBOARD_FAB2(SCH_1):PAGE52

M_E_CKE<3> @BASEBOARD_FAB2_LIB.BASEBOARD_FAB2(SCH_1):M_E_CKE(3)
  U5D1 DR64 DDR4_CKE<3> SKX_EXT_B_BGA1-IC,TBD   I172 @BASEBOARD_FAB2_LIB.BASEBOARD_FAB2(SCH_1):PAGE27
  J6L2  203 CKE<1> SCONN288_H44441003_PIP-SCONN,HA    I12 @BASEBOARD_FAB2_LIB.BASEBOARD_FAB2(SCH_1):PAGE52

M_E_CLK_DN<0> @BASEBOARD_FAB2_LIB.BASEBOARD_FAB2(SCH_1):M_E_CLK_DN(0)
  U5D1 DM55 DDR4_CLK_DN<0> SKX_EXT_B_BGA1-IC,TBD   I172 @BASEBOARD_FAB2_LIB.BASEBOARD_FAB2(SCH_1):PAGE27
  J4A2   75   CK0N SCONN288_H44441004_PIP-SCONN,HA   I111 @BASEBOARD_FAB2_LIB.BASEBOARD_FAB2(SCH_1):PAGE51

M_E_CLK_DN<1> @BASEBOARD_FAB2_LIB.BASEBOARD_FAB2(SCH_1):M_E_CLK_DN(1)
  U5D1 DR54 DDR4_CLK_DN<1> SKX_EXT_B_BGA1-IC,TBD   I172 @BASEBOARD_FAB2_LIB.BASEBOARD_FAB2(SCH_1):PAGE27
  J4A2  219   CK1N SCONN288_H44441004_PIP-SCONN,HA   I111 @BASEBOARD_FAB2_LIB.BASEBOARD_FAB2(SCH_1):PAGE51

M_E_CLK_DN<2> @BASEBOARD_FAB2_LIB.BASEBOARD_FAB2(SCH_1):M_E_CLK_DN(2)
  U5D1 DM57 DDR4_CLK_DN<2> SKX_EXT_B_BGA1-IC,TBD   I172 @BASEBOARD_FAB2_LIB.BASEBOARD_FAB2(SCH_1):PAGE27
  J6L2   75   CK0N SCONN288_H44441003_PIP-SCONN,HA    I12 @BASEBOARD_FAB2_LIB.BASEBOARD_FAB2(SCH_1):PAGE52

M_E_CLK_DN<3> @BASEBOARD_FAB2_LIB.BASEBOARD_FAB2(SCH_1):M_E_CLK_DN(3)
  U5D1 DT57 DDR4_CLK_DN<3> SKX_EXT_B_BGA1-IC,TBD   I172 @BASEBOARD_FAB2_LIB.BASEBOARD_FAB2(SCH_1):PAGE27
  J6L2  219   CK1N SCONN288_H44441003_PIP-SCONN,HA    I12 @BASEBOARD_FAB2_LIB.BASEBOARD_FAB2(SCH_1):PAGE52

M_E_CLK_DP<0> @BASEBOARD_FAB2_LIB.BASEBOARD_FAB2(SCH_1):M_E_CLK_DP(0)
  U5D1 DN54 DDR4_CLK_DP<0> SKX_EXT_B_BGA1-IC,TBD   I172 @BASEBOARD_FAB2_LIB.BASEBOARD_FAB2(SCH_1):PAGE27
  J4A2   74   CK0P SCONN288_H44441004_PIP-SCONN,HA   I111 @BASEBOARD_FAB2_LIB.BASEBOARD_FAB2(SCH_1):PAGE51

M_E_CLK_DP<1> @BASEBOARD_FAB2_LIB.BASEBOARD_FAB2(SCH_1):M_E_CLK_DP(1)
  U5D1 DT53 DDR4_CLK_DP<1> SKX_EXT_B_BGA1-IC,TBD   I172 @BASEBOARD_FAB2_LIB.BASEBOARD_FAB2(SCH_1):PAGE27
  J4A2  218   CK1P SCONN288_H44441004_PIP-SCONN,HA   I111 @BASEBOARD_FAB2_LIB.BASEBOARD_FAB2(SCH_1):PAGE51

M_E_CLK_DP<2> @BASEBOARD_FAB2_LIB.BASEBOARD_FAB2(SCH_1):M_E_CLK_DP(2)
  U5D1 DN56 DDR4_CLK_DP<2> SKX_EXT_B_BGA1-IC,TBD   I172 @BASEBOARD_FAB2_LIB.BASEBOARD_FAB2(SCH_1):PAGE27
  J6L2   74   CK0P SCONN288_H44441003_PIP-SCONN,HA    I12 @BASEBOARD_FAB2_LIB.BASEBOARD_FAB2(SCH_1):PAGE52

M_E_CLK_DP<3> @BASEBOARD_FAB2_LIB.BASEBOARD_FAB2(SCH_1):M_E_CLK_DP(3)
  U5D1 DR56 DDR4_CLK_DP<3> SKX_EXT_B_BGA1-IC,TBD   I172 @BASEBOARD_FAB2_LIB.BASEBOARD_FAB2(SCH_1):PAGE27
  J6L2  218   CK1P SCONN288_H44441003_PIP-SCONN,HA    I12 @BASEBOARD_FAB2_LIB.BASEBOARD_FAB2(SCH_1):PAGE52

M_E_CPU_VREF @BASEBOARD_FAB2_LIB.BASEBOARD_FAB2(SCH_1):M_E_CPU_VREF
  U5D1 CT61 DDR4_CAVREF SKX_EXT_B_BGA1-IC,TBD   I259 @BASEBOARD_FAB2_LIB.BASEBOARD_FAB2(SCH_1):PAGE21
 R6L14    1      A RES_0402-2,1.0%,1/16W,CHIP,G21A    I58 @BASEBOARD_FAB2_LIB.BASEBOARD_FAB2(SCH_1):PAGE98
  C6L7    1      A CAP_A_0402V-0.01UF,25V,10%,X7RA    I59 @BASEBOARD_FAB2_LIB.BASEBOARD_FAB2(SCH_1):PAGE98

M_E_CS_N<0> @BASEBOARD_FAB2_LIB.BASEBOARD_FAB2(SCH_1):M_E_CS_N(0)
  U5D1 DV51 DDR4_CS_N<0> SKX_EXT_B_BGA1-IC,TBD   I172 @BASEBOARD_FAB2_LIB.BASEBOARD_FAB2(SCH_1):PAGE27
  J4A2   84   S0_N SCONN288_H44441004_PIP-SCONN,HA   I111 @BASEBOARD_FAB2_LIB.BASEBOARD_FAB2(SCH_1):PAGE51

M_E_CS_N<1> @BASEBOARD_FAB2_LIB.BASEBOARD_FAB2(SCH_1):M_E_CS_N(1)
  U5D1 DN50 DDR4_CS_N<1> SKX_EXT_B_BGA1-IC,TBD   I172 @BASEBOARD_FAB2_LIB.BASEBOARD_FAB2(SCH_1):PAGE27
  J4A2   89   S1_N SCONN288_H44441004_PIP-SCONN,HA   I111 @BASEBOARD_FAB2_LIB.BASEBOARD_FAB2(SCH_1):PAGE51

M_E_CS_N<2> @BASEBOARD_FAB2_LIB.BASEBOARD_FAB2(SCH_1):M_E_CS_N(2)
  U5D1 DR46 DDR4_CS_N<2> SKX_EXT_B_BGA1-IC,TBD   I172 @BASEBOARD_FAB2_LIB.BASEBOARD_FAB2(SCH_1):PAGE27
  J4A2   93 S2_N_C<0> SCONN288_H44441004_PIP-SCONN,HA   I111 @BASEBOARD_FAB2_LIB.BASEBOARD_FAB2(SCH_1):PAGE51

M_E_CS_N<3> @BASEBOARD_FAB2_LIB.BASEBOARD_FAB2(SCH_1):M_E_CS_N(3)
  U5D1 DK47 DDR4_CS_N<3> SKX_EXT_B_BGA1-IC,TBD   I172 @BASEBOARD_FAB2_LIB.BASEBOARD_FAB2(SCH_1):PAGE27
  J4A2  237 S3_N_C<1> SCONN288_H44441004_PIP-SCONN,HA   I111 @BASEBOARD_FAB2_LIB.BASEBOARD_FAB2(SCH_1):PAGE51

M_E_CS_N<4> @BASEBOARD_FAB2_LIB.BASEBOARD_FAB2(SCH_1):M_E_CS_N(4)
  U5D1 DW50 DDR4_CS_N<4> SKX_EXT_B_BGA1-IC,TBD   I172 @BASEBOARD_FAB2_LIB.BASEBOARD_FAB2(SCH_1):PAGE27
  J6L2   84   S0_N SCONN288_H44441003_PIP-SCONN,HA    I12 @BASEBOARD_FAB2_LIB.BASEBOARD_FAB2(SCH_1):PAGE52

M_E_CS_N<5> @BASEBOARD_FAB2_LIB.BASEBOARD_FAB2(SCH_1):M_E_CS_N(5)
  U5D1 DM49 DDR4_CS_N<5> SKX_EXT_B_BGA1-IC,TBD   I172 @BASEBOARD_FAB2_LIB.BASEBOARD_FAB2(SCH_1):PAGE27
  J6L2   89   S1_N SCONN288_H44441003_PIP-SCONN,HA    I12 @BASEBOARD_FAB2_LIB.BASEBOARD_FAB2(SCH_1):PAGE52

M_E_CS_N<6> @BASEBOARD_FAB2_LIB.BASEBOARD_FAB2(SCH_1):M_E_CS_N(6)
  U5D1 DT45 DDR4_CS_N<6> SKX_EXT_B_BGA1-IC,TBD   I172 @BASEBOARD_FAB2_LIB.BASEBOARD_FAB2(SCH_1):PAGE27
  J6L2   93 S2_N_C<0> SCONN288_H44441003_PIP-SCONN,HA    I12 @BASEBOARD_FAB2_LIB.BASEBOARD_FAB2(SCH_1):PAGE52

M_E_CS_N<7> @BASEBOARD_FAB2_LIB.BASEBOARD_FAB2(SCH_1):M_E_CS_N(7)
  U5D1 DN46 DDR4_CS_N<7> SKX_EXT_B_BGA1-IC,TBD   I172 @BASEBOARD_FAB2_LIB.BASEBOARD_FAB2(SCH_1):PAGE27
  J6L2  237 S3_N_C<1> SCONN288_H44441003_PIP-SCONN,HA    I12 @BASEBOARD_FAB2_LIB.BASEBOARD_FAB2(SCH_1):PAGE52

M_E_DQ<0> @BASEBOARD_FAB2_LIB.BASEBOARD_FAB2(SCH_1):M_E_DQ(0)
  U5D1 CM79 DDR4_DQ<0> SKX_EXT_B_BGA1-IC,TBD   I172 @BASEBOARD_FAB2_LIB.BASEBOARD_FAB2(SCH_1):PAGE27
  J4A2  150  DQ<1> SCONN288_H44441004_PIP-SCONN,HA   I111 @BASEBOARD_FAB2_LIB.BASEBOARD_FAB2(SCH_1):PAGE51
  J6L2    5  DQ<0> SCONN288_H44441003_PIP-SCONN,HA    I12 @BASEBOARD_FAB2_LIB.BASEBOARD_FAB2(SCH_1):PAGE52

M_E_DQ<10> @BASEBOARD_FAB2_LIB.BASEBOARD_FAB2(SCH_1):M_E_DQ(10)
  U5D1 DE80 DDR4_DQ<10> SKX_EXT_B_BGA1-IC,TBD   I172 @BASEBOARD_FAB2_LIB.BASEBOARD_FAB2(SCH_1):PAGE27
  J4A2  168 DQ<11> SCONN288_H44441004_PIP-SCONN,HA   I111 @BASEBOARD_FAB2_LIB.BASEBOARD_FAB2(SCH_1):PAGE51
  J6L2   23 DQ<10> SCONN288_H44441003_PIP-SCONN,HA    I12 @BASEBOARD_FAB2_LIB.BASEBOARD_FAB2(SCH_1):PAGE52

M_E_DQ<11> @BASEBOARD_FAB2_LIB.BASEBOARD_FAB2(SCH_1):M_E_DQ(11)
  U5D1 DF81 DDR4_DQ<11> SKX_EXT_B_BGA1-IC,TBD   I172 @BASEBOARD_FAB2_LIB.BASEBOARD_FAB2(SCH_1):PAGE27
  J4A2   23 DQ<10> SCONN288_H44441004_PIP-SCONN,HA   I111 @BASEBOARD_FAB2_LIB.BASEBOARD_FAB2(SCH_1):PAGE51
  J6L2  168 DQ<11> SCONN288_H44441003_PIP-SCONN,HA    I12 @BASEBOARD_FAB2_LIB.BASEBOARD_FAB2(SCH_1):PAGE52

M_E_DQ<12> @BASEBOARD_FAB2_LIB.BASEBOARD_FAB2(SCH_1):M_E_DQ(12)
  U5D1 CY79 DDR4_DQ<12> SKX_EXT_B_BGA1-IC,TBD   I172 @BASEBOARD_FAB2_LIB.BASEBOARD_FAB2(SCH_1):PAGE27
  J4A2  159 DQ<13> SCONN288_H44441004_PIP-SCONN,HA   I111 @BASEBOARD_FAB2_LIB.BASEBOARD_FAB2(SCH_1):PAGE51
  J6L2   14 DQ<12> SCONN288_H44441003_PIP-SCONN,HA    I12 @BASEBOARD_FAB2_LIB.BASEBOARD_FAB2(SCH_1):PAGE52

M_E_DQ<13> @BASEBOARD_FAB2_LIB.BASEBOARD_FAB2(SCH_1):M_E_DQ(13)
  U5D1 CW80 DDR4_DQ<13> SKX_EXT_B_BGA1-IC,TBD   I172 @BASEBOARD_FAB2_LIB.BASEBOARD_FAB2(SCH_1):PAGE27
  J4A2   14 DQ<12> SCONN288_H44441004_PIP-SCONN,HA   I111 @BASEBOARD_FAB2_LIB.BASEBOARD_FAB2(SCH_1):PAGE51
  J6L2  159 DQ<13> SCONN288_H44441003_PIP-SCONN,HA    I12 @BASEBOARD_FAB2_LIB.BASEBOARD_FAB2(SCH_1):PAGE52

M_E_DQ<14> @BASEBOARD_FAB2_LIB.BASEBOARD_FAB2(SCH_1):M_E_DQ(14)
  U5D1 DC82 DDR4_DQ<14> SKX_EXT_B_BGA1-IC,TBD   I172 @BASEBOARD_FAB2_LIB.BASEBOARD_FAB2(SCH_1):PAGE27
  J4A2  166 DQ<15> SCONN288_H44441004_PIP-SCONN,HA   I111 @BASEBOARD_FAB2_LIB.BASEBOARD_FAB2(SCH_1):PAGE51
  J6L2   21 DQ<14> SCONN288_H44441003_PIP-SCONN,HA    I12 @BASEBOARD_FAB2_LIB.BASEBOARD_FAB2(SCH_1):PAGE52

M_E_DQ<15> @BASEBOARD_FAB2_LIB.BASEBOARD_FAB2(SCH_1):M_E_DQ(15)
  U5D1 DE82 DDR4_DQ<15> SKX_EXT_B_BGA1-IC,TBD   I172 @BASEBOARD_FAB2_LIB.BASEBOARD_FAB2(SCH_1):PAGE27
  J4A2   21 DQ<14> SCONN288_H44441004_PIP-SCONN,HA   I111 @BASEBOARD_FAB2_LIB.BASEBOARD_FAB2(SCH_1):PAGE51
  J6L2  166 DQ<15> SCONN288_H44441003_PIP-SCONN,HA    I12 @BASEBOARD_FAB2_LIB.BASEBOARD_FAB2(SCH_1):PAGE52

M_E_DQ<16> @BASEBOARD_FAB2_LIB.BASEBOARD_FAB2(SCH_1):M_E_DQ(16)
  U5D1 DW80 DDR4_DQ<16> SKX_EXT_B_BGA1-IC,TBD   I172 @BASEBOARD_FAB2_LIB.BASEBOARD_FAB2(SCH_1):PAGE27
  J4A2  172 DQ<17> SCONN288_H44441004_PIP-SCONN,HA   I111 @BASEBOARD_FAB2_LIB.BASEBOARD_FAB2(SCH_1):PAGE51
  J6L2   27 DQ<16> SCONN288_H44441003_PIP-SCONN,HA    I12 @BASEBOARD_FAB2_LIB.BASEBOARD_FAB2(SCH_1):PAGE52

M_E_DQ<17> @BASEBOARD_FAB2_LIB.BASEBOARD_FAB2(SCH_1):M_E_DQ(17)
  U5D1 EC80 DDR4_DQ<17> SKX_EXT_B_BGA1-IC,TBD   I172 @BASEBOARD_FAB2_LIB.BASEBOARD_FAB2(SCH_1):PAGE27
  J4A2   27 DQ<16> SCONN288_H44441004_PIP-SCONN,HA   I111 @BASEBOARD_FAB2_LIB.BASEBOARD_FAB2(SCH_1):PAGE51
  J6L2  172 DQ<17> SCONN288_H44441003_PIP-SCONN,HA    I12 @BASEBOARD_FAB2_LIB.BASEBOARD_FAB2(SCH_1):PAGE52

M_E_DQ<18> @BASEBOARD_FAB2_LIB.BASEBOARD_FAB2(SCH_1):M_E_DQ(18)
  U5D1 DY77 DDR4_DQ<18> SKX_EXT_B_BGA1-IC,TBD   I172 @BASEBOARD_FAB2_LIB.BASEBOARD_FAB2(SCH_1):PAGE27
  J4A2  179 DQ<19> SCONN288_H44441004_PIP-SCONN,HA   I111 @BASEBOARD_FAB2_LIB.BASEBOARD_FAB2(SCH_1):PAGE51
  J6L2   34 DQ<18> SCONN288_H44441003_PIP-SCONN,HA    I12 @BASEBOARD_FAB2_LIB.BASEBOARD_FAB2(SCH_1):PAGE52

M_E_DQ<19> @BASEBOARD_FAB2_LIB.BASEBOARD_FAB2(SCH_1):M_E_DQ(19)
  U5D1 EB77 DDR4_DQ<19> SKX_EXT_B_BGA1-IC,TBD   I172 @BASEBOARD_FAB2_LIB.BASEBOARD_FAB2(SCH_1):PAGE27
  J4A2   34 DQ<18> SCONN288_H44441004_PIP-SCONN,HA   I111 @BASEBOARD_FAB2_LIB.BASEBOARD_FAB2(SCH_1):PAGE51
  J6L2  179 DQ<19> SCONN288_H44441003_PIP-SCONN,HA    I12 @BASEBOARD_FAB2_LIB.BASEBOARD_FAB2(SCH_1):PAGE52

M_E_DQ<1> @BASEBOARD_FAB2_LIB.BASEBOARD_FAB2(SCH_1):M_E_DQ(1)
  U5D1 CK81 DDR4_DQ<1> SKX_EXT_B_BGA1-IC,TBD   I172 @BASEBOARD_FAB2_LIB.BASEBOARD_FAB2(SCH_1):PAGE27
  J4A2    5  DQ<0> SCONN288_H44441004_PIP-SCONN,HA   I111 @BASEBOARD_FAB2_LIB.BASEBOARD_FAB2(SCH_1):PAGE51
  J6L2  150  DQ<1> SCONN288_H44441003_PIP-SCONN,HA    I12 @BASEBOARD_FAB2_LIB.BASEBOARD_FAB2(SCH_1):PAGE52

M_E_DQ<20> @BASEBOARD_FAB2_LIB.BASEBOARD_FAB2(SCH_1):M_E_DQ(20)
  U5D1 DY81 DDR4_DQ<20> SKX_EXT_B_BGA1-IC,TBD   I172 @BASEBOARD_FAB2_LIB.BASEBOARD_FAB2(SCH_1):PAGE27
  J4A2  170 DQ<21> SCONN288_H44441004_PIP-SCONN,HA   I111 @BASEBOARD_FAB2_LIB.BASEBOARD_FAB2(SCH_1):PAGE51
  J6L2   25 DQ<20> SCONN288_H44441003_PIP-SCONN,HA    I12 @BASEBOARD_FAB2_LIB.BASEBOARD_FAB2(SCH_1):PAGE52

M_E_DQ<21> @BASEBOARD_FAB2_LIB.BASEBOARD_FAB2(SCH_1):M_E_DQ(21)
  U5D1 EB81 DDR4_DQ<21> SKX_EXT_B_BGA1-IC,TBD   I172 @BASEBOARD_FAB2_LIB.BASEBOARD_FAB2(SCH_1):PAGE27
  J4A2   25 DQ<20> SCONN288_H44441004_PIP-SCONN,HA   I111 @BASEBOARD_FAB2_LIB.BASEBOARD_FAB2(SCH_1):PAGE51
  J6L2  170 DQ<21> SCONN288_H44441003_PIP-SCONN,HA    I12 @BASEBOARD_FAB2_LIB.BASEBOARD_FAB2(SCH_1):PAGE52

M_E_DQ<22> @BASEBOARD_FAB2_LIB.BASEBOARD_FAB2(SCH_1):M_E_DQ(22)
  U5D1 DW78 DDR4_DQ<22> SKX_EXT_B_BGA1-IC,TBD   I172 @BASEBOARD_FAB2_LIB.BASEBOARD_FAB2(SCH_1):PAGE27
  J4A2  177 DQ<23> SCONN288_H44441004_PIP-SCONN,HA   I111 @BASEBOARD_FAB2_LIB.BASEBOARD_FAB2(SCH_1):PAGE51
  J6L2   32 DQ<22> SCONN288_H44441003_PIP-SCONN,HA    I12 @BASEBOARD_FAB2_LIB.BASEBOARD_FAB2(SCH_1):PAGE52

M_E_DQ<23> @BASEBOARD_FAB2_LIB.BASEBOARD_FAB2(SCH_1):M_E_DQ(23)
  U5D1 EC78 DDR4_DQ<23> SKX_EXT_B_BGA1-IC,TBD   I172 @BASEBOARD_FAB2_LIB.BASEBOARD_FAB2(SCH_1):PAGE27
  J4A2   32 DQ<22> SCONN288_H44441004_PIP-SCONN,HA   I111 @BASEBOARD_FAB2_LIB.BASEBOARD_FAB2(SCH_1):PAGE51
  J6L2  177 DQ<23> SCONN288_H44441003_PIP-SCONN,HA    I12 @BASEBOARD_FAB2_LIB.BASEBOARD_FAB2(SCH_1):PAGE52

M_E_DQ<24> @BASEBOARD_FAB2_LIB.BASEBOARD_FAB2(SCH_1):M_E_DQ(24)
  U5D1 ED75 DDR4_DQ<24> SKX_EXT_B_BGA1-IC,TBD   I172 @BASEBOARD_FAB2_LIB.BASEBOARD_FAB2(SCH_1):PAGE27
  J4A2  183 DQ<25> SCONN288_H44441004_PIP-SCONN,HA   I111 @BASEBOARD_FAB2_LIB.BASEBOARD_FAB2(SCH_1):PAGE51
  J6L2   38 DQ<24> SCONN288_H44441003_PIP-SCONN,HA    I12 @BASEBOARD_FAB2_LIB.BASEBOARD_FAB2(SCH_1):PAGE52

M_E_DQ<25> @BASEBOARD_FAB2_LIB.BASEBOARD_FAB2(SCH_1):M_E_DQ(25)
  U5D1 EE74 DDR4_DQ<25> SKX_EXT_B_BGA1-IC,TBD   I172 @BASEBOARD_FAB2_LIB.BASEBOARD_FAB2(SCH_1):PAGE27
  J4A2   38 DQ<24> SCONN288_H44441004_PIP-SCONN,HA   I111 @BASEBOARD_FAB2_LIB.BASEBOARD_FAB2(SCH_1):PAGE51
  J6L2  183 DQ<25> SCONN288_H44441003_PIP-SCONN,HA    I12 @BASEBOARD_FAB2_LIB.BASEBOARD_FAB2(SCH_1):PAGE52

M_E_DQ<26> @BASEBOARD_FAB2_LIB.BASEBOARD_FAB2(SCH_1):M_E_DQ(26)
  U5D1 EB71 DDR4_DQ<26> SKX_EXT_B_BGA1-IC,TBD   I172 @BASEBOARD_FAB2_LIB.BASEBOARD_FAB2(SCH_1):PAGE27
  J4A2  190 DQ<27> SCONN288_H44441004_PIP-SCONN,HA   I111 @BASEBOARD_FAB2_LIB.BASEBOARD_FAB2(SCH_1):PAGE51
  J6L2   45 DQ<26> SCONN288_H44441003_PIP-SCONN,HA    I12 @BASEBOARD_FAB2_LIB.BASEBOARD_FAB2(SCH_1):PAGE52

M_E_DQ<27> @BASEBOARD_FAB2_LIB.BASEBOARD_FAB2(SCH_1):M_E_DQ(27)
  U5D1 ED71 DDR4_DQ<27> SKX_EXT_B_BGA1-IC,TBD   I172 @BASEBOARD_FAB2_LIB.BASEBOARD_FAB2(SCH_1):PAGE27
  J4A2   45 DQ<26> SCONN288_H44441004_PIP-SCONN,HA   I111 @BASEBOARD_FAB2_LIB.BASEBOARD_FAB2(SCH_1):PAGE51
  J6L2  190 DQ<27> SCONN288_H44441003_PIP-SCONN,HA    I12 @BASEBOARD_FAB2_LIB.BASEBOARD_FAB2(SCH_1):PAGE52

M_E_DQ<28> @BASEBOARD_FAB2_LIB.BASEBOARD_FAB2(SCH_1):M_E_DQ(28)
  U5D1 EA74 DDR4_DQ<28> SKX_EXT_B_BGA1-IC,TBD   I172 @BASEBOARD_FAB2_LIB.BASEBOARD_FAB2(SCH_1):PAGE27
  J4A2  181 DQ<29> SCONN288_H44441004_PIP-SCONN,HA   I111 @BASEBOARD_FAB2_LIB.BASEBOARD_FAB2(SCH_1):PAGE51
  J6L2   36 DQ<28> SCONN288_H44441003_PIP-SCONN,HA    I12 @BASEBOARD_FAB2_LIB.BASEBOARD_FAB2(SCH_1):PAGE52

M_E_DQ<29> @BASEBOARD_FAB2_LIB.BASEBOARD_FAB2(SCH_1):M_E_DQ(29)
  U5D1 EB75 DDR4_DQ<29> SKX_EXT_B_BGA1-IC,TBD   I172 @BASEBOARD_FAB2_LIB.BASEBOARD_FAB2(SCH_1):PAGE27
  J4A2   36 DQ<28> SCONN288_H44441004_PIP-SCONN,HA   I111 @BASEBOARD_FAB2_LIB.BASEBOARD_FAB2(SCH_1):PAGE51
  J6L2  181 DQ<29> SCONN288_H44441003_PIP-SCONN,HA    I12 @BASEBOARD_FAB2_LIB.BASEBOARD_FAB2(SCH_1):PAGE52

M_E_DQ<2> @BASEBOARD_FAB2_LIB.BASEBOARD_FAB2(SCH_1):M_E_DQ(2)
  U5D1 CT81 DDR4_DQ<2> SKX_EXT_B_BGA1-IC,TBD   I172 @BASEBOARD_FAB2_LIB.BASEBOARD_FAB2(SCH_1):PAGE27
  J4A2  157  DQ<3> SCONN288_H44441004_PIP-SCONN,HA   I111 @BASEBOARD_FAB2_LIB.BASEBOARD_FAB2(SCH_1):PAGE51
  J6L2   12  DQ<2> SCONN288_H44441003_PIP-SCONN,HA    I12 @BASEBOARD_FAB2_LIB.BASEBOARD_FAB2(SCH_1):PAGE52

M_E_DQ<30> @BASEBOARD_FAB2_LIB.BASEBOARD_FAB2(SCH_1):M_E_DQ(30)
  U5D1 EA72 DDR4_DQ<30> SKX_EXT_B_BGA1-IC,TBD   I172 @BASEBOARD_FAB2_LIB.BASEBOARD_FAB2(SCH_1):PAGE27
  J4A2  188 DQ<31> SCONN288_H44441004_PIP-SCONN,HA   I111 @BASEBOARD_FAB2_LIB.BASEBOARD_FAB2(SCH_1):PAGE51
  J6L2   43 DQ<30> SCONN288_H44441003_PIP-SCONN,HA    I12 @BASEBOARD_FAB2_LIB.BASEBOARD_FAB2(SCH_1):PAGE52

M_E_DQ<31> @BASEBOARD_FAB2_LIB.BASEBOARD_FAB2(SCH_1):M_E_DQ(31)
  U5D1 EE72 DDR4_DQ<31> SKX_EXT_B_BGA1-IC,TBD   I172 @BASEBOARD_FAB2_LIB.BASEBOARD_FAB2(SCH_1):PAGE27
  J4A2   43 DQ<30> SCONN288_H44441004_PIP-SCONN,HA   I111 @BASEBOARD_FAB2_LIB.BASEBOARD_FAB2(SCH_1):PAGE51
  J6L2  188 DQ<31> SCONN288_H44441003_PIP-SCONN,HA    I12 @BASEBOARD_FAB2_LIB.BASEBOARD_FAB2(SCH_1):PAGE52

M_E_DQ<32> @BASEBOARD_FAB2_LIB.BASEBOARD_FAB2(SCH_1):M_E_DQ(32)
  U5D1 DU42 DDR4_DQ<32> SKX_EXT_B_BGA1-IC,TBD   I172 @BASEBOARD_FAB2_LIB.BASEBOARD_FAB2(SCH_1):PAGE27
  J4A2  242 DQ<33> SCONN288_H44441004_PIP-SCONN,HA   I111 @BASEBOARD_FAB2_LIB.BASEBOARD_FAB2(SCH_1):PAGE51
  J6L2   97 DQ<32> SCONN288_H44441003_PIP-SCONN,HA    I12 @BASEBOARD_FAB2_LIB.BASEBOARD_FAB2(SCH_1):PAGE52

M_E_DQ<33> @BASEBOARD_FAB2_LIB.BASEBOARD_FAB2(SCH_1):M_E_DQ(33)
  U5D1 DW42 DDR4_DQ<33> SKX_EXT_B_BGA1-IC,TBD   I172 @BASEBOARD_FAB2_LIB.BASEBOARD_FAB2(SCH_1):PAGE27
  J4A2   97 DQ<32> SCONN288_H44441004_PIP-SCONN,HA   I111 @BASEBOARD_FAB2_LIB.BASEBOARD_FAB2(SCH_1):PAGE51
  J6L2  242 DQ<33> SCONN288_H44441003_PIP-SCONN,HA    I12 @BASEBOARD_FAB2_LIB.BASEBOARD_FAB2(SCH_1):PAGE52

M_E_DQ<34> @BASEBOARD_FAB2_LIB.BASEBOARD_FAB2(SCH_1):M_E_DQ(34)
  U5D1 DP39 DDR4_DQ<34> SKX_EXT_B_BGA1-IC,TBD   I172 @BASEBOARD_FAB2_LIB.BASEBOARD_FAB2(SCH_1):PAGE27
  J4A2  249 DQ<35> SCONN288_H44441004_PIP-SCONN,HA   I111 @BASEBOARD_FAB2_LIB.BASEBOARD_FAB2(SCH_1):PAGE51
  J6L2  104 DQ<34> SCONN288_H44441003_PIP-SCONN,HA    I12 @BASEBOARD_FAB2_LIB.BASEBOARD_FAB2(SCH_1):PAGE52

M_E_DQ<35> @BASEBOARD_FAB2_LIB.BASEBOARD_FAB2(SCH_1):M_E_DQ(35)
  U5D1 DT39 DDR4_DQ<35> SKX_EXT_B_BGA1-IC,TBD   I172 @BASEBOARD_FAB2_LIB.BASEBOARD_FAB2(SCH_1):PAGE27
  J4A2  104 DQ<34> SCONN288_H44441004_PIP-SCONN,HA   I111 @BASEBOARD_FAB2_LIB.BASEBOARD_FAB2(SCH_1):PAGE51
  J6L2  249 DQ<35> SCONN288_H44441003_PIP-SCONN,HA    I12 @BASEBOARD_FAB2_LIB.BASEBOARD_FAB2(SCH_1):PAGE52

M_E_DQ<36> @BASEBOARD_FAB2_LIB.BASEBOARD_FAB2(SCH_1):M_E_DQ(36)
  U5D1 DL42 DDR4_DQ<36> SKX_EXT_B_BGA1-IC,TBD   I172 @BASEBOARD_FAB2_LIB.BASEBOARD_FAB2(SCH_1):PAGE27
  J4A2  240 DQ<37> SCONN288_H44441004_PIP-SCONN,HA   I111 @BASEBOARD_FAB2_LIB.BASEBOARD_FAB2(SCH_1):PAGE51
  J6L2   95 DQ<36> SCONN288_H44441003_PIP-SCONN,HA    I12 @BASEBOARD_FAB2_LIB.BASEBOARD_FAB2(SCH_1):PAGE52

M_E_DQ<37> @BASEBOARD_FAB2_LIB.BASEBOARD_FAB2(SCH_1):M_E_DQ(37)
  U5D1 DN42 DDR4_DQ<37> SKX_EXT_B_BGA1-IC,TBD   I172 @BASEBOARD_FAB2_LIB.BASEBOARD_FAB2(SCH_1):PAGE27
  J4A2   95 DQ<36> SCONN288_H44441004_PIP-SCONN,HA   I111 @BASEBOARD_FAB2_LIB.BASEBOARD_FAB2(SCH_1):PAGE51
  J6L2  240 DQ<37> SCONN288_H44441003_PIP-SCONN,HA    I12 @BASEBOARD_FAB2_LIB.BASEBOARD_FAB2(SCH_1):PAGE52

M_E_DQ<38> @BASEBOARD_FAB2_LIB.BASEBOARD_FAB2(SCH_1):M_E_DQ(38)
  U5D1 DN40 DDR4_DQ<38> SKX_EXT_B_BGA1-IC,TBD   I172 @BASEBOARD_FAB2_LIB.BASEBOARD_FAB2(SCH_1):PAGE27
  J4A2  247 DQ<39> SCONN288_H44441004_PIP-SCONN,HA   I111 @BASEBOARD_FAB2_LIB.BASEBOARD_FAB2(SCH_1):PAGE51
  J6L2  102 DQ<38> SCONN288_H44441003_PIP-SCONN,HA    I12 @BASEBOARD_FAB2_LIB.BASEBOARD_FAB2(SCH_1):PAGE52

M_E_DQ<39> @BASEBOARD_FAB2_LIB.BASEBOARD_FAB2(SCH_1):M_E_DQ(39)
  U5D1 DU40 DDR4_DQ<39> SKX_EXT_B_BGA1-IC,TBD   I172 @BASEBOARD_FAB2_LIB.BASEBOARD_FAB2(SCH_1):PAGE27
  J4A2  102 DQ<38> SCONN288_H44441004_PIP-SCONN,HA   I111 @BASEBOARD_FAB2_LIB.BASEBOARD_FAB2(SCH_1):PAGE51
  J6L2  247 DQ<39> SCONN288_H44441003_PIP-SCONN,HA    I12 @BASEBOARD_FAB2_LIB.BASEBOARD_FAB2(SCH_1):PAGE52

M_E_DQ<3> @BASEBOARD_FAB2_LIB.BASEBOARD_FAB2(SCH_1):M_E_DQ(3)
  U5D1 CR82 DDR4_DQ<3> SKX_EXT_B_BGA1-IC,TBD   I172 @BASEBOARD_FAB2_LIB.BASEBOARD_FAB2(SCH_1):PAGE27
  J4A2   12  DQ<2> SCONN288_H44441004_PIP-SCONN,HA   I111 @BASEBOARD_FAB2_LIB.BASEBOARD_FAB2(SCH_1):PAGE51
  J6L2  157  DQ<3> SCONN288_H44441003_PIP-SCONN,HA    I12 @BASEBOARD_FAB2_LIB.BASEBOARD_FAB2(SCH_1):PAGE52

M_E_DQ<40> @BASEBOARD_FAB2_LIB.BASEBOARD_FAB2(SCH_1):M_E_DQ(40)
  U5D1 EC34 DDR4_DQ<40> SKX_EXT_B_BGA1-IC,TBD   I172 @BASEBOARD_FAB2_LIB.BASEBOARD_FAB2(SCH_1):PAGE27
  J4A2  253 DQ<41> SCONN288_H44441004_PIP-SCONN,HA   I111 @BASEBOARD_FAB2_LIB.BASEBOARD_FAB2(SCH_1):PAGE51
  J6L2  108 DQ<40> SCONN288_H44441003_PIP-SCONN,HA    I12 @BASEBOARD_FAB2_LIB.BASEBOARD_FAB2(SCH_1):PAGE52

M_E_DQ<41> @BASEBOARD_FAB2_LIB.BASEBOARD_FAB2(SCH_1):M_E_DQ(41)
  U5D1 ED33 DDR4_DQ<41> SKX_EXT_B_BGA1-IC,TBD   I172 @BASEBOARD_FAB2_LIB.BASEBOARD_FAB2(SCH_1):PAGE27
  J4A2  108 DQ<40> SCONN288_H44441004_PIP-SCONN,HA   I111 @BASEBOARD_FAB2_LIB.BASEBOARD_FAB2(SCH_1):PAGE51
  J6L2  253 DQ<41> SCONN288_H44441003_PIP-SCONN,HA    I12 @BASEBOARD_FAB2_LIB.BASEBOARD_FAB2(SCH_1):PAGE52

M_E_DQ<42> @BASEBOARD_FAB2_LIB.BASEBOARD_FAB2(SCH_1):M_E_DQ(42)
  U5D1 EA30 DDR4_DQ<42> SKX_EXT_B_BGA1-IC,TBD   I172 @BASEBOARD_FAB2_LIB.BASEBOARD_FAB2(SCH_1):PAGE27
  J4A2  260 DQ<43> SCONN288_H44441004_PIP-SCONN,HA   I111 @BASEBOARD_FAB2_LIB.BASEBOARD_FAB2(SCH_1):PAGE51
  J6L2  115 DQ<42> SCONN288_H44441003_PIP-SCONN,HA    I12 @BASEBOARD_FAB2_LIB.BASEBOARD_FAB2(SCH_1):PAGE52

M_E_DQ<43> @BASEBOARD_FAB2_LIB.BASEBOARD_FAB2(SCH_1):M_E_DQ(43)
  U5D1 EC30 DDR4_DQ<43> SKX_EXT_B_BGA1-IC,TBD   I172 @BASEBOARD_FAB2_LIB.BASEBOARD_FAB2(SCH_1):PAGE27
  J4A2  115 DQ<42> SCONN288_H44441004_PIP-SCONN,HA   I111 @BASEBOARD_FAB2_LIB.BASEBOARD_FAB2(SCH_1):PAGE51
  J6L2  260 DQ<43> SCONN288_H44441003_PIP-SCONN,HA    I12 @BASEBOARD_FAB2_LIB.BASEBOARD_FAB2(SCH_1):PAGE52

M_E_DQ<44> @BASEBOARD_FAB2_LIB.BASEBOARD_FAB2(SCH_1):M_E_DQ(44)
  U5D1 DY33 DDR4_DQ<44> SKX_EXT_B_BGA1-IC,TBD   I172 @BASEBOARD_FAB2_LIB.BASEBOARD_FAB2(SCH_1):PAGE27
  J4A2  251 DQ<45> SCONN288_H44441004_PIP-SCONN,HA   I111 @BASEBOARD_FAB2_LIB.BASEBOARD_FAB2(SCH_1):PAGE51
  J6L2  106 DQ<44> SCONN288_H44441003_PIP-SCONN,HA    I12 @BASEBOARD_FAB2_LIB.BASEBOARD_FAB2(SCH_1):PAGE52

M_E_DQ<45> @BASEBOARD_FAB2_LIB.BASEBOARD_FAB2(SCH_1):M_E_DQ(45)
  U5D1 EA34 DDR4_DQ<45> SKX_EXT_B_BGA1-IC,TBD   I172 @BASEBOARD_FAB2_LIB.BASEBOARD_FAB2(SCH_1):PAGE27
  J4A2  106 DQ<44> SCONN288_H44441004_PIP-SCONN,HA   I111 @BASEBOARD_FAB2_LIB.BASEBOARD_FAB2(SCH_1):PAGE51
  J6L2  251 DQ<45> SCONN288_H44441003_PIP-SCONN,HA    I12 @BASEBOARD_FAB2_LIB.BASEBOARD_FAB2(SCH_1):PAGE52

M_E_DQ<46> @BASEBOARD_FAB2_LIB.BASEBOARD_FAB2(SCH_1):M_E_DQ(46)
  U5D1 DY31 DDR4_DQ<46> SKX_EXT_B_BGA1-IC,TBD   I172 @BASEBOARD_FAB2_LIB.BASEBOARD_FAB2(SCH_1):PAGE27
  J4A2  258 DQ<47> SCONN288_H44441004_PIP-SCONN,HA   I111 @BASEBOARD_FAB2_LIB.BASEBOARD_FAB2(SCH_1):PAGE51
  J6L2  113 DQ<46> SCONN288_H44441003_PIP-SCONN,HA    I12 @BASEBOARD_FAB2_LIB.BASEBOARD_FAB2(SCH_1):PAGE52

M_E_DQ<47> @BASEBOARD_FAB2_LIB.BASEBOARD_FAB2(SCH_1):M_E_DQ(47)
  U5D1 ED31 DDR4_DQ<47> SKX_EXT_B_BGA1-IC,TBD   I172 @BASEBOARD_FAB2_LIB.BASEBOARD_FAB2(SCH_1):PAGE27
  J4A2  113 DQ<46> SCONN288_H44441004_PIP-SCONN,HA   I111 @BASEBOARD_FAB2_LIB.BASEBOARD_FAB2(SCH_1):PAGE51
  J6L2  258 DQ<47> SCONN288_H44441003_PIP-SCONN,HA    I12 @BASEBOARD_FAB2_LIB.BASEBOARD_FAB2(SCH_1):PAGE52

M_E_DQ<48> @BASEBOARD_FAB2_LIB.BASEBOARD_FAB2(SCH_1):M_E_DQ(48)
  U5D1 EC28 DDR4_DQ<48> SKX_EXT_B_BGA1-IC,TBD   I172 @BASEBOARD_FAB2_LIB.BASEBOARD_FAB2(SCH_1):PAGE27
  J4A2  264 DQ<49> SCONN288_H44441004_PIP-SCONN,HA   I111 @BASEBOARD_FAB2_LIB.BASEBOARD_FAB2(SCH_1):PAGE51
  J6L2  119 DQ<48> SCONN288_H44441003_PIP-SCONN,HA    I12 @BASEBOARD_FAB2_LIB.BASEBOARD_FAB2(SCH_1):PAGE52

M_E_DQ<49> @BASEBOARD_FAB2_LIB.BASEBOARD_FAB2(SCH_1):M_E_DQ(49)
  U5D1 ED27 DDR4_DQ<49> SKX_EXT_B_BGA1-IC,TBD   I172 @BASEBOARD_FAB2_LIB.BASEBOARD_FAB2(SCH_1):PAGE27
  J4A2  119 DQ<48> SCONN288_H44441004_PIP-SCONN,HA   I111 @BASEBOARD_FAB2_LIB.BASEBOARD_FAB2(SCH_1):PAGE51
  J6L2  264 DQ<49> SCONN288_H44441003_PIP-SCONN,HA    I12 @BASEBOARD_FAB2_LIB.BASEBOARD_FAB2(SCH_1):PAGE52

M_E_DQ<4> @BASEBOARD_FAB2_LIB.BASEBOARD_FAB2(SCH_1):M_E_DQ(4)
  U5D1 CK79 DDR4_DQ<4> SKX_EXT_B_BGA1-IC,TBD   I172 @BASEBOARD_FAB2_LIB.BASEBOARD_FAB2(SCH_1):PAGE27
  J4A2  148  DQ<5> SCONN288_H44441004_PIP-SCONN,HA   I111 @BASEBOARD_FAB2_LIB.BASEBOARD_FAB2(SCH_1):PAGE51
  J6L2    3  DQ<4> SCONN288_H44441003_PIP-SCONN,HA    I12 @BASEBOARD_FAB2_LIB.BASEBOARD_FAB2(SCH_1):PAGE52

M_E_DQ<50> @BASEBOARD_FAB2_LIB.BASEBOARD_FAB2(SCH_1):M_E_DQ(50)
  U5D1 EA24 DDR4_DQ<50> SKX_EXT_B_BGA1-IC,TBD   I172 @BASEBOARD_FAB2_LIB.BASEBOARD_FAB2(SCH_1):PAGE27
  J4A2  271 DQ<51> SCONN288_H44441004_PIP-SCONN,HA   I111 @BASEBOARD_FAB2_LIB.BASEBOARD_FAB2(SCH_1):PAGE51
  J6L2  126 DQ<50> SCONN288_H44441003_PIP-SCONN,HA    I12 @BASEBOARD_FAB2_LIB.BASEBOARD_FAB2(SCH_1):PAGE52

M_E_DQ<51> @BASEBOARD_FAB2_LIB.BASEBOARD_FAB2(SCH_1):M_E_DQ(51)
  U5D1 EC24 DDR4_DQ<51> SKX_EXT_B_BGA1-IC,TBD   I172 @BASEBOARD_FAB2_LIB.BASEBOARD_FAB2(SCH_1):PAGE27
  J4A2  126 DQ<50> SCONN288_H44441004_PIP-SCONN,HA   I111 @BASEBOARD_FAB2_LIB.BASEBOARD_FAB2(SCH_1):PAGE51
  J6L2  271 DQ<51> SCONN288_H44441003_PIP-SCONN,HA    I12 @BASEBOARD_FAB2_LIB.BASEBOARD_FAB2(SCH_1):PAGE52

M_E_DQ<52> @BASEBOARD_FAB2_LIB.BASEBOARD_FAB2(SCH_1):M_E_DQ(52)
  U5D1 DY27 DDR4_DQ<52> SKX_EXT_B_BGA1-IC,TBD   I172 @BASEBOARD_FAB2_LIB.BASEBOARD_FAB2(SCH_1):PAGE27
  J4A2  262 DQ<53> SCONN288_H44441004_PIP-SCONN,HA   I111 @BASEBOARD_FAB2_LIB.BASEBOARD_FAB2(SCH_1):PAGE51
  J6L2  117 DQ<52> SCONN288_H44441003_PIP-SCONN,HA    I12 @BASEBOARD_FAB2_LIB.BASEBOARD_FAB2(SCH_1):PAGE52

M_E_DQ<53> @BASEBOARD_FAB2_LIB.BASEBOARD_FAB2(SCH_1):M_E_DQ(53)
  U5D1 EA28 DDR4_DQ<53> SKX_EXT_B_BGA1-IC,TBD   I172 @BASEBOARD_FAB2_LIB.BASEBOARD_FAB2(SCH_1):PAGE27
  J4A2  117 DQ<52> SCONN288_H44441004_PIP-SCONN,HA   I111 @BASEBOARD_FAB2_LIB.BASEBOARD_FAB2(SCH_1):PAGE51
  J6L2  262 DQ<53> SCONN288_H44441003_PIP-SCONN,HA    I12 @BASEBOARD_FAB2_LIB.BASEBOARD_FAB2(SCH_1):PAGE52

M_E_DQ<54> @BASEBOARD_FAB2_LIB.BASEBOARD_FAB2(SCH_1):M_E_DQ(54)
  U5D1 DY25 DDR4_DQ<54> SKX_EXT_B_BGA1-IC,TBD   I172 @BASEBOARD_FAB2_LIB.BASEBOARD_FAB2(SCH_1):PAGE27
  J4A2  269 DQ<55> SCONN288_H44441004_PIP-SCONN,HA   I111 @BASEBOARD_FAB2_LIB.BASEBOARD_FAB2(SCH_1):PAGE51
  J6L2  124 DQ<54> SCONN288_H44441003_PIP-SCONN,HA    I12 @BASEBOARD_FAB2_LIB.BASEBOARD_FAB2(SCH_1):PAGE52

M_E_DQ<55> @BASEBOARD_FAB2_LIB.BASEBOARD_FAB2(SCH_1):M_E_DQ(55)
  U5D1 ED25 DDR4_DQ<55> SKX_EXT_B_BGA1-IC,TBD   I172 @BASEBOARD_FAB2_LIB.BASEBOARD_FAB2(SCH_1):PAGE27
  J4A2  124 DQ<54> SCONN288_H44441004_PIP-SCONN,HA   I111 @BASEBOARD_FAB2_LIB.BASEBOARD_FAB2(SCH_1):PAGE51
  J6L2  269 DQ<55> SCONN288_H44441003_PIP-SCONN,HA    I12 @BASEBOARD_FAB2_LIB.BASEBOARD_FAB2(SCH_1):PAGE52

M_E_DQ<56> @BASEBOARD_FAB2_LIB.BASEBOARD_FAB2(SCH_1):M_E_DQ(56)
  U5D1 DF27 DDR4_DQ<56> SKX_EXT_B_BGA1-IC,TBD   I172 @BASEBOARD_FAB2_LIB.BASEBOARD_FAB2(SCH_1):PAGE27
  J4A2  275 DQ<57> SCONN288_H44441004_PIP-SCONN,HA   I111 @BASEBOARD_FAB2_LIB.BASEBOARD_FAB2(SCH_1):PAGE51
  J6L2  130 DQ<56> SCONN288_H44441003_PIP-SCONN,HA    I12 @BASEBOARD_FAB2_LIB.BASEBOARD_FAB2(SCH_1):PAGE52

M_E_DQ<57> @BASEBOARD_FAB2_LIB.BASEBOARD_FAB2(SCH_1):M_E_DQ(57)
  U5D1 DK27 DDR4_DQ<57> SKX_EXT_B_BGA1-IC,TBD   I172 @BASEBOARD_FAB2_LIB.BASEBOARD_FAB2(SCH_1):PAGE27
  J4A2  130 DQ<56> SCONN288_H44441004_PIP-SCONN,HA   I111 @BASEBOARD_FAB2_LIB.BASEBOARD_FAB2(SCH_1):PAGE51
  J6L2  275 DQ<57> SCONN288_H44441003_PIP-SCONN,HA    I12 @BASEBOARD_FAB2_LIB.BASEBOARD_FAB2(SCH_1):PAGE52

M_E_DQ<58> @BASEBOARD_FAB2_LIB.BASEBOARD_FAB2(SCH_1):M_E_DQ(58)
  U5D1 DD25 DDR4_DQ<58> SKX_EXT_B_BGA1-IC,TBD   I172 @BASEBOARD_FAB2_LIB.BASEBOARD_FAB2(SCH_1):PAGE27
  J4A2  282 DQ<59> SCONN288_H44441004_PIP-SCONN,HA   I111 @BASEBOARD_FAB2_LIB.BASEBOARD_FAB2(SCH_1):PAGE51
  J6L2  137 DQ<58> SCONN288_H44441003_PIP-SCONN,HA    I12 @BASEBOARD_FAB2_LIB.BASEBOARD_FAB2(SCH_1):PAGE52

M_E_DQ<59> @BASEBOARD_FAB2_LIB.BASEBOARD_FAB2(SCH_1):M_E_DQ(59)
  U5D1 DJ24 DDR4_DQ<59> SKX_EXT_B_BGA1-IC,TBD   I172 @BASEBOARD_FAB2_LIB.BASEBOARD_FAB2(SCH_1):PAGE27
  J4A2  137 DQ<58> SCONN288_H44441004_PIP-SCONN,HA   I111 @BASEBOARD_FAB2_LIB.BASEBOARD_FAB2(SCH_1):PAGE51
  J6L2  282 DQ<59> SCONN288_H44441003_PIP-SCONN,HA    I12 @BASEBOARD_FAB2_LIB.BASEBOARD_FAB2(SCH_1):PAGE52

M_E_DQ<5> @BASEBOARD_FAB2_LIB.BASEBOARD_FAB2(SCH_1):M_E_DQ(5)
  U5D1 CJ80 DDR4_DQ<5> SKX_EXT_B_BGA1-IC,TBD   I172 @BASEBOARD_FAB2_LIB.BASEBOARD_FAB2(SCH_1):PAGE27
  J4A2    3  DQ<4> SCONN288_H44441004_PIP-SCONN,HA   I111 @BASEBOARD_FAB2_LIB.BASEBOARD_FAB2(SCH_1):PAGE51
  J6L2  148  DQ<5> SCONN288_H44441003_PIP-SCONN,HA    I12 @BASEBOARD_FAB2_LIB.BASEBOARD_FAB2(SCH_1):PAGE52

M_E_DQ<60> @BASEBOARD_FAB2_LIB.BASEBOARD_FAB2(SCH_1):M_E_DQ(60)
  U5D1 DG28 DDR4_DQ<60> SKX_EXT_B_BGA1-IC,TBD   I172 @BASEBOARD_FAB2_LIB.BASEBOARD_FAB2(SCH_1):PAGE27
  J4A2  273 DQ<61> SCONN288_H44441004_PIP-SCONN,HA   I111 @BASEBOARD_FAB2_LIB.BASEBOARD_FAB2(SCH_1):PAGE51
  J6L2  128 DQ<60> SCONN288_H44441003_PIP-SCONN,HA    I12 @BASEBOARD_FAB2_LIB.BASEBOARD_FAB2(SCH_1):PAGE52

M_E_DQ<61> @BASEBOARD_FAB2_LIB.BASEBOARD_FAB2(SCH_1):M_E_DQ(61)
  U5D1 DJ28 DDR4_DQ<61> SKX_EXT_B_BGA1-IC,TBD   I172 @BASEBOARD_FAB2_LIB.BASEBOARD_FAB2(SCH_1):PAGE27
  J4A2  128 DQ<60> SCONN288_H44441004_PIP-SCONN,HA   I111 @BASEBOARD_FAB2_LIB.BASEBOARD_FAB2(SCH_1):PAGE51
  J6L2  273 DQ<61> SCONN288_H44441003_PIP-SCONN,HA    I12 @BASEBOARD_FAB2_LIB.BASEBOARD_FAB2(SCH_1):PAGE52

M_E_DQ<62> @BASEBOARD_FAB2_LIB.BASEBOARD_FAB2(SCH_1):M_E_DQ(62)
  U5D1 DF25 DDR4_DQ<62> SKX_EXT_B_BGA1-IC,TBD   I172 @BASEBOARD_FAB2_LIB.BASEBOARD_FAB2(SCH_1):PAGE27
  J4A2  280 DQ<63> SCONN288_H44441004_PIP-SCONN,HA   I111 @BASEBOARD_FAB2_LIB.BASEBOARD_FAB2(SCH_1):PAGE51
  J6L2  135 DQ<62> SCONN288_H44441003_PIP-SCONN,HA    I12 @BASEBOARD_FAB2_LIB.BASEBOARD_FAB2(SCH_1):PAGE52

M_E_DQ<63> @BASEBOARD_FAB2_LIB.BASEBOARD_FAB2(SCH_1):M_E_DQ(63)
  U5D1 DK25 DDR4_DQ<63> SKX_EXT_B_BGA1-IC,TBD   I172 @BASEBOARD_FAB2_LIB.BASEBOARD_FAB2(SCH_1):PAGE27
  J4A2  135 DQ<62> SCONN288_H44441004_PIP-SCONN,HA   I111 @BASEBOARD_FAB2_LIB.BASEBOARD_FAB2(SCH_1):PAGE51
  J6L2  280 DQ<63> SCONN288_H44441003_PIP-SCONN,HA    I12 @BASEBOARD_FAB2_LIB.BASEBOARD_FAB2(SCH_1):PAGE52

M_E_DQ<6> @BASEBOARD_FAB2_LIB.BASEBOARD_FAB2(SCH_1):M_E_DQ(6)
  U5D1 CR80 DDR4_DQ<6> SKX_EXT_B_BGA1-IC,TBD   I172 @BASEBOARD_FAB2_LIB.BASEBOARD_FAB2(SCH_1):PAGE27
  J4A2  155  DQ<7> SCONN288_H44441004_PIP-SCONN,HA   I111 @BASEBOARD_FAB2_LIB.BASEBOARD_FAB2(SCH_1):PAGE51
  J6L2   10  DQ<6> SCONN288_H44441003_PIP-SCONN,HA    I12 @BASEBOARD_FAB2_LIB.BASEBOARD_FAB2(SCH_1):PAGE52

M_E_DQ<7> @BASEBOARD_FAB2_LIB.BASEBOARD_FAB2(SCH_1):M_E_DQ(7)
  U5D1 CN82 DDR4_DQ<7> SKX_EXT_B_BGA1-IC,TBD   I172 @BASEBOARD_FAB2_LIB.BASEBOARD_FAB2(SCH_1):PAGE27
  J4A2   10  DQ<6> SCONN288_H44441004_PIP-SCONN,HA   I111 @BASEBOARD_FAB2_LIB.BASEBOARD_FAB2(SCH_1):PAGE51
  J6L2  155  DQ<7> SCONN288_H44441003_PIP-SCONN,HA    I12 @BASEBOARD_FAB2_LIB.BASEBOARD_FAB2(SCH_1):PAGE52

M_E_DQ<8> @BASEBOARD_FAB2_LIB.BASEBOARD_FAB2(SCH_1):M_E_DQ(8)
  U5D1 DB79 DDR4_DQ<8> SKX_EXT_B_BGA1-IC,TBD   I172 @BASEBOARD_FAB2_LIB.BASEBOARD_FAB2(SCH_1):PAGE27
  J4A2  161  DQ<9> SCONN288_H44441004_PIP-SCONN,HA   I111 @BASEBOARD_FAB2_LIB.BASEBOARD_FAB2(SCH_1):PAGE51
  J6L2   16  DQ<8> SCONN288_H44441003_PIP-SCONN,HA    I12 @BASEBOARD_FAB2_LIB.BASEBOARD_FAB2(SCH_1):PAGE52

M_E_DQ<9> @BASEBOARD_FAB2_LIB.BASEBOARD_FAB2(SCH_1):M_E_DQ(9)
  U5D1 CY81 DDR4_DQ<9> SKX_EXT_B_BGA1-IC,TBD   I172 @BASEBOARD_FAB2_LIB.BASEBOARD_FAB2(SCH_1):PAGE27
  J4A2   16  DQ<8> SCONN288_H44441004_PIP-SCONN,HA   I111 @BASEBOARD_FAB2_LIB.BASEBOARD_FAB2(SCH_1):PAGE51
  J6L2  161  DQ<9> SCONN288_H44441003_PIP-SCONN,HA    I12 @BASEBOARD_FAB2_LIB.BASEBOARD_FAB2(SCH_1):PAGE52

M_E_DQS_DN<0> @BASEBOARD_FAB2_LIB.BASEBOARD_FAB2(SCH_1):M_E_DQS_DN(0)
  U5D1 CL82 DDR4_DQS_DN<0> SKX_EXT_B_BGA1-IC,TBD   I172 @BASEBOARD_FAB2_LIB.BASEBOARD_FAB2(SCH_1):PAGE27
  J4A2  152  DQS0N SCONN288_H44441004_PIP-SCONN,HA    I66 @BASEBOARD_FAB2_LIB.BASEBOARD_FAB2(SCH_1):PAGE51
  J6L2  152  DQS0N SCONN288_H44441003_PIP-SCONN,HA   I100 @BASEBOARD_FAB2_LIB.BASEBOARD_FAB2(SCH_1):PAGE52

M_E_DQS_DN<10> @BASEBOARD_FAB2_LIB.BASEBOARD_FAB2(SCH_1):M_E_DQS_DN(10)
  U5D1 DC80 DDR4_DQS_DN<10> SKX_EXT_B_BGA1-IC,TBD   I172 @BASEBOARD_FAB2_LIB.BASEBOARD_FAB2(SCH_1):PAGE27
  J4A2   19 DQS10N SCONN288_H44441004_PIP-SCONN,HA    I66 @BASEBOARD_FAB2_LIB.BASEBOARD_FAB2(SCH_1):PAGE51
  J6L2   19 DQS10N SCONN288_H44441003_PIP-SCONN,HA   I100 @BASEBOARD_FAB2_LIB.BASEBOARD_FAB2(SCH_1):PAGE52

M_E_DQS_DN<11> @BASEBOARD_FAB2_LIB.BASEBOARD_FAB2(SCH_1):M_E_DQS_DN(11)
  U5D1 DY79 DDR4_DQS_DN<11> SKX_EXT_B_BGA1-IC,TBD   I172 @BASEBOARD_FAB2_LIB.BASEBOARD_FAB2(SCH_1):PAGE27
  J4A2   30 DQS11N SCONN288_H44441004_PIP-SCONN,HA    I66 @BASEBOARD_FAB2_LIB.BASEBOARD_FAB2(SCH_1):PAGE51
  J6L2   30 DQS11N SCONN288_H44441003_PIP-SCONN,HA   I100 @BASEBOARD_FAB2_LIB.BASEBOARD_FAB2(SCH_1):PAGE52

M_E_DQS_DN<12> @BASEBOARD_FAB2_LIB.BASEBOARD_FAB2(SCH_1):M_E_DQS_DN(12)
  U5D1 EB73 DDR4_DQS_DN<12> SKX_EXT_B_BGA1-IC,TBD   I172 @BASEBOARD_FAB2_LIB.BASEBOARD_FAB2(SCH_1):PAGE27
  J4A2   41 DQS12N SCONN288_H44441004_PIP-SCONN,HA    I66 @BASEBOARD_FAB2_LIB.BASEBOARD_FAB2(SCH_1):PAGE51
  J6L2   41 DQS12N SCONN288_H44441003_PIP-SCONN,HA   I100 @BASEBOARD_FAB2_LIB.BASEBOARD_FAB2(SCH_1):PAGE52

M_E_DQS_DN<13> @BASEBOARD_FAB2_LIB.BASEBOARD_FAB2(SCH_1):M_E_DQS_DN(13)
  U5D1 DP41 DDR4_DQS_DN<13> SKX_EXT_B_BGA1-IC,TBD   I172 @BASEBOARD_FAB2_LIB.BASEBOARD_FAB2(SCH_1):PAGE27
  J4A2  100 DQS13N SCONN288_H44441004_PIP-SCONN,HA    I66 @BASEBOARD_FAB2_LIB.BASEBOARD_FAB2(SCH_1):PAGE51
  J6L2  100 DQS13N SCONN288_H44441003_PIP-SCONN,HA   I100 @BASEBOARD_FAB2_LIB.BASEBOARD_FAB2(SCH_1):PAGE52

M_E_DQS_DN<14> @BASEBOARD_FAB2_LIB.BASEBOARD_FAB2(SCH_1):M_E_DQS_DN(14)
  U5D1 EA32 DDR4_DQS_DN<14> SKX_EXT_B_BGA1-IC,TBD   I172 @BASEBOARD_FAB2_LIB.BASEBOARD_FAB2(SCH_1):PAGE27
  J4A2  111 DQS14N SCONN288_H44441004_PIP-SCONN,HA    I66 @BASEBOARD_FAB2_LIB.BASEBOARD_FAB2(SCH_1):PAGE51
  J6L2  111 DQS14N SCONN288_H44441003_PIP-SCONN,HA   I100 @BASEBOARD_FAB2_LIB.BASEBOARD_FAB2(SCH_1):PAGE52

M_E_DQS_DN<15> @BASEBOARD_FAB2_LIB.BASEBOARD_FAB2(SCH_1):M_E_DQS_DN(15)
  U5D1 EA26 DDR4_DQS_DN<15> SKX_EXT_B_BGA1-IC,TBD   I172 @BASEBOARD_FAB2_LIB.BASEBOARD_FAB2(SCH_1):PAGE27
  J4A2  122 DQS15N SCONN288_H44441004_PIP-SCONN,HA    I66 @BASEBOARD_FAB2_LIB.BASEBOARD_FAB2(SCH_1):PAGE51
  J6L2  122 DQS15N SCONN288_H44441003_PIP-SCONN,HA   I100 @BASEBOARD_FAB2_LIB.BASEBOARD_FAB2(SCH_1):PAGE52

M_E_DQS_DN<16> @BASEBOARD_FAB2_LIB.BASEBOARD_FAB2(SCH_1):M_E_DQS_DN(16)
  U5D1 DG26 DDR4_DQS_DN<16> SKX_EXT_B_BGA1-IC,TBD   I172 @BASEBOARD_FAB2_LIB.BASEBOARD_FAB2(SCH_1):PAGE27
  J4A2  133 DQS16N SCONN288_H44441004_PIP-SCONN,HA    I66 @BASEBOARD_FAB2_LIB.BASEBOARD_FAB2(SCH_1):PAGE51
  J6L2  133 DQS16N SCONN288_H44441003_PIP-SCONN,HA   I100 @BASEBOARD_FAB2_LIB.BASEBOARD_FAB2(SCH_1):PAGE52

M_E_DQS_DN<17> @BASEBOARD_FAB2_LIB.BASEBOARD_FAB2(SCH_1):M_E_DQS_DN(17)
  U5D1 DV67 DDR4_DQS_DN<17> SKX_EXT_B_BGA1-IC,TBD   I172 @BASEBOARD_FAB2_LIB.BASEBOARD_FAB2(SCH_1):PAGE27
  J4A2   52 DQS17N SCONN288_H44441004_PIP-SCONN,HA    I66 @BASEBOARD_FAB2_LIB.BASEBOARD_FAB2(SCH_1):PAGE51
  J6L2   52 DQS17N SCONN288_H44441003_PIP-SCONN,HA   I100 @BASEBOARD_FAB2_LIB.BASEBOARD_FAB2(SCH_1):PAGE52

M_E_DQS_DN<1> @BASEBOARD_FAB2_LIB.BASEBOARD_FAB2(SCH_1):M_E_DQS_DN(1)
  U5D1 DA82 DDR4_DQS_DN<1> SKX_EXT_B_BGA1-IC,TBD   I172 @BASEBOARD_FAB2_LIB.BASEBOARD_FAB2(SCH_1):PAGE27
  J4A2  163  DQS1N SCONN288_H44441004_PIP-SCONN,HA    I66 @BASEBOARD_FAB2_LIB.BASEBOARD_FAB2(SCH_1):PAGE51
  J6L2  163  DQS1N SCONN288_H44441003_PIP-SCONN,HA   I100 @BASEBOARD_FAB2_LIB.BASEBOARD_FAB2(SCH_1):PAGE52

M_E_DQS_DN<2> @BASEBOARD_FAB2_LIB.BASEBOARD_FAB2(SCH_1):M_E_DQS_DN(2)
  U5D1 ED79 DDR4_DQS_DN<2> SKX_EXT_B_BGA1-IC,TBD   I172 @BASEBOARD_FAB2_LIB.BASEBOARD_FAB2(SCH_1):PAGE27
  J4A2  174  DQS2N SCONN288_H44441004_PIP-SCONN,HA    I66 @BASEBOARD_FAB2_LIB.BASEBOARD_FAB2(SCH_1):PAGE51
  J6L2  174  DQS2N SCONN288_H44441003_PIP-SCONN,HA   I100 @BASEBOARD_FAB2_LIB.BASEBOARD_FAB2(SCH_1):PAGE52

M_E_DQS_DN<3> @BASEBOARD_FAB2_LIB.BASEBOARD_FAB2(SCH_1):M_E_DQS_DN(3)
  U5D1 EF73 DDR4_DQS_DN<3> SKX_EXT_B_BGA1-IC,TBD   I172 @BASEBOARD_FAB2_LIB.BASEBOARD_FAB2(SCH_1):PAGE27
  J4A2  185  DQS3N SCONN288_H44441004_PIP-SCONN,HA    I66 @BASEBOARD_FAB2_LIB.BASEBOARD_FAB2(SCH_1):PAGE51
  J6L2  185  DQS3N SCONN288_H44441003_PIP-SCONN,HA   I100 @BASEBOARD_FAB2_LIB.BASEBOARD_FAB2(SCH_1):PAGE52

M_E_DQS_DN<4> @BASEBOARD_FAB2_LIB.BASEBOARD_FAB2(SCH_1):M_E_DQS_DN(4)
  U5D1 DV41 DDR4_DQS_DN<4> SKX_EXT_B_BGA1-IC,TBD   I172 @BASEBOARD_FAB2_LIB.BASEBOARD_FAB2(SCH_1):PAGE27
  J4A2  244  DQS4N SCONN288_H44441004_PIP-SCONN,HA    I66 @BASEBOARD_FAB2_LIB.BASEBOARD_FAB2(SCH_1):PAGE51
  J6L2  244  DQS4N SCONN288_H44441003_PIP-SCONN,HA   I100 @BASEBOARD_FAB2_LIB.BASEBOARD_FAB2(SCH_1):PAGE52

M_E_DQS_DN<5> @BASEBOARD_FAB2_LIB.BASEBOARD_FAB2(SCH_1):M_E_DQS_DN(5)
  U5D1 EE32 DDR4_DQS_DN<5> SKX_EXT_B_BGA1-IC,TBD   I172 @BASEBOARD_FAB2_LIB.BASEBOARD_FAB2(SCH_1):PAGE27
  J4A2  255  DQS5N SCONN288_H44441004_PIP-SCONN,HA    I66 @BASEBOARD_FAB2_LIB.BASEBOARD_FAB2(SCH_1):PAGE51
  J6L2  255  DQS5N SCONN288_H44441003_PIP-SCONN,HA   I100 @BASEBOARD_FAB2_LIB.BASEBOARD_FAB2(SCH_1):PAGE52

M_E_DQS_DN<6> @BASEBOARD_FAB2_LIB.BASEBOARD_FAB2(SCH_1):M_E_DQS_DN(6)
  U5D1 EE26 DDR4_DQS_DN<6> SKX_EXT_B_BGA1-IC,TBD   I172 @BASEBOARD_FAB2_LIB.BASEBOARD_FAB2(SCH_1):PAGE27
  J4A2  266  DQS6N SCONN288_H44441004_PIP-SCONN,HA    I66 @BASEBOARD_FAB2_LIB.BASEBOARD_FAB2(SCH_1):PAGE51
  J6L2  266  DQS6N SCONN288_H44441003_PIP-SCONN,HA   I100 @BASEBOARD_FAB2_LIB.BASEBOARD_FAB2(SCH_1):PAGE52

M_E_DQS_DN<7> @BASEBOARD_FAB2_LIB.BASEBOARD_FAB2(SCH_1):M_E_DQS_DN(7)
  U5D1 DL26 DDR4_DQS_DN<7> SKX_EXT_B_BGA1-IC,TBD   I172 @BASEBOARD_FAB2_LIB.BASEBOARD_FAB2(SCH_1):PAGE27
  J4A2  277  DQS7N SCONN288_H44441004_PIP-SCONN,HA    I66 @BASEBOARD_FAB2_LIB.BASEBOARD_FAB2(SCH_1):PAGE51
  J6L2  277  DQS7N SCONN288_H44441003_PIP-SCONN,HA   I100 @BASEBOARD_FAB2_LIB.BASEBOARD_FAB2(SCH_1):PAGE52

M_E_DQS_DN<8> @BASEBOARD_FAB2_LIB.BASEBOARD_FAB2(SCH_1):M_E_DQS_DN(8)
  U5D1 EB67 DDR4_DQS_DN<8> SKX_EXT_B_BGA1-IC,TBD   I172 @BASEBOARD_FAB2_LIB.BASEBOARD_FAB2(SCH_1):PAGE27
  J4A2  196  DQS8N SCONN288_H44441004_PIP-SCONN,HA    I66 @BASEBOARD_FAB2_LIB.BASEBOARD_FAB2(SCH_1):PAGE51
  J6L2  196  DQS8N SCONN288_H44441003_PIP-SCONN,HA   I100 @BASEBOARD_FAB2_LIB.BASEBOARD_FAB2(SCH_1):PAGE52

M_E_DQS_DN<9> @BASEBOARD_FAB2_LIB.BASEBOARD_FAB2(SCH_1):M_E_DQS_DN(9)
  U5D1 CN80 DDR4_DQS_DN<9> SKX_EXT_B_BGA1-IC,TBD   I172 @BASEBOARD_FAB2_LIB.BASEBOARD_FAB2(SCH_1):PAGE27
  J4A2    8  DQS9N SCONN288_H44441004_PIP-SCONN,HA    I66 @BASEBOARD_FAB2_LIB.BASEBOARD_FAB2(SCH_1):PAGE51
  J6L2    8  DQS9N SCONN288_H44441003_PIP-SCONN,HA   I100 @BASEBOARD_FAB2_LIB.BASEBOARD_FAB2(SCH_1):PAGE52

M_E_DQS_DP<0> @BASEBOARD_FAB2_LIB.BASEBOARD_FAB2(SCH_1):M_E_DQS_DP(0)
  U5D1 CM81 DDR4_DQS_DP<0> SKX_EXT_B_BGA1-IC,TBD   I172 @BASEBOARD_FAB2_LIB.BASEBOARD_FAB2(SCH_1):PAGE27
  J4A2  153  DQS0P SCONN288_H44441004_PIP-SCONN,HA    I66 @BASEBOARD_FAB2_LIB.BASEBOARD_FAB2(SCH_1):PAGE51
  J6L2  153  DQS0P SCONN288_H44441003_PIP-SCONN,HA   I100 @BASEBOARD_FAB2_LIB.BASEBOARD_FAB2(SCH_1):PAGE52

M_E_DQS_DP<10> @BASEBOARD_FAB2_LIB.BASEBOARD_FAB2(SCH_1):M_E_DQS_DP(10)
  U5D1 DD79 DDR4_DQS_DP<10> SKX_EXT_B_BGA1-IC,TBD   I172 @BASEBOARD_FAB2_LIB.BASEBOARD_FAB2(SCH_1):PAGE27
  J4A2   18 DQS10P SCONN288_H44441004_PIP-SCONN,HA    I66 @BASEBOARD_FAB2_LIB.BASEBOARD_FAB2(SCH_1):PAGE51
  J6L2   18 DQS10P SCONN288_H44441003_PIP-SCONN,HA   I100 @BASEBOARD_FAB2_LIB.BASEBOARD_FAB2(SCH_1):PAGE52

M_E_DQS_DP<11> @BASEBOARD_FAB2_LIB.BASEBOARD_FAB2(SCH_1):M_E_DQS_DP(11)
  U5D1 DV79 DDR4_DQS_DP<11> SKX_EXT_B_BGA1-IC,TBD   I172 @BASEBOARD_FAB2_LIB.BASEBOARD_FAB2(SCH_1):PAGE27
  J4A2   29 DQS11P SCONN288_H44441004_PIP-SCONN,HA    I66 @BASEBOARD_FAB2_LIB.BASEBOARD_FAB2(SCH_1):PAGE51
  J6L2   29 DQS11P SCONN288_H44441003_PIP-SCONN,HA   I100 @BASEBOARD_FAB2_LIB.BASEBOARD_FAB2(SCH_1):PAGE52

M_E_DQS_DP<12> @BASEBOARD_FAB2_LIB.BASEBOARD_FAB2(SCH_1):M_E_DQS_DP(12)
  U5D1 DY73 DDR4_DQS_DP<12> SKX_EXT_B_BGA1-IC,TBD   I172 @BASEBOARD_FAB2_LIB.BASEBOARD_FAB2(SCH_1):PAGE27
  J4A2   40 DQS12P SCONN288_H44441004_PIP-SCONN,HA    I66 @BASEBOARD_FAB2_LIB.BASEBOARD_FAB2(SCH_1):PAGE51
  J6L2   40 DQS12P SCONN288_H44441003_PIP-SCONN,HA   I100 @BASEBOARD_FAB2_LIB.BASEBOARD_FAB2(SCH_1):PAGE52

M_E_DQS_DP<13> @BASEBOARD_FAB2_LIB.BASEBOARD_FAB2(SCH_1):M_E_DQS_DP(13)
  U5D1 DM41 DDR4_DQS_DP<13> SKX_EXT_B_BGA1-IC,TBD   I172 @BASEBOARD_FAB2_LIB.BASEBOARD_FAB2(SCH_1):PAGE27
  J4A2   99 DQS13P SCONN288_H44441004_PIP-SCONN,HA    I66 @BASEBOARD_FAB2_LIB.BASEBOARD_FAB2(SCH_1):PAGE51
  J6L2   99 DQS13P SCONN288_H44441003_PIP-SCONN,HA   I100 @BASEBOARD_FAB2_LIB.BASEBOARD_FAB2(SCH_1):PAGE52

M_E_DQS_DP<14> @BASEBOARD_FAB2_LIB.BASEBOARD_FAB2(SCH_1):M_E_DQS_DP(14)
  U5D1 DW32 DDR4_DQS_DP<14> SKX_EXT_B_BGA1-IC,TBD   I172 @BASEBOARD_FAB2_LIB.BASEBOARD_FAB2(SCH_1):PAGE27
  J4A2  110 DQS14P SCONN288_H44441004_PIP-SCONN,HA    I66 @BASEBOARD_FAB2_LIB.BASEBOARD_FAB2(SCH_1):PAGE51
  J6L2  110 DQS14P SCONN288_H44441003_PIP-SCONN,HA   I100 @BASEBOARD_FAB2_LIB.BASEBOARD_FAB2(SCH_1):PAGE52

M_E_DQS_DP<15> @BASEBOARD_FAB2_LIB.BASEBOARD_FAB2(SCH_1):M_E_DQS_DP(15)
  U5D1 DW26 DDR4_DQS_DP<15> SKX_EXT_B_BGA1-IC,TBD   I172 @BASEBOARD_FAB2_LIB.BASEBOARD_FAB2(SCH_1):PAGE27
  J4A2  121 DQS15P SCONN288_H44441004_PIP-SCONN,HA    I66 @BASEBOARD_FAB2_LIB.BASEBOARD_FAB2(SCH_1):PAGE51
  J6L2  121 DQS15P SCONN288_H44441003_PIP-SCONN,HA   I100 @BASEBOARD_FAB2_LIB.BASEBOARD_FAB2(SCH_1):PAGE52

M_E_DQS_DP<16> @BASEBOARD_FAB2_LIB.BASEBOARD_FAB2(SCH_1):M_E_DQS_DP(16)
  U5D1 DE26 DDR4_DQS_DP<16> SKX_EXT_B_BGA1-IC,TBD   I172 @BASEBOARD_FAB2_LIB.BASEBOARD_FAB2(SCH_1):PAGE27
  J4A2  132 DQS16P SCONN288_H44441004_PIP-SCONN,HA    I66 @BASEBOARD_FAB2_LIB.BASEBOARD_FAB2(SCH_1):PAGE51
  J6L2  132 DQS16P SCONN288_H44441003_PIP-SCONN,HA   I100 @BASEBOARD_FAB2_LIB.BASEBOARD_FAB2(SCH_1):PAGE52

M_E_DQS_DP<17> @BASEBOARD_FAB2_LIB.BASEBOARD_FAB2(SCH_1):M_E_DQS_DP(17)
  U5D1 DT67 DDR4_DQS_DP<17> SKX_EXT_B_BGA1-IC,TBD   I172 @BASEBOARD_FAB2_LIB.BASEBOARD_FAB2(SCH_1):PAGE27
  J4A2   51 DQS17P SCONN288_H44441004_PIP-SCONN,HA    I66 @BASEBOARD_FAB2_LIB.BASEBOARD_FAB2(SCH_1):PAGE51
  J6L2   51 DQS17P SCONN288_H44441003_PIP-SCONN,HA   I100 @BASEBOARD_FAB2_LIB.BASEBOARD_FAB2(SCH_1):PAGE52

M_E_DQS_DP<1> @BASEBOARD_FAB2_LIB.BASEBOARD_FAB2(SCH_1):M_E_DQS_DP(1)
  U5D1 DB81 DDR4_DQS_DP<1> SKX_EXT_B_BGA1-IC,TBD   I172 @BASEBOARD_FAB2_LIB.BASEBOARD_FAB2(SCH_1):PAGE27
  J4A2  164  DQS1P SCONN288_H44441004_PIP-SCONN,HA    I66 @BASEBOARD_FAB2_LIB.BASEBOARD_FAB2(SCH_1):PAGE51
  J6L2  164  DQS1P SCONN288_H44441003_PIP-SCONN,HA   I100 @BASEBOARD_FAB2_LIB.BASEBOARD_FAB2(SCH_1):PAGE52

M_E_DQS_DP<2> @BASEBOARD_FAB2_LIB.BASEBOARD_FAB2(SCH_1):M_E_DQS_DP(2)
  U5D1 EB79 DDR4_DQS_DP<2> SKX_EXT_B_BGA1-IC,TBD   I172 @BASEBOARD_FAB2_LIB.BASEBOARD_FAB2(SCH_1):PAGE27
  J4A2  175  DQS2P SCONN288_H44441004_PIP-SCONN,HA    I66 @BASEBOARD_FAB2_LIB.BASEBOARD_FAB2(SCH_1):PAGE51
  J6L2  175  DQS2P SCONN288_H44441003_PIP-SCONN,HA   I100 @BASEBOARD_FAB2_LIB.BASEBOARD_FAB2(SCH_1):PAGE52

M_E_DQS_DP<3> @BASEBOARD_FAB2_LIB.BASEBOARD_FAB2(SCH_1):M_E_DQS_DP(3)
  U5D1 ED73 DDR4_DQS_DP<3> SKX_EXT_B_BGA1-IC,TBD   I172 @BASEBOARD_FAB2_LIB.BASEBOARD_FAB2(SCH_1):PAGE27
  J4A2  186  DQS3P SCONN288_H44441004_PIP-SCONN,HA    I66 @BASEBOARD_FAB2_LIB.BASEBOARD_FAB2(SCH_1):PAGE51
  J6L2  186  DQS3P SCONN288_H44441003_PIP-SCONN,HA   I100 @BASEBOARD_FAB2_LIB.BASEBOARD_FAB2(SCH_1):PAGE52

M_E_DQS_DP<4> @BASEBOARD_FAB2_LIB.BASEBOARD_FAB2(SCH_1):M_E_DQS_DP(4)
  U5D1 DT41 DDR4_DQS_DP<4> SKX_EXT_B_BGA1-IC,TBD   I172 @BASEBOARD_FAB2_LIB.BASEBOARD_FAB2(SCH_1):PAGE27
  J4A2  245  DQS4P SCONN288_H44441004_PIP-SCONN,HA    I66 @BASEBOARD_FAB2_LIB.BASEBOARD_FAB2(SCH_1):PAGE51
  J6L2  245  DQS4P SCONN288_H44441003_PIP-SCONN,HA   I100 @BASEBOARD_FAB2_LIB.BASEBOARD_FAB2(SCH_1):PAGE52

M_E_DQS_DP<5> @BASEBOARD_FAB2_LIB.BASEBOARD_FAB2(SCH_1):M_E_DQS_DP(5)
  U5D1 EC32 DDR4_DQS_DP<5> SKX_EXT_B_BGA1-IC,TBD   I172 @BASEBOARD_FAB2_LIB.BASEBOARD_FAB2(SCH_1):PAGE27
  J4A2  256  DQS5P SCONN288_H44441004_PIP-SCONN,HA    I66 @BASEBOARD_FAB2_LIB.BASEBOARD_FAB2(SCH_1):PAGE51
  J6L2  256  DQS5P SCONN288_H44441003_PIP-SCONN,HA   I100 @BASEBOARD_FAB2_LIB.BASEBOARD_FAB2(SCH_1):PAGE52

M_E_DQS_DP<6> @BASEBOARD_FAB2_LIB.BASEBOARD_FAB2(SCH_1):M_E_DQS_DP(6)
  U5D1 EC26 DDR4_DQS_DP<6> SKX_EXT_B_BGA1-IC,TBD   I172 @BASEBOARD_FAB2_LIB.BASEBOARD_FAB2(SCH_1):PAGE27
  J4A2  267  DQS6P SCONN288_H44441004_PIP-SCONN,HA    I66 @BASEBOARD_FAB2_LIB.BASEBOARD_FAB2(SCH_1):PAGE51
  J6L2  267  DQS6P SCONN288_H44441003_PIP-SCONN,HA   I100 @BASEBOARD_FAB2_LIB.BASEBOARD_FAB2(SCH_1):PAGE52

M_E_DQS_DP<7> @BASEBOARD_FAB2_LIB.BASEBOARD_FAB2(SCH_1):M_E_DQS_DP(7)
  U5D1 DJ26 DDR4_DQS_DP<7> SKX_EXT_B_BGA1-IC,TBD   I172 @BASEBOARD_FAB2_LIB.BASEBOARD_FAB2(SCH_1):PAGE27
  J4A2  278  DQS7P SCONN288_H44441004_PIP-SCONN,HA    I66 @BASEBOARD_FAB2_LIB.BASEBOARD_FAB2(SCH_1):PAGE51
  J6L2  278  DQS7P SCONN288_H44441003_PIP-SCONN,HA   I100 @BASEBOARD_FAB2_LIB.BASEBOARD_FAB2(SCH_1):PAGE52

M_E_DQS_DP<8> @BASEBOARD_FAB2_LIB.BASEBOARD_FAB2(SCH_1):M_E_DQS_DP(8)
  U5D1 DY67 DDR4_DQS_DP<8> SKX_EXT_B_BGA1-IC,TBD   I172 @BASEBOARD_FAB2_LIB.BASEBOARD_FAB2(SCH_1):PAGE27
  J4A2  197  DQS8P SCONN288_H44441004_PIP-SCONN,HA    I66 @BASEBOARD_FAB2_LIB.BASEBOARD_FAB2(SCH_1):PAGE51
  J6L2  197  DQS8P SCONN288_H44441003_PIP-SCONN,HA   I100 @BASEBOARD_FAB2_LIB.BASEBOARD_FAB2(SCH_1):PAGE52

M_E_DQS_DP<9> @BASEBOARD_FAB2_LIB.BASEBOARD_FAB2(SCH_1):M_E_DQS_DP(9)
  U5D1 CP79 DDR4_DQS_DP<9> SKX_EXT_B_BGA1-IC,TBD   I172 @BASEBOARD_FAB2_LIB.BASEBOARD_FAB2(SCH_1):PAGE27
  J4A2    7  DQS9P SCONN288_H44441004_PIP-SCONN,HA    I66 @BASEBOARD_FAB2_LIB.BASEBOARD_FAB2(SCH_1):PAGE51
  J6L2    7  DQS9P SCONN288_H44441003_PIP-SCONN,HA   I100 @BASEBOARD_FAB2_LIB.BASEBOARD_FAB2(SCH_1):PAGE52

M_E_ECC<0> @BASEBOARD_FAB2_LIB.BASEBOARD_FAB2(SCH_1):M_E_ECC(0)
  U5D1 DY69 DDR4_ECC<0> SKX_EXT_B_BGA1-IC,TBD   I172 @BASEBOARD_FAB2_LIB.BASEBOARD_FAB2(SCH_1):PAGE27
  J4A2  194  CB<1> SCONN288_H44441004_PIP-SCONN,HA   I111 @BASEBOARD_FAB2_LIB.BASEBOARD_FAB2(SCH_1):PAGE51
  J6L2   49  CB<0> SCONN288_H44441003_PIP-SCONN,HA    I12 @BASEBOARD_FAB2_LIB.BASEBOARD_FAB2(SCH_1):PAGE52

M_E_ECC<1> @BASEBOARD_FAB2_LIB.BASEBOARD_FAB2(SCH_1):M_E_ECC(1)
  U5D1 EA68 DDR4_ECC<1> SKX_EXT_B_BGA1-IC,TBD   I172 @BASEBOARD_FAB2_LIB.BASEBOARD_FAB2(SCH_1):PAGE27
  J4A2   49  CB<0> SCONN288_H44441004_PIP-SCONN,HA   I111 @BASEBOARD_FAB2_LIB.BASEBOARD_FAB2(SCH_1):PAGE51
  J6L2  194  CB<1> SCONN288_H44441003_PIP-SCONN,HA    I12 @BASEBOARD_FAB2_LIB.BASEBOARD_FAB2(SCH_1):PAGE52

M_E_ECC<2> @BASEBOARD_FAB2_LIB.BASEBOARD_FAB2(SCH_1):M_E_ECC(2)
  U5D1 DV65 DDR4_ECC<2> SKX_EXT_B_BGA1-IC,TBD   I172 @BASEBOARD_FAB2_LIB.BASEBOARD_FAB2(SCH_1):PAGE27
  J4A2  201  CB<3> SCONN288_H44441004_PIP-SCONN,HA   I111 @BASEBOARD_FAB2_LIB.BASEBOARD_FAB2(SCH_1):PAGE51
  J6L2   56  CB<2> SCONN288_H44441003_PIP-SCONN,HA    I12 @BASEBOARD_FAB2_LIB.BASEBOARD_FAB2(SCH_1):PAGE52

M_E_ECC<3> @BASEBOARD_FAB2_LIB.BASEBOARD_FAB2(SCH_1):M_E_ECC(3)
  U5D1 DY65 DDR4_ECC<3> SKX_EXT_B_BGA1-IC,TBD   I172 @BASEBOARD_FAB2_LIB.BASEBOARD_FAB2(SCH_1):PAGE27
  J4A2   56  CB<2> SCONN288_H44441004_PIP-SCONN,HA   I111 @BASEBOARD_FAB2_LIB.BASEBOARD_FAB2(SCH_1):PAGE51
  J6L2  201  CB<3> SCONN288_H44441003_PIP-SCONN,HA    I12 @BASEBOARD_FAB2_LIB.BASEBOARD_FAB2(SCH_1):PAGE52

M_E_ECC<4> @BASEBOARD_FAB2_LIB.BASEBOARD_FAB2(SCH_1):M_E_ECC(4)
  U5D1 DU68 DDR4_ECC<4> SKX_EXT_B_BGA1-IC,TBD   I172 @BASEBOARD_FAB2_LIB.BASEBOARD_FAB2(SCH_1):PAGE27
  J4A2  192  CB<5> SCONN288_H44441004_PIP-SCONN,HA   I111 @BASEBOARD_FAB2_LIB.BASEBOARD_FAB2(SCH_1):PAGE51
  J6L2   47  CB<4> SCONN288_H44441003_PIP-SCONN,HA    I12 @BASEBOARD_FAB2_LIB.BASEBOARD_FAB2(SCH_1):PAGE52

M_E_ECC<5> @BASEBOARD_FAB2_LIB.BASEBOARD_FAB2(SCH_1):M_E_ECC(5)
  U5D1 DV69 DDR4_ECC<5> SKX_EXT_B_BGA1-IC,TBD   I172 @BASEBOARD_FAB2_LIB.BASEBOARD_FAB2(SCH_1):PAGE27
  J4A2   47  CB<4> SCONN288_H44441004_PIP-SCONN,HA   I111 @BASEBOARD_FAB2_LIB.BASEBOARD_FAB2(SCH_1):PAGE51
  J6L2  192  CB<5> SCONN288_H44441003_PIP-SCONN,HA    I12 @BASEBOARD_FAB2_LIB.BASEBOARD_FAB2(SCH_1):PAGE52

M_E_ECC<6> @BASEBOARD_FAB2_LIB.BASEBOARD_FAB2(SCH_1):M_E_ECC(6)
  U5D1 DU66 DDR4_ECC<6> SKX_EXT_B_BGA1-IC,TBD   I172 @BASEBOARD_FAB2_LIB.BASEBOARD_FAB2(SCH_1):PAGE27
  J4A2  199  CB<7> SCONN288_H44441004_PIP-SCONN,HA   I111 @BASEBOARD_FAB2_LIB.BASEBOARD_FAB2(SCH_1):PAGE51
  J6L2   54  CB<6> SCONN288_H44441003_PIP-SCONN,HA    I12 @BASEBOARD_FAB2_LIB.BASEBOARD_FAB2(SCH_1):PAGE52

M_E_ECC<7> @BASEBOARD_FAB2_LIB.BASEBOARD_FAB2(SCH_1):M_E_ECC(7)
  U5D1 EA66 DDR4_ECC<7> SKX_EXT_B_BGA1-IC,TBD   I172 @BASEBOARD_FAB2_LIB.BASEBOARD_FAB2(SCH_1):PAGE27
  J4A2   54  CB<6> SCONN288_H44441004_PIP-SCONN,HA   I111 @BASEBOARD_FAB2_LIB.BASEBOARD_FAB2(SCH_1):PAGE51
  J6L2  199  CB<7> SCONN288_H44441003_PIP-SCONN,HA    I12 @BASEBOARD_FAB2_LIB.BASEBOARD_FAB2(SCH_1):PAGE52

M_E_MA<0> @BASEBOARD_FAB2_LIB.BASEBOARD_FAB2(SCH_1):M_E_MA(0)
  U5D1 DW52 DDR4_MA<0> SKX_EXT_B_BGA1-IC,TBD   I172 @BASEBOARD_FAB2_LIB.BASEBOARD_FAB2(SCH_1):PAGE27
  J4A2   79     A0 SCONN288_H44441004_PIP-SCONN,HA   I111 @BASEBOARD_FAB2_LIB.BASEBOARD_FAB2(SCH_1):PAGE51
  J6L2   79     A0 SCONN288_H44441003_PIP-SCONN,HA    I12 @BASEBOARD_FAB2_LIB.BASEBOARD_FAB2(SCH_1):PAGE52

M_E_MA<10> @BASEBOARD_FAB2_LIB.BASEBOARD_FAB2(SCH_1):M_E_MA(10)
  U5D1 DT55 DDR4_MA<10> SKX_EXT_B_BGA1-IC,TBD   I172 @BASEBOARD_FAB2_LIB.BASEBOARD_FAB2(SCH_1):PAGE27
  J4A2  225    A10 SCONN288_H44441004_PIP-SCONN,HA   I111 @BASEBOARD_FAB2_LIB.BASEBOARD_FAB2(SCH_1):PAGE51
  J6L2  225    A10 SCONN288_H44441003_PIP-SCONN,HA    I12 @BASEBOARD_FAB2_LIB.BASEBOARD_FAB2(SCH_1):PAGE52

M_E_MA<11> @BASEBOARD_FAB2_LIB.BASEBOARD_FAB2(SCH_1):M_E_MA(11)
  U5D1 DR60 DDR4_MA<11> SKX_EXT_B_BGA1-IC,TBD   I172 @BASEBOARD_FAB2_LIB.BASEBOARD_FAB2(SCH_1):PAGE27
  J4A2  210    A11 SCONN288_H44441004_PIP-SCONN,HA   I111 @BASEBOARD_FAB2_LIB.BASEBOARD_FAB2(SCH_1):PAGE51
  J6L2  210    A11 SCONN288_H44441003_PIP-SCONN,HA    I12 @BASEBOARD_FAB2_LIB.BASEBOARD_FAB2(SCH_1):PAGE52

M_E_MA<12> @BASEBOARD_FAB2_LIB.BASEBOARD_FAB2(SCH_1):M_E_MA(12)
  U5D1 DN60 DDR4_MA<12> SKX_EXT_B_BGA1-IC,TBD   I172 @BASEBOARD_FAB2_LIB.BASEBOARD_FAB2(SCH_1):PAGE27
  J4A2   65    A12 SCONN288_H44441004_PIP-SCONN,HA   I111 @BASEBOARD_FAB2_LIB.BASEBOARD_FAB2(SCH_1):PAGE51
  J6L2   65    A12 SCONN288_H44441003_PIP-SCONN,HA    I12 @BASEBOARD_FAB2_LIB.BASEBOARD_FAB2(SCH_1):PAGE52

M_E_MA<13> @BASEBOARD_FAB2_LIB.BASEBOARD_FAB2(SCH_1):M_E_MA(13)
  U5D1 DT51 DDR4_MA<13> SKX_EXT_B_BGA1-IC,TBD   I172 @BASEBOARD_FAB2_LIB.BASEBOARD_FAB2(SCH_1):PAGE27
  J4A2  232    A13 SCONN288_H44441004_PIP-SCONN,HA   I111 @BASEBOARD_FAB2_LIB.BASEBOARD_FAB2(SCH_1):PAGE51
  J6L2  232    A13 SCONN288_H44441003_PIP-SCONN,HA    I12 @BASEBOARD_FAB2_LIB.BASEBOARD_FAB2(SCH_1):PAGE52

M_E_MA<14> @BASEBOARD_FAB2_LIB.BASEBOARD_FAB2(SCH_1):M_E_MA(14)
  U5D1 DM51 DDR4_MA<14> SKX_EXT_B_BGA1-IC,TBD   I172 @BASEBOARD_FAB2_LIB.BASEBOARD_FAB2(SCH_1):PAGE27
  J4A2  228 A14_WE_N SCONN288_H44441004_PIP-SCONN,HA   I111 @BASEBOARD_FAB2_LIB.BASEBOARD_FAB2(SCH_1):PAGE51
  J6L2  228 A14_WE_N SCONN288_H44441003_PIP-SCONN,HA    I12 @BASEBOARD_FAB2_LIB.BASEBOARD_FAB2(SCH_1):PAGE52

M_E_MA<15> @BASEBOARD_FAB2_LIB.BASEBOARD_FAB2(SCH_1):M_E_MA(15)
  U5D1 DR52 DDR4_MA<15> SKX_EXT_B_BGA1-IC,TBD   I172 @BASEBOARD_FAB2_LIB.BASEBOARD_FAB2(SCH_1):PAGE27
  J4A2   86 A15_CAS_N SCONN288_H44441004_PIP-SCONN,HA   I111 @BASEBOARD_FAB2_LIB.BASEBOARD_FAB2(SCH_1):PAGE51
  J6L2   86 A15_CAS_N SCONN288_H44441003_PIP-SCONN,HA    I12 @BASEBOARD_FAB2_LIB.BASEBOARD_FAB2(SCH_1):PAGE52

M_E_MA<16> @BASEBOARD_FAB2_LIB.BASEBOARD_FAB2(SCH_1):M_E_MA(16)
  U5D1 DN52 DDR4_MA<16> SKX_EXT_B_BGA1-IC,TBD   I172 @BASEBOARD_FAB2_LIB.BASEBOARD_FAB2(SCH_1):PAGE27
  J4A2   82 A16_RAS_N SCONN288_H44441004_PIP-SCONN,HA   I111 @BASEBOARD_FAB2_LIB.BASEBOARD_FAB2(SCH_1):PAGE51
  J6L2   82 A16_RAS_N SCONN288_H44441003_PIP-SCONN,HA    I12 @BASEBOARD_FAB2_LIB.BASEBOARD_FAB2(SCH_1):PAGE52

M_E_MA<17> @BASEBOARD_FAB2_LIB.BASEBOARD_FAB2(SCH_1):M_E_MA(17)
  U5D1 DR48 DDR4_MA<17> SKX_EXT_B_BGA1-IC,TBD   I172 @BASEBOARD_FAB2_LIB.BASEBOARD_FAB2(SCH_1):PAGE27
  J4A2  234    A17 SCONN288_H44441004_PIP-SCONN,HA   I111 @BASEBOARD_FAB2_LIB.BASEBOARD_FAB2(SCH_1):PAGE51
  J6L2  234    A17 SCONN288_H44441003_PIP-SCONN,HA    I12 @BASEBOARD_FAB2_LIB.BASEBOARD_FAB2(SCH_1):PAGE52

M_E_MA<1> @BASEBOARD_FAB2_LIB.BASEBOARD_FAB2(SCH_1):M_E_MA(1)
  U5D1 DW58 DDR4_MA<1> SKX_EXT_B_BGA1-IC,TBD   I172 @BASEBOARD_FAB2_LIB.BASEBOARD_FAB2(SCH_1):PAGE27
  J4A2   72     A1 SCONN288_H44441004_PIP-SCONN,HA   I111 @BASEBOARD_FAB2_LIB.BASEBOARD_FAB2(SCH_1):PAGE51
  J6L2   72     A1 SCONN288_H44441003_PIP-SCONN,HA    I12 @BASEBOARD_FAB2_LIB.BASEBOARD_FAB2(SCH_1):PAGE52

M_E_MA<2> @BASEBOARD_FAB2_LIB.BASEBOARD_FAB2(SCH_1):M_E_MA(2)
  U5D1 DV57 DDR4_MA<2> SKX_EXT_B_BGA1-IC,TBD   I172 @BASEBOARD_FAB2_LIB.BASEBOARD_FAB2(SCH_1):PAGE27
  J4A2  216     A2 SCONN288_H44441004_PIP-SCONN,HA   I111 @BASEBOARD_FAB2_LIB.BASEBOARD_FAB2(SCH_1):PAGE51
  J6L2  216     A2 SCONN288_H44441003_PIP-SCONN,HA    I12 @BASEBOARD_FAB2_LIB.BASEBOARD_FAB2(SCH_1):PAGE52

M_E_MA<3> @BASEBOARD_FAB2_LIB.BASEBOARD_FAB2(SCH_1):M_E_MA(3)
  U5D1 DR58 DDR4_MA<3> SKX_EXT_B_BGA1-IC,TBD   I172 @BASEBOARD_FAB2_LIB.BASEBOARD_FAB2(SCH_1):PAGE27
  J4A2   71     A3 SCONN288_H44441004_PIP-SCONN,HA   I111 @BASEBOARD_FAB2_LIB.BASEBOARD_FAB2(SCH_1):PAGE51
  J6L2   71     A3 SCONN288_H44441003_PIP-SCONN,HA    I12 @BASEBOARD_FAB2_LIB.BASEBOARD_FAB2(SCH_1):PAGE52

M_E_MA<4> @BASEBOARD_FAB2_LIB.BASEBOARD_FAB2(SCH_1):M_E_MA(4)
  U5D1 DT59 DDR4_MA<4> SKX_EXT_B_BGA1-IC,TBD   I172 @BASEBOARD_FAB2_LIB.BASEBOARD_FAB2(SCH_1):PAGE27
  J4A2  214     A4 SCONN288_H44441004_PIP-SCONN,HA   I111 @BASEBOARD_FAB2_LIB.BASEBOARD_FAB2(SCH_1):PAGE51
  J6L2  214     A4 SCONN288_H44441003_PIP-SCONN,HA    I12 @BASEBOARD_FAB2_LIB.BASEBOARD_FAB2(SCH_1):PAGE52

M_E_MA<5> @BASEBOARD_FAB2_LIB.BASEBOARD_FAB2(SCH_1):M_E_MA(5)
  U5D1 DN58 DDR4_MA<5> SKX_EXT_B_BGA1-IC,TBD   I172 @BASEBOARD_FAB2_LIB.BASEBOARD_FAB2(SCH_1):PAGE27
  J4A2  213     A5 SCONN288_H44441004_PIP-SCONN,HA   I111 @BASEBOARD_FAB2_LIB.BASEBOARD_FAB2(SCH_1):PAGE51
  J6L2  213     A5 SCONN288_H44441003_PIP-SCONN,HA    I12 @BASEBOARD_FAB2_LIB.BASEBOARD_FAB2(SCH_1):PAGE52

M_E_MA<6> @BASEBOARD_FAB2_LIB.BASEBOARD_FAB2(SCH_1):M_E_MA(6)
  U5D1 DM59 DDR4_MA<6> SKX_EXT_B_BGA1-IC,TBD   I172 @BASEBOARD_FAB2_LIB.BASEBOARD_FAB2(SCH_1):PAGE27
  J4A2   69     A6 SCONN288_H44441004_PIP-SCONN,HA   I111 @BASEBOARD_FAB2_LIB.BASEBOARD_FAB2(SCH_1):PAGE51
  J6L2   69     A6 SCONN288_H44441003_PIP-SCONN,HA    I12 @BASEBOARD_FAB2_LIB.BASEBOARD_FAB2(SCH_1):PAGE52

M_E_MA<7> @BASEBOARD_FAB2_LIB.BASEBOARD_FAB2(SCH_1):M_E_MA(7)
  U5D1 DK61 DDR4_MA<7> SKX_EXT_B_BGA1-IC,TBD   I172 @BASEBOARD_FAB2_LIB.BASEBOARD_FAB2(SCH_1):PAGE27
  J4A2  211     A7 SCONN288_H44441004_PIP-SCONN,HA   I111 @BASEBOARD_FAB2_LIB.BASEBOARD_FAB2(SCH_1):PAGE51
  J6L2  211     A7 SCONN288_H44441003_PIP-SCONN,HA    I12 @BASEBOARD_FAB2_LIB.BASEBOARD_FAB2(SCH_1):PAGE52

M_E_MA<8> @BASEBOARD_FAB2_LIB.BASEBOARD_FAB2(SCH_1):M_E_MA(8)
  U5D1 DJ60 DDR4_MA<8> SKX_EXT_B_BGA1-IC,TBD   I172 @BASEBOARD_FAB2_LIB.BASEBOARD_FAB2(SCH_1):PAGE27
  J4A2   68     A8 SCONN288_H44441004_PIP-SCONN,HA   I111 @BASEBOARD_FAB2_LIB.BASEBOARD_FAB2(SCH_1):PAGE51
  J6L2   68     A8 SCONN288_H44441003_PIP-SCONN,HA    I12 @BASEBOARD_FAB2_LIB.BASEBOARD_FAB2(SCH_1):PAGE52

M_E_MA<9> @BASEBOARD_FAB2_LIB.BASEBOARD_FAB2(SCH_1):M_E_MA(9)
  U5D1 DV59 DDR4_MA<9> SKX_EXT_B_BGA1-IC,TBD   I172 @BASEBOARD_FAB2_LIB.BASEBOARD_FAB2(SCH_1):PAGE27
  J4A2   66     A9 SCONN288_H44441004_PIP-SCONN,HA   I111 @BASEBOARD_FAB2_LIB.BASEBOARD_FAB2(SCH_1):PAGE51
  J6L2   66     A9 SCONN288_H44441003_PIP-SCONN,HA    I12 @BASEBOARD_FAB2_LIB.BASEBOARD_FAB2(SCH_1):PAGE52

M_E_ODT<0> @BASEBOARD_FAB2_LIB.BASEBOARD_FAB2(SCH_1):M_E_ODT(0)
  U5D1 DR50 DDR4_ODT<0> SKX_EXT_B_BGA1-IC,TBD   I172 @BASEBOARD_FAB2_LIB.BASEBOARD_FAB2(SCH_1):PAGE27
  J4A2   87 ODT<0> SCONN288_H44441004_PIP-SCONN,HA   I111 @BASEBOARD_FAB2_LIB.BASEBOARD_FAB2(SCH_1):PAGE51

M_E_ODT<1> @BASEBOARD_FAB2_LIB.BASEBOARD_FAB2(SCH_1):M_E_ODT(1)
  U5D1 DN48 DDR4_ODT<1> SKX_EXT_B_BGA1-IC,TBD   I172 @BASEBOARD_FAB2_LIB.BASEBOARD_FAB2(SCH_1):PAGE27
  J4A2   91 ODT<1> SCONN288_H44441004_PIP-SCONN,HA   I111 @BASEBOARD_FAB2_LIB.BASEBOARD_FAB2(SCH_1):PAGE51

M_E_ODT<2> @BASEBOARD_FAB2_LIB.BASEBOARD_FAB2(SCH_1):M_E_ODT(2)
  U5D1 DT49 DDR4_ODT<2> SKX_EXT_B_BGA1-IC,TBD   I172 @BASEBOARD_FAB2_LIB.BASEBOARD_FAB2(SCH_1):PAGE27
  J6L2   87 ODT<0> SCONN288_H44441003_PIP-SCONN,HA    I12 @BASEBOARD_FAB2_LIB.BASEBOARD_FAB2(SCH_1):PAGE52

M_E_ODT<3> @BASEBOARD_FAB2_LIB.BASEBOARD_FAB2(SCH_1):M_E_ODT(3)
  U5D1 DM47 DDR4_ODT<3> SKX_EXT_B_BGA1-IC,TBD   I172 @BASEBOARD_FAB2_LIB.BASEBOARD_FAB2(SCH_1):PAGE27
  J6L2   91 ODT<1> SCONN288_H44441003_PIP-SCONN,HA    I12 @BASEBOARD_FAB2_LIB.BASEBOARD_FAB2(SCH_1):PAGE52

M_E_PAR @BASEBOARD_FAB2_LIB.BASEBOARD_FAB2(SCH_1):M_E_PAR
  U5D1 DV53 DDR4_PAR SKX_EXT_B_BGA1-IC,TBD   I172 @BASEBOARD_FAB2_LIB.BASEBOARD_FAB2(SCH_1):PAGE27
  J4A2  222    PAR SCONN288_H44441004_PIP-SCONN,HA   I111 @BASEBOARD_FAB2_LIB.BASEBOARD_FAB2(SCH_1):PAGE51
  J6L2  222    PAR SCONN288_H44441003_PIP-SCONN,HA    I12 @BASEBOARD_FAB2_LIB.BASEBOARD_FAB2(SCH_1):PAGE52

M_E_VREF @BASEBOARD_FAB2_LIB.BASEBOARD_FAB2(SCH_1):M_E_VREF
  J4A2  146 VREFCA SCONN288_H44441004_PIP-SCONN,HA   I111 @BASEBOARD_FAB2_LIB.BASEBOARD_FAB2(SCH_1):PAGE51
  C6L6    1      A CAP_A_0402V-0.01UF,25V,10%,X7RA   I175 @BASEBOARD_FAB2_LIB.BASEBOARD_FAB2(SCH_1):PAGE51
 C4A18    1      A CAP_A_0402V-0.01UF,25V,10%,X7RA     I3 @BASEBOARD_FAB2_LIB.BASEBOARD_FAB2(SCH_1):PAGE52
  J6L2  146 VREFCA SCONN288_H44441003_PIP-SCONN,HA    I12 @BASEBOARD_FAB2_LIB.BASEBOARD_FAB2(SCH_1):PAGE52
 R6L13    2      B RES_0402-1.00K,1%,1/16W,CHIP,GA    I54 @BASEBOARD_FAB2_LIB.BASEBOARD_FAB2(SCH_1):PAGE98
 R6L12    1      A RES_0402-1.00K,1%,1/16W,CHIP,GA    I56 @BASEBOARD_FAB2_LIB.BASEBOARD_FAB2(SCH_1):PAGE98
 R6L14    2      B RES_0402-2,1.0%,1/16W,CHIP,G21A    I58 @BASEBOARD_FAB2_LIB.BASEBOARD_FAB2(SCH_1):PAGE98

M_F_ACT_N @BASEBOARD_FAB2_LIB.BASEBOARD_FAB2(SCH_1):M_F_ACT_N
  U5D1 DC62 DDR5_ACT_N SKX_EXT_B_BGA1-IC,TBD   I172 @BASEBOARD_FAB2_LIB.BASEBOARD_FAB2(SCH_1):PAGE28
  J4A1   62  ACT_N SCONN288_H44441004_PIP-SCONN,HA   I111 @BASEBOARD_FAB2_LIB.BASEBOARD_FAB2(SCH_1):PAGE53
  J6L1   62  ACT_N SCONN288_H44441003_PIP-SCONN,HA   I111 @BASEBOARD_FAB2_LIB.BASEBOARD_FAB2(SCH_1):PAGE54

M_F_ALERT_N @BASEBOARD_FAB2_LIB.BASEBOARD_FAB2(SCH_1):M_F_ALERT_N
  U5D1 DD61 DDR5_ALERT_N SKX_EXT_B_BGA1-IC,TBD   I172 @BASEBOARD_FAB2_LIB.BASEBOARD_FAB2(SCH_1):PAGE28
  J4A1  208 ALERT_N SCONN288_H44441004_PIP-SCONN,HA   I111 @BASEBOARD_FAB2_LIB.BASEBOARD_FAB2(SCH_1):PAGE53
  J6L1  208 ALERT_N SCONN288_H44441003_PIP-SCONN,HA   I111 @BASEBOARD_FAB2_LIB.BASEBOARD_FAB2(SCH_1):PAGE54

M_F_BA<0> @BASEBOARD_FAB2_LIB.BASEBOARD_FAB2(SCH_1):M_F_BA(0)
  U5D1 DJ52 DDR5_BA<0> SKX_EXT_B_BGA1-IC,TBD   I172 @BASEBOARD_FAB2_LIB.BASEBOARD_FAB2(SCH_1):PAGE28
  J4A1   81  BA<0> SCONN288_H44441004_PIP-SCONN,HA   I111 @BASEBOARD_FAB2_LIB.BASEBOARD_FAB2(SCH_1):PAGE53
  J6L1   81  BA<0> SCONN288_H44441003_PIP-SCONN,HA   I111 @BASEBOARD_FAB2_LIB.BASEBOARD_FAB2(SCH_1):PAGE54

M_F_BA<1> @BASEBOARD_FAB2_LIB.BASEBOARD_FAB2(SCH_1):M_F_BA(1)
  U5D1 DC56 DDR5_BA<1> SKX_EXT_B_BGA1-IC,TBD   I172 @BASEBOARD_FAB2_LIB.BASEBOARD_FAB2(SCH_1):PAGE28
  J4A1  224  BA<1> SCONN288_H44441004_PIP-SCONN,HA   I111 @BASEBOARD_FAB2_LIB.BASEBOARD_FAB2(SCH_1):PAGE53
  J6L1  224  BA<1> SCONN288_H44441003_PIP-SCONN,HA   I111 @BASEBOARD_FAB2_LIB.BASEBOARD_FAB2(SCH_1):PAGE54

M_F_BG<0> @BASEBOARD_FAB2_LIB.BASEBOARD_FAB2(SCH_1):M_F_BG(0)
  U5D1 DA62 DDR5_BG<0> SKX_EXT_B_BGA1-IC,TBD   I172 @BASEBOARD_FAB2_LIB.BASEBOARD_FAB2(SCH_1):PAGE28
  J4A1   63  BG<0> SCONN288_H44441004_PIP-SCONN,HA   I111 @BASEBOARD_FAB2_LIB.BASEBOARD_FAB2(SCH_1):PAGE53
  J6L1   63  BG<0> SCONN288_H44441003_PIP-SCONN,HA   I111 @BASEBOARD_FAB2_LIB.BASEBOARD_FAB2(SCH_1):PAGE54

M_F_BG<1> @BASEBOARD_FAB2_LIB.BASEBOARD_FAB2(SCH_1):M_F_BG(1)
  U5D1 DF61 DDR5_BG<1> SKX_EXT_B_BGA1-IC,TBD   I172 @BASEBOARD_FAB2_LIB.BASEBOARD_FAB2(SCH_1):PAGE28
  J4A1  207  BG<1> SCONN288_H44441004_PIP-SCONN,HA   I111 @BASEBOARD_FAB2_LIB.BASEBOARD_FAB2(SCH_1):PAGE53
  J6L1  207  BG<1> SCONN288_H44441003_PIP-SCONN,HA   I111 @BASEBOARD_FAB2_LIB.BASEBOARD_FAB2(SCH_1):PAGE54

M_F_C<2> @BASEBOARD_FAB2_LIB.BASEBOARD_FAB2(SCH_1):M_F_C(2)
  U5D1 DF45 DDR5_CID<2> SKX_EXT_B_BGA1-IC,TBD   I172 @BASEBOARD_FAB2_LIB.BASEBOARD_FAB2(SCH_1):PAGE28
  J4A1  235   C<2> SCONN288_H44441004_PIP-SCONN,HA   I111 @BASEBOARD_FAB2_LIB.BASEBOARD_FAB2(SCH_1):PAGE53
  J6L1  235   C<2> SCONN288_H44441003_PIP-SCONN,HA   I111 @BASEBOARD_FAB2_LIB.BASEBOARD_FAB2(SCH_1):PAGE54

M_F_CKE<0> @BASEBOARD_FAB2_LIB.BASEBOARD_FAB2(SCH_1):M_F_CKE(0)
  U5D1 DG62 DDR5_CKE<0> SKX_EXT_B_BGA1-IC,TBD   I172 @BASEBOARD_FAB2_LIB.BASEBOARD_FAB2(SCH_1):PAGE28
  J4A1   60 CKE<0> SCONN288_H44441004_PIP-SCONN,HA   I111 @BASEBOARD_FAB2_LIB.BASEBOARD_FAB2(SCH_1):PAGE53

M_F_CKE<1> @BASEBOARD_FAB2_LIB.BASEBOARD_FAB2(SCH_1):M_F_CKE(1)
  U5D1 DD63 DDR5_CKE<1> SKX_EXT_B_BGA1-IC,TBD   I172 @BASEBOARD_FAB2_LIB.BASEBOARD_FAB2(SCH_1):PAGE28
  J4A1  203 CKE<1> SCONN288_H44441004_PIP-SCONN,HA   I111 @BASEBOARD_FAB2_LIB.BASEBOARD_FAB2(SCH_1):PAGE53

M_F_CKE<2> @BASEBOARD_FAB2_LIB.BASEBOARD_FAB2(SCH_1):M_F_CKE(2)
  U5D1 DK63 DDR5_CKE<2> SKX_EXT_B_BGA1-IC,TBD   I172 @BASEBOARD_FAB2_LIB.BASEBOARD_FAB2(SCH_1):PAGE28
  J6L1   60 CKE<0> SCONN288_H44441003_PIP-SCONN,HA   I111 @BASEBOARD_FAB2_LIB.BASEBOARD_FAB2(SCH_1):PAGE54

M_F_CKE<3> @BASEBOARD_FAB2_LIB.BASEBOARD_FAB2(SCH_1):M_F_CKE(3)
  U5D1 DF63 DDR5_CKE<3> SKX_EXT_B_BGA1-IC,TBD   I172 @BASEBOARD_FAB2_LIB.BASEBOARD_FAB2(SCH_1):PAGE28
  J6L1  203 CKE<1> SCONN288_H44441003_PIP-SCONN,HA   I111 @BASEBOARD_FAB2_LIB.BASEBOARD_FAB2(SCH_1):PAGE54

M_F_CLK_DN<0> @BASEBOARD_FAB2_LIB.BASEBOARD_FAB2(SCH_1):M_F_CLK_DN(0)
  U5D1 DK55 DDR5_CLK_DN<0> SKX_EXT_B_BGA1-IC,TBD   I172 @BASEBOARD_FAB2_LIB.BASEBOARD_FAB2(SCH_1):PAGE28
  J4A1   75   CK0N SCONN288_H44441004_PIP-SCONN,HA   I111 @BASEBOARD_FAB2_LIB.BASEBOARD_FAB2(SCH_1):PAGE53

M_F_CLK_DN<1> @BASEBOARD_FAB2_LIB.BASEBOARD_FAB2(SCH_1):M_F_CLK_DN(1)
  U5D1 DF55 DDR5_CLK_DN<1> SKX_EXT_B_BGA1-IC,TBD   I172 @BASEBOARD_FAB2_LIB.BASEBOARD_FAB2(SCH_1):PAGE28
  J4A1  219   CK1N SCONN288_H44441004_PIP-SCONN,HA   I111 @BASEBOARD_FAB2_LIB.BASEBOARD_FAB2(SCH_1):PAGE53

M_F_CLK_DN<2> @BASEBOARD_FAB2_LIB.BASEBOARD_FAB2(SCH_1):M_F_CLK_DN(2)
  U5D1 DK57 DDR5_CLK_DN<2> SKX_EXT_B_BGA1-IC,TBD   I172 @BASEBOARD_FAB2_LIB.BASEBOARD_FAB2(SCH_1):PAGE28
  J6L1   75   CK0N SCONN288_H44441003_PIP-SCONN,HA   I111 @BASEBOARD_FAB2_LIB.BASEBOARD_FAB2(SCH_1):PAGE54

M_F_CLK_DN<3> @BASEBOARD_FAB2_LIB.BASEBOARD_FAB2(SCH_1):M_F_CLK_DN(3)
  U5D1 DF57 DDR5_CLK_DN<3> SKX_EXT_B_BGA1-IC,TBD   I172 @BASEBOARD_FAB2_LIB.BASEBOARD_FAB2(SCH_1):PAGE28
  J6L1  219   CK1N SCONN288_H44441003_PIP-SCONN,HA   I111 @BASEBOARD_FAB2_LIB.BASEBOARD_FAB2(SCH_1):PAGE54

M_F_CLK_DP<0> @BASEBOARD_FAB2_LIB.BASEBOARD_FAB2(SCH_1):M_F_CLK_DP(0)
  U5D1 DJ54 DDR5_CLK_DP<0> SKX_EXT_B_BGA1-IC,TBD   I172 @BASEBOARD_FAB2_LIB.BASEBOARD_FAB2(SCH_1):PAGE28
  J4A1   74   CK0P SCONN288_H44441004_PIP-SCONN,HA   I111 @BASEBOARD_FAB2_LIB.BASEBOARD_FAB2(SCH_1):PAGE53

M_F_CLK_DP<1> @BASEBOARD_FAB2_LIB.BASEBOARD_FAB2(SCH_1):M_F_CLK_DP(1)
  U5D1 DG54 DDR5_CLK_DP<1> SKX_EXT_B_BGA1-IC,TBD   I172 @BASEBOARD_FAB2_LIB.BASEBOARD_FAB2(SCH_1):PAGE28
  J4A1  218   CK1P SCONN288_H44441004_PIP-SCONN,HA   I111 @BASEBOARD_FAB2_LIB.BASEBOARD_FAB2(SCH_1):PAGE53

M_F_CLK_DP<2> @BASEBOARD_FAB2_LIB.BASEBOARD_FAB2(SCH_1):M_F_CLK_DP(2)
  U5D1 DJ56 DDR5_CLK_DP<2> SKX_EXT_B_BGA1-IC,TBD   I172 @BASEBOARD_FAB2_LIB.BASEBOARD_FAB2(SCH_1):PAGE28
  J6L1   74   CK0P SCONN288_H44441003_PIP-SCONN,HA   I111 @BASEBOARD_FAB2_LIB.BASEBOARD_FAB2(SCH_1):PAGE54

M_F_CLK_DP<3> @BASEBOARD_FAB2_LIB.BASEBOARD_FAB2(SCH_1):M_F_CLK_DP(3)
  U5D1 DG56 DDR5_CLK_DP<3> SKX_EXT_B_BGA1-IC,TBD   I172 @BASEBOARD_FAB2_LIB.BASEBOARD_FAB2(SCH_1):PAGE28
  J6L1  218   CK1P SCONN288_H44441003_PIP-SCONN,HA   I111 @BASEBOARD_FAB2_LIB.BASEBOARD_FAB2(SCH_1):PAGE54

M_F_CPU_VREF @BASEBOARD_FAB2_LIB.BASEBOARD_FAB2(SCH_1):M_F_CPU_VREF
  U5D1 CV61 DDR5_CAVREF SKX_EXT_B_BGA1-IC,TBD   I259 @BASEBOARD_FAB2_LIB.BASEBOARD_FAB2(SCH_1):PAGE21
  R6L3    1      A RES_0402-2,1.0%,1/16W,CHIP,G21A    I66 @BASEBOARD_FAB2_LIB.BASEBOARD_FAB2(SCH_1):PAGE98
  C6L2    1      A CAP_A_0402V-0.01UF,25V,10%,X7RA    I67 @BASEBOARD_FAB2_LIB.BASEBOARD_FAB2(SCH_1):PAGE98

M_F_CS_N<0> @BASEBOARD_FAB2_LIB.BASEBOARD_FAB2(SCH_1):M_F_CS_N(0)
  U5D1 DK51 DDR5_CS_N<0> SKX_EXT_B_BGA1-IC,TBD   I172 @BASEBOARD_FAB2_LIB.BASEBOARD_FAB2(SCH_1):PAGE28
  J4A1   84   S0_N SCONN288_H44441004_PIP-SCONN,HA   I111 @BASEBOARD_FAB2_LIB.BASEBOARD_FAB2(SCH_1):PAGE53

M_F_CS_N<1> @BASEBOARD_FAB2_LIB.BASEBOARD_FAB2(SCH_1):M_F_CS_N(1)
  U5D1 DF49 DDR5_CS_N<1> SKX_EXT_B_BGA1-IC,TBD   I172 @BASEBOARD_FAB2_LIB.BASEBOARD_FAB2(SCH_1):PAGE28
  J4A1   89   S1_N SCONN288_H44441004_PIP-SCONN,HA   I111 @BASEBOARD_FAB2_LIB.BASEBOARD_FAB2(SCH_1):PAGE53

M_F_CS_N<2> @BASEBOARD_FAB2_LIB.BASEBOARD_FAB2(SCH_1):M_F_CS_N(2)
  U5D1 DJ46 DDR5_CS_N<2> SKX_EXT_B_BGA1-IC,TBD   I172 @BASEBOARD_FAB2_LIB.BASEBOARD_FAB2(SCH_1):PAGE28
  J4A1   93 S2_N_C<0> SCONN288_H44441004_PIP-SCONN,HA   I111 @BASEBOARD_FAB2_LIB.BASEBOARD_FAB2(SCH_1):PAGE53

M_F_CS_N<3> @BASEBOARD_FAB2_LIB.BASEBOARD_FAB2(SCH_1):M_F_CS_N(3)
  U5D1 DG46 DDR5_CS_N<3> SKX_EXT_B_BGA1-IC,TBD   I172 @BASEBOARD_FAB2_LIB.BASEBOARD_FAB2(SCH_1):PAGE28
  J4A1  237 S3_N_C<1> SCONN288_H44441004_PIP-SCONN,HA   I111 @BASEBOARD_FAB2_LIB.BASEBOARD_FAB2(SCH_1):PAGE53

M_F_CS_N<4> @BASEBOARD_FAB2_LIB.BASEBOARD_FAB2(SCH_1):M_F_CS_N(4)
  U5D1 DF51 DDR5_CS_N<4> SKX_EXT_B_BGA1-IC,TBD   I172 @BASEBOARD_FAB2_LIB.BASEBOARD_FAB2(SCH_1):PAGE28
  J6L1   84   S0_N SCONN288_H44441003_PIP-SCONN,HA   I111 @BASEBOARD_FAB2_LIB.BASEBOARD_FAB2(SCH_1):PAGE54

M_F_CS_N<5> @BASEBOARD_FAB2_LIB.BASEBOARD_FAB2(SCH_1):M_F_CS_N(5)
  U5D1 DJ48 DDR5_CS_N<5> SKX_EXT_B_BGA1-IC,TBD   I172 @BASEBOARD_FAB2_LIB.BASEBOARD_FAB2(SCH_1):PAGE28
  J6L1   89   S1_N SCONN288_H44441003_PIP-SCONN,HA   I111 @BASEBOARD_FAB2_LIB.BASEBOARD_FAB2(SCH_1):PAGE54

M_F_CS_N<6> @BASEBOARD_FAB2_LIB.BASEBOARD_FAB2(SCH_1):M_F_CS_N(6)
  U5D1 DM45 DDR5_CS_N<6> SKX_EXT_B_BGA1-IC,TBD   I172 @BASEBOARD_FAB2_LIB.BASEBOARD_FAB2(SCH_1):PAGE28
  J6L1   93 S2_N_C<0> SCONN288_H44441003_PIP-SCONN,HA   I111 @BASEBOARD_FAB2_LIB.BASEBOARD_FAB2(SCH_1):PAGE54

M_F_CS_N<7> @BASEBOARD_FAB2_LIB.BASEBOARD_FAB2(SCH_1):M_F_CS_N(7)
  U5D1 DK45 DDR5_CS_N<7> SKX_EXT_B_BGA1-IC,TBD   I172 @BASEBOARD_FAB2_LIB.BASEBOARD_FAB2(SCH_1):PAGE28
  J6L1  237 S3_N_C<1> SCONN288_H44441003_PIP-SCONN,HA   I111 @BASEBOARD_FAB2_LIB.BASEBOARD_FAB2(SCH_1):PAGE54

M_F_DQ<0> @BASEBOARD_FAB2_LIB.BASEBOARD_FAB2(SCH_1):M_F_DQ(0)
  U5D1 CR74 DDR5_DQ<0> SKX_EXT_B_BGA1-IC,TBD   I172 @BASEBOARD_FAB2_LIB.BASEBOARD_FAB2(SCH_1):PAGE28
  J4A1  150  DQ<1> SCONN288_H44441004_PIP-SCONN,HA   I111 @BASEBOARD_FAB2_LIB.BASEBOARD_FAB2(SCH_1):PAGE53
  J6L1    5  DQ<0> SCONN288_H44441003_PIP-SCONN,HA   I111 @BASEBOARD_FAB2_LIB.BASEBOARD_FAB2(SCH_1):PAGE54

M_F_DQ<10> @BASEBOARD_FAB2_LIB.BASEBOARD_FAB2(SCH_1):M_F_DQ(10)
  U5D1 DH75 DDR5_DQ<10> SKX_EXT_B_BGA1-IC,TBD   I172 @BASEBOARD_FAB2_LIB.BASEBOARD_FAB2(SCH_1):PAGE28
  J4A1  168 DQ<11> SCONN288_H44441004_PIP-SCONN,HA   I111 @BASEBOARD_FAB2_LIB.BASEBOARD_FAB2(SCH_1):PAGE53
  J6L1   23 DQ<10> SCONN288_H44441003_PIP-SCONN,HA   I111 @BASEBOARD_FAB2_LIB.BASEBOARD_FAB2(SCH_1):PAGE54

M_F_DQ<11> @BASEBOARD_FAB2_LIB.BASEBOARD_FAB2(SCH_1):M_F_DQ(11)
  U5D1 DJ76 DDR5_DQ<11> SKX_EXT_B_BGA1-IC,TBD   I172 @BASEBOARD_FAB2_LIB.BASEBOARD_FAB2(SCH_1):PAGE28
  J4A1   23 DQ<10> SCONN288_H44441004_PIP-SCONN,HA   I111 @BASEBOARD_FAB2_LIB.BASEBOARD_FAB2(SCH_1):PAGE53
  J6L1  168 DQ<11> SCONN288_H44441003_PIP-SCONN,HA   I111 @BASEBOARD_FAB2_LIB.BASEBOARD_FAB2(SCH_1):PAGE54

M_F_DQ<12> @BASEBOARD_FAB2_LIB.BASEBOARD_FAB2(SCH_1):M_F_DQ(12)
  U5D1 DC74 DDR5_DQ<12> SKX_EXT_B_BGA1-IC,TBD   I172 @BASEBOARD_FAB2_LIB.BASEBOARD_FAB2(SCH_1):PAGE28
  J4A1  159 DQ<13> SCONN288_H44441004_PIP-SCONN,HA   I111 @BASEBOARD_FAB2_LIB.BASEBOARD_FAB2(SCH_1):PAGE53
  J6L1   14 DQ<12> SCONN288_H44441003_PIP-SCONN,HA   I111 @BASEBOARD_FAB2_LIB.BASEBOARD_FAB2(SCH_1):PAGE54

M_F_DQ<13> @BASEBOARD_FAB2_LIB.BASEBOARD_FAB2(SCH_1):M_F_DQ(13)
  U5D1 DB75 DDR5_DQ<13> SKX_EXT_B_BGA1-IC,TBD   I172 @BASEBOARD_FAB2_LIB.BASEBOARD_FAB2(SCH_1):PAGE28
  J4A1   14 DQ<12> SCONN288_H44441004_PIP-SCONN,HA   I111 @BASEBOARD_FAB2_LIB.BASEBOARD_FAB2(SCH_1):PAGE53
  J6L1  159 DQ<13> SCONN288_H44441003_PIP-SCONN,HA   I111 @BASEBOARD_FAB2_LIB.BASEBOARD_FAB2(SCH_1):PAGE54

M_F_DQ<14> @BASEBOARD_FAB2_LIB.BASEBOARD_FAB2(SCH_1):M_F_DQ(14)
  U5D1 DF77 DDR5_DQ<14> SKX_EXT_B_BGA1-IC,TBD   I172 @BASEBOARD_FAB2_LIB.BASEBOARD_FAB2(SCH_1):PAGE28
  J4A1  166 DQ<15> SCONN288_H44441004_PIP-SCONN,HA   I111 @BASEBOARD_FAB2_LIB.BASEBOARD_FAB2(SCH_1):PAGE53
  J6L1   21 DQ<14> SCONN288_H44441003_PIP-SCONN,HA   I111 @BASEBOARD_FAB2_LIB.BASEBOARD_FAB2(SCH_1):PAGE54

M_F_DQ<15> @BASEBOARD_FAB2_LIB.BASEBOARD_FAB2(SCH_1):M_F_DQ(15)
  U5D1 DH77 DDR5_DQ<15> SKX_EXT_B_BGA1-IC,TBD   I172 @BASEBOARD_FAB2_LIB.BASEBOARD_FAB2(SCH_1):PAGE28
  J4A1   21 DQ<14> SCONN288_H44441004_PIP-SCONN,HA   I111 @BASEBOARD_FAB2_LIB.BASEBOARD_FAB2(SCH_1):PAGE53
  J6L1  166 DQ<15> SCONN288_H44441003_PIP-SCONN,HA   I111 @BASEBOARD_FAB2_LIB.BASEBOARD_FAB2(SCH_1):PAGE54

M_F_DQ<16> @BASEBOARD_FAB2_LIB.BASEBOARD_FAB2(SCH_1):M_F_DQ(16)
  U5D1 DG70 DDR5_DQ<16> SKX_EXT_B_BGA1-IC,TBD   I172 @BASEBOARD_FAB2_LIB.BASEBOARD_FAB2(SCH_1):PAGE28
  J4A1  172 DQ<17> SCONN288_H44441004_PIP-SCONN,HA   I111 @BASEBOARD_FAB2_LIB.BASEBOARD_FAB2(SCH_1):PAGE53
  J6L1   27 DQ<16> SCONN288_H44441003_PIP-SCONN,HA   I111 @BASEBOARD_FAB2_LIB.BASEBOARD_FAB2(SCH_1):PAGE54

M_F_DQ<17> @BASEBOARD_FAB2_LIB.BASEBOARD_FAB2(SCH_1):M_F_DQ(17)
  U5D1 DJ72 DDR5_DQ<17> SKX_EXT_B_BGA1-IC,TBD   I172 @BASEBOARD_FAB2_LIB.BASEBOARD_FAB2(SCH_1):PAGE28
  J4A1   27 DQ<16> SCONN288_H44441004_PIP-SCONN,HA   I111 @BASEBOARD_FAB2_LIB.BASEBOARD_FAB2(SCH_1):PAGE53
  J6L1  172 DQ<17> SCONN288_H44441003_PIP-SCONN,HA   I111 @BASEBOARD_FAB2_LIB.BASEBOARD_FAB2(SCH_1):PAGE54

M_F_DQ<18> @BASEBOARD_FAB2_LIB.BASEBOARD_FAB2(SCH_1):M_F_DQ(18)
  U5D1 DM69 DDR5_DQ<18> SKX_EXT_B_BGA1-IC,TBD   I172 @BASEBOARD_FAB2_LIB.BASEBOARD_FAB2(SCH_1):PAGE28
  J4A1  179 DQ<19> SCONN288_H44441004_PIP-SCONN,HA   I111 @BASEBOARD_FAB2_LIB.BASEBOARD_FAB2(SCH_1):PAGE53
  J6L1   34 DQ<18> SCONN288_H44441003_PIP-SCONN,HA   I111 @BASEBOARD_FAB2_LIB.BASEBOARD_FAB2(SCH_1):PAGE54

M_F_DQ<19> @BASEBOARD_FAB2_LIB.BASEBOARD_FAB2(SCH_1):M_F_DQ(19)
  U5D1 DN70 DDR5_DQ<19> SKX_EXT_B_BGA1-IC,TBD   I172 @BASEBOARD_FAB2_LIB.BASEBOARD_FAB2(SCH_1):PAGE28
  J4A1   34 DQ<18> SCONN288_H44441004_PIP-SCONN,HA   I111 @BASEBOARD_FAB2_LIB.BASEBOARD_FAB2(SCH_1):PAGE53
  J6L1  179 DQ<19> SCONN288_H44441003_PIP-SCONN,HA   I111 @BASEBOARD_FAB2_LIB.BASEBOARD_FAB2(SCH_1):PAGE54

M_F_DQ<1> @BASEBOARD_FAB2_LIB.BASEBOARD_FAB2(SCH_1):M_F_DQ(1)
  U5D1 CN76 DDR5_DQ<1> SKX_EXT_B_BGA1-IC,TBD   I172 @BASEBOARD_FAB2_LIB.BASEBOARD_FAB2(SCH_1):PAGE28
  J4A1    5  DQ<0> SCONN288_H44441004_PIP-SCONN,HA   I111 @BASEBOARD_FAB2_LIB.BASEBOARD_FAB2(SCH_1):PAGE53
  J6L1  150  DQ<1> SCONN288_H44441003_PIP-SCONN,HA   I111 @BASEBOARD_FAB2_LIB.BASEBOARD_FAB2(SCH_1):PAGE54

M_F_DQ<20> @BASEBOARD_FAB2_LIB.BASEBOARD_FAB2(SCH_1):M_F_DQ(20)
  U5D1 DF71 DDR5_DQ<20> SKX_EXT_B_BGA1-IC,TBD   I172 @BASEBOARD_FAB2_LIB.BASEBOARD_FAB2(SCH_1):PAGE28
  J4A1  170 DQ<21> SCONN288_H44441004_PIP-SCONN,HA   I111 @BASEBOARD_FAB2_LIB.BASEBOARD_FAB2(SCH_1):PAGE53
  J6L1   25 DQ<20> SCONN288_H44441003_PIP-SCONN,HA   I111 @BASEBOARD_FAB2_LIB.BASEBOARD_FAB2(SCH_1):PAGE54

M_F_DQ<21> @BASEBOARD_FAB2_LIB.BASEBOARD_FAB2(SCH_1):M_F_DQ(21)
  U5D1 DG72 DDR5_DQ<21> SKX_EXT_B_BGA1-IC,TBD   I172 @BASEBOARD_FAB2_LIB.BASEBOARD_FAB2(SCH_1):PAGE28
  J4A1   25 DQ<20> SCONN288_H44441004_PIP-SCONN,HA   I111 @BASEBOARD_FAB2_LIB.BASEBOARD_FAB2(SCH_1):PAGE53
  J6L1  170 DQ<21> SCONN288_H44441003_PIP-SCONN,HA   I111 @BASEBOARD_FAB2_LIB.BASEBOARD_FAB2(SCH_1):PAGE54

M_F_DQ<22> @BASEBOARD_FAB2_LIB.BASEBOARD_FAB2(SCH_1):M_F_DQ(22)
  U5D1 DK69 DDR5_DQ<22> SKX_EXT_B_BGA1-IC,TBD   I172 @BASEBOARD_FAB2_LIB.BASEBOARD_FAB2(SCH_1):PAGE28
  J4A1  177 DQ<23> SCONN288_H44441004_PIP-SCONN,HA   I111 @BASEBOARD_FAB2_LIB.BASEBOARD_FAB2(SCH_1):PAGE53
  J6L1   32 DQ<22> SCONN288_H44441003_PIP-SCONN,HA   I111 @BASEBOARD_FAB2_LIB.BASEBOARD_FAB2(SCH_1):PAGE54

M_F_DQ<23> @BASEBOARD_FAB2_LIB.BASEBOARD_FAB2(SCH_1):M_F_DQ(23)
  U5D1 DM71 DDR5_DQ<23> SKX_EXT_B_BGA1-IC,TBD   I172 @BASEBOARD_FAB2_LIB.BASEBOARD_FAB2(SCH_1):PAGE28
  J4A1   32 DQ<22> SCONN288_H44441004_PIP-SCONN,HA   I111 @BASEBOARD_FAB2_LIB.BASEBOARD_FAB2(SCH_1):PAGE53
  J6L1  177 DQ<23> SCONN288_H44441003_PIP-SCONN,HA   I111 @BASEBOARD_FAB2_LIB.BASEBOARD_FAB2(SCH_1):PAGE54

M_F_DQ<24> @BASEBOARD_FAB2_LIB.BASEBOARD_FAB2(SCH_1):M_F_DQ(24)
  U5D1 CN66 DDR5_DQ<24> SKX_EXT_B_BGA1-IC,TBD   I172 @BASEBOARD_FAB2_LIB.BASEBOARD_FAB2(SCH_1):PAGE28
  J4A1  183 DQ<25> SCONN288_H44441004_PIP-SCONN,HA   I111 @BASEBOARD_FAB2_LIB.BASEBOARD_FAB2(SCH_1):PAGE53
  J6L1   38 DQ<24> SCONN288_H44441003_PIP-SCONN,HA   I111 @BASEBOARD_FAB2_LIB.BASEBOARD_FAB2(SCH_1):PAGE54

M_F_DQ<25> @BASEBOARD_FAB2_LIB.BASEBOARD_FAB2(SCH_1):M_F_DQ(25)
  U5D1 CU66 DDR5_DQ<25> SKX_EXT_B_BGA1-IC,TBD   I172 @BASEBOARD_FAB2_LIB.BASEBOARD_FAB2(SCH_1):PAGE28
  J4A1   38 DQ<24> SCONN288_H44441004_PIP-SCONN,HA   I111 @BASEBOARD_FAB2_LIB.BASEBOARD_FAB2(SCH_1):PAGE53
  J6L1  183 DQ<25> SCONN288_H44441003_PIP-SCONN,HA   I111 @BASEBOARD_FAB2_LIB.BASEBOARD_FAB2(SCH_1):PAGE54

M_F_DQ<26> @BASEBOARD_FAB2_LIB.BASEBOARD_FAB2(SCH_1):M_F_DQ(26)
  U5D1 CP63 DDR5_DQ<26> SKX_EXT_B_BGA1-IC,TBD   I172 @BASEBOARD_FAB2_LIB.BASEBOARD_FAB2(SCH_1):PAGE28
  J4A1  190 DQ<27> SCONN288_H44441004_PIP-SCONN,HA   I111 @BASEBOARD_FAB2_LIB.BASEBOARD_FAB2(SCH_1):PAGE53
  J6L1   45 DQ<26> SCONN288_H44441003_PIP-SCONN,HA   I111 @BASEBOARD_FAB2_LIB.BASEBOARD_FAB2(SCH_1):PAGE54

M_F_DQ<27> @BASEBOARD_FAB2_LIB.BASEBOARD_FAB2(SCH_1):M_F_DQ(27)
  U5D1 CT63 DDR5_DQ<27> SKX_EXT_B_BGA1-IC,TBD   I172 @BASEBOARD_FAB2_LIB.BASEBOARD_FAB2(SCH_1):PAGE28
  J4A1   45 DQ<26> SCONN288_H44441004_PIP-SCONN,HA   I111 @BASEBOARD_FAB2_LIB.BASEBOARD_FAB2(SCH_1):PAGE53
  J6L1  190 DQ<27> SCONN288_H44441003_PIP-SCONN,HA   I111 @BASEBOARD_FAB2_LIB.BASEBOARD_FAB2(SCH_1):PAGE54

M_F_DQ<28> @BASEBOARD_FAB2_LIB.BASEBOARD_FAB2(SCH_1):M_F_DQ(28)
  U5D1 CP67 DDR5_DQ<28> SKX_EXT_B_BGA1-IC,TBD   I172 @BASEBOARD_FAB2_LIB.BASEBOARD_FAB2(SCH_1):PAGE28
  J4A1  181 DQ<29> SCONN288_H44441004_PIP-SCONN,HA   I111 @BASEBOARD_FAB2_LIB.BASEBOARD_FAB2(SCH_1):PAGE53
  J6L1   36 DQ<28> SCONN288_H44441003_PIP-SCONN,HA   I111 @BASEBOARD_FAB2_LIB.BASEBOARD_FAB2(SCH_1):PAGE54

M_F_DQ<29> @BASEBOARD_FAB2_LIB.BASEBOARD_FAB2(SCH_1):M_F_DQ(29)
  U5D1 CT67 DDR5_DQ<29> SKX_EXT_B_BGA1-IC,TBD   I172 @BASEBOARD_FAB2_LIB.BASEBOARD_FAB2(SCH_1):PAGE28
  J4A1   36 DQ<28> SCONN288_H44441004_PIP-SCONN,HA   I111 @BASEBOARD_FAB2_LIB.BASEBOARD_FAB2(SCH_1):PAGE53
  J6L1  181 DQ<29> SCONN288_H44441003_PIP-SCONN,HA   I111 @BASEBOARD_FAB2_LIB.BASEBOARD_FAB2(SCH_1):PAGE54

M_F_DQ<2> @BASEBOARD_FAB2_LIB.BASEBOARD_FAB2(SCH_1):M_F_DQ(2)
  U5D1 CW76 DDR5_DQ<2> SKX_EXT_B_BGA1-IC,TBD   I172 @BASEBOARD_FAB2_LIB.BASEBOARD_FAB2(SCH_1):PAGE28
  J4A1  157  DQ<3> SCONN288_H44441004_PIP-SCONN,HA   I111 @BASEBOARD_FAB2_LIB.BASEBOARD_FAB2(SCH_1):PAGE53
  J6L1   12  DQ<2> SCONN288_H44441003_PIP-SCONN,HA   I111 @BASEBOARD_FAB2_LIB.BASEBOARD_FAB2(SCH_1):PAGE54

M_F_DQ<30> @BASEBOARD_FAB2_LIB.BASEBOARD_FAB2(SCH_1):M_F_DQ(30)
  U5D1 CN64 DDR5_DQ<30> SKX_EXT_B_BGA1-IC,TBD   I172 @BASEBOARD_FAB2_LIB.BASEBOARD_FAB2(SCH_1):PAGE28
  J4A1  188 DQ<31> SCONN288_H44441004_PIP-SCONN,HA   I111 @BASEBOARD_FAB2_LIB.BASEBOARD_FAB2(SCH_1):PAGE53
  J6L1   43 DQ<30> SCONN288_H44441003_PIP-SCONN,HA   I111 @BASEBOARD_FAB2_LIB.BASEBOARD_FAB2(SCH_1):PAGE54

M_F_DQ<31> @BASEBOARD_FAB2_LIB.BASEBOARD_FAB2(SCH_1):M_F_DQ(31)
  U5D1 CU64 DDR5_DQ<31> SKX_EXT_B_BGA1-IC,TBD   I172 @BASEBOARD_FAB2_LIB.BASEBOARD_FAB2(SCH_1):PAGE28
  J4A1   43 DQ<30> SCONN288_H44441004_PIP-SCONN,HA   I111 @BASEBOARD_FAB2_LIB.BASEBOARD_FAB2(SCH_1):PAGE53
  J6L1  188 DQ<31> SCONN288_H44441003_PIP-SCONN,HA   I111 @BASEBOARD_FAB2_LIB.BASEBOARD_FAB2(SCH_1):PAGE54

M_F_DQ<32> @BASEBOARD_FAB2_LIB.BASEBOARD_FAB2(SCH_1):M_F_DQ(32)
  U5D1 DD41 DDR5_DQ<32> SKX_EXT_B_BGA1-IC,TBD   I172 @BASEBOARD_FAB2_LIB.BASEBOARD_FAB2(SCH_1):PAGE28
  J4A1  242 DQ<33> SCONN288_H44441004_PIP-SCONN,HA   I111 @BASEBOARD_FAB2_LIB.BASEBOARD_FAB2(SCH_1):PAGE53
  J6L1   97 DQ<32> SCONN288_H44441003_PIP-SCONN,HA   I111 @BASEBOARD_FAB2_LIB.BASEBOARD_FAB2(SCH_1):PAGE54

M_F_DQ<33> @BASEBOARD_FAB2_LIB.BASEBOARD_FAB2(SCH_1):M_F_DQ(33)
  U5D1 DG42 DDR5_DQ<33> SKX_EXT_B_BGA1-IC,TBD   I172 @BASEBOARD_FAB2_LIB.BASEBOARD_FAB2(SCH_1):PAGE28
  J4A1   97 DQ<32> SCONN288_H44441004_PIP-SCONN,HA   I111 @BASEBOARD_FAB2_LIB.BASEBOARD_FAB2(SCH_1):PAGE53
  J6L1  242 DQ<33> SCONN288_H44441003_PIP-SCONN,HA   I111 @BASEBOARD_FAB2_LIB.BASEBOARD_FAB2(SCH_1):PAGE54

M_F_DQ<34> @BASEBOARD_FAB2_LIB.BASEBOARD_FAB2(SCH_1):M_F_DQ(34)
  U5D1 DE38 DDR5_DQ<34> SKX_EXT_B_BGA1-IC,TBD   I172 @BASEBOARD_FAB2_LIB.BASEBOARD_FAB2(SCH_1):PAGE28
  J4A1  249 DQ<35> SCONN288_H44441004_PIP-SCONN,HA   I111 @BASEBOARD_FAB2_LIB.BASEBOARD_FAB2(SCH_1):PAGE53
  J6L1  104 DQ<34> SCONN288_H44441003_PIP-SCONN,HA   I111 @BASEBOARD_FAB2_LIB.BASEBOARD_FAB2(SCH_1):PAGE54

M_F_DQ<35> @BASEBOARD_FAB2_LIB.BASEBOARD_FAB2(SCH_1):M_F_DQ(35)
  U5D1 DG38 DDR5_DQ<35> SKX_EXT_B_BGA1-IC,TBD   I172 @BASEBOARD_FAB2_LIB.BASEBOARD_FAB2(SCH_1):PAGE28
  J4A1  104 DQ<34> SCONN288_H44441004_PIP-SCONN,HA   I111 @BASEBOARD_FAB2_LIB.BASEBOARD_FAB2(SCH_1):PAGE53
  J6L1  249 DQ<35> SCONN288_H44441003_PIP-SCONN,HA   I111 @BASEBOARD_FAB2_LIB.BASEBOARD_FAB2(SCH_1):PAGE54

M_F_DQ<36> @BASEBOARD_FAB2_LIB.BASEBOARD_FAB2(SCH_1):M_F_DQ(36)
  U5D1 DA42 DDR5_DQ<36> SKX_EXT_B_BGA1-IC,TBD   I172 @BASEBOARD_FAB2_LIB.BASEBOARD_FAB2(SCH_1):PAGE28
  J4A1  240 DQ<37> SCONN288_H44441004_PIP-SCONN,HA   I111 @BASEBOARD_FAB2_LIB.BASEBOARD_FAB2(SCH_1):PAGE53
  J6L1   95 DQ<36> SCONN288_H44441003_PIP-SCONN,HA   I111 @BASEBOARD_FAB2_LIB.BASEBOARD_FAB2(SCH_1):PAGE54

M_F_DQ<37> @BASEBOARD_FAB2_LIB.BASEBOARD_FAB2(SCH_1):M_F_DQ(37)
  U5D1 DE42 DDR5_DQ<37> SKX_EXT_B_BGA1-IC,TBD   I172 @BASEBOARD_FAB2_LIB.BASEBOARD_FAB2(SCH_1):PAGE28
  J4A1   95 DQ<36> SCONN288_H44441004_PIP-SCONN,HA   I111 @BASEBOARD_FAB2_LIB.BASEBOARD_FAB2(SCH_1):PAGE53
  J6L1  240 DQ<37> SCONN288_H44441003_PIP-SCONN,HA   I111 @BASEBOARD_FAB2_LIB.BASEBOARD_FAB2(SCH_1):PAGE54

M_F_DQ<38> @BASEBOARD_FAB2_LIB.BASEBOARD_FAB2(SCH_1):M_F_DQ(38)
  U5D1 DD39 DDR5_DQ<38> SKX_EXT_B_BGA1-IC,TBD   I172 @BASEBOARD_FAB2_LIB.BASEBOARD_FAB2(SCH_1):PAGE28
  J4A1  247 DQ<39> SCONN288_H44441004_PIP-SCONN,HA   I111 @BASEBOARD_FAB2_LIB.BASEBOARD_FAB2(SCH_1):PAGE53
  J6L1  102 DQ<38> SCONN288_H44441003_PIP-SCONN,HA   I111 @BASEBOARD_FAB2_LIB.BASEBOARD_FAB2(SCH_1):PAGE54

M_F_DQ<39> @BASEBOARD_FAB2_LIB.BASEBOARD_FAB2(SCH_1):M_F_DQ(39)
  U5D1 DH39 DDR5_DQ<39> SKX_EXT_B_BGA1-IC,TBD   I172 @BASEBOARD_FAB2_LIB.BASEBOARD_FAB2(SCH_1):PAGE28
  J4A1  102 DQ<38> SCONN288_H44441004_PIP-SCONN,HA   I111 @BASEBOARD_FAB2_LIB.BASEBOARD_FAB2(SCH_1):PAGE53
  J6L1  247 DQ<39> SCONN288_H44441003_PIP-SCONN,HA   I111 @BASEBOARD_FAB2_LIB.BASEBOARD_FAB2(SCH_1):PAGE54

M_F_DQ<3> @BASEBOARD_FAB2_LIB.BASEBOARD_FAB2(SCH_1):M_F_DQ(3)
  U5D1 CV77 DDR5_DQ<3> SKX_EXT_B_BGA1-IC,TBD   I172 @BASEBOARD_FAB2_LIB.BASEBOARD_FAB2(SCH_1):PAGE28
  J4A1   12  DQ<2> SCONN288_H44441004_PIP-SCONN,HA   I111 @BASEBOARD_FAB2_LIB.BASEBOARD_FAB2(SCH_1):PAGE53
  J6L1  157  DQ<3> SCONN288_H44441003_PIP-SCONN,HA   I111 @BASEBOARD_FAB2_LIB.BASEBOARD_FAB2(SCH_1):PAGE54

M_F_DQ<40> @BASEBOARD_FAB2_LIB.BASEBOARD_FAB2(SCH_1):M_F_DQ(40)
  U5D1 DF33 DDR5_DQ<40> SKX_EXT_B_BGA1-IC,TBD   I172 @BASEBOARD_FAB2_LIB.BASEBOARD_FAB2(SCH_1):PAGE28
  J4A1  253 DQ<41> SCONN288_H44441004_PIP-SCONN,HA   I111 @BASEBOARD_FAB2_LIB.BASEBOARD_FAB2(SCH_1):PAGE53
  J6L1  108 DQ<40> SCONN288_H44441003_PIP-SCONN,HA   I111 @BASEBOARD_FAB2_LIB.BASEBOARD_FAB2(SCH_1):PAGE54

M_F_DQ<41> @BASEBOARD_FAB2_LIB.BASEBOARD_FAB2(SCH_1):M_F_DQ(41)
  U5D1 DK33 DDR5_DQ<41> SKX_EXT_B_BGA1-IC,TBD   I172 @BASEBOARD_FAB2_LIB.BASEBOARD_FAB2(SCH_1):PAGE28
  J4A1  108 DQ<40> SCONN288_H44441004_PIP-SCONN,HA   I111 @BASEBOARD_FAB2_LIB.BASEBOARD_FAB2(SCH_1):PAGE53
  J6L1  253 DQ<41> SCONN288_H44441003_PIP-SCONN,HA   I111 @BASEBOARD_FAB2_LIB.BASEBOARD_FAB2(SCH_1):PAGE54

M_F_DQ<42> @BASEBOARD_FAB2_LIB.BASEBOARD_FAB2(SCH_1):M_F_DQ(42)
  U5D1 DG30 DDR5_DQ<42> SKX_EXT_B_BGA1-IC,TBD   I172 @BASEBOARD_FAB2_LIB.BASEBOARD_FAB2(SCH_1):PAGE28
  J4A1  260 DQ<43> SCONN288_H44441004_PIP-SCONN,HA   I111 @BASEBOARD_FAB2_LIB.BASEBOARD_FAB2(SCH_1):PAGE53
  J6L1  115 DQ<42> SCONN288_H44441003_PIP-SCONN,HA   I111 @BASEBOARD_FAB2_LIB.BASEBOARD_FAB2(SCH_1):PAGE54

M_F_DQ<43> @BASEBOARD_FAB2_LIB.BASEBOARD_FAB2(SCH_1):M_F_DQ(43)
  U5D1 DJ30 DDR5_DQ<43> SKX_EXT_B_BGA1-IC,TBD   I172 @BASEBOARD_FAB2_LIB.BASEBOARD_FAB2(SCH_1):PAGE28
  J4A1  115 DQ<42> SCONN288_H44441004_PIP-SCONN,HA   I111 @BASEBOARD_FAB2_LIB.BASEBOARD_FAB2(SCH_1):PAGE53
  J6L1  260 DQ<43> SCONN288_H44441003_PIP-SCONN,HA   I111 @BASEBOARD_FAB2_LIB.BASEBOARD_FAB2(SCH_1):PAGE54

M_F_DQ<44> @BASEBOARD_FAB2_LIB.BASEBOARD_FAB2(SCH_1):M_F_DQ(44)
  U5D1 DG34 DDR5_DQ<44> SKX_EXT_B_BGA1-IC,TBD   I172 @BASEBOARD_FAB2_LIB.BASEBOARD_FAB2(SCH_1):PAGE28
  J4A1  251 DQ<45> SCONN288_H44441004_PIP-SCONN,HA   I111 @BASEBOARD_FAB2_LIB.BASEBOARD_FAB2(SCH_1):PAGE53
  J6L1  106 DQ<44> SCONN288_H44441003_PIP-SCONN,HA   I111 @BASEBOARD_FAB2_LIB.BASEBOARD_FAB2(SCH_1):PAGE54

M_F_DQ<45> @BASEBOARD_FAB2_LIB.BASEBOARD_FAB2(SCH_1):M_F_DQ(45)
  U5D1 DJ34 DDR5_DQ<45> SKX_EXT_B_BGA1-IC,TBD   I172 @BASEBOARD_FAB2_LIB.BASEBOARD_FAB2(SCH_1):PAGE28
  J4A1  106 DQ<44> SCONN288_H44441004_PIP-SCONN,HA   I111 @BASEBOARD_FAB2_LIB.BASEBOARD_FAB2(SCH_1):PAGE53
  J6L1  251 DQ<45> SCONN288_H44441003_PIP-SCONN,HA   I111 @BASEBOARD_FAB2_LIB.BASEBOARD_FAB2(SCH_1):PAGE54

M_F_DQ<46> @BASEBOARD_FAB2_LIB.BASEBOARD_FAB2(SCH_1):M_F_DQ(46)
  U5D1 DF31 DDR5_DQ<46> SKX_EXT_B_BGA1-IC,TBD   I172 @BASEBOARD_FAB2_LIB.BASEBOARD_FAB2(SCH_1):PAGE28
  J4A1  258 DQ<47> SCONN288_H44441004_PIP-SCONN,HA   I111 @BASEBOARD_FAB2_LIB.BASEBOARD_FAB2(SCH_1):PAGE53
  J6L1  113 DQ<46> SCONN288_H44441003_PIP-SCONN,HA   I111 @BASEBOARD_FAB2_LIB.BASEBOARD_FAB2(SCH_1):PAGE54

M_F_DQ<47> @BASEBOARD_FAB2_LIB.BASEBOARD_FAB2(SCH_1):M_F_DQ(47)
  U5D1 DK31 DDR5_DQ<47> SKX_EXT_B_BGA1-IC,TBD   I172 @BASEBOARD_FAB2_LIB.BASEBOARD_FAB2(SCH_1):PAGE28
  J4A1  113 DQ<46> SCONN288_H44441004_PIP-SCONN,HA   I111 @BASEBOARD_FAB2_LIB.BASEBOARD_FAB2(SCH_1):PAGE53
  J6L1  258 DQ<47> SCONN288_H44441003_PIP-SCONN,HA   I111 @BASEBOARD_FAB2_LIB.BASEBOARD_FAB2(SCH_1):PAGE54

M_F_DQ<48> @BASEBOARD_FAB2_LIB.BASEBOARD_FAB2(SCH_1):M_F_DQ(48)
  U5D1 CW36 DDR5_DQ<48> SKX_EXT_B_BGA1-IC,TBD   I172 @BASEBOARD_FAB2_LIB.BASEBOARD_FAB2(SCH_1):PAGE28
  J4A1  264 DQ<49> SCONN288_H44441004_PIP-SCONN,HA   I111 @BASEBOARD_FAB2_LIB.BASEBOARD_FAB2(SCH_1):PAGE53
  J6L1  119 DQ<48> SCONN288_H44441003_PIP-SCONN,HA   I111 @BASEBOARD_FAB2_LIB.BASEBOARD_FAB2(SCH_1):PAGE54

M_F_DQ<49> @BASEBOARD_FAB2_LIB.BASEBOARD_FAB2(SCH_1):M_F_DQ(49)
  U5D1 DC36 DDR5_DQ<49> SKX_EXT_B_BGA1-IC,TBD   I172 @BASEBOARD_FAB2_LIB.BASEBOARD_FAB2(SCH_1):PAGE28
  J4A1  119 DQ<48> SCONN288_H44441004_PIP-SCONN,HA   I111 @BASEBOARD_FAB2_LIB.BASEBOARD_FAB2(SCH_1):PAGE53
  J6L1  264 DQ<49> SCONN288_H44441003_PIP-SCONN,HA   I111 @BASEBOARD_FAB2_LIB.BASEBOARD_FAB2(SCH_1):PAGE54

M_F_DQ<4> @BASEBOARD_FAB2_LIB.BASEBOARD_FAB2(SCH_1):M_F_DQ(4)
  U5D1 CN74 DDR5_DQ<4> SKX_EXT_B_BGA1-IC,TBD   I172 @BASEBOARD_FAB2_LIB.BASEBOARD_FAB2(SCH_1):PAGE28
  J4A1  148  DQ<5> SCONN288_H44441004_PIP-SCONN,HA   I111 @BASEBOARD_FAB2_LIB.BASEBOARD_FAB2(SCH_1):PAGE53
  J6L1    3  DQ<4> SCONN288_H44441003_PIP-SCONN,HA   I111 @BASEBOARD_FAB2_LIB.BASEBOARD_FAB2(SCH_1):PAGE54

M_F_DQ<50> @BASEBOARD_FAB2_LIB.BASEBOARD_FAB2(SCH_1):M_F_DQ(50)
  U5D1 CY33 DDR5_DQ<50> SKX_EXT_B_BGA1-IC,TBD   I172 @BASEBOARD_FAB2_LIB.BASEBOARD_FAB2(SCH_1):PAGE28
  J4A1  271 DQ<51> SCONN288_H44441004_PIP-SCONN,HA   I111 @BASEBOARD_FAB2_LIB.BASEBOARD_FAB2(SCH_1):PAGE53
  J6L1  126 DQ<50> SCONN288_H44441003_PIP-SCONN,HA   I111 @BASEBOARD_FAB2_LIB.BASEBOARD_FAB2(SCH_1):PAGE54

M_F_DQ<51> @BASEBOARD_FAB2_LIB.BASEBOARD_FAB2(SCH_1):M_F_DQ(51)
  U5D1 DB33 DDR5_DQ<51> SKX_EXT_B_BGA1-IC,TBD   I172 @BASEBOARD_FAB2_LIB.BASEBOARD_FAB2(SCH_1):PAGE28
  J4A1  126 DQ<50> SCONN288_H44441004_PIP-SCONN,HA   I111 @BASEBOARD_FAB2_LIB.BASEBOARD_FAB2(SCH_1):PAGE53
  J6L1  271 DQ<51> SCONN288_H44441003_PIP-SCONN,HA   I111 @BASEBOARD_FAB2_LIB.BASEBOARD_FAB2(SCH_1):PAGE54

M_F_DQ<52> @BASEBOARD_FAB2_LIB.BASEBOARD_FAB2(SCH_1):M_F_DQ(52)
  U5D1 CY37 DDR5_DQ<52> SKX_EXT_B_BGA1-IC,TBD   I172 @BASEBOARD_FAB2_LIB.BASEBOARD_FAB2(SCH_1):PAGE28
  J4A1  262 DQ<53> SCONN288_H44441004_PIP-SCONN,HA   I111 @BASEBOARD_FAB2_LIB.BASEBOARD_FAB2(SCH_1):PAGE53
  J6L1  117 DQ<52> SCONN288_H44441003_PIP-SCONN,HA   I111 @BASEBOARD_FAB2_LIB.BASEBOARD_FAB2(SCH_1):PAGE54

M_F_DQ<53> @BASEBOARD_FAB2_LIB.BASEBOARD_FAB2(SCH_1):M_F_DQ(53)
  U5D1 DB37 DDR5_DQ<53> SKX_EXT_B_BGA1-IC,TBD   I172 @BASEBOARD_FAB2_LIB.BASEBOARD_FAB2(SCH_1):PAGE28
  J4A1  117 DQ<52> SCONN288_H44441004_PIP-SCONN,HA   I111 @BASEBOARD_FAB2_LIB.BASEBOARD_FAB2(SCH_1):PAGE53
  J6L1  262 DQ<53> SCONN288_H44441003_PIP-SCONN,HA   I111 @BASEBOARD_FAB2_LIB.BASEBOARD_FAB2(SCH_1):PAGE54

M_F_DQ<54> @BASEBOARD_FAB2_LIB.BASEBOARD_FAB2(SCH_1):M_F_DQ(54)
  U5D1 CW34 DDR5_DQ<54> SKX_EXT_B_BGA1-IC,TBD   I172 @BASEBOARD_FAB2_LIB.BASEBOARD_FAB2(SCH_1):PAGE28
  J4A1  269 DQ<55> SCONN288_H44441004_PIP-SCONN,HA   I111 @BASEBOARD_FAB2_LIB.BASEBOARD_FAB2(SCH_1):PAGE53
  J6L1  124 DQ<54> SCONN288_H44441003_PIP-SCONN,HA   I111 @BASEBOARD_FAB2_LIB.BASEBOARD_FAB2(SCH_1):PAGE54

M_F_DQ<55> @BASEBOARD_FAB2_LIB.BASEBOARD_FAB2(SCH_1):M_F_DQ(55)
  U5D1 DC34 DDR5_DQ<55> SKX_EXT_B_BGA1-IC,TBD   I172 @BASEBOARD_FAB2_LIB.BASEBOARD_FAB2(SCH_1):PAGE28
  J4A1  124 DQ<54> SCONN288_H44441004_PIP-SCONN,HA   I111 @BASEBOARD_FAB2_LIB.BASEBOARD_FAB2(SCH_1):PAGE53
  J6L1  269 DQ<55> SCONN288_H44441003_PIP-SCONN,HA   I111 @BASEBOARD_FAB2_LIB.BASEBOARD_FAB2(SCH_1):PAGE54

M_F_DQ<56> @BASEBOARD_FAB2_LIB.BASEBOARD_FAB2(SCH_1):M_F_DQ(56)
  U5D1 CW30 DDR5_DQ<56> SKX_EXT_B_BGA1-IC,TBD   I172 @BASEBOARD_FAB2_LIB.BASEBOARD_FAB2(SCH_1):PAGE28
  J4A1  275 DQ<57> SCONN288_H44441004_PIP-SCONN,HA   I111 @BASEBOARD_FAB2_LIB.BASEBOARD_FAB2(SCH_1):PAGE53
  J6L1  130 DQ<56> SCONN288_H44441003_PIP-SCONN,HA   I111 @BASEBOARD_FAB2_LIB.BASEBOARD_FAB2(SCH_1):PAGE54

M_F_DQ<57> @BASEBOARD_FAB2_LIB.BASEBOARD_FAB2(SCH_1):M_F_DQ(57)
  U5D1 DC30 DDR5_DQ<57> SKX_EXT_B_BGA1-IC,TBD   I172 @BASEBOARD_FAB2_LIB.BASEBOARD_FAB2(SCH_1):PAGE28
  J4A1  130 DQ<56> SCONN288_H44441004_PIP-SCONN,HA   I111 @BASEBOARD_FAB2_LIB.BASEBOARD_FAB2(SCH_1):PAGE53
  J6L1  275 DQ<57> SCONN288_H44441003_PIP-SCONN,HA   I111 @BASEBOARD_FAB2_LIB.BASEBOARD_FAB2(SCH_1):PAGE54

M_F_DQ<58> @BASEBOARD_FAB2_LIB.BASEBOARD_FAB2(SCH_1):M_F_DQ(58)
  U5D1 CY27 DDR5_DQ<58> SKX_EXT_B_BGA1-IC,TBD   I172 @BASEBOARD_FAB2_LIB.BASEBOARD_FAB2(SCH_1):PAGE28
  J4A1  282 DQ<59> SCONN288_H44441004_PIP-SCONN,HA   I111 @BASEBOARD_FAB2_LIB.BASEBOARD_FAB2(SCH_1):PAGE53
  J6L1  137 DQ<58> SCONN288_H44441003_PIP-SCONN,HA   I111 @BASEBOARD_FAB2_LIB.BASEBOARD_FAB2(SCH_1):PAGE54

M_F_DQ<59> @BASEBOARD_FAB2_LIB.BASEBOARD_FAB2(SCH_1):M_F_DQ(59)
  U5D1 DB27 DDR5_DQ<59> SKX_EXT_B_BGA1-IC,TBD   I172 @BASEBOARD_FAB2_LIB.BASEBOARD_FAB2(SCH_1):PAGE28
  J4A1  137 DQ<58> SCONN288_H44441004_PIP-SCONN,HA   I111 @BASEBOARD_FAB2_LIB.BASEBOARD_FAB2(SCH_1):PAGE53
  J6L1  282 DQ<59> SCONN288_H44441003_PIP-SCONN,HA   I111 @BASEBOARD_FAB2_LIB.BASEBOARD_FAB2(SCH_1):PAGE54

M_F_DQ<5> @BASEBOARD_FAB2_LIB.BASEBOARD_FAB2(SCH_1):M_F_DQ(5)
  U5D1 CM75 DDR5_DQ<5> SKX_EXT_B_BGA1-IC,TBD   I172 @BASEBOARD_FAB2_LIB.BASEBOARD_FAB2(SCH_1):PAGE28
  J4A1    3  DQ<4> SCONN288_H44441004_PIP-SCONN,HA   I111 @BASEBOARD_FAB2_LIB.BASEBOARD_FAB2(SCH_1):PAGE53
  J6L1  148  DQ<5> SCONN288_H44441003_PIP-SCONN,HA   I111 @BASEBOARD_FAB2_LIB.BASEBOARD_FAB2(SCH_1):PAGE54

M_F_DQ<60> @BASEBOARD_FAB2_LIB.BASEBOARD_FAB2(SCH_1):M_F_DQ(60)
  U5D1 CY31 DDR5_DQ<60> SKX_EXT_B_BGA1-IC,TBD   I172 @BASEBOARD_FAB2_LIB.BASEBOARD_FAB2(SCH_1):PAGE28
  J4A1  273 DQ<61> SCONN288_H44441004_PIP-SCONN,HA   I111 @BASEBOARD_FAB2_LIB.BASEBOARD_FAB2(SCH_1):PAGE53
  J6L1  128 DQ<60> SCONN288_H44441003_PIP-SCONN,HA   I111 @BASEBOARD_FAB2_LIB.BASEBOARD_FAB2(SCH_1):PAGE54

M_F_DQ<61> @BASEBOARD_FAB2_LIB.BASEBOARD_FAB2(SCH_1):M_F_DQ(61)
  U5D1 DB31 DDR5_DQ<61> SKX_EXT_B_BGA1-IC,TBD   I172 @BASEBOARD_FAB2_LIB.BASEBOARD_FAB2(SCH_1):PAGE28
  J4A1  128 DQ<60> SCONN288_H44441004_PIP-SCONN,HA   I111 @BASEBOARD_FAB2_LIB.BASEBOARD_FAB2(SCH_1):PAGE53
  J6L1  273 DQ<61> SCONN288_H44441003_PIP-SCONN,HA   I111 @BASEBOARD_FAB2_LIB.BASEBOARD_FAB2(SCH_1):PAGE54

M_F_DQ<62> @BASEBOARD_FAB2_LIB.BASEBOARD_FAB2(SCH_1):M_F_DQ(62)
  U5D1 CW28 DDR5_DQ<62> SKX_EXT_B_BGA1-IC,TBD   I172 @BASEBOARD_FAB2_LIB.BASEBOARD_FAB2(SCH_1):PAGE28
  J4A1  280 DQ<63> SCONN288_H44441004_PIP-SCONN,HA   I111 @BASEBOARD_FAB2_LIB.BASEBOARD_FAB2(SCH_1):PAGE53
  J6L1  135 DQ<62> SCONN288_H44441003_PIP-SCONN,HA   I111 @BASEBOARD_FAB2_LIB.BASEBOARD_FAB2(SCH_1):PAGE54

M_F_DQ<63> @BASEBOARD_FAB2_LIB.BASEBOARD_FAB2(SCH_1):M_F_DQ(63)
  U5D1 DC28 DDR5_DQ<63> SKX_EXT_B_BGA1-IC,TBD   I172 @BASEBOARD_FAB2_LIB.BASEBOARD_FAB2(SCH_1):PAGE28
  J4A1  135 DQ<62> SCONN288_H44441004_PIP-SCONN,HA   I111 @BASEBOARD_FAB2_LIB.BASEBOARD_FAB2(SCH_1):PAGE53
  J6L1  280 DQ<63> SCONN288_H44441003_PIP-SCONN,HA   I111 @BASEBOARD_FAB2_LIB.BASEBOARD_FAB2(SCH_1):PAGE54

M_F_DQ<6> @BASEBOARD_FAB2_LIB.BASEBOARD_FAB2(SCH_1):M_F_DQ(6)
  U5D1 CV75 DDR5_DQ<6> SKX_EXT_B_BGA1-IC,TBD   I172 @BASEBOARD_FAB2_LIB.BASEBOARD_FAB2(SCH_1):PAGE28
  J4A1  155  DQ<7> SCONN288_H44441004_PIP-SCONN,HA   I111 @BASEBOARD_FAB2_LIB.BASEBOARD_FAB2(SCH_1):PAGE53
  J6L1   10  DQ<6> SCONN288_H44441003_PIP-SCONN,HA   I111 @BASEBOARD_FAB2_LIB.BASEBOARD_FAB2(SCH_1):PAGE54

M_F_DQ<7> @BASEBOARD_FAB2_LIB.BASEBOARD_FAB2(SCH_1):M_F_DQ(7)
  U5D1 CT77 DDR5_DQ<7> SKX_EXT_B_BGA1-IC,TBD   I172 @BASEBOARD_FAB2_LIB.BASEBOARD_FAB2(SCH_1):PAGE28
  J4A1   10  DQ<6> SCONN288_H44441004_PIP-SCONN,HA   I111 @BASEBOARD_FAB2_LIB.BASEBOARD_FAB2(SCH_1):PAGE53
  J6L1  155  DQ<7> SCONN288_H44441003_PIP-SCONN,HA   I111 @BASEBOARD_FAB2_LIB.BASEBOARD_FAB2(SCH_1):PAGE54

M_F_DQ<8> @BASEBOARD_FAB2_LIB.BASEBOARD_FAB2(SCH_1):M_F_DQ(8)
  U5D1 DE74 DDR5_DQ<8> SKX_EXT_B_BGA1-IC,TBD   I172 @BASEBOARD_FAB2_LIB.BASEBOARD_FAB2(SCH_1):PAGE28
  J4A1  161  DQ<9> SCONN288_H44441004_PIP-SCONN,HA   I111 @BASEBOARD_FAB2_LIB.BASEBOARD_FAB2(SCH_1):PAGE53
  J6L1   16  DQ<8> SCONN288_H44441003_PIP-SCONN,HA   I111 @BASEBOARD_FAB2_LIB.BASEBOARD_FAB2(SCH_1):PAGE54

M_F_DQ<9> @BASEBOARD_FAB2_LIB.BASEBOARD_FAB2(SCH_1):M_F_DQ(9)
  U5D1 DC76 DDR5_DQ<9> SKX_EXT_B_BGA1-IC,TBD   I172 @BASEBOARD_FAB2_LIB.BASEBOARD_FAB2(SCH_1):PAGE28
  J4A1   16  DQ<8> SCONN288_H44441004_PIP-SCONN,HA   I111 @BASEBOARD_FAB2_LIB.BASEBOARD_FAB2(SCH_1):PAGE53
  J6L1  161  DQ<9> SCONN288_H44441003_PIP-SCONN,HA   I111 @BASEBOARD_FAB2_LIB.BASEBOARD_FAB2(SCH_1):PAGE54

M_F_DQS_DN<0> @BASEBOARD_FAB2_LIB.BASEBOARD_FAB2(SCH_1):M_F_DQS_DN(0)
  U5D1 CP77 DDR5_DQS_DN<0> SKX_EXT_B_BGA1-IC,TBD   I172 @BASEBOARD_FAB2_LIB.BASEBOARD_FAB2(SCH_1):PAGE28
  J4A1  152  DQS0N SCONN288_H44441004_PIP-SCONN,HA    I66 @BASEBOARD_FAB2_LIB.BASEBOARD_FAB2(SCH_1):PAGE53
  J6L1  152  DQS0N SCONN288_H44441003_PIP-SCONN,HA    I66 @BASEBOARD_FAB2_LIB.BASEBOARD_FAB2(SCH_1):PAGE54

M_F_DQS_DN<10> @BASEBOARD_FAB2_LIB.BASEBOARD_FAB2(SCH_1):M_F_DQS_DN(10)
  U5D1 DF75 DDR5_DQS_DN<10> SKX_EXT_B_BGA1-IC,TBD   I172 @BASEBOARD_FAB2_LIB.BASEBOARD_FAB2(SCH_1):PAGE28
  J4A1   19 DQS10N SCONN288_H44441004_PIP-SCONN,HA    I66 @BASEBOARD_FAB2_LIB.BASEBOARD_FAB2(SCH_1):PAGE53
  J6L1   19 DQS10N SCONN288_H44441003_PIP-SCONN,HA    I66 @BASEBOARD_FAB2_LIB.BASEBOARD_FAB2(SCH_1):PAGE54

M_F_DQS_DN<11> @BASEBOARD_FAB2_LIB.BASEBOARD_FAB2(SCH_1):M_F_DQS_DN(11)
  U5D1 DJ70 DDR5_DQS_DN<11> SKX_EXT_B_BGA1-IC,TBD   I172 @BASEBOARD_FAB2_LIB.BASEBOARD_FAB2(SCH_1):PAGE28
  J4A1   30 DQS11N SCONN288_H44441004_PIP-SCONN,HA    I66 @BASEBOARD_FAB2_LIB.BASEBOARD_FAB2(SCH_1):PAGE53
  J6L1   30 DQS11N SCONN288_H44441003_PIP-SCONN,HA    I66 @BASEBOARD_FAB2_LIB.BASEBOARD_FAB2(SCH_1):PAGE54

M_F_DQS_DN<12> @BASEBOARD_FAB2_LIB.BASEBOARD_FAB2(SCH_1):M_F_DQS_DN(12)
  U5D1 CP65 DDR5_DQS_DN<12> SKX_EXT_B_BGA1-IC,TBD   I172 @BASEBOARD_FAB2_LIB.BASEBOARD_FAB2(SCH_1):PAGE28
  J4A1   41 DQS12N SCONN288_H44441004_PIP-SCONN,HA    I66 @BASEBOARD_FAB2_LIB.BASEBOARD_FAB2(SCH_1):PAGE53
  J6L1   41 DQS12N SCONN288_H44441003_PIP-SCONN,HA    I66 @BASEBOARD_FAB2_LIB.BASEBOARD_FAB2(SCH_1):PAGE54

M_F_DQS_DN<13> @BASEBOARD_FAB2_LIB.BASEBOARD_FAB2(SCH_1):M_F_DQS_DN(13)
  U5D1 DE40 DDR5_DQS_DN<13> SKX_EXT_B_BGA1-IC,TBD   I172 @BASEBOARD_FAB2_LIB.BASEBOARD_FAB2(SCH_1):PAGE28
  J4A1  100 DQS13N SCONN288_H44441004_PIP-SCONN,HA    I66 @BASEBOARD_FAB2_LIB.BASEBOARD_FAB2(SCH_1):PAGE53
  J6L1  100 DQS13N SCONN288_H44441003_PIP-SCONN,HA    I66 @BASEBOARD_FAB2_LIB.BASEBOARD_FAB2(SCH_1):PAGE54

M_F_DQS_DN<14> @BASEBOARD_FAB2_LIB.BASEBOARD_FAB2(SCH_1):M_F_DQS_DN(14)
  U5D1 DG32 DDR5_DQS_DN<14> SKX_EXT_B_BGA1-IC,TBD   I172 @BASEBOARD_FAB2_LIB.BASEBOARD_FAB2(SCH_1):PAGE28
  J4A1  111 DQS14N SCONN288_H44441004_PIP-SCONN,HA    I66 @BASEBOARD_FAB2_LIB.BASEBOARD_FAB2(SCH_1):PAGE53
  J6L1  111 DQS14N SCONN288_H44441003_PIP-SCONN,HA    I66 @BASEBOARD_FAB2_LIB.BASEBOARD_FAB2(SCH_1):PAGE54

M_F_DQS_DN<15> @BASEBOARD_FAB2_LIB.BASEBOARD_FAB2(SCH_1):M_F_DQS_DN(15)
  U5D1 CY35 DDR5_DQS_DN<15> SKX_EXT_B_BGA1-IC,TBD   I172 @BASEBOARD_FAB2_LIB.BASEBOARD_FAB2(SCH_1):PAGE28
  J4A1  122 DQS15N SCONN288_H44441004_PIP-SCONN,HA    I66 @BASEBOARD_FAB2_LIB.BASEBOARD_FAB2(SCH_1):PAGE53
  J6L1  122 DQS15N SCONN288_H44441003_PIP-SCONN,HA    I66 @BASEBOARD_FAB2_LIB.BASEBOARD_FAB2(SCH_1):PAGE54

M_F_DQS_DN<16> @BASEBOARD_FAB2_LIB.BASEBOARD_FAB2(SCH_1):M_F_DQS_DN(16)
  U5D1 CY29 DDR5_DQS_DN<16> SKX_EXT_B_BGA1-IC,TBD   I172 @BASEBOARD_FAB2_LIB.BASEBOARD_FAB2(SCH_1):PAGE28
  J4A1  133 DQS16N SCONN288_H44441004_PIP-SCONN,HA    I66 @BASEBOARD_FAB2_LIB.BASEBOARD_FAB2(SCH_1):PAGE53
  J6L1  133 DQS16N SCONN288_H44441003_PIP-SCONN,HA    I66 @BASEBOARD_FAB2_LIB.BASEBOARD_FAB2(SCH_1):PAGE54

M_F_DQS_DN<17> @BASEBOARD_FAB2_LIB.BASEBOARD_FAB2(SCH_1):M_F_DQS_DN(17)
  U5D1 CJ70 DDR5_DQS_DN<17> SKX_EXT_B_BGA1-IC,TBD   I172 @BASEBOARD_FAB2_LIB.BASEBOARD_FAB2(SCH_1):PAGE28
  J4A1   52 DQS17N SCONN288_H44441004_PIP-SCONN,HA    I66 @BASEBOARD_FAB2_LIB.BASEBOARD_FAB2(SCH_1):PAGE53
  J6L1   52 DQS17N SCONN288_H44441003_PIP-SCONN,HA    I66 @BASEBOARD_FAB2_LIB.BASEBOARD_FAB2(SCH_1):PAGE54

M_F_DQS_DN<1> @BASEBOARD_FAB2_LIB.BASEBOARD_FAB2(SCH_1):M_F_DQS_DN(1)
  U5D1 DD77 DDR5_DQS_DN<1> SKX_EXT_B_BGA1-IC,TBD   I172 @BASEBOARD_FAB2_LIB.BASEBOARD_FAB2(SCH_1):PAGE28
  J4A1  163  DQS1N SCONN288_H44441004_PIP-SCONN,HA    I66 @BASEBOARD_FAB2_LIB.BASEBOARD_FAB2(SCH_1):PAGE53
  J6L1  163  DQS1N SCONN288_H44441003_PIP-SCONN,HA    I66 @BASEBOARD_FAB2_LIB.BASEBOARD_FAB2(SCH_1):PAGE54

M_F_DQS_DN<2> @BASEBOARD_FAB2_LIB.BASEBOARD_FAB2(SCH_1):M_F_DQS_DN(2)
  U5D1 DL72 DDR5_DQS_DN<2> SKX_EXT_B_BGA1-IC,TBD   I172 @BASEBOARD_FAB2_LIB.BASEBOARD_FAB2(SCH_1):PAGE28
  J4A1  174  DQS2N SCONN288_H44441004_PIP-SCONN,HA    I66 @BASEBOARD_FAB2_LIB.BASEBOARD_FAB2(SCH_1):PAGE53
  J6L1  174  DQS2N SCONN288_H44441003_PIP-SCONN,HA    I66 @BASEBOARD_FAB2_LIB.BASEBOARD_FAB2(SCH_1):PAGE54

M_F_DQS_DN<3> @BASEBOARD_FAB2_LIB.BASEBOARD_FAB2(SCH_1):M_F_DQS_DN(3)
  U5D1 CV65 DDR5_DQS_DN<3> SKX_EXT_B_BGA1-IC,TBD   I172 @BASEBOARD_FAB2_LIB.BASEBOARD_FAB2(SCH_1):PAGE28
  J4A1  185  DQS3N SCONN288_H44441004_PIP-SCONN,HA    I66 @BASEBOARD_FAB2_LIB.BASEBOARD_FAB2(SCH_1):PAGE53
  J6L1  185  DQS3N SCONN288_H44441003_PIP-SCONN,HA    I66 @BASEBOARD_FAB2_LIB.BASEBOARD_FAB2(SCH_1):PAGE54

M_F_DQS_DN<4> @BASEBOARD_FAB2_LIB.BASEBOARD_FAB2(SCH_1):M_F_DQS_DN(4)
  U5D1 DG40 DDR5_DQS_DN<4> SKX_EXT_B_BGA1-IC,TBD   I172 @BASEBOARD_FAB2_LIB.BASEBOARD_FAB2(SCH_1):PAGE28
  J4A1  244  DQS4N SCONN288_H44441004_PIP-SCONN,HA    I66 @BASEBOARD_FAB2_LIB.BASEBOARD_FAB2(SCH_1):PAGE53
  J6L1  244  DQS4N SCONN288_H44441003_PIP-SCONN,HA    I66 @BASEBOARD_FAB2_LIB.BASEBOARD_FAB2(SCH_1):PAGE54

M_F_DQS_DN<5> @BASEBOARD_FAB2_LIB.BASEBOARD_FAB2(SCH_1):M_F_DQS_DN(5)
  U5D1 DL32 DDR5_DQS_DN<5> SKX_EXT_B_BGA1-IC,TBD   I172 @BASEBOARD_FAB2_LIB.BASEBOARD_FAB2(SCH_1):PAGE28
  J4A1  255  DQS5N SCONN288_H44441004_PIP-SCONN,HA    I66 @BASEBOARD_FAB2_LIB.BASEBOARD_FAB2(SCH_1):PAGE53
  J6L1  255  DQS5N SCONN288_H44441003_PIP-SCONN,HA    I66 @BASEBOARD_FAB2_LIB.BASEBOARD_FAB2(SCH_1):PAGE54

M_F_DQS_DN<6> @BASEBOARD_FAB2_LIB.BASEBOARD_FAB2(SCH_1):M_F_DQS_DN(6)
  U5D1 DD35 DDR5_DQS_DN<6> SKX_EXT_B_BGA1-IC,TBD   I172 @BASEBOARD_FAB2_LIB.BASEBOARD_FAB2(SCH_1):PAGE28
  J4A1  266  DQS6N SCONN288_H44441004_PIP-SCONN,HA    I66 @BASEBOARD_FAB2_LIB.BASEBOARD_FAB2(SCH_1):PAGE53
  J6L1  266  DQS6N SCONN288_H44441003_PIP-SCONN,HA    I66 @BASEBOARD_FAB2_LIB.BASEBOARD_FAB2(SCH_1):PAGE54

M_F_DQS_DN<7> @BASEBOARD_FAB2_LIB.BASEBOARD_FAB2(SCH_1):M_F_DQS_DN(7)
  U5D1 DD29 DDR5_DQS_DN<7> SKX_EXT_B_BGA1-IC,TBD   I172 @BASEBOARD_FAB2_LIB.BASEBOARD_FAB2(SCH_1):PAGE28
  J4A1  277  DQS7N SCONN288_H44441004_PIP-SCONN,HA    I66 @BASEBOARD_FAB2_LIB.BASEBOARD_FAB2(SCH_1):PAGE53
  J6L1  277  DQS7N SCONN288_H44441003_PIP-SCONN,HA    I66 @BASEBOARD_FAB2_LIB.BASEBOARD_FAB2(SCH_1):PAGE54

M_F_DQS_DN<8> @BASEBOARD_FAB2_LIB.BASEBOARD_FAB2(SCH_1):M_F_DQS_DN(8)
  U5D1 CN70 DDR5_DQS_DN<8> SKX_EXT_B_BGA1-IC,TBD   I172 @BASEBOARD_FAB2_LIB.BASEBOARD_FAB2(SCH_1):PAGE28
  J4A1  196  DQS8N SCONN288_H44441004_PIP-SCONN,HA    I66 @BASEBOARD_FAB2_LIB.BASEBOARD_FAB2(SCH_1):PAGE53
  J6L1  196  DQS8N SCONN288_H44441003_PIP-SCONN,HA    I66 @BASEBOARD_FAB2_LIB.BASEBOARD_FAB2(SCH_1):PAGE54

M_F_DQS_DN<9> @BASEBOARD_FAB2_LIB.BASEBOARD_FAB2(SCH_1):M_F_DQS_DN(9)
  U5D1 CT75 DDR5_DQS_DN<9> SKX_EXT_B_BGA1-IC,TBD   I172 @BASEBOARD_FAB2_LIB.BASEBOARD_FAB2(SCH_1):PAGE28
  J4A1    8  DQS9N SCONN288_H44441004_PIP-SCONN,HA    I66 @BASEBOARD_FAB2_LIB.BASEBOARD_FAB2(SCH_1):PAGE53
  J6L1    8  DQS9N SCONN288_H44441003_PIP-SCONN,HA    I66 @BASEBOARD_FAB2_LIB.BASEBOARD_FAB2(SCH_1):PAGE54

M_F_DQS_DP<0> @BASEBOARD_FAB2_LIB.BASEBOARD_FAB2(SCH_1):M_F_DQS_DP(0)
  U5D1 CR76 DDR5_DQS_DP<0> SKX_EXT_B_BGA1-IC,TBD   I172 @BASEBOARD_FAB2_LIB.BASEBOARD_FAB2(SCH_1):PAGE28
  J4A1  153  DQS0P SCONN288_H44441004_PIP-SCONN,HA    I66 @BASEBOARD_FAB2_LIB.BASEBOARD_FAB2(SCH_1):PAGE53
  J6L1  153  DQS0P SCONN288_H44441003_PIP-SCONN,HA    I66 @BASEBOARD_FAB2_LIB.BASEBOARD_FAB2(SCH_1):PAGE54

M_F_DQS_DP<10> @BASEBOARD_FAB2_LIB.BASEBOARD_FAB2(SCH_1):M_F_DQS_DP(10)
  U5D1 DG74 DDR5_DQS_DP<10> SKX_EXT_B_BGA1-IC,TBD   I172 @BASEBOARD_FAB2_LIB.BASEBOARD_FAB2(SCH_1):PAGE28
  J4A1   18 DQS10P SCONN288_H44441004_PIP-SCONN,HA    I66 @BASEBOARD_FAB2_LIB.BASEBOARD_FAB2(SCH_1):PAGE53
  J6L1   18 DQS10P SCONN288_H44441003_PIP-SCONN,HA    I66 @BASEBOARD_FAB2_LIB.BASEBOARD_FAB2(SCH_1):PAGE54

M_F_DQS_DP<11> @BASEBOARD_FAB2_LIB.BASEBOARD_FAB2(SCH_1):M_F_DQS_DP(11)
  U5D1 DH69 DDR5_DQS_DP<11> SKX_EXT_B_BGA1-IC,TBD   I172 @BASEBOARD_FAB2_LIB.BASEBOARD_FAB2(SCH_1):PAGE28
  J4A1   29 DQS11P SCONN288_H44441004_PIP-SCONN,HA    I66 @BASEBOARD_FAB2_LIB.BASEBOARD_FAB2(SCH_1):PAGE53
  J6L1   29 DQS11P SCONN288_H44441003_PIP-SCONN,HA    I66 @BASEBOARD_FAB2_LIB.BASEBOARD_FAB2(SCH_1):PAGE54

M_F_DQS_DP<12> @BASEBOARD_FAB2_LIB.BASEBOARD_FAB2(SCH_1):M_F_DQS_DP(12)
  U5D1 CM65 DDR5_DQS_DP<12> SKX_EXT_B_BGA1-IC,TBD   I172 @BASEBOARD_FAB2_LIB.BASEBOARD_FAB2(SCH_1):PAGE28
  J4A1   40 DQS12P SCONN288_H44441004_PIP-SCONN,HA    I66 @BASEBOARD_FAB2_LIB.BASEBOARD_FAB2(SCH_1):PAGE53
  J6L1   40 DQS12P SCONN288_H44441003_PIP-SCONN,HA    I66 @BASEBOARD_FAB2_LIB.BASEBOARD_FAB2(SCH_1):PAGE54

M_F_DQS_DP<13> @BASEBOARD_FAB2_LIB.BASEBOARD_FAB2(SCH_1):M_F_DQS_DP(13)
  U5D1 DC40 DDR5_DQS_DP<13> SKX_EXT_B_BGA1-IC,TBD   I172 @BASEBOARD_FAB2_LIB.BASEBOARD_FAB2(SCH_1):PAGE28
  J4A1   99 DQS13P SCONN288_H44441004_PIP-SCONN,HA    I66 @BASEBOARD_FAB2_LIB.BASEBOARD_FAB2(SCH_1):PAGE53
  J6L1   99 DQS13P SCONN288_H44441003_PIP-SCONN,HA    I66 @BASEBOARD_FAB2_LIB.BASEBOARD_FAB2(SCH_1):PAGE54

M_F_DQS_DP<14> @BASEBOARD_FAB2_LIB.BASEBOARD_FAB2(SCH_1):M_F_DQS_DP(14)
  U5D1 DE32 DDR5_DQS_DP<14> SKX_EXT_B_BGA1-IC,TBD   I172 @BASEBOARD_FAB2_LIB.BASEBOARD_FAB2(SCH_1):PAGE28
  J4A1  110 DQS14P SCONN288_H44441004_PIP-SCONN,HA    I66 @BASEBOARD_FAB2_LIB.BASEBOARD_FAB2(SCH_1):PAGE53
  J6L1  110 DQS14P SCONN288_H44441003_PIP-SCONN,HA    I66 @BASEBOARD_FAB2_LIB.BASEBOARD_FAB2(SCH_1):PAGE54

M_F_DQS_DP<15> @BASEBOARD_FAB2_LIB.BASEBOARD_FAB2(SCH_1):M_F_DQS_DP(15)
  U5D1 CV35 DDR5_DQS_DP<15> SKX_EXT_B_BGA1-IC,TBD   I172 @BASEBOARD_FAB2_LIB.BASEBOARD_FAB2(SCH_1):PAGE28
  J4A1  121 DQS15P SCONN288_H44441004_PIP-SCONN,HA    I66 @BASEBOARD_FAB2_LIB.BASEBOARD_FAB2(SCH_1):PAGE53
  J6L1  121 DQS15P SCONN288_H44441003_PIP-SCONN,HA    I66 @BASEBOARD_FAB2_LIB.BASEBOARD_FAB2(SCH_1):PAGE54

M_F_DQS_DP<16> @BASEBOARD_FAB2_LIB.BASEBOARD_FAB2(SCH_1):M_F_DQS_DP(16)
  U5D1 CV29 DDR5_DQS_DP<16> SKX_EXT_B_BGA1-IC,TBD   I172 @BASEBOARD_FAB2_LIB.BASEBOARD_FAB2(SCH_1):PAGE28
  J4A1  132 DQS16P SCONN288_H44441004_PIP-SCONN,HA    I66 @BASEBOARD_FAB2_LIB.BASEBOARD_FAB2(SCH_1):PAGE53
  J6L1  132 DQS16P SCONN288_H44441003_PIP-SCONN,HA    I66 @BASEBOARD_FAB2_LIB.BASEBOARD_FAB2(SCH_1):PAGE54

M_F_DQS_DP<17> @BASEBOARD_FAB2_LIB.BASEBOARD_FAB2(SCH_1):M_F_DQS_DP(17)
  U5D1 CG70 DDR5_DQS_DP<17> SKX_EXT_B_BGA1-IC,TBD   I172 @BASEBOARD_FAB2_LIB.BASEBOARD_FAB2(SCH_1):PAGE28
  J4A1   51 DQS17P SCONN288_H44441004_PIP-SCONN,HA    I66 @BASEBOARD_FAB2_LIB.BASEBOARD_FAB2(SCH_1):PAGE53
  J6L1   51 DQS17P SCONN288_H44441003_PIP-SCONN,HA    I66 @BASEBOARD_FAB2_LIB.BASEBOARD_FAB2(SCH_1):PAGE54

M_F_DQS_DP<1> @BASEBOARD_FAB2_LIB.BASEBOARD_FAB2(SCH_1):M_F_DQS_DP(1)
  U5D1 DE76 DDR5_DQS_DP<1> SKX_EXT_B_BGA1-IC,TBD   I172 @BASEBOARD_FAB2_LIB.BASEBOARD_FAB2(SCH_1):PAGE28
  J4A1  164  DQS1P SCONN288_H44441004_PIP-SCONN,HA    I66 @BASEBOARD_FAB2_LIB.BASEBOARD_FAB2(SCH_1):PAGE53
  J6L1  164  DQS1P SCONN288_H44441003_PIP-SCONN,HA    I66 @BASEBOARD_FAB2_LIB.BASEBOARD_FAB2(SCH_1):PAGE54

M_F_DQS_DP<2> @BASEBOARD_FAB2_LIB.BASEBOARD_FAB2(SCH_1):M_F_DQS_DP(2)
  U5D1 DK71 DDR5_DQS_DP<2> SKX_EXT_B_BGA1-IC,TBD   I172 @BASEBOARD_FAB2_LIB.BASEBOARD_FAB2(SCH_1):PAGE28
  J4A1  175  DQS2P SCONN288_H44441004_PIP-SCONN,HA    I66 @BASEBOARD_FAB2_LIB.BASEBOARD_FAB2(SCH_1):PAGE53
  J6L1  175  DQS2P SCONN288_H44441003_PIP-SCONN,HA    I66 @BASEBOARD_FAB2_LIB.BASEBOARD_FAB2(SCH_1):PAGE54

M_F_DQS_DP<3> @BASEBOARD_FAB2_LIB.BASEBOARD_FAB2(SCH_1):M_F_DQS_DP(3)
  U5D1 CT65 DDR5_DQS_DP<3> SKX_EXT_B_BGA1-IC,TBD   I172 @BASEBOARD_FAB2_LIB.BASEBOARD_FAB2(SCH_1):PAGE28
  J4A1  186  DQS3P SCONN288_H44441004_PIP-SCONN,HA    I66 @BASEBOARD_FAB2_LIB.BASEBOARD_FAB2(SCH_1):PAGE53
  J6L1  186  DQS3P SCONN288_H44441003_PIP-SCONN,HA    I66 @BASEBOARD_FAB2_LIB.BASEBOARD_FAB2(SCH_1):PAGE54

M_F_DQS_DP<4> @BASEBOARD_FAB2_LIB.BASEBOARD_FAB2(SCH_1):M_F_DQS_DP(4)
  U5D1 DJ40 DDR5_DQS_DP<4> SKX_EXT_B_BGA1-IC,TBD   I172 @BASEBOARD_FAB2_LIB.BASEBOARD_FAB2(SCH_1):PAGE28
  J4A1  245  DQS4P SCONN288_H44441004_PIP-SCONN,HA    I66 @BASEBOARD_FAB2_LIB.BASEBOARD_FAB2(SCH_1):PAGE53
  J6L1  245  DQS4P SCONN288_H44441003_PIP-SCONN,HA    I66 @BASEBOARD_FAB2_LIB.BASEBOARD_FAB2(SCH_1):PAGE54

M_F_DQS_DP<5> @BASEBOARD_FAB2_LIB.BASEBOARD_FAB2(SCH_1):M_F_DQS_DP(5)
  U5D1 DJ32 DDR5_DQS_DP<5> SKX_EXT_B_BGA1-IC,TBD   I172 @BASEBOARD_FAB2_LIB.BASEBOARD_FAB2(SCH_1):PAGE28
  J4A1  256  DQS5P SCONN288_H44441004_PIP-SCONN,HA    I66 @BASEBOARD_FAB2_LIB.BASEBOARD_FAB2(SCH_1):PAGE53
  J6L1  256  DQS5P SCONN288_H44441003_PIP-SCONN,HA    I66 @BASEBOARD_FAB2_LIB.BASEBOARD_FAB2(SCH_1):PAGE54

M_F_DQS_DP<6> @BASEBOARD_FAB2_LIB.BASEBOARD_FAB2(SCH_1):M_F_DQS_DP(6)
  U5D1 DB35 DDR5_DQS_DP<6> SKX_EXT_B_BGA1-IC,TBD   I172 @BASEBOARD_FAB2_LIB.BASEBOARD_FAB2(SCH_1):PAGE28
  J4A1  267  DQS6P SCONN288_H44441004_PIP-SCONN,HA    I66 @BASEBOARD_FAB2_LIB.BASEBOARD_FAB2(SCH_1):PAGE53
  J6L1  267  DQS6P SCONN288_H44441003_PIP-SCONN,HA    I66 @BASEBOARD_FAB2_LIB.BASEBOARD_FAB2(SCH_1):PAGE54

M_F_DQS_DP<7> @BASEBOARD_FAB2_LIB.BASEBOARD_FAB2(SCH_1):M_F_DQS_DP(7)
  U5D1 DB29 DDR5_DQS_DP<7> SKX_EXT_B_BGA1-IC,TBD   I172 @BASEBOARD_FAB2_LIB.BASEBOARD_FAB2(SCH_1):PAGE28
  J4A1  278  DQS7P SCONN288_H44441004_PIP-SCONN,HA    I66 @BASEBOARD_FAB2_LIB.BASEBOARD_FAB2(SCH_1):PAGE53
  J6L1  278  DQS7P SCONN288_H44441003_PIP-SCONN,HA    I66 @BASEBOARD_FAB2_LIB.BASEBOARD_FAB2(SCH_1):PAGE54

M_F_DQS_DP<8> @BASEBOARD_FAB2_LIB.BASEBOARD_FAB2(SCH_1):M_F_DQS_DP(8)
  U5D1 CL70 DDR5_DQS_DP<8> SKX_EXT_B_BGA1-IC,TBD   I172 @BASEBOARD_FAB2_LIB.BASEBOARD_FAB2(SCH_1):PAGE28
  J4A1  197  DQS8P SCONN288_H44441004_PIP-SCONN,HA    I66 @BASEBOARD_FAB2_LIB.BASEBOARD_FAB2(SCH_1):PAGE53
  J6L1  197  DQS8P SCONN288_H44441003_PIP-SCONN,HA    I66 @BASEBOARD_FAB2_LIB.BASEBOARD_FAB2(SCH_1):PAGE54

M_F_DQS_DP<9> @BASEBOARD_FAB2_LIB.BASEBOARD_FAB2(SCH_1):M_F_DQS_DP(9)
  U5D1 CU74 DDR5_DQS_DP<9> SKX_EXT_B_BGA1-IC,TBD   I172 @BASEBOARD_FAB2_LIB.BASEBOARD_FAB2(SCH_1):PAGE28
  J4A1    7  DQS9P SCONN288_H44441004_PIP-SCONN,HA    I66 @BASEBOARD_FAB2_LIB.BASEBOARD_FAB2(SCH_1):PAGE53
  J6L1    7  DQS9P SCONN288_H44441003_PIP-SCONN,HA    I66 @BASEBOARD_FAB2_LIB.BASEBOARD_FAB2(SCH_1):PAGE54

M_F_ECC<0> @BASEBOARD_FAB2_LIB.BASEBOARD_FAB2(SCH_1):M_F_ECC(0)
  U5D1 CH71 DDR5_ECC<0> SKX_EXT_B_BGA1-IC,TBD   I172 @BASEBOARD_FAB2_LIB.BASEBOARD_FAB2(SCH_1):PAGE28
  J4A1  194  CB<1> SCONN288_H44441004_PIP-SCONN,HA   I111 @BASEBOARD_FAB2_LIB.BASEBOARD_FAB2(SCH_1):PAGE53
  J6L1   49  CB<0> SCONN288_H44441003_PIP-SCONN,HA   I111 @BASEBOARD_FAB2_LIB.BASEBOARD_FAB2(SCH_1):PAGE54

M_F_ECC<1> @BASEBOARD_FAB2_LIB.BASEBOARD_FAB2(SCH_1):M_F_ECC(1)
  U5D1 CM71 DDR5_ECC<1> SKX_EXT_B_BGA1-IC,TBD   I172 @BASEBOARD_FAB2_LIB.BASEBOARD_FAB2(SCH_1):PAGE28
  J4A1   49  CB<0> SCONN288_H44441004_PIP-SCONN,HA   I111 @BASEBOARD_FAB2_LIB.BASEBOARD_FAB2(SCH_1):PAGE53
  J6L1  194  CB<1> SCONN288_H44441003_PIP-SCONN,HA   I111 @BASEBOARD_FAB2_LIB.BASEBOARD_FAB2(SCH_1):PAGE54

M_F_ECC<2> @BASEBOARD_FAB2_LIB.BASEBOARD_FAB2(SCH_1):M_F_ECC(2)
  U5D1 CJ68 DDR5_ECC<2> SKX_EXT_B_BGA1-IC,TBD   I172 @BASEBOARD_FAB2_LIB.BASEBOARD_FAB2(SCH_1):PAGE28
  J4A1  201  CB<3> SCONN288_H44441004_PIP-SCONN,HA   I111 @BASEBOARD_FAB2_LIB.BASEBOARD_FAB2(SCH_1):PAGE53
  J6L1   56  CB<2> SCONN288_H44441003_PIP-SCONN,HA   I111 @BASEBOARD_FAB2_LIB.BASEBOARD_FAB2(SCH_1):PAGE54

M_F_ECC<3> @BASEBOARD_FAB2_LIB.BASEBOARD_FAB2(SCH_1):M_F_ECC(3)
  U5D1 CL68 DDR5_ECC<3> SKX_EXT_B_BGA1-IC,TBD   I172 @BASEBOARD_FAB2_LIB.BASEBOARD_FAB2(SCH_1):PAGE28
  J4A1   56  CB<2> SCONN288_H44441004_PIP-SCONN,HA   I111 @BASEBOARD_FAB2_LIB.BASEBOARD_FAB2(SCH_1):PAGE53
  J6L1  201  CB<3> SCONN288_H44441003_PIP-SCONN,HA   I111 @BASEBOARD_FAB2_LIB.BASEBOARD_FAB2(SCH_1):PAGE54

M_F_ECC<4> @BASEBOARD_FAB2_LIB.BASEBOARD_FAB2(SCH_1):M_F_ECC(4)
  U5D1 CJ72 DDR5_ECC<4> SKX_EXT_B_BGA1-IC,TBD   I172 @BASEBOARD_FAB2_LIB.BASEBOARD_FAB2(SCH_1):PAGE28
  J4A1  192  CB<5> SCONN288_H44441004_PIP-SCONN,HA   I111 @BASEBOARD_FAB2_LIB.BASEBOARD_FAB2(SCH_1):PAGE53
  J6L1   47  CB<4> SCONN288_H44441003_PIP-SCONN,HA   I111 @BASEBOARD_FAB2_LIB.BASEBOARD_FAB2(SCH_1):PAGE54

M_F_ECC<5> @BASEBOARD_FAB2_LIB.BASEBOARD_FAB2(SCH_1):M_F_ECC(5)
  U5D1 CL72 DDR5_ECC<5> SKX_EXT_B_BGA1-IC,TBD   I172 @BASEBOARD_FAB2_LIB.BASEBOARD_FAB2(SCH_1):PAGE28
  J4A1   47  CB<4> SCONN288_H44441004_PIP-SCONN,HA   I111 @BASEBOARD_FAB2_LIB.BASEBOARD_FAB2(SCH_1):PAGE53
  J6L1  192  CB<5> SCONN288_H44441003_PIP-SCONN,HA   I111 @BASEBOARD_FAB2_LIB.BASEBOARD_FAB2(SCH_1):PAGE54

M_F_ECC<6> @BASEBOARD_FAB2_LIB.BASEBOARD_FAB2(SCH_1):M_F_ECC(6)
  U5D1 CH69 DDR5_ECC<6> SKX_EXT_B_BGA1-IC,TBD   I172 @BASEBOARD_FAB2_LIB.BASEBOARD_FAB2(SCH_1):PAGE28
  J4A1  199  CB<7> SCONN288_H44441004_PIP-SCONN,HA   I111 @BASEBOARD_FAB2_LIB.BASEBOARD_FAB2(SCH_1):PAGE53
  J6L1   54  CB<6> SCONN288_H44441003_PIP-SCONN,HA   I111 @BASEBOARD_FAB2_LIB.BASEBOARD_FAB2(SCH_1):PAGE54

M_F_ECC<7> @BASEBOARD_FAB2_LIB.BASEBOARD_FAB2(SCH_1):M_F_ECC(7)
  U5D1 CM69 DDR5_ECC<7> SKX_EXT_B_BGA1-IC,TBD   I172 @BASEBOARD_FAB2_LIB.BASEBOARD_FAB2(SCH_1):PAGE28
  J4A1   54  CB<6> SCONN288_H44441004_PIP-SCONN,HA   I111 @BASEBOARD_FAB2_LIB.BASEBOARD_FAB2(SCH_1):PAGE53
  J6L1  199  CB<7> SCONN288_H44441003_PIP-SCONN,HA   I111 @BASEBOARD_FAB2_LIB.BASEBOARD_FAB2(SCH_1):PAGE54

M_F_MA<0> @BASEBOARD_FAB2_LIB.BASEBOARD_FAB2(SCH_1):M_F_MA(0)
  U5D1 DF53 DDR5_MA<0> SKX_EXT_B_BGA1-IC,TBD   I172 @BASEBOARD_FAB2_LIB.BASEBOARD_FAB2(SCH_1):PAGE28
  J4A1   79     A0 SCONN288_H44441004_PIP-SCONN,HA   I111 @BASEBOARD_FAB2_LIB.BASEBOARD_FAB2(SCH_1):PAGE53
  J6L1   79     A0 SCONN288_H44441003_PIP-SCONN,HA   I111 @BASEBOARD_FAB2_LIB.BASEBOARD_FAB2(SCH_1):PAGE54

M_F_MA<10> @BASEBOARD_FAB2_LIB.BASEBOARD_FAB2(SCH_1):M_F_MA(10)
  U5D1 DD55 DDR5_MA<10> SKX_EXT_B_BGA1-IC,TBD   I172 @BASEBOARD_FAB2_LIB.BASEBOARD_FAB2(SCH_1):PAGE28
  J4A1  225    A10 SCONN288_H44441004_PIP-SCONN,HA   I111 @BASEBOARD_FAB2_LIB.BASEBOARD_FAB2(SCH_1):PAGE53
  J6L1  225    A10 SCONN288_H44441003_PIP-SCONN,HA   I111 @BASEBOARD_FAB2_LIB.BASEBOARD_FAB2(SCH_1):PAGE54

M_F_MA<11> @BASEBOARD_FAB2_LIB.BASEBOARD_FAB2(SCH_1):M_F_MA(11)
  U5D1 DA60 DDR5_MA<11> SKX_EXT_B_BGA1-IC,TBD   I172 @BASEBOARD_FAB2_LIB.BASEBOARD_FAB2(SCH_1):PAGE28
  J4A1  210    A11 SCONN288_H44441004_PIP-SCONN,HA   I111 @BASEBOARD_FAB2_LIB.BASEBOARD_FAB2(SCH_1):PAGE53
  J6L1  210    A11 SCONN288_H44441003_PIP-SCONN,HA   I111 @BASEBOARD_FAB2_LIB.BASEBOARD_FAB2(SCH_1):PAGE54

M_F_MA<12> @BASEBOARD_FAB2_LIB.BASEBOARD_FAB2(SCH_1):M_F_MA(12)
  U5D1 DG60 DDR5_MA<12> SKX_EXT_B_BGA1-IC,TBD   I172 @BASEBOARD_FAB2_LIB.BASEBOARD_FAB2(SCH_1):PAGE28
  J4A1   65    A12 SCONN288_H44441004_PIP-SCONN,HA   I111 @BASEBOARD_FAB2_LIB.BASEBOARD_FAB2(SCH_1):PAGE53
  J6L1   65    A12 SCONN288_H44441003_PIP-SCONN,HA   I111 @BASEBOARD_FAB2_LIB.BASEBOARD_FAB2(SCH_1):PAGE54

M_F_MA<13> @BASEBOARD_FAB2_LIB.BASEBOARD_FAB2(SCH_1):M_F_MA(13)
  U5D1 DD53 DDR5_MA<13> SKX_EXT_B_BGA1-IC,TBD   I172 @BASEBOARD_FAB2_LIB.BASEBOARD_FAB2(SCH_1):PAGE28
  J4A1  232    A13 SCONN288_H44441004_PIP-SCONN,HA   I111 @BASEBOARD_FAB2_LIB.BASEBOARD_FAB2(SCH_1):PAGE53
  J6L1  232    A13 SCONN288_H44441003_PIP-SCONN,HA   I111 @BASEBOARD_FAB2_LIB.BASEBOARD_FAB2(SCH_1):PAGE54

M_F_MA<14> @BASEBOARD_FAB2_LIB.BASEBOARD_FAB2(SCH_1):M_F_MA(14)
  U5D1 DJ50 DDR5_MA<14> SKX_EXT_B_BGA1-IC,TBD   I172 @BASEBOARD_FAB2_LIB.BASEBOARD_FAB2(SCH_1):PAGE28
  J4A1  228 A14_WE_N SCONN288_H44441004_PIP-SCONN,HA   I111 @BASEBOARD_FAB2_LIB.BASEBOARD_FAB2(SCH_1):PAGE53
  J6L1  228 A14_WE_N SCONN288_H44441003_PIP-SCONN,HA   I111 @BASEBOARD_FAB2_LIB.BASEBOARD_FAB2(SCH_1):PAGE54

M_F_MA<15> @BASEBOARD_FAB2_LIB.BASEBOARD_FAB2(SCH_1):M_F_MA(15)
  U5D1 DC54 DDR5_MA<15> SKX_EXT_B_BGA1-IC,TBD   I172 @BASEBOARD_FAB2_LIB.BASEBOARD_FAB2(SCH_1):PAGE28
  J4A1   86 A15_CAS_N SCONN288_H44441004_PIP-SCONN,HA   I111 @BASEBOARD_FAB2_LIB.BASEBOARD_FAB2(SCH_1):PAGE53
  J6L1   86 A15_CAS_N SCONN288_H44441003_PIP-SCONN,HA   I111 @BASEBOARD_FAB2_LIB.BASEBOARD_FAB2(SCH_1):PAGE54

M_F_MA<16> @BASEBOARD_FAB2_LIB.BASEBOARD_FAB2(SCH_1):M_F_MA(16)
  U5D1 DG52 DDR5_MA<16> SKX_EXT_B_BGA1-IC,TBD   I172 @BASEBOARD_FAB2_LIB.BASEBOARD_FAB2(SCH_1):PAGE28
  J4A1   82 A16_RAS_N SCONN288_H44441004_PIP-SCONN,HA   I111 @BASEBOARD_FAB2_LIB.BASEBOARD_FAB2(SCH_1):PAGE53
  J6L1   82 A16_RAS_N SCONN288_H44441003_PIP-SCONN,HA   I111 @BASEBOARD_FAB2_LIB.BASEBOARD_FAB2(SCH_1):PAGE54

M_F_MA<17> @BASEBOARD_FAB2_LIB.BASEBOARD_FAB2(SCH_1):M_F_MA(17)
  U5D1 DE46 DDR5_MA<17> SKX_EXT_B_BGA1-IC,TBD   I172 @BASEBOARD_FAB2_LIB.BASEBOARD_FAB2(SCH_1):PAGE28
  J4A1  234    A17 SCONN288_H44441004_PIP-SCONN,HA   I111 @BASEBOARD_FAB2_LIB.BASEBOARD_FAB2(SCH_1):PAGE53
  J6L1  234    A17 SCONN288_H44441003_PIP-SCONN,HA   I111 @BASEBOARD_FAB2_LIB.BASEBOARD_FAB2(SCH_1):PAGE54

M_F_MA<1> @BASEBOARD_FAB2_LIB.BASEBOARD_FAB2(SCH_1):M_F_MA(1)
  U5D1 DC58 DDR5_MA<1> SKX_EXT_B_BGA1-IC,TBD   I172 @BASEBOARD_FAB2_LIB.BASEBOARD_FAB2(SCH_1):PAGE28
  J4A1   72     A1 SCONN288_H44441004_PIP-SCONN,HA   I111 @BASEBOARD_FAB2_LIB.BASEBOARD_FAB2(SCH_1):PAGE53
  J6L1   72     A1 SCONN288_H44441003_PIP-SCONN,HA   I111 @BASEBOARD_FAB2_LIB.BASEBOARD_FAB2(SCH_1):PAGE54

M_F_MA<2> @BASEBOARD_FAB2_LIB.BASEBOARD_FAB2(SCH_1):M_F_MA(2)
  U5D1 DD57 DDR5_MA<2> SKX_EXT_B_BGA1-IC,TBD   I172 @BASEBOARD_FAB2_LIB.BASEBOARD_FAB2(SCH_1):PAGE28
  J4A1  216     A2 SCONN288_H44441004_PIP-SCONN,HA   I111 @BASEBOARD_FAB2_LIB.BASEBOARD_FAB2(SCH_1):PAGE53
  J6L1  216     A2 SCONN288_H44441003_PIP-SCONN,HA   I111 @BASEBOARD_FAB2_LIB.BASEBOARD_FAB2(SCH_1):PAGE54

M_F_MA<3> @BASEBOARD_FAB2_LIB.BASEBOARD_FAB2(SCH_1):M_F_MA(3)
  U5D1 DG58 DDR5_MA<3> SKX_EXT_B_BGA1-IC,TBD   I172 @BASEBOARD_FAB2_LIB.BASEBOARD_FAB2(SCH_1):PAGE28
  J4A1   71     A3 SCONN288_H44441004_PIP-SCONN,HA   I111 @BASEBOARD_FAB2_LIB.BASEBOARD_FAB2(SCH_1):PAGE53
  J6L1   71     A3 SCONN288_H44441003_PIP-SCONN,HA   I111 @BASEBOARD_FAB2_LIB.BASEBOARD_FAB2(SCH_1):PAGE54

M_F_MA<4> @BASEBOARD_FAB2_LIB.BASEBOARD_FAB2(SCH_1):M_F_MA(4)
  U5D1 DJ58 DDR5_MA<4> SKX_EXT_B_BGA1-IC,TBD   I172 @BASEBOARD_FAB2_LIB.BASEBOARD_FAB2(SCH_1):PAGE28
  J4A1  214     A4 SCONN288_H44441004_PIP-SCONN,HA   I111 @BASEBOARD_FAB2_LIB.BASEBOARD_FAB2(SCH_1):PAGE53
  J6L1  214     A4 SCONN288_H44441003_PIP-SCONN,HA   I111 @BASEBOARD_FAB2_LIB.BASEBOARD_FAB2(SCH_1):PAGE54

M_F_MA<5> @BASEBOARD_FAB2_LIB.BASEBOARD_FAB2(SCH_1):M_F_MA(5)
  U5D1 DF59 DDR5_MA<5> SKX_EXT_B_BGA1-IC,TBD   I172 @BASEBOARD_FAB2_LIB.BASEBOARD_FAB2(SCH_1):PAGE28
  J4A1  213     A5 SCONN288_H44441004_PIP-SCONN,HA   I111 @BASEBOARD_FAB2_LIB.BASEBOARD_FAB2(SCH_1):PAGE53
  J6L1  213     A5 SCONN288_H44441003_PIP-SCONN,HA   I111 @BASEBOARD_FAB2_LIB.BASEBOARD_FAB2(SCH_1):PAGE54

M_F_MA<6> @BASEBOARD_FAB2_LIB.BASEBOARD_FAB2(SCH_1):M_F_MA(6)
  U5D1 DK59 DDR5_MA<6> SKX_EXT_B_BGA1-IC,TBD   I172 @BASEBOARD_FAB2_LIB.BASEBOARD_FAB2(SCH_1):PAGE28
  J4A1   69     A6 SCONN288_H44441004_PIP-SCONN,HA   I111 @BASEBOARD_FAB2_LIB.BASEBOARD_FAB2(SCH_1):PAGE53
  J6L1   69     A6 SCONN288_H44441003_PIP-SCONN,HA   I111 @BASEBOARD_FAB2_LIB.BASEBOARD_FAB2(SCH_1):PAGE54

M_F_MA<7> @BASEBOARD_FAB2_LIB.BASEBOARD_FAB2(SCH_1):M_F_MA(7)
  U5D1 DC60 DDR5_MA<7> SKX_EXT_B_BGA1-IC,TBD   I172 @BASEBOARD_FAB2_LIB.BASEBOARD_FAB2(SCH_1):PAGE28
  J4A1  211     A7 SCONN288_H44441004_PIP-SCONN,HA   I111 @BASEBOARD_FAB2_LIB.BASEBOARD_FAB2(SCH_1):PAGE53
  J6L1  211     A7 SCONN288_H44441003_PIP-SCONN,HA   I111 @BASEBOARD_FAB2_LIB.BASEBOARD_FAB2(SCH_1):PAGE54

M_F_MA<8> @BASEBOARD_FAB2_LIB.BASEBOARD_FAB2(SCH_1):M_F_MA(8)
  U5D1 DD59 DDR5_MA<8> SKX_EXT_B_BGA1-IC,TBD   I172 @BASEBOARD_FAB2_LIB.BASEBOARD_FAB2(SCH_1):PAGE28
  J4A1   68     A8 SCONN288_H44441004_PIP-SCONN,HA   I111 @BASEBOARD_FAB2_LIB.BASEBOARD_FAB2(SCH_1):PAGE53
  J6L1   68     A8 SCONN288_H44441003_PIP-SCONN,HA   I111 @BASEBOARD_FAB2_LIB.BASEBOARD_FAB2(SCH_1):PAGE54

M_F_MA<9> @BASEBOARD_FAB2_LIB.BASEBOARD_FAB2(SCH_1):M_F_MA(9)
  U5D1 DA58 DDR5_MA<9> SKX_EXT_B_BGA1-IC,TBD   I172 @BASEBOARD_FAB2_LIB.BASEBOARD_FAB2(SCH_1):PAGE28
  J4A1   66     A9 SCONN288_H44441004_PIP-SCONN,HA   I111 @BASEBOARD_FAB2_LIB.BASEBOARD_FAB2(SCH_1):PAGE53
  J6L1   66     A9 SCONN288_H44441003_PIP-SCONN,HA   I111 @BASEBOARD_FAB2_LIB.BASEBOARD_FAB2(SCH_1):PAGE54

M_F_ODT<0> @BASEBOARD_FAB2_LIB.BASEBOARD_FAB2(SCH_1):M_F_ODT(0)
  U5D1 DG50 DDR5_ODT<0> SKX_EXT_B_BGA1-IC,TBD   I172 @BASEBOARD_FAB2_LIB.BASEBOARD_FAB2(SCH_1):PAGE28
  J4A1   87 ODT<0> SCONN288_H44441004_PIP-SCONN,HA   I111 @BASEBOARD_FAB2_LIB.BASEBOARD_FAB2(SCH_1):PAGE53

M_F_ODT<1> @BASEBOARD_FAB2_LIB.BASEBOARD_FAB2(SCH_1):M_F_ODT(1)
  U5D1 DG48 DDR5_ODT<1> SKX_EXT_B_BGA1-IC,TBD   I172 @BASEBOARD_FAB2_LIB.BASEBOARD_FAB2(SCH_1):PAGE28
  J4A1   91 ODT<1> SCONN288_H44441004_PIP-SCONN,HA   I111 @BASEBOARD_FAB2_LIB.BASEBOARD_FAB2(SCH_1):PAGE53

M_F_ODT<2> @BASEBOARD_FAB2_LIB.BASEBOARD_FAB2(SCH_1):M_F_ODT(2)
  U5D1 DK49 DDR5_ODT<2> SKX_EXT_B_BGA1-IC,TBD   I172 @BASEBOARD_FAB2_LIB.BASEBOARD_FAB2(SCH_1):PAGE28
  J6L1   87 ODT<0> SCONN288_H44441003_PIP-SCONN,HA   I111 @BASEBOARD_FAB2_LIB.BASEBOARD_FAB2(SCH_1):PAGE54

M_F_ODT<3> @BASEBOARD_FAB2_LIB.BASEBOARD_FAB2(SCH_1):M_F_ODT(3)
  U5D1 DF47 DDR5_ODT<3> SKX_EXT_B_BGA1-IC,TBD   I172 @BASEBOARD_FAB2_LIB.BASEBOARD_FAB2(SCH_1):PAGE28
  J6L1   91 ODT<1> SCONN288_H44441003_PIP-SCONN,HA   I111 @BASEBOARD_FAB2_LIB.BASEBOARD_FAB2(SCH_1):PAGE54

M_F_PAR @BASEBOARD_FAB2_LIB.BASEBOARD_FAB2(SCH_1):M_F_PAR
  U5D1 DK53 DDR5_PAR SKX_EXT_B_BGA1-IC,TBD   I172 @BASEBOARD_FAB2_LIB.BASEBOARD_FAB2(SCH_1):PAGE28
  J4A1  222    PAR SCONN288_H44441004_PIP-SCONN,HA   I111 @BASEBOARD_FAB2_LIB.BASEBOARD_FAB2(SCH_1):PAGE53
  J6L1  222    PAR SCONN288_H44441003_PIP-SCONN,HA   I111 @BASEBOARD_FAB2_LIB.BASEBOARD_FAB2(SCH_1):PAGE54

M_F_VREF @BASEBOARD_FAB2_LIB.BASEBOARD_FAB2(SCH_1):M_F_VREF
  J4A1  146 VREFCA SCONN288_H44441004_PIP-SCONN,HA   I111 @BASEBOARD_FAB2_LIB.BASEBOARD_FAB2(SCH_1):PAGE53
  C6L1    1      A CAP_A_0402V-0.01UF,25V,10%,X7RA   I178 @BASEBOARD_FAB2_LIB.BASEBOARD_FAB2(SCH_1):PAGE53
  J6L1  146 VREFCA SCONN288_H44441003_PIP-SCONN,HA   I111 @BASEBOARD_FAB2_LIB.BASEBOARD_FAB2(SCH_1):PAGE54
  C4A5    1      A CAP_A_0402V-0.01UF,25V,10%,X7RA   I179 @BASEBOARD_FAB2_LIB.BASEBOARD_FAB2(SCH_1):PAGE54
  R6L2    2      B RES_0402-1.00K,1%,1/16W,CHIP,GA    I62 @BASEBOARD_FAB2_LIB.BASEBOARD_FAB2(SCH_1):PAGE98
  R6L1    1      A RES_0402-1.00K,1%,1/16W,CHIP,GA    I64 @BASEBOARD_FAB2_LIB.BASEBOARD_FAB2(SCH_1):PAGE98
  R6L3    2      B RES_0402-2,1.0%,1/16W,CHIP,G21A    I66 @BASEBOARD_FAB2_LIB.BASEBOARD_FAB2(SCH_1):PAGE98

M_GHJ_RST_N @BASEBOARD_FAB2_LIB.BASEBOARD_FAB2(SCH_1):M_GHJ_RST_N
  U2D1  U64 DDR012_RESET_N SKX_EXT_B_BGA1-IC,TBD   I172 @BASEBOARD_FAB2_LIB.BASEBOARD_FAB2(SCH_1):PAGE55
  J1G1   58 RESET_N SCONN288_H44441004_PIP-SCONN,HA   I111 @BASEBOARD_FAB2_LIB.BASEBOARD_FAB2(SCH_1):PAGE77
  J9T1   58 RESET_N SCONN288_H44441003_PIP-SCONN,HA    I13 @BASEBOARD_FAB2_LIB.BASEBOARD_FAB2(SCH_1):PAGE78
  J1G2   58 RESET_N SCONN288_H44441004_PIP-SCONN,HA   I111 @BASEBOARD_FAB2_LIB.BASEBOARD_FAB2(SCH_1):PAGE79
  J9U1   58 RESET_N SCONN288_H44441003_PIP-SCONN,HA    I24 @BASEBOARD_FAB2_LIB.BASEBOARD_FAB2(SCH_1):PAGE80
  J1G3   58 RESET_N SCONN288_H44441004_PIP-SCONN,HA   I186 @BASEBOARD_FAB2_LIB.BASEBOARD_FAB2(SCH_1):PAGE81
  J9U2   58 RESET_N SCONN288_H44441003_PIP-SCONN,HA   I187 @BASEBOARD_FAB2_LIB.BASEBOARD_FAB2(SCH_1):PAGE82

M_G_ACT_N @BASEBOARD_FAB2_LIB.BASEBOARD_FAB2(SCH_1):M_G_ACT_N
  U2D1  J60 DDR0_ACT_N SKX_EXT_B_BGA1-IC,TBD   I172 @BASEBOARD_FAB2_LIB.BASEBOARD_FAB2(SCH_1):PAGE57
  J1G1   62  ACT_N SCONN288_H44441004_PIP-SCONN,HA   I111 @BASEBOARD_FAB2_LIB.BASEBOARD_FAB2(SCH_1):PAGE77
  J9T1   62  ACT_N SCONN288_H44441003_PIP-SCONN,HA    I13 @BASEBOARD_FAB2_LIB.BASEBOARD_FAB2(SCH_1):PAGE78

M_G_ALERT_N @BASEBOARD_FAB2_LIB.BASEBOARD_FAB2(SCH_1):M_G_ALERT_N
  U2D1  B61 DDR0_ALERT_N SKX_EXT_B_BGA1-IC,TBD   I172 @BASEBOARD_FAB2_LIB.BASEBOARD_FAB2(SCH_1):PAGE57
  J1G1  208 ALERT_N SCONN288_H44441004_PIP-SCONN,HA   I111 @BASEBOARD_FAB2_LIB.BASEBOARD_FAB2(SCH_1):PAGE77
  J9T1  208 ALERT_N SCONN288_H44441003_PIP-SCONN,HA    I13 @BASEBOARD_FAB2_LIB.BASEBOARD_FAB2(SCH_1):PAGE78

M_G_BA<0> @BASEBOARD_FAB2_LIB.BASEBOARD_FAB2(SCH_1):M_G_BA(0)
  U2D1  C52 DDR0_BA<0> SKX_EXT_B_BGA1-IC,TBD   I172 @BASEBOARD_FAB2_LIB.BASEBOARD_FAB2(SCH_1):PAGE57
  J1G1   81  BA<0> SCONN288_H44441004_PIP-SCONN,HA   I111 @BASEBOARD_FAB2_LIB.BASEBOARD_FAB2(SCH_1):PAGE77
  J9T1   81  BA<0> SCONN288_H44441003_PIP-SCONN,HA    I13 @BASEBOARD_FAB2_LIB.BASEBOARD_FAB2(SCH_1):PAGE78

M_G_BA<1> @BASEBOARD_FAB2_LIB.BASEBOARD_FAB2(SCH_1):M_G_BA(1)
  U2D1  G54 DDR0_BA<1> SKX_EXT_B_BGA1-IC,TBD   I172 @BASEBOARD_FAB2_LIB.BASEBOARD_FAB2(SCH_1):PAGE57
  J1G1  224  BA<1> SCONN288_H44441004_PIP-SCONN,HA   I111 @BASEBOARD_FAB2_LIB.BASEBOARD_FAB2(SCH_1):PAGE77
  J9T1  224  BA<1> SCONN288_H44441003_PIP-SCONN,HA    I13 @BASEBOARD_FAB2_LIB.BASEBOARD_FAB2(SCH_1):PAGE78

M_G_BG<0> @BASEBOARD_FAB2_LIB.BASEBOARD_FAB2(SCH_1):M_G_BG(0)
  U2D1  D61 DDR0_BG<0> SKX_EXT_B_BGA1-IC,TBD   I172 @BASEBOARD_FAB2_LIB.BASEBOARD_FAB2(SCH_1):PAGE57
  J1G1   63  BG<0> SCONN288_H44441004_PIP-SCONN,HA   I111 @BASEBOARD_FAB2_LIB.BASEBOARD_FAB2(SCH_1):PAGE77
  J9T1   63  BG<0> SCONN288_H44441003_PIP-SCONN,HA    I13 @BASEBOARD_FAB2_LIB.BASEBOARD_FAB2(SCH_1):PAGE78

M_G_BG<1> @BASEBOARD_FAB2_LIB.BASEBOARD_FAB2(SCH_1):M_G_BG(1)
  U2D1  F63 DDR0_BG<1> SKX_EXT_B_BGA1-IC,TBD   I172 @BASEBOARD_FAB2_LIB.BASEBOARD_FAB2(SCH_1):PAGE57
  J1G1  207  BG<1> SCONN288_H44441004_PIP-SCONN,HA   I111 @BASEBOARD_FAB2_LIB.BASEBOARD_FAB2(SCH_1):PAGE77
  J9T1  207  BG<1> SCONN288_H44441003_PIP-SCONN,HA    I13 @BASEBOARD_FAB2_LIB.BASEBOARD_FAB2(SCH_1):PAGE78

M_G_C<2> @BASEBOARD_FAB2_LIB.BASEBOARD_FAB2(SCH_1):M_G_C(2)
  U2D1  G46 DDR0_CID<2> SKX_EXT_B_BGA1-IC,TBD   I172 @BASEBOARD_FAB2_LIB.BASEBOARD_FAB2(SCH_1):PAGE57
  J1G1  235   C<2> SCONN288_H44441004_PIP-SCONN,HA   I111 @BASEBOARD_FAB2_LIB.BASEBOARD_FAB2(SCH_1):PAGE77
  J9T1  235   C<2> SCONN288_H44441003_PIP-SCONN,HA    I13 @BASEBOARD_FAB2_LIB.BASEBOARD_FAB2(SCH_1):PAGE78

M_G_CKE<0> @BASEBOARD_FAB2_LIB.BASEBOARD_FAB2(SCH_1):M_G_CKE(0)
  U2D1  C62 DDR0_CKE<0> SKX_EXT_B_BGA1-IC,TBD   I172 @BASEBOARD_FAB2_LIB.BASEBOARD_FAB2(SCH_1):PAGE57
  J1G1   60 CKE<0> SCONN288_H44441004_PIP-SCONN,HA   I111 @BASEBOARD_FAB2_LIB.BASEBOARD_FAB2(SCH_1):PAGE77

M_G_CKE<1> @BASEBOARD_FAB2_LIB.BASEBOARD_FAB2(SCH_1):M_G_CKE(1)
  U2D1  C64 DDR0_CKE<1> SKX_EXT_B_BGA1-IC,TBD   I172 @BASEBOARD_FAB2_LIB.BASEBOARD_FAB2(SCH_1):PAGE57
  J1G1  203 CKE<1> SCONN288_H44441004_PIP-SCONN,HA   I111 @BASEBOARD_FAB2_LIB.BASEBOARD_FAB2(SCH_1):PAGE77

M_G_CKE<2> @BASEBOARD_FAB2_LIB.BASEBOARD_FAB2(SCH_1):M_G_CKE(2)
  U2D1  B63 DDR0_CKE<2> SKX_EXT_B_BGA1-IC,TBD   I172 @BASEBOARD_FAB2_LIB.BASEBOARD_FAB2(SCH_1):PAGE57
  J9T1   60 CKE<0> SCONN288_H44441003_PIP-SCONN,HA    I13 @BASEBOARD_FAB2_LIB.BASEBOARD_FAB2(SCH_1):PAGE78

M_G_CKE<3> @BASEBOARD_FAB2_LIB.BASEBOARD_FAB2(SCH_1):M_G_CKE(3)
  U2D1  D63 DDR0_CKE<3> SKX_EXT_B_BGA1-IC,TBD   I172 @BASEBOARD_FAB2_LIB.BASEBOARD_FAB2(SCH_1):PAGE57
  J9T1  203 CKE<1> SCONN288_H44441003_PIP-SCONN,HA    I13 @BASEBOARD_FAB2_LIB.BASEBOARD_FAB2(SCH_1):PAGE78

M_G_CLK_DN<0> @BASEBOARD_FAB2_LIB.BASEBOARD_FAB2(SCH_1):M_G_CLK_DN(0)
  U2D1  F55 DDR0_CLK_DN<0> SKX_EXT_B_BGA1-IC,TBD   I172 @BASEBOARD_FAB2_LIB.BASEBOARD_FAB2(SCH_1):PAGE57
  J1G1   75   CK0N SCONN288_H44441004_PIP-SCONN,HA   I111 @BASEBOARD_FAB2_LIB.BASEBOARD_FAB2(SCH_1):PAGE77

M_G_CLK_DN<1> @BASEBOARD_FAB2_LIB.BASEBOARD_FAB2(SCH_1):M_G_CLK_DN(1)
  U2D1  C54 DDR0_CLK_DN<1> SKX_EXT_B_BGA1-IC,TBD   I172 @BASEBOARD_FAB2_LIB.BASEBOARD_FAB2(SCH_1):PAGE57
  J1G1  219   CK1N SCONN288_H44441004_PIP-SCONN,HA   I111 @BASEBOARD_FAB2_LIB.BASEBOARD_FAB2(SCH_1):PAGE77

M_G_CLK_DN<2> @BASEBOARD_FAB2_LIB.BASEBOARD_FAB2(SCH_1):M_G_CLK_DN(2)
  U2D1  J56 DDR0_CLK_DN<2> SKX_EXT_B_BGA1-IC,TBD   I172 @BASEBOARD_FAB2_LIB.BASEBOARD_FAB2(SCH_1):PAGE57
  J9T1   75   CK0N SCONN288_H44441003_PIP-SCONN,HA    I13 @BASEBOARD_FAB2_LIB.BASEBOARD_FAB2(SCH_1):PAGE78

M_G_CLK_DN<3> @BASEBOARD_FAB2_LIB.BASEBOARD_FAB2(SCH_1):M_G_CLK_DN(3)
  U2D1  C56 DDR0_CLK_DN<3> SKX_EXT_B_BGA1-IC,TBD   I172 @BASEBOARD_FAB2_LIB.BASEBOARD_FAB2(SCH_1):PAGE57
  J9T1  219   CK1N SCONN288_H44441003_PIP-SCONN,HA    I13 @BASEBOARD_FAB2_LIB.BASEBOARD_FAB2(SCH_1):PAGE78

M_G_CLK_DP<0> @BASEBOARD_FAB2_LIB.BASEBOARD_FAB2(SCH_1):M_G_CLK_DP(0)
  U2D1  D55 DDR0_CLK_DP<0> SKX_EXT_B_BGA1-IC,TBD   I172 @BASEBOARD_FAB2_LIB.BASEBOARD_FAB2(SCH_1):PAGE57
  J1G1   74   CK0P SCONN288_H44441004_PIP-SCONN,HA   I111 @BASEBOARD_FAB2_LIB.BASEBOARD_FAB2(SCH_1):PAGE77

M_G_CLK_DP<1> @BASEBOARD_FAB2_LIB.BASEBOARD_FAB2(SCH_1):M_G_CLK_DP(1)
  U2D1  B55 DDR0_CLK_DP<1> SKX_EXT_B_BGA1-IC,TBD   I172 @BASEBOARD_FAB2_LIB.BASEBOARD_FAB2(SCH_1):PAGE57
  J1G1  218   CK1P SCONN288_H44441004_PIP-SCONN,HA   I111 @BASEBOARD_FAB2_LIB.BASEBOARD_FAB2(SCH_1):PAGE77

M_G_CLK_DP<2> @BASEBOARD_FAB2_LIB.BASEBOARD_FAB2(SCH_1):M_G_CLK_DP(2)
  U2D1  G56 DDR0_CLK_DP<2> SKX_EXT_B_BGA1-IC,TBD   I172 @BASEBOARD_FAB2_LIB.BASEBOARD_FAB2(SCH_1):PAGE57
  J9T1   74   CK0P SCONN288_H44441003_PIP-SCONN,HA    I13 @BASEBOARD_FAB2_LIB.BASEBOARD_FAB2(SCH_1):PAGE78

M_G_CLK_DP<3> @BASEBOARD_FAB2_LIB.BASEBOARD_FAB2(SCH_1):M_G_CLK_DP(3)
  U2D1  B57 DDR0_CLK_DP<3> SKX_EXT_B_BGA1-IC,TBD   I172 @BASEBOARD_FAB2_LIB.BASEBOARD_FAB2(SCH_1):PAGE57
  J9T1  218   CK1P SCONN288_H44441003_PIP-SCONN,HA    I13 @BASEBOARD_FAB2_LIB.BASEBOARD_FAB2(SCH_1):PAGE78

M_G_CPU_VREF @BASEBOARD_FAB2_LIB.BASEBOARD_FAB2(SCH_1):M_G_CPU_VREF
  U2D1 AJ64 DDR0_CAVREF SKX_EXT_B_BGA1-IC,TBD   I172 @BASEBOARD_FAB2_LIB.BASEBOARD_FAB2(SCH_1):PAGE55
  R1F4    1      A RES_0402-2,1.0%,1/16W,CHIP,G21A     I7 @BASEBOARD_FAB2_LIB.BASEBOARD_FAB2(SCH_1):PAGE100
 C1F19    1      A CAP_A_0402V-0.01UF,25V,10%,X7RA     I8 @BASEBOARD_FAB2_LIB.BASEBOARD_FAB2(SCH_1):PAGE100

M_G_CS_N<0> @BASEBOARD_FAB2_LIB.BASEBOARD_FAB2(SCH_1):M_G_CS_N(0)
  U2D1  G52 DDR0_CS_N<0> SKX_EXT_B_BGA1-IC,TBD   I172 @BASEBOARD_FAB2_LIB.BASEBOARD_FAB2(SCH_1):PAGE57
  J1G1   84   S0_N SCONN288_H44441004_PIP-SCONN,HA   I111 @BASEBOARD_FAB2_LIB.BASEBOARD_FAB2(SCH_1):PAGE77

M_G_CS_N<1> @BASEBOARD_FAB2_LIB.BASEBOARD_FAB2(SCH_1):M_G_CS_N(1)
  U2D1  F49 DDR0_CS_N<1> SKX_EXT_B_BGA1-IC,TBD   I172 @BASEBOARD_FAB2_LIB.BASEBOARD_FAB2(SCH_1):PAGE57
  J1G1   89   S1_N SCONN288_H44441004_PIP-SCONN,HA   I111 @BASEBOARD_FAB2_LIB.BASEBOARD_FAB2(SCH_1):PAGE77

M_G_CS_N<2> @BASEBOARD_FAB2_LIB.BASEBOARD_FAB2(SCH_1):M_G_CS_N(2)
  U2D1  D47 DDR0_CS_N<2> SKX_EXT_B_BGA1-IC,TBD   I172 @BASEBOARD_FAB2_LIB.BASEBOARD_FAB2(SCH_1):PAGE57
  J1G1   93 S2_N_C<0> SCONN288_H44441004_PIP-SCONN,HA   I111 @BASEBOARD_FAB2_LIB.BASEBOARD_FAB2(SCH_1):PAGE77

M_G_CS_N<3> @BASEBOARD_FAB2_LIB.BASEBOARD_FAB2(SCH_1):M_G_CS_N(3)
  U2D1  F47 DDR0_CS_N<3> SKX_EXT_B_BGA1-IC,TBD   I172 @BASEBOARD_FAB2_LIB.BASEBOARD_FAB2(SCH_1):PAGE57
  J1G1  237 S3_N_C<1> SCONN288_H44441004_PIP-SCONN,HA   I111 @BASEBOARD_FAB2_LIB.BASEBOARD_FAB2(SCH_1):PAGE77

M_G_CS_N<4> @BASEBOARD_FAB2_LIB.BASEBOARD_FAB2(SCH_1):M_G_CS_N(4)
  U2D1  B51 DDR0_CS_N<4> SKX_EXT_B_BGA1-IC,TBD   I172 @BASEBOARD_FAB2_LIB.BASEBOARD_FAB2(SCH_1):PAGE57
  J9T1   84   S0_N SCONN288_H44441003_PIP-SCONN,HA    I13 @BASEBOARD_FAB2_LIB.BASEBOARD_FAB2(SCH_1):PAGE78

M_G_CS_N<5> @BASEBOARD_FAB2_LIB.BASEBOARD_FAB2(SCH_1):M_G_CS_N(5)
  U2D1  D49 DDR0_CS_N<5> SKX_EXT_B_BGA1-IC,TBD   I172 @BASEBOARD_FAB2_LIB.BASEBOARD_FAB2(SCH_1):PAGE57
  J9T1   89   S1_N SCONN288_H44441003_PIP-SCONN,HA    I13 @BASEBOARD_FAB2_LIB.BASEBOARD_FAB2(SCH_1):PAGE78

M_G_CS_N<6> @BASEBOARD_FAB2_LIB.BASEBOARD_FAB2(SCH_1):M_G_CS_N(6)
  U2D1  F45 DDR0_CS_N<6> SKX_EXT_B_BGA1-IC,TBD   I172 @BASEBOARD_FAB2_LIB.BASEBOARD_FAB2(SCH_1):PAGE57
  J9T1   93 S2_N_C<0> SCONN288_H44441003_PIP-SCONN,HA    I13 @BASEBOARD_FAB2_LIB.BASEBOARD_FAB2(SCH_1):PAGE78

M_G_CS_N<7> @BASEBOARD_FAB2_LIB.BASEBOARD_FAB2(SCH_1):M_G_CS_N(7)
  U2D1  K45 DDR0_CS_N<7> SKX_EXT_B_BGA1-IC,TBD   I172 @BASEBOARD_FAB2_LIB.BASEBOARD_FAB2(SCH_1):PAGE57
  J9T1  237 S3_N_C<1> SCONN288_H44441003_PIP-SCONN,HA    I13 @BASEBOARD_FAB2_LIB.BASEBOARD_FAB2(SCH_1):PAGE78

M_G_DQ<0> @BASEBOARD_FAB2_LIB.BASEBOARD_FAB2(SCH_1):M_G_DQ(0)
  U2D1 AN86 DDR0_DQ<0> SKX_EXT_B_BGA1-IC,TBD   I172 @BASEBOARD_FAB2_LIB.BASEBOARD_FAB2(SCH_1):PAGE57
  J1G1  150  DQ<1> SCONN288_H44441004_PIP-SCONN,HA   I111 @BASEBOARD_FAB2_LIB.BASEBOARD_FAB2(SCH_1):PAGE77
  J9T1    5  DQ<0> SCONN288_H44441003_PIP-SCONN,HA    I13 @BASEBOARD_FAB2_LIB.BASEBOARD_FAB2(SCH_1):PAGE78

M_G_DQ<10> @BASEBOARD_FAB2_LIB.BASEBOARD_FAB2(SCH_1):M_G_DQ(10)
  U2D1  L86 DDR0_DQ<10> SKX_EXT_B_BGA1-IC,TBD   I172 @BASEBOARD_FAB2_LIB.BASEBOARD_FAB2(SCH_1):PAGE57
  J1G1  168 DQ<11> SCONN288_H44441004_PIP-SCONN,HA   I111 @BASEBOARD_FAB2_LIB.BASEBOARD_FAB2(SCH_1):PAGE77
  J9T1   23 DQ<10> SCONN288_H44441003_PIP-SCONN,HA    I13 @BASEBOARD_FAB2_LIB.BASEBOARD_FAB2(SCH_1):PAGE78

M_G_DQ<11> @BASEBOARD_FAB2_LIB.BASEBOARD_FAB2(SCH_1):M_G_DQ(11)
  U2D1  L84 DDR0_DQ<11> SKX_EXT_B_BGA1-IC,TBD   I172 @BASEBOARD_FAB2_LIB.BASEBOARD_FAB2(SCH_1):PAGE57
  J1G1   23 DQ<10> SCONN288_H44441004_PIP-SCONN,HA   I111 @BASEBOARD_FAB2_LIB.BASEBOARD_FAB2(SCH_1):PAGE77
  J9T1  168 DQ<11> SCONN288_H44441003_PIP-SCONN,HA    I13 @BASEBOARD_FAB2_LIB.BASEBOARD_FAB2(SCH_1):PAGE78

M_G_DQ<12> @BASEBOARD_FAB2_LIB.BASEBOARD_FAB2(SCH_1):M_G_DQ(12)
  U2D1 AA86 DDR0_DQ<12> SKX_EXT_B_BGA1-IC,TBD   I172 @BASEBOARD_FAB2_LIB.BASEBOARD_FAB2(SCH_1):PAGE57
  J1G1  159 DQ<13> SCONN288_H44441004_PIP-SCONN,HA   I111 @BASEBOARD_FAB2_LIB.BASEBOARD_FAB2(SCH_1):PAGE77
  J9T1   14 DQ<12> SCONN288_H44441003_PIP-SCONN,HA    I13 @BASEBOARD_FAB2_LIB.BASEBOARD_FAB2(SCH_1):PAGE78

M_G_DQ<13> @BASEBOARD_FAB2_LIB.BASEBOARD_FAB2(SCH_1):M_G_DQ(13)
  U2D1 AA84 DDR0_DQ<13> SKX_EXT_B_BGA1-IC,TBD   I172 @BASEBOARD_FAB2_LIB.BASEBOARD_FAB2(SCH_1):PAGE57
  J1G1   14 DQ<12> SCONN288_H44441004_PIP-SCONN,HA   I111 @BASEBOARD_FAB2_LIB.BASEBOARD_FAB2(SCH_1):PAGE77
  J9T1  159 DQ<13> SCONN288_H44441003_PIP-SCONN,HA    I13 @BASEBOARD_FAB2_LIB.BASEBOARD_FAB2(SCH_1):PAGE78

M_G_DQ<14> @BASEBOARD_FAB2_LIB.BASEBOARD_FAB2(SCH_1):M_G_DQ(14)
  U2D1  N86 DDR0_DQ<14> SKX_EXT_B_BGA1-IC,TBD   I172 @BASEBOARD_FAB2_LIB.BASEBOARD_FAB2(SCH_1):PAGE57
  J1G1  166 DQ<15> SCONN288_H44441004_PIP-SCONN,HA   I111 @BASEBOARD_FAB2_LIB.BASEBOARD_FAB2(SCH_1):PAGE77
  J9T1   21 DQ<14> SCONN288_H44441003_PIP-SCONN,HA    I13 @BASEBOARD_FAB2_LIB.BASEBOARD_FAB2(SCH_1):PAGE78

M_G_DQ<15> @BASEBOARD_FAB2_LIB.BASEBOARD_FAB2(SCH_1):M_G_DQ(15)
  U2D1  N84 DDR0_DQ<15> SKX_EXT_B_BGA1-IC,TBD   I172 @BASEBOARD_FAB2_LIB.BASEBOARD_FAB2(SCH_1):PAGE57
  J1G1   21 DQ<14> SCONN288_H44441004_PIP-SCONN,HA   I111 @BASEBOARD_FAB2_LIB.BASEBOARD_FAB2(SCH_1):PAGE77
  J9T1  166 DQ<15> SCONN288_H44441003_PIP-SCONN,HA    I13 @BASEBOARD_FAB2_LIB.BASEBOARD_FAB2(SCH_1):PAGE78

M_G_DQ<16> @BASEBOARD_FAB2_LIB.BASEBOARD_FAB2(SCH_1):M_G_DQ(16)
  U2D1  V81 DDR0_DQ<16> SKX_EXT_B_BGA1-IC,TBD   I172 @BASEBOARD_FAB2_LIB.BASEBOARD_FAB2(SCH_1):PAGE57
  J1G1  172 DQ<17> SCONN288_H44441004_PIP-SCONN,HA   I111 @BASEBOARD_FAB2_LIB.BASEBOARD_FAB2(SCH_1):PAGE77
  J9T1   27 DQ<16> SCONN288_H44441003_PIP-SCONN,HA    I13 @BASEBOARD_FAB2_LIB.BASEBOARD_FAB2(SCH_1):PAGE78

M_G_DQ<17> @BASEBOARD_FAB2_LIB.BASEBOARD_FAB2(SCH_1):M_G_DQ(17)
  U2D1  T79 DDR0_DQ<17> SKX_EXT_B_BGA1-IC,TBD   I172 @BASEBOARD_FAB2_LIB.BASEBOARD_FAB2(SCH_1):PAGE57
  J1G1   27 DQ<16> SCONN288_H44441004_PIP-SCONN,HA   I111 @BASEBOARD_FAB2_LIB.BASEBOARD_FAB2(SCH_1):PAGE77
  J9T1  172 DQ<17> SCONN288_H44441003_PIP-SCONN,HA    I13 @BASEBOARD_FAB2_LIB.BASEBOARD_FAB2(SCH_1):PAGE78

M_G_DQ<18> @BASEBOARD_FAB2_LIB.BASEBOARD_FAB2(SCH_1):M_G_DQ(18)
  U2D1  N82 DDR0_DQ<18> SKX_EXT_B_BGA1-IC,TBD   I172 @BASEBOARD_FAB2_LIB.BASEBOARD_FAB2(SCH_1):PAGE57
  J1G1  179 DQ<19> SCONN288_H44441004_PIP-SCONN,HA   I111 @BASEBOARD_FAB2_LIB.BASEBOARD_FAB2(SCH_1):PAGE77
  J9T1   34 DQ<18> SCONN288_H44441003_PIP-SCONN,HA    I13 @BASEBOARD_FAB2_LIB.BASEBOARD_FAB2(SCH_1):PAGE78

M_G_DQ<19> @BASEBOARD_FAB2_LIB.BASEBOARD_FAB2(SCH_1):M_G_DQ(19)
  U2D1  M81 DDR0_DQ<19> SKX_EXT_B_BGA1-IC,TBD   I172 @BASEBOARD_FAB2_LIB.BASEBOARD_FAB2(SCH_1):PAGE57
  J1G1   34 DQ<18> SCONN288_H44441004_PIP-SCONN,HA   I111 @BASEBOARD_FAB2_LIB.BASEBOARD_FAB2(SCH_1):PAGE77
  J9T1  179 DQ<19> SCONN288_H44441003_PIP-SCONN,HA    I13 @BASEBOARD_FAB2_LIB.BASEBOARD_FAB2(SCH_1):PAGE78

M_G_DQ<1> @BASEBOARD_FAB2_LIB.BASEBOARD_FAB2(SCH_1):M_G_DQ(1)
  U2D1 AN84 DDR0_DQ<1> SKX_EXT_B_BGA1-IC,TBD   I172 @BASEBOARD_FAB2_LIB.BASEBOARD_FAB2(SCH_1):PAGE57
  J1G1    5  DQ<0> SCONN288_H44441004_PIP-SCONN,HA   I111 @BASEBOARD_FAB2_LIB.BASEBOARD_FAB2(SCH_1):PAGE77
  J9T1  150  DQ<1> SCONN288_H44441003_PIP-SCONN,HA    I13 @BASEBOARD_FAB2_LIB.BASEBOARD_FAB2(SCH_1):PAGE78

M_G_DQ<20> @BASEBOARD_FAB2_LIB.BASEBOARD_FAB2(SCH_1):M_G_DQ(20)
  U2D1  W80 DDR0_DQ<20> SKX_EXT_B_BGA1-IC,TBD   I172 @BASEBOARD_FAB2_LIB.BASEBOARD_FAB2(SCH_1):PAGE57
  J1G1  170 DQ<21> SCONN288_H44441004_PIP-SCONN,HA   I111 @BASEBOARD_FAB2_LIB.BASEBOARD_FAB2(SCH_1):PAGE77
  J9T1   25 DQ<20> SCONN288_H44441003_PIP-SCONN,HA    I13 @BASEBOARD_FAB2_LIB.BASEBOARD_FAB2(SCH_1):PAGE78

M_G_DQ<21> @BASEBOARD_FAB2_LIB.BASEBOARD_FAB2(SCH_1):M_G_DQ(21)
  U2D1  V79 DDR0_DQ<21> SKX_EXT_B_BGA1-IC,TBD   I172 @BASEBOARD_FAB2_LIB.BASEBOARD_FAB2(SCH_1):PAGE57
  J1G1   25 DQ<20> SCONN288_H44441004_PIP-SCONN,HA   I111 @BASEBOARD_FAB2_LIB.BASEBOARD_FAB2(SCH_1):PAGE77
  J9T1  170 DQ<21> SCONN288_H44441003_PIP-SCONN,HA    I13 @BASEBOARD_FAB2_LIB.BASEBOARD_FAB2(SCH_1):PAGE78

M_G_DQ<22> @BASEBOARD_FAB2_LIB.BASEBOARD_FAB2(SCH_1):M_G_DQ(22)
  U2D1  R82 DDR0_DQ<22> SKX_EXT_B_BGA1-IC,TBD   I172 @BASEBOARD_FAB2_LIB.BASEBOARD_FAB2(SCH_1):PAGE57
  J1G1  177 DQ<23> SCONN288_H44441004_PIP-SCONN,HA   I111 @BASEBOARD_FAB2_LIB.BASEBOARD_FAB2(SCH_1):PAGE77
  J9T1   32 DQ<22> SCONN288_H44441003_PIP-SCONN,HA    I13 @BASEBOARD_FAB2_LIB.BASEBOARD_FAB2(SCH_1):PAGE78

M_G_DQ<23> @BASEBOARD_FAB2_LIB.BASEBOARD_FAB2(SCH_1):M_G_DQ(23)
  U2D1  N80 DDR0_DQ<23> SKX_EXT_B_BGA1-IC,TBD   I172 @BASEBOARD_FAB2_LIB.BASEBOARD_FAB2(SCH_1):PAGE57
  J1G1   32 DQ<22> SCONN288_H44441004_PIP-SCONN,HA   I111 @BASEBOARD_FAB2_LIB.BASEBOARD_FAB2(SCH_1):PAGE77
  J9T1  177 DQ<23> SCONN288_H44441003_PIP-SCONN,HA    I13 @BASEBOARD_FAB2_LIB.BASEBOARD_FAB2(SCH_1):PAGE78

M_G_DQ<24> @BASEBOARD_FAB2_LIB.BASEBOARD_FAB2(SCH_1):M_G_DQ(24)
  U2D1  L76 DDR0_DQ<24> SKX_EXT_B_BGA1-IC,TBD   I172 @BASEBOARD_FAB2_LIB.BASEBOARD_FAB2(SCH_1):PAGE57
  J1G1  183 DQ<25> SCONN288_H44441004_PIP-SCONN,HA   I111 @BASEBOARD_FAB2_LIB.BASEBOARD_FAB2(SCH_1):PAGE77
  J9T1   38 DQ<24> SCONN288_H44441003_PIP-SCONN,HA    I13 @BASEBOARD_FAB2_LIB.BASEBOARD_FAB2(SCH_1):PAGE78

M_G_DQ<25> @BASEBOARD_FAB2_LIB.BASEBOARD_FAB2(SCH_1):M_G_DQ(25)
  U2D1  R76 DDR0_DQ<25> SKX_EXT_B_BGA1-IC,TBD   I172 @BASEBOARD_FAB2_LIB.BASEBOARD_FAB2(SCH_1):PAGE57
  J1G1   38 DQ<24> SCONN288_H44441004_PIP-SCONN,HA   I111 @BASEBOARD_FAB2_LIB.BASEBOARD_FAB2(SCH_1):PAGE77
  J9T1  183 DQ<25> SCONN288_H44441003_PIP-SCONN,HA    I13 @BASEBOARD_FAB2_LIB.BASEBOARD_FAB2(SCH_1):PAGE78

M_G_DQ<26> @BASEBOARD_FAB2_LIB.BASEBOARD_FAB2(SCH_1):M_G_DQ(26)
  U2D1  M73 DDR0_DQ<26> SKX_EXT_B_BGA1-IC,TBD   I172 @BASEBOARD_FAB2_LIB.BASEBOARD_FAB2(SCH_1):PAGE57
  J1G1  190 DQ<27> SCONN288_H44441004_PIP-SCONN,HA   I111 @BASEBOARD_FAB2_LIB.BASEBOARD_FAB2(SCH_1):PAGE77
  J9T1   45 DQ<26> SCONN288_H44441003_PIP-SCONN,HA    I13 @BASEBOARD_FAB2_LIB.BASEBOARD_FAB2(SCH_1):PAGE78

M_G_DQ<27> @BASEBOARD_FAB2_LIB.BASEBOARD_FAB2(SCH_1):M_G_DQ(27)
  U2D1  P73 DDR0_DQ<27> SKX_EXT_B_BGA1-IC,TBD   I172 @BASEBOARD_FAB2_LIB.BASEBOARD_FAB2(SCH_1):PAGE57
  J1G1   45 DQ<26> SCONN288_H44441004_PIP-SCONN,HA   I111 @BASEBOARD_FAB2_LIB.BASEBOARD_FAB2(SCH_1):PAGE77
  J9T1  190 DQ<27> SCONN288_H44441003_PIP-SCONN,HA    I13 @BASEBOARD_FAB2_LIB.BASEBOARD_FAB2(SCH_1):PAGE78

M_G_DQ<28> @BASEBOARD_FAB2_LIB.BASEBOARD_FAB2(SCH_1):M_G_DQ(28)
  U2D1  M77 DDR0_DQ<28> SKX_EXT_B_BGA1-IC,TBD   I172 @BASEBOARD_FAB2_LIB.BASEBOARD_FAB2(SCH_1):PAGE57
  J1G1  181 DQ<29> SCONN288_H44441004_PIP-SCONN,HA   I111 @BASEBOARD_FAB2_LIB.BASEBOARD_FAB2(SCH_1):PAGE77
  J9T1   36 DQ<28> SCONN288_H44441003_PIP-SCONN,HA    I13 @BASEBOARD_FAB2_LIB.BASEBOARD_FAB2(SCH_1):PAGE78

M_G_DQ<29> @BASEBOARD_FAB2_LIB.BASEBOARD_FAB2(SCH_1):M_G_DQ(29)
  U2D1  P77 DDR0_DQ<29> SKX_EXT_B_BGA1-IC,TBD   I172 @BASEBOARD_FAB2_LIB.BASEBOARD_FAB2(SCH_1):PAGE57
  J1G1   36 DQ<28> SCONN288_H44441004_PIP-SCONN,HA   I111 @BASEBOARD_FAB2_LIB.BASEBOARD_FAB2(SCH_1):PAGE77
  J9T1  181 DQ<29> SCONN288_H44441003_PIP-SCONN,HA    I13 @BASEBOARD_FAB2_LIB.BASEBOARD_FAB2(SCH_1):PAGE78

M_G_DQ<2> @BASEBOARD_FAB2_LIB.BASEBOARD_FAB2(SCH_1):M_G_DQ(2)
  U2D1 AE86 DDR0_DQ<2> SKX_EXT_B_BGA1-IC,TBD   I172 @BASEBOARD_FAB2_LIB.BASEBOARD_FAB2(SCH_1):PAGE57
  J1G1  157  DQ<3> SCONN288_H44441004_PIP-SCONN,HA   I111 @BASEBOARD_FAB2_LIB.BASEBOARD_FAB2(SCH_1):PAGE77
  J9T1   12  DQ<2> SCONN288_H44441003_PIP-SCONN,HA    I13 @BASEBOARD_FAB2_LIB.BASEBOARD_FAB2(SCH_1):PAGE78

M_G_DQ<30> @BASEBOARD_FAB2_LIB.BASEBOARD_FAB2(SCH_1):M_G_DQ(30)
  U2D1  L74 DDR0_DQ<30> SKX_EXT_B_BGA1-IC,TBD   I172 @BASEBOARD_FAB2_LIB.BASEBOARD_FAB2(SCH_1):PAGE57
  J1G1  188 DQ<31> SCONN288_H44441004_PIP-SCONN,HA   I111 @BASEBOARD_FAB2_LIB.BASEBOARD_FAB2(SCH_1):PAGE77
  J9T1   43 DQ<30> SCONN288_H44441003_PIP-SCONN,HA    I13 @BASEBOARD_FAB2_LIB.BASEBOARD_FAB2(SCH_1):PAGE78

M_G_DQ<31> @BASEBOARD_FAB2_LIB.BASEBOARD_FAB2(SCH_1):M_G_DQ(31)
  U2D1  R74 DDR0_DQ<31> SKX_EXT_B_BGA1-IC,TBD   I172 @BASEBOARD_FAB2_LIB.BASEBOARD_FAB2(SCH_1):PAGE57
  J1G1   43 DQ<30> SCONN288_H44441004_PIP-SCONN,HA   I111 @BASEBOARD_FAB2_LIB.BASEBOARD_FAB2(SCH_1):PAGE77
  J9T1  188 DQ<31> SCONN288_H44441003_PIP-SCONN,HA    I13 @BASEBOARD_FAB2_LIB.BASEBOARD_FAB2(SCH_1):PAGE78

M_G_DQ<32> @BASEBOARD_FAB2_LIB.BASEBOARD_FAB2(SCH_1):M_G_DQ(32)
  U2D1  C42 DDR0_DQ<32> SKX_EXT_B_BGA1-IC,TBD   I172 @BASEBOARD_FAB2_LIB.BASEBOARD_FAB2(SCH_1):PAGE57
  J1G1  242 DQ<33> SCONN288_H44441004_PIP-SCONN,HA   I111 @BASEBOARD_FAB2_LIB.BASEBOARD_FAB2(SCH_1):PAGE77
  J9T1   97 DQ<32> SCONN288_H44441003_PIP-SCONN,HA    I13 @BASEBOARD_FAB2_LIB.BASEBOARD_FAB2(SCH_1):PAGE78

M_G_DQ<33> @BASEBOARD_FAB2_LIB.BASEBOARD_FAB2(SCH_1):M_G_DQ(33)
  U2D1  B41 DDR0_DQ<33> SKX_EXT_B_BGA1-IC,TBD   I172 @BASEBOARD_FAB2_LIB.BASEBOARD_FAB2(SCH_1):PAGE57
  J1G1   97 DQ<32> SCONN288_H44441004_PIP-SCONN,HA   I111 @BASEBOARD_FAB2_LIB.BASEBOARD_FAB2(SCH_1):PAGE77
  J9T1  242 DQ<33> SCONN288_H44441003_PIP-SCONN,HA    I13 @BASEBOARD_FAB2_LIB.BASEBOARD_FAB2(SCH_1):PAGE78

M_G_DQ<34> @BASEBOARD_FAB2_LIB.BASEBOARD_FAB2(SCH_1):M_G_DQ(34)
  U2D1  C38 DDR0_DQ<34> SKX_EXT_B_BGA1-IC,TBD   I172 @BASEBOARD_FAB2_LIB.BASEBOARD_FAB2(SCH_1):PAGE57
  J1G1  249 DQ<35> SCONN288_H44441004_PIP-SCONN,HA   I111 @BASEBOARD_FAB2_LIB.BASEBOARD_FAB2(SCH_1):PAGE77
  J9T1  104 DQ<34> SCONN288_H44441003_PIP-SCONN,HA    I13 @BASEBOARD_FAB2_LIB.BASEBOARD_FAB2(SCH_1):PAGE78

M_G_DQ<35> @BASEBOARD_FAB2_LIB.BASEBOARD_FAB2(SCH_1):M_G_DQ(35)
  U2D1  E38 DDR0_DQ<35> SKX_EXT_B_BGA1-IC,TBD   I172 @BASEBOARD_FAB2_LIB.BASEBOARD_FAB2(SCH_1):PAGE57
  J1G1  104 DQ<34> SCONN288_H44441004_PIP-SCONN,HA   I111 @BASEBOARD_FAB2_LIB.BASEBOARD_FAB2(SCH_1):PAGE77
  J9T1  249 DQ<35> SCONN288_H44441003_PIP-SCONN,HA    I13 @BASEBOARD_FAB2_LIB.BASEBOARD_FAB2(SCH_1):PAGE78

M_G_DQ<36> @BASEBOARD_FAB2_LIB.BASEBOARD_FAB2(SCH_1):M_G_DQ(36)
  U2D1  E42 DDR0_DQ<36> SKX_EXT_B_BGA1-IC,TBD   I172 @BASEBOARD_FAB2_LIB.BASEBOARD_FAB2(SCH_1):PAGE57
  J1G1  240 DQ<37> SCONN288_H44441004_PIP-SCONN,HA   I111 @BASEBOARD_FAB2_LIB.BASEBOARD_FAB2(SCH_1):PAGE77
  J9T1   95 DQ<36> SCONN288_H44441003_PIP-SCONN,HA    I13 @BASEBOARD_FAB2_LIB.BASEBOARD_FAB2(SCH_1):PAGE78

M_G_DQ<37> @BASEBOARD_FAB2_LIB.BASEBOARD_FAB2(SCH_1):M_G_DQ(37)
  U2D1  F41 DDR0_DQ<37> SKX_EXT_B_BGA1-IC,TBD   I172 @BASEBOARD_FAB2_LIB.BASEBOARD_FAB2(SCH_1):PAGE57
  J1G1   95 DQ<36> SCONN288_H44441004_PIP-SCONN,HA   I111 @BASEBOARD_FAB2_LIB.BASEBOARD_FAB2(SCH_1):PAGE77
  J9T1  240 DQ<37> SCONN288_H44441003_PIP-SCONN,HA    I13 @BASEBOARD_FAB2_LIB.BASEBOARD_FAB2(SCH_1):PAGE78

M_G_DQ<38> @BASEBOARD_FAB2_LIB.BASEBOARD_FAB2(SCH_1):M_G_DQ(38)
  U2D1  B39 DDR0_DQ<38> SKX_EXT_B_BGA1-IC,TBD   I172 @BASEBOARD_FAB2_LIB.BASEBOARD_FAB2(SCH_1):PAGE57
  J1G1  247 DQ<39> SCONN288_H44441004_PIP-SCONN,HA   I111 @BASEBOARD_FAB2_LIB.BASEBOARD_FAB2(SCH_1):PAGE77
  J9T1  102 DQ<38> SCONN288_H44441003_PIP-SCONN,HA    I13 @BASEBOARD_FAB2_LIB.BASEBOARD_FAB2(SCH_1):PAGE78

M_G_DQ<39> @BASEBOARD_FAB2_LIB.BASEBOARD_FAB2(SCH_1):M_G_DQ(39)
  U2D1  F39 DDR0_DQ<39> SKX_EXT_B_BGA1-IC,TBD   I172 @BASEBOARD_FAB2_LIB.BASEBOARD_FAB2(SCH_1):PAGE57
  J1G1  102 DQ<38> SCONN288_H44441004_PIP-SCONN,HA   I111 @BASEBOARD_FAB2_LIB.BASEBOARD_FAB2(SCH_1):PAGE77
  J9T1  247 DQ<39> SCONN288_H44441003_PIP-SCONN,HA    I13 @BASEBOARD_FAB2_LIB.BASEBOARD_FAB2(SCH_1):PAGE78

M_G_DQ<3> @BASEBOARD_FAB2_LIB.BASEBOARD_FAB2(SCH_1):M_G_DQ(3)
  U2D1 AE84 DDR0_DQ<3> SKX_EXT_B_BGA1-IC,TBD   I172 @BASEBOARD_FAB2_LIB.BASEBOARD_FAB2(SCH_1):PAGE57
  J1G1   12  DQ<2> SCONN288_H44441004_PIP-SCONN,HA   I111 @BASEBOARD_FAB2_LIB.BASEBOARD_FAB2(SCH_1):PAGE77
  J9T1  157  DQ<3> SCONN288_H44441003_PIP-SCONN,HA    I13 @BASEBOARD_FAB2_LIB.BASEBOARD_FAB2(SCH_1):PAGE78

M_G_DQ<40> @BASEBOARD_FAB2_LIB.BASEBOARD_FAB2(SCH_1):M_G_DQ(40)
  U2D1  K37 DDR0_DQ<40> SKX_EXT_B_BGA1-IC,TBD   I172 @BASEBOARD_FAB2_LIB.BASEBOARD_FAB2(SCH_1):PAGE57
  J1G1  253 DQ<41> SCONN288_H44441004_PIP-SCONN,HA   I111 @BASEBOARD_FAB2_LIB.BASEBOARD_FAB2(SCH_1):PAGE77
  J9T1  108 DQ<40> SCONN288_H44441003_PIP-SCONN,HA    I13 @BASEBOARD_FAB2_LIB.BASEBOARD_FAB2(SCH_1):PAGE78

M_G_DQ<41> @BASEBOARD_FAB2_LIB.BASEBOARD_FAB2(SCH_1):M_G_DQ(41)
  U2D1  P37 DDR0_DQ<41> SKX_EXT_B_BGA1-IC,TBD   I172 @BASEBOARD_FAB2_LIB.BASEBOARD_FAB2(SCH_1):PAGE57
  J1G1  108 DQ<40> SCONN288_H44441004_PIP-SCONN,HA   I111 @BASEBOARD_FAB2_LIB.BASEBOARD_FAB2(SCH_1):PAGE77
  J9T1  253 DQ<41> SCONN288_H44441003_PIP-SCONN,HA    I13 @BASEBOARD_FAB2_LIB.BASEBOARD_FAB2(SCH_1):PAGE78

M_G_DQ<42> @BASEBOARD_FAB2_LIB.BASEBOARD_FAB2(SCH_1):M_G_DQ(42)
  U2D1  L34 DDR0_DQ<42> SKX_EXT_B_BGA1-IC,TBD   I172 @BASEBOARD_FAB2_LIB.BASEBOARD_FAB2(SCH_1):PAGE57
  J1G1  260 DQ<43> SCONN288_H44441004_PIP-SCONN,HA   I111 @BASEBOARD_FAB2_LIB.BASEBOARD_FAB2(SCH_1):PAGE77
  J9T1  115 DQ<42> SCONN288_H44441003_PIP-SCONN,HA    I13 @BASEBOARD_FAB2_LIB.BASEBOARD_FAB2(SCH_1):PAGE78

M_G_DQ<43> @BASEBOARD_FAB2_LIB.BASEBOARD_FAB2(SCH_1):M_G_DQ(43)
  U2D1  N34 DDR0_DQ<43> SKX_EXT_B_BGA1-IC,TBD   I172 @BASEBOARD_FAB2_LIB.BASEBOARD_FAB2(SCH_1):PAGE57
  J1G1  115 DQ<42> SCONN288_H44441004_PIP-SCONN,HA   I111 @BASEBOARD_FAB2_LIB.BASEBOARD_FAB2(SCH_1):PAGE77
  J9T1  260 DQ<43> SCONN288_H44441003_PIP-SCONN,HA    I13 @BASEBOARD_FAB2_LIB.BASEBOARD_FAB2(SCH_1):PAGE78

M_G_DQ<44> @BASEBOARD_FAB2_LIB.BASEBOARD_FAB2(SCH_1):M_G_DQ(44)
  U2D1  L38 DDR0_DQ<44> SKX_EXT_B_BGA1-IC,TBD   I172 @BASEBOARD_FAB2_LIB.BASEBOARD_FAB2(SCH_1):PAGE57
  J1G1  251 DQ<45> SCONN288_H44441004_PIP-SCONN,HA   I111 @BASEBOARD_FAB2_LIB.BASEBOARD_FAB2(SCH_1):PAGE77
  J9T1  106 DQ<44> SCONN288_H44441003_PIP-SCONN,HA    I13 @BASEBOARD_FAB2_LIB.BASEBOARD_FAB2(SCH_1):PAGE78

M_G_DQ<45> @BASEBOARD_FAB2_LIB.BASEBOARD_FAB2(SCH_1):M_G_DQ(45)
  U2D1  N38 DDR0_DQ<45> SKX_EXT_B_BGA1-IC,TBD   I172 @BASEBOARD_FAB2_LIB.BASEBOARD_FAB2(SCH_1):PAGE57
  J1G1  106 DQ<44> SCONN288_H44441004_PIP-SCONN,HA   I111 @BASEBOARD_FAB2_LIB.BASEBOARD_FAB2(SCH_1):PAGE77
  J9T1  251 DQ<45> SCONN288_H44441003_PIP-SCONN,HA    I13 @BASEBOARD_FAB2_LIB.BASEBOARD_FAB2(SCH_1):PAGE78

M_G_DQ<46> @BASEBOARD_FAB2_LIB.BASEBOARD_FAB2(SCH_1):M_G_DQ(46)
  U2D1  K35 DDR0_DQ<46> SKX_EXT_B_BGA1-IC,TBD   I172 @BASEBOARD_FAB2_LIB.BASEBOARD_FAB2(SCH_1):PAGE57
  J1G1  258 DQ<47> SCONN288_H44441004_PIP-SCONN,HA   I111 @BASEBOARD_FAB2_LIB.BASEBOARD_FAB2(SCH_1):PAGE77
  J9T1  113 DQ<46> SCONN288_H44441003_PIP-SCONN,HA    I13 @BASEBOARD_FAB2_LIB.BASEBOARD_FAB2(SCH_1):PAGE78

M_G_DQ<47> @BASEBOARD_FAB2_LIB.BASEBOARD_FAB2(SCH_1):M_G_DQ(47)
  U2D1  P35 DDR0_DQ<47> SKX_EXT_B_BGA1-IC,TBD   I172 @BASEBOARD_FAB2_LIB.BASEBOARD_FAB2(SCH_1):PAGE57
  J1G1  113 DQ<46> SCONN288_H44441004_PIP-SCONN,HA   I111 @BASEBOARD_FAB2_LIB.BASEBOARD_FAB2(SCH_1):PAGE77
  J9T1  258 DQ<47> SCONN288_H44441003_PIP-SCONN,HA    I13 @BASEBOARD_FAB2_LIB.BASEBOARD_FAB2(SCH_1):PAGE78

M_G_DQ<48> @BASEBOARD_FAB2_LIB.BASEBOARD_FAB2(SCH_1):M_G_DQ(48)
  U2D1  K31 DDR0_DQ<48> SKX_EXT_B_BGA1-IC,TBD   I172 @BASEBOARD_FAB2_LIB.BASEBOARD_FAB2(SCH_1):PAGE57
  J1G1  264 DQ<49> SCONN288_H44441004_PIP-SCONN,HA   I111 @BASEBOARD_FAB2_LIB.BASEBOARD_FAB2(SCH_1):PAGE77
  J9T1  119 DQ<48> SCONN288_H44441003_PIP-SCONN,HA    I13 @BASEBOARD_FAB2_LIB.BASEBOARD_FAB2(SCH_1):PAGE78

M_G_DQ<49> @BASEBOARD_FAB2_LIB.BASEBOARD_FAB2(SCH_1):M_G_DQ(49)
  U2D1  P31 DDR0_DQ<49> SKX_EXT_B_BGA1-IC,TBD   I172 @BASEBOARD_FAB2_LIB.BASEBOARD_FAB2(SCH_1):PAGE57
  J1G1  119 DQ<48> SCONN288_H44441004_PIP-SCONN,HA   I111 @BASEBOARD_FAB2_LIB.BASEBOARD_FAB2(SCH_1):PAGE77
  J9T1  264 DQ<49> SCONN288_H44441003_PIP-SCONN,HA    I13 @BASEBOARD_FAB2_LIB.BASEBOARD_FAB2(SCH_1):PAGE78

M_G_DQ<4> @BASEBOARD_FAB2_LIB.BASEBOARD_FAB2(SCH_1):M_G_DQ(4)
  U2D1 AR86 DDR0_DQ<4> SKX_EXT_B_BGA1-IC,TBD   I172 @BASEBOARD_FAB2_LIB.BASEBOARD_FAB2(SCH_1):PAGE57
  J1G1  148  DQ<5> SCONN288_H44441004_PIP-SCONN,HA   I111 @BASEBOARD_FAB2_LIB.BASEBOARD_FAB2(SCH_1):PAGE77
  J9T1    3  DQ<4> SCONN288_H44441003_PIP-SCONN,HA    I13 @BASEBOARD_FAB2_LIB.BASEBOARD_FAB2(SCH_1):PAGE78

M_G_DQ<50> @BASEBOARD_FAB2_LIB.BASEBOARD_FAB2(SCH_1):M_G_DQ(50)
  U2D1  L28 DDR0_DQ<50> SKX_EXT_B_BGA1-IC,TBD   I172 @BASEBOARD_FAB2_LIB.BASEBOARD_FAB2(SCH_1):PAGE57
  J1G1  271 DQ<51> SCONN288_H44441004_PIP-SCONN,HA   I111 @BASEBOARD_FAB2_LIB.BASEBOARD_FAB2(SCH_1):PAGE77
  J9T1  126 DQ<50> SCONN288_H44441003_PIP-SCONN,HA    I13 @BASEBOARD_FAB2_LIB.BASEBOARD_FAB2(SCH_1):PAGE78

M_G_DQ<51> @BASEBOARD_FAB2_LIB.BASEBOARD_FAB2(SCH_1):M_G_DQ(51)
  U2D1  N28 DDR0_DQ<51> SKX_EXT_B_BGA1-IC,TBD   I172 @BASEBOARD_FAB2_LIB.BASEBOARD_FAB2(SCH_1):PAGE57
  J1G1  126 DQ<50> SCONN288_H44441004_PIP-SCONN,HA   I111 @BASEBOARD_FAB2_LIB.BASEBOARD_FAB2(SCH_1):PAGE77
  J9T1  271 DQ<51> SCONN288_H44441003_PIP-SCONN,HA    I13 @BASEBOARD_FAB2_LIB.BASEBOARD_FAB2(SCH_1):PAGE78

M_G_DQ<52> @BASEBOARD_FAB2_LIB.BASEBOARD_FAB2(SCH_1):M_G_DQ(52)
  U2D1  L32 DDR0_DQ<52> SKX_EXT_B_BGA1-IC,TBD   I172 @BASEBOARD_FAB2_LIB.BASEBOARD_FAB2(SCH_1):PAGE57
  J1G1  262 DQ<53> SCONN288_H44441004_PIP-SCONN,HA   I111 @BASEBOARD_FAB2_LIB.BASEBOARD_FAB2(SCH_1):PAGE77
  J9T1  117 DQ<52> SCONN288_H44441003_PIP-SCONN,HA    I13 @BASEBOARD_FAB2_LIB.BASEBOARD_FAB2(SCH_1):PAGE78

M_G_DQ<53> @BASEBOARD_FAB2_LIB.BASEBOARD_FAB2(SCH_1):M_G_DQ(53)
  U2D1  N32 DDR0_DQ<53> SKX_EXT_B_BGA1-IC,TBD   I172 @BASEBOARD_FAB2_LIB.BASEBOARD_FAB2(SCH_1):PAGE57
  J1G1  117 DQ<52> SCONN288_H44441004_PIP-SCONN,HA   I111 @BASEBOARD_FAB2_LIB.BASEBOARD_FAB2(SCH_1):PAGE77
  J9T1  262 DQ<53> SCONN288_H44441003_PIP-SCONN,HA    I13 @BASEBOARD_FAB2_LIB.BASEBOARD_FAB2(SCH_1):PAGE78

M_G_DQ<54> @BASEBOARD_FAB2_LIB.BASEBOARD_FAB2(SCH_1):M_G_DQ(54)
  U2D1  K29 DDR0_DQ<54> SKX_EXT_B_BGA1-IC,TBD   I172 @BASEBOARD_FAB2_LIB.BASEBOARD_FAB2(SCH_1):PAGE57
  J1G1  269 DQ<55> SCONN288_H44441004_PIP-SCONN,HA   I111 @BASEBOARD_FAB2_LIB.BASEBOARD_FAB2(SCH_1):PAGE77
  J9T1  124 DQ<54> SCONN288_H44441003_PIP-SCONN,HA    I13 @BASEBOARD_FAB2_LIB.BASEBOARD_FAB2(SCH_1):PAGE78

M_G_DQ<55> @BASEBOARD_FAB2_LIB.BASEBOARD_FAB2(SCH_1):M_G_DQ(55)
  U2D1  P29 DDR0_DQ<55> SKX_EXT_B_BGA1-IC,TBD   I172 @BASEBOARD_FAB2_LIB.BASEBOARD_FAB2(SCH_1):PAGE57
  J1G1  124 DQ<54> SCONN288_H44441004_PIP-SCONN,HA   I111 @BASEBOARD_FAB2_LIB.BASEBOARD_FAB2(SCH_1):PAGE77
  J9T1  269 DQ<55> SCONN288_H44441003_PIP-SCONN,HA    I13 @BASEBOARD_FAB2_LIB.BASEBOARD_FAB2(SCH_1):PAGE78

M_G_DQ<56> @BASEBOARD_FAB2_LIB.BASEBOARD_FAB2(SCH_1):M_G_DQ(56)
  U2D1  K25 DDR0_DQ<56> SKX_EXT_B_BGA1-IC,TBD   I172 @BASEBOARD_FAB2_LIB.BASEBOARD_FAB2(SCH_1):PAGE57
  J1G1  275 DQ<57> SCONN288_H44441004_PIP-SCONN,HA   I111 @BASEBOARD_FAB2_LIB.BASEBOARD_FAB2(SCH_1):PAGE77
  J9T1  130 DQ<56> SCONN288_H44441003_PIP-SCONN,HA    I13 @BASEBOARD_FAB2_LIB.BASEBOARD_FAB2(SCH_1):PAGE78

M_G_DQ<57> @BASEBOARD_FAB2_LIB.BASEBOARD_FAB2(SCH_1):M_G_DQ(57)
  U2D1  P25 DDR0_DQ<57> SKX_EXT_B_BGA1-IC,TBD   I172 @BASEBOARD_FAB2_LIB.BASEBOARD_FAB2(SCH_1):PAGE57
  J1G1  130 DQ<56> SCONN288_H44441004_PIP-SCONN,HA   I111 @BASEBOARD_FAB2_LIB.BASEBOARD_FAB2(SCH_1):PAGE77
  J9T1  275 DQ<57> SCONN288_H44441003_PIP-SCONN,HA    I13 @BASEBOARD_FAB2_LIB.BASEBOARD_FAB2(SCH_1):PAGE78

M_G_DQ<58> @BASEBOARD_FAB2_LIB.BASEBOARD_FAB2(SCH_1):M_G_DQ(58)
  U2D1  P23 DDR0_DQ<58> SKX_EXT_B_BGA1-IC,TBD   I172 @BASEBOARD_FAB2_LIB.BASEBOARD_FAB2(SCH_1):PAGE57
  J1G1  282 DQ<59> SCONN288_H44441004_PIP-SCONN,HA   I111 @BASEBOARD_FAB2_LIB.BASEBOARD_FAB2(SCH_1):PAGE77
  J9T1  137 DQ<58> SCONN288_H44441003_PIP-SCONN,HA    I13 @BASEBOARD_FAB2_LIB.BASEBOARD_FAB2(SCH_1):PAGE78

M_G_DQ<59> @BASEBOARD_FAB2_LIB.BASEBOARD_FAB2(SCH_1):M_G_DQ(59)
  U2D1  T23 DDR0_DQ<59> SKX_EXT_B_BGA1-IC,TBD   I172 @BASEBOARD_FAB2_LIB.BASEBOARD_FAB2(SCH_1):PAGE57
  J1G1  137 DQ<58> SCONN288_H44441004_PIP-SCONN,HA   I111 @BASEBOARD_FAB2_LIB.BASEBOARD_FAB2(SCH_1):PAGE77
  J9T1  282 DQ<59> SCONN288_H44441003_PIP-SCONN,HA    I13 @BASEBOARD_FAB2_LIB.BASEBOARD_FAB2(SCH_1):PAGE78

M_G_DQ<5> @BASEBOARD_FAB2_LIB.BASEBOARD_FAB2(SCH_1):M_G_DQ(5)
  U2D1 AR84 DDR0_DQ<5> SKX_EXT_B_BGA1-IC,TBD   I172 @BASEBOARD_FAB2_LIB.BASEBOARD_FAB2(SCH_1):PAGE57
  J1G1    3  DQ<4> SCONN288_H44441004_PIP-SCONN,HA   I111 @BASEBOARD_FAB2_LIB.BASEBOARD_FAB2(SCH_1):PAGE77
  J9T1  148  DQ<5> SCONN288_H44441003_PIP-SCONN,HA    I13 @BASEBOARD_FAB2_LIB.BASEBOARD_FAB2(SCH_1):PAGE78

M_G_DQ<60> @BASEBOARD_FAB2_LIB.BASEBOARD_FAB2(SCH_1):M_G_DQ(60)
  U2D1  L26 DDR0_DQ<60> SKX_EXT_B_BGA1-IC,TBD   I172 @BASEBOARD_FAB2_LIB.BASEBOARD_FAB2(SCH_1):PAGE57
  J1G1  273 DQ<61> SCONN288_H44441004_PIP-SCONN,HA   I111 @BASEBOARD_FAB2_LIB.BASEBOARD_FAB2(SCH_1):PAGE77
  J9T1  128 DQ<60> SCONN288_H44441003_PIP-SCONN,HA    I13 @BASEBOARD_FAB2_LIB.BASEBOARD_FAB2(SCH_1):PAGE78

M_G_DQ<61> @BASEBOARD_FAB2_LIB.BASEBOARD_FAB2(SCH_1):M_G_DQ(61)
  U2D1  N26 DDR0_DQ<61> SKX_EXT_B_BGA1-IC,TBD   I172 @BASEBOARD_FAB2_LIB.BASEBOARD_FAB2(SCH_1):PAGE57
  J1G1  128 DQ<60> SCONN288_H44441004_PIP-SCONN,HA   I111 @BASEBOARD_FAB2_LIB.BASEBOARD_FAB2(SCH_1):PAGE77
  J9T1  273 DQ<61> SCONN288_H44441003_PIP-SCONN,HA    I13 @BASEBOARD_FAB2_LIB.BASEBOARD_FAB2(SCH_1):PAGE78

M_G_DQ<62> @BASEBOARD_FAB2_LIB.BASEBOARD_FAB2(SCH_1):M_G_DQ(62)
  U2D1  H23 DDR0_DQ<62> SKX_EXT_B_BGA1-IC,TBD   I172 @BASEBOARD_FAB2_LIB.BASEBOARD_FAB2(SCH_1):PAGE57
  J1G1  280 DQ<63> SCONN288_H44441004_PIP-SCONN,HA   I111 @BASEBOARD_FAB2_LIB.BASEBOARD_FAB2(SCH_1):PAGE77
  J9T1  135 DQ<62> SCONN288_H44441003_PIP-SCONN,HA    I13 @BASEBOARD_FAB2_LIB.BASEBOARD_FAB2(SCH_1):PAGE78

M_G_DQ<63> @BASEBOARD_FAB2_LIB.BASEBOARD_FAB2(SCH_1):M_G_DQ(63)
  U2D1  K23 DDR0_DQ<63> SKX_EXT_B_BGA1-IC,TBD   I172 @BASEBOARD_FAB2_LIB.BASEBOARD_FAB2(SCH_1):PAGE57
  J1G1  135 DQ<62> SCONN288_H44441004_PIP-SCONN,HA   I111 @BASEBOARD_FAB2_LIB.BASEBOARD_FAB2(SCH_1):PAGE77
  J9T1  280 DQ<63> SCONN288_H44441003_PIP-SCONN,HA    I13 @BASEBOARD_FAB2_LIB.BASEBOARD_FAB2(SCH_1):PAGE78

M_G_DQ<6> @BASEBOARD_FAB2_LIB.BASEBOARD_FAB2(SCH_1):M_G_DQ(6)
  U2D1 AG86 DDR0_DQ<6> SKX_EXT_B_BGA1-IC,TBD   I172 @BASEBOARD_FAB2_LIB.BASEBOARD_FAB2(SCH_1):PAGE57
  J1G1  155  DQ<7> SCONN288_H44441004_PIP-SCONN,HA   I111 @BASEBOARD_FAB2_LIB.BASEBOARD_FAB2(SCH_1):PAGE77
  J9T1   10  DQ<6> SCONN288_H44441003_PIP-SCONN,HA    I13 @BASEBOARD_FAB2_LIB.BASEBOARD_FAB2(SCH_1):PAGE78

M_G_DQ<7> @BASEBOARD_FAB2_LIB.BASEBOARD_FAB2(SCH_1):M_G_DQ(7)
  U2D1 AG84 DDR0_DQ<7> SKX_EXT_B_BGA1-IC,TBD   I172 @BASEBOARD_FAB2_LIB.BASEBOARD_FAB2(SCH_1):PAGE57
  J1G1   10  DQ<6> SCONN288_H44441004_PIP-SCONN,HA   I111 @BASEBOARD_FAB2_LIB.BASEBOARD_FAB2(SCH_1):PAGE77
  J9T1  155  DQ<7> SCONN288_H44441003_PIP-SCONN,HA    I13 @BASEBOARD_FAB2_LIB.BASEBOARD_FAB2(SCH_1):PAGE78

M_G_DQ<8> @BASEBOARD_FAB2_LIB.BASEBOARD_FAB2(SCH_1):M_G_DQ(8)
  U2D1  W86 DDR0_DQ<8> SKX_EXT_B_BGA1-IC,TBD   I172 @BASEBOARD_FAB2_LIB.BASEBOARD_FAB2(SCH_1):PAGE57
  J1G1  161  DQ<9> SCONN288_H44441004_PIP-SCONN,HA   I111 @BASEBOARD_FAB2_LIB.BASEBOARD_FAB2(SCH_1):PAGE77
  J9T1   16  DQ<8> SCONN288_H44441003_PIP-SCONN,HA    I13 @BASEBOARD_FAB2_LIB.BASEBOARD_FAB2(SCH_1):PAGE78

M_G_DQ<9> @BASEBOARD_FAB2_LIB.BASEBOARD_FAB2(SCH_1):M_G_DQ(9)
  U2D1  W84 DDR0_DQ<9> SKX_EXT_B_BGA1-IC,TBD   I172 @BASEBOARD_FAB2_LIB.BASEBOARD_FAB2(SCH_1):PAGE57
  J1G1   16  DQ<8> SCONN288_H44441004_PIP-SCONN,HA   I111 @BASEBOARD_FAB2_LIB.BASEBOARD_FAB2(SCH_1):PAGE77
  J9T1  161  DQ<9> SCONN288_H44441003_PIP-SCONN,HA    I13 @BASEBOARD_FAB2_LIB.BASEBOARD_FAB2(SCH_1):PAGE78

M_G_DQS_DN<0> @BASEBOARD_FAB2_LIB.BASEBOARD_FAB2(SCH_1):M_G_DQS_DN(0)
  U2D1 AJ84 DDR0_DQS_DN<0> SKX_EXT_B_BGA1-IC,TBD   I172 @BASEBOARD_FAB2_LIB.BASEBOARD_FAB2(SCH_1):PAGE57
  J1G1  152  DQS0N SCONN288_H44441004_PIP-SCONN,HA    I66 @BASEBOARD_FAB2_LIB.BASEBOARD_FAB2(SCH_1):PAGE77
  J9T1  152  DQS0N SCONN288_H44441003_PIP-SCONN,HA   I120 @BASEBOARD_FAB2_LIB.BASEBOARD_FAB2(SCH_1):PAGE78

M_G_DQS_DN<10> @BASEBOARD_FAB2_LIB.BASEBOARD_FAB2(SCH_1):M_G_DQS_DN(10)
  U2D1  U84 DDR0_DQS_DN<10> SKX_EXT_B_BGA1-IC,TBD   I172 @BASEBOARD_FAB2_LIB.BASEBOARD_FAB2(SCH_1):PAGE57
  J1G1   19 DQS10N SCONN288_H44441004_PIP-SCONN,HA    I66 @BASEBOARD_FAB2_LIB.BASEBOARD_FAB2(SCH_1):PAGE77
  J9T1   19 DQS10N SCONN288_H44441003_PIP-SCONN,HA   I120 @BASEBOARD_FAB2_LIB.BASEBOARD_FAB2(SCH_1):PAGE78

M_G_DQS_DN<11> @BASEBOARD_FAB2_LIB.BASEBOARD_FAB2(SCH_1):M_G_DQS_DN(11)
  U2D1  U82 DDR0_DQS_DN<11> SKX_EXT_B_BGA1-IC,TBD   I172 @BASEBOARD_FAB2_LIB.BASEBOARD_FAB2(SCH_1):PAGE57
  J1G1   30 DQS11N SCONN288_H44441004_PIP-SCONN,HA    I66 @BASEBOARD_FAB2_LIB.BASEBOARD_FAB2(SCH_1):PAGE77
  J9T1   30 DQS11N SCONN288_H44441003_PIP-SCONN,HA   I120 @BASEBOARD_FAB2_LIB.BASEBOARD_FAB2(SCH_1):PAGE78

M_G_DQS_DN<12> @BASEBOARD_FAB2_LIB.BASEBOARD_FAB2(SCH_1):M_G_DQS_DN(12)
  U2D1  K75 DDR0_DQS_DN<12> SKX_EXT_B_BGA1-IC,TBD   I172 @BASEBOARD_FAB2_LIB.BASEBOARD_FAB2(SCH_1):PAGE57
  J1G1   41 DQS12N SCONN288_H44441004_PIP-SCONN,HA    I66 @BASEBOARD_FAB2_LIB.BASEBOARD_FAB2(SCH_1):PAGE77
  J9T1   41 DQS12N SCONN288_H44441003_PIP-SCONN,HA   I120 @BASEBOARD_FAB2_LIB.BASEBOARD_FAB2(SCH_1):PAGE78

M_G_DQS_DN<13> @BASEBOARD_FAB2_LIB.BASEBOARD_FAB2(SCH_1):M_G_DQS_DN(13)
  U2D1  A40 DDR0_DQS_DN<13> SKX_EXT_B_BGA1-IC,TBD   I172 @BASEBOARD_FAB2_LIB.BASEBOARD_FAB2(SCH_1):PAGE57
  J1G1  100 DQS13N SCONN288_H44441004_PIP-SCONN,HA    I66 @BASEBOARD_FAB2_LIB.BASEBOARD_FAB2(SCH_1):PAGE77
  J9T1  100 DQS13N SCONN288_H44441003_PIP-SCONN,HA   I120 @BASEBOARD_FAB2_LIB.BASEBOARD_FAB2(SCH_1):PAGE78

M_G_DQS_DN<14> @BASEBOARD_FAB2_LIB.BASEBOARD_FAB2(SCH_1):M_G_DQS_DN(14)
  U2D1  J36 DDR0_DQS_DN<14> SKX_EXT_B_BGA1-IC,TBD   I172 @BASEBOARD_FAB2_LIB.BASEBOARD_FAB2(SCH_1):PAGE57
  J1G1  111 DQS14N SCONN288_H44441004_PIP-SCONN,HA    I66 @BASEBOARD_FAB2_LIB.BASEBOARD_FAB2(SCH_1):PAGE77
  J9T1  111 DQS14N SCONN288_H44441003_PIP-SCONN,HA   I120 @BASEBOARD_FAB2_LIB.BASEBOARD_FAB2(SCH_1):PAGE78

M_G_DQS_DN<15> @BASEBOARD_FAB2_LIB.BASEBOARD_FAB2(SCH_1):M_G_DQS_DN(15)
  U2D1  J30 DDR0_DQS_DN<15> SKX_EXT_B_BGA1-IC,TBD   I172 @BASEBOARD_FAB2_LIB.BASEBOARD_FAB2(SCH_1):PAGE57
  J1G1  122 DQS15N SCONN288_H44441004_PIP-SCONN,HA    I66 @BASEBOARD_FAB2_LIB.BASEBOARD_FAB2(SCH_1):PAGE77
  J9T1  122 DQS15N SCONN288_H44441003_PIP-SCONN,HA   I120 @BASEBOARD_FAB2_LIB.BASEBOARD_FAB2(SCH_1):PAGE78

M_G_DQS_DN<16> @BASEBOARD_FAB2_LIB.BASEBOARD_FAB2(SCH_1):M_G_DQS_DN(16)
  U2D1  J24 DDR0_DQS_DN<16> SKX_EXT_B_BGA1-IC,TBD   I172 @BASEBOARD_FAB2_LIB.BASEBOARD_FAB2(SCH_1):PAGE57
  J1G1  133 DQS16N SCONN288_H44441004_PIP-SCONN,HA    I66 @BASEBOARD_FAB2_LIB.BASEBOARD_FAB2(SCH_1):PAGE77
  J9T1  133 DQS16N SCONN288_H44441003_PIP-SCONN,HA   I120 @BASEBOARD_FAB2_LIB.BASEBOARD_FAB2(SCH_1):PAGE78

M_G_DQS_DN<17> @BASEBOARD_FAB2_LIB.BASEBOARD_FAB2(SCH_1):M_G_DQS_DN(17)
  U2D1 AB67 DDR0_DQS_DN<17> SKX_EXT_B_BGA1-IC,TBD   I172 @BASEBOARD_FAB2_LIB.BASEBOARD_FAB2(SCH_1):PAGE57
  J1G1   52 DQS17N SCONN288_H44441004_PIP-SCONN,HA    I66 @BASEBOARD_FAB2_LIB.BASEBOARD_FAB2(SCH_1):PAGE77
  J9T1   52 DQS17N SCONN288_H44441003_PIP-SCONN,HA   I120 @BASEBOARD_FAB2_LIB.BASEBOARD_FAB2(SCH_1):PAGE78

M_G_DQS_DN<1> @BASEBOARD_FAB2_LIB.BASEBOARD_FAB2(SCH_1):M_G_DQS_DN(1)
  U2D1  R84 DDR0_DQS_DN<1> SKX_EXT_B_BGA1-IC,TBD   I172 @BASEBOARD_FAB2_LIB.BASEBOARD_FAB2(SCH_1):PAGE57
  J1G1  163  DQS1N SCONN288_H44441004_PIP-SCONN,HA    I66 @BASEBOARD_FAB2_LIB.BASEBOARD_FAB2(SCH_1):PAGE77
  J9T1  163  DQS1N SCONN288_H44441003_PIP-SCONN,HA   I120 @BASEBOARD_FAB2_LIB.BASEBOARD_FAB2(SCH_1):PAGE78

M_G_DQS_DN<2> @BASEBOARD_FAB2_LIB.BASEBOARD_FAB2(SCH_1):M_G_DQS_DN(2)
  U2D1  P79 DDR0_DQS_DN<2> SKX_EXT_B_BGA1-IC,TBD   I172 @BASEBOARD_FAB2_LIB.BASEBOARD_FAB2(SCH_1):PAGE57
  J1G1  174  DQS2N SCONN288_H44441004_PIP-SCONN,HA    I66 @BASEBOARD_FAB2_LIB.BASEBOARD_FAB2(SCH_1):PAGE77
  J9T1  174  DQS2N SCONN288_H44441003_PIP-SCONN,HA   I120 @BASEBOARD_FAB2_LIB.BASEBOARD_FAB2(SCH_1):PAGE78

M_G_DQS_DN<3> @BASEBOARD_FAB2_LIB.BASEBOARD_FAB2(SCH_1):M_G_DQS_DN(3)
  U2D1  T75 DDR0_DQS_DN<3> SKX_EXT_B_BGA1-IC,TBD   I172 @BASEBOARD_FAB2_LIB.BASEBOARD_FAB2(SCH_1):PAGE57
  J1G1  185  DQS3N SCONN288_H44441004_PIP-SCONN,HA    I66 @BASEBOARD_FAB2_LIB.BASEBOARD_FAB2(SCH_1):PAGE77
  J9T1  185  DQS3N SCONN288_H44441003_PIP-SCONN,HA   I120 @BASEBOARD_FAB2_LIB.BASEBOARD_FAB2(SCH_1):PAGE78

M_G_DQS_DN<4> @BASEBOARD_FAB2_LIB.BASEBOARD_FAB2(SCH_1):M_G_DQS_DN(4)
  U2D1  G40 DDR0_DQS_DN<4> SKX_EXT_B_BGA1-IC,TBD   I172 @BASEBOARD_FAB2_LIB.BASEBOARD_FAB2(SCH_1):PAGE57
  J1G1  244  DQS4N SCONN288_H44441004_PIP-SCONN,HA    I66 @BASEBOARD_FAB2_LIB.BASEBOARD_FAB2(SCH_1):PAGE77
  J9T1  244  DQS4N SCONN288_H44441003_PIP-SCONN,HA   I120 @BASEBOARD_FAB2_LIB.BASEBOARD_FAB2(SCH_1):PAGE78

M_G_DQS_DN<5> @BASEBOARD_FAB2_LIB.BASEBOARD_FAB2(SCH_1):M_G_DQS_DN(5)
  U2D1  R36 DDR0_DQS_DN<5> SKX_EXT_B_BGA1-IC,TBD   I172 @BASEBOARD_FAB2_LIB.BASEBOARD_FAB2(SCH_1):PAGE57
  J1G1  255  DQS5N SCONN288_H44441004_PIP-SCONN,HA    I66 @BASEBOARD_FAB2_LIB.BASEBOARD_FAB2(SCH_1):PAGE77
  J9T1  255  DQS5N SCONN288_H44441003_PIP-SCONN,HA   I120 @BASEBOARD_FAB2_LIB.BASEBOARD_FAB2(SCH_1):PAGE78

M_G_DQS_DN<6> @BASEBOARD_FAB2_LIB.BASEBOARD_FAB2(SCH_1):M_G_DQS_DN(6)
  U2D1  R30 DDR0_DQS_DN<6> SKX_EXT_B_BGA1-IC,TBD   I172 @BASEBOARD_FAB2_LIB.BASEBOARD_FAB2(SCH_1):PAGE57
  J1G1  266  DQS6N SCONN288_H44441004_PIP-SCONN,HA    I66 @BASEBOARD_FAB2_LIB.BASEBOARD_FAB2(SCH_1):PAGE77
  J9T1  266  DQS6N SCONN288_H44441003_PIP-SCONN,HA   I120 @BASEBOARD_FAB2_LIB.BASEBOARD_FAB2(SCH_1):PAGE78

M_G_DQS_DN<7> @BASEBOARD_FAB2_LIB.BASEBOARD_FAB2(SCH_1):M_G_DQS_DN(7)
  U2D1  N24 DDR0_DQS_DN<7> SKX_EXT_B_BGA1-IC,TBD   I172 @BASEBOARD_FAB2_LIB.BASEBOARD_FAB2(SCH_1):PAGE57
  J1G1  277  DQS7N SCONN288_H44441004_PIP-SCONN,HA    I66 @BASEBOARD_FAB2_LIB.BASEBOARD_FAB2(SCH_1):PAGE77
  J9T1  277  DQS7N SCONN288_H44441003_PIP-SCONN,HA   I120 @BASEBOARD_FAB2_LIB.BASEBOARD_FAB2(SCH_1):PAGE78

M_G_DQS_DN<8> @BASEBOARD_FAB2_LIB.BASEBOARD_FAB2(SCH_1):M_G_DQS_DN(8)
  U2D1 AH67 DDR0_DQS_DN<8> SKX_EXT_B_BGA1-IC,TBD   I172 @BASEBOARD_FAB2_LIB.BASEBOARD_FAB2(SCH_1):PAGE57
  J1G1  196  DQS8N SCONN288_H44441004_PIP-SCONN,HA    I66 @BASEBOARD_FAB2_LIB.BASEBOARD_FAB2(SCH_1):PAGE77
  J9T1  196  DQS8N SCONN288_H44441003_PIP-SCONN,HA   I120 @BASEBOARD_FAB2_LIB.BASEBOARD_FAB2(SCH_1):PAGE78

M_G_DQS_DN<9> @BASEBOARD_FAB2_LIB.BASEBOARD_FAB2(SCH_1):M_G_DQS_DN(9)
  U2D1 AL84 DDR0_DQS_DN<9> SKX_EXT_B_BGA1-IC,TBD   I172 @BASEBOARD_FAB2_LIB.BASEBOARD_FAB2(SCH_1):PAGE57
  J1G1    8  DQS9N SCONN288_H44441004_PIP-SCONN,HA    I66 @BASEBOARD_FAB2_LIB.BASEBOARD_FAB2(SCH_1):PAGE77
  J9T1    8  DQS9N SCONN288_H44441003_PIP-SCONN,HA   I120 @BASEBOARD_FAB2_LIB.BASEBOARD_FAB2(SCH_1):PAGE78

M_G_DQS_DP<0> @BASEBOARD_FAB2_LIB.BASEBOARD_FAB2(SCH_1):M_G_DQS_DP(0)
  U2D1 AH85 DDR0_DQS_DP<0> SKX_EXT_B_BGA1-IC,TBD   I172 @BASEBOARD_FAB2_LIB.BASEBOARD_FAB2(SCH_1):PAGE57
  J1G1  153  DQS0P SCONN288_H44441004_PIP-SCONN,HA    I66 @BASEBOARD_FAB2_LIB.BASEBOARD_FAB2(SCH_1):PAGE77
  J9T1  153  DQS0P SCONN288_H44441003_PIP-SCONN,HA   I120 @BASEBOARD_FAB2_LIB.BASEBOARD_FAB2(SCH_1):PAGE78

M_G_DQS_DP<10> @BASEBOARD_FAB2_LIB.BASEBOARD_FAB2(SCH_1):M_G_DQS_DP(10)
  U2D1  V85 DDR0_DQS_DP<10> SKX_EXT_B_BGA1-IC,TBD   I172 @BASEBOARD_FAB2_LIB.BASEBOARD_FAB2(SCH_1):PAGE57
  J1G1   18 DQS10P SCONN288_H44441004_PIP-SCONN,HA    I66 @BASEBOARD_FAB2_LIB.BASEBOARD_FAB2(SCH_1):PAGE77
  J9T1   18 DQS10P SCONN288_H44441003_PIP-SCONN,HA   I120 @BASEBOARD_FAB2_LIB.BASEBOARD_FAB2(SCH_1):PAGE78

M_G_DQS_DP<11> @BASEBOARD_FAB2_LIB.BASEBOARD_FAB2(SCH_1):M_G_DQS_DP(11)
  U2D1  T81 DDR0_DQS_DP<11> SKX_EXT_B_BGA1-IC,TBD   I172 @BASEBOARD_FAB2_LIB.BASEBOARD_FAB2(SCH_1):PAGE57
  J1G1   29 DQS11P SCONN288_H44441004_PIP-SCONN,HA    I66 @BASEBOARD_FAB2_LIB.BASEBOARD_FAB2(SCH_1):PAGE77
  J9T1   29 DQS11P SCONN288_H44441003_PIP-SCONN,HA   I120 @BASEBOARD_FAB2_LIB.BASEBOARD_FAB2(SCH_1):PAGE78

M_G_DQS_DP<12> @BASEBOARD_FAB2_LIB.BASEBOARD_FAB2(SCH_1):M_G_DQS_DP(12)
  U2D1  M75 DDR0_DQS_DP<12> SKX_EXT_B_BGA1-IC,TBD   I172 @BASEBOARD_FAB2_LIB.BASEBOARD_FAB2(SCH_1):PAGE57
  J1G1   40 DQS12P SCONN288_H44441004_PIP-SCONN,HA    I66 @BASEBOARD_FAB2_LIB.BASEBOARD_FAB2(SCH_1):PAGE77
  J9T1   40 DQS12P SCONN288_H44441003_PIP-SCONN,HA   I120 @BASEBOARD_FAB2_LIB.BASEBOARD_FAB2(SCH_1):PAGE78

M_G_DQS_DP<13> @BASEBOARD_FAB2_LIB.BASEBOARD_FAB2(SCH_1):M_G_DQS_DP(13)
  U2D1  C40 DDR0_DQS_DP<13> SKX_EXT_B_BGA1-IC,TBD   I172 @BASEBOARD_FAB2_LIB.BASEBOARD_FAB2(SCH_1):PAGE57
  J1G1   99 DQS13P SCONN288_H44441004_PIP-SCONN,HA    I66 @BASEBOARD_FAB2_LIB.BASEBOARD_FAB2(SCH_1):PAGE77
  J9T1   99 DQS13P SCONN288_H44441003_PIP-SCONN,HA   I120 @BASEBOARD_FAB2_LIB.BASEBOARD_FAB2(SCH_1):PAGE78

M_G_DQS_DP<14> @BASEBOARD_FAB2_LIB.BASEBOARD_FAB2(SCH_1):M_G_DQS_DP(14)
  U2D1  L36 DDR0_DQS_DP<14> SKX_EXT_B_BGA1-IC,TBD   I172 @BASEBOARD_FAB2_LIB.BASEBOARD_FAB2(SCH_1):PAGE57
  J1G1  110 DQS14P SCONN288_H44441004_PIP-SCONN,HA    I66 @BASEBOARD_FAB2_LIB.BASEBOARD_FAB2(SCH_1):PAGE77
  J9T1  110 DQS14P SCONN288_H44441003_PIP-SCONN,HA   I120 @BASEBOARD_FAB2_LIB.BASEBOARD_FAB2(SCH_1):PAGE78

M_G_DQS_DP<15> @BASEBOARD_FAB2_LIB.BASEBOARD_FAB2(SCH_1):M_G_DQS_DP(15)
  U2D1  L30 DDR0_DQS_DP<15> SKX_EXT_B_BGA1-IC,TBD   I172 @BASEBOARD_FAB2_LIB.BASEBOARD_FAB2(SCH_1):PAGE57
  J1G1  121 DQS15P SCONN288_H44441004_PIP-SCONN,HA    I66 @BASEBOARD_FAB2_LIB.BASEBOARD_FAB2(SCH_1):PAGE77
  J9T1  121 DQS15P SCONN288_H44441003_PIP-SCONN,HA   I120 @BASEBOARD_FAB2_LIB.BASEBOARD_FAB2(SCH_1):PAGE78

M_G_DQS_DP<16> @BASEBOARD_FAB2_LIB.BASEBOARD_FAB2(SCH_1):M_G_DQS_DP(16)
  U2D1  L24 DDR0_DQS_DP<16> SKX_EXT_B_BGA1-IC,TBD   I172 @BASEBOARD_FAB2_LIB.BASEBOARD_FAB2(SCH_1):PAGE57
  J1G1  132 DQS16P SCONN288_H44441004_PIP-SCONN,HA    I66 @BASEBOARD_FAB2_LIB.BASEBOARD_FAB2(SCH_1):PAGE77
  J9T1  132 DQS16P SCONN288_H44441003_PIP-SCONN,HA   I120 @BASEBOARD_FAB2_LIB.BASEBOARD_FAB2(SCH_1):PAGE78

M_G_DQS_DP<17> @BASEBOARD_FAB2_LIB.BASEBOARD_FAB2(SCH_1):M_G_DQS_DP(17)
  U2D1 AD67 DDR0_DQS_DP<17> SKX_EXT_B_BGA1-IC,TBD   I172 @BASEBOARD_FAB2_LIB.BASEBOARD_FAB2(SCH_1):PAGE57
  J1G1   51 DQS17P SCONN288_H44441004_PIP-SCONN,HA    I66 @BASEBOARD_FAB2_LIB.BASEBOARD_FAB2(SCH_1):PAGE77
  J9T1   51 DQS17P SCONN288_H44441003_PIP-SCONN,HA   I120 @BASEBOARD_FAB2_LIB.BASEBOARD_FAB2(SCH_1):PAGE78

M_G_DQS_DP<1> @BASEBOARD_FAB2_LIB.BASEBOARD_FAB2(SCH_1):M_G_DQS_DP(1)
  U2D1  P85 DDR0_DQS_DP<1> SKX_EXT_B_BGA1-IC,TBD   I172 @BASEBOARD_FAB2_LIB.BASEBOARD_FAB2(SCH_1):PAGE57
  J1G1  164  DQS1P SCONN288_H44441004_PIP-SCONN,HA    I66 @BASEBOARD_FAB2_LIB.BASEBOARD_FAB2(SCH_1):PAGE77
  J9T1  164  DQS1P SCONN288_H44441003_PIP-SCONN,HA   I120 @BASEBOARD_FAB2_LIB.BASEBOARD_FAB2(SCH_1):PAGE78

M_G_DQS_DP<2> @BASEBOARD_FAB2_LIB.BASEBOARD_FAB2(SCH_1):M_G_DQS_DP(2)
  U2D1  R80 DDR0_DQS_DP<2> SKX_EXT_B_BGA1-IC,TBD   I172 @BASEBOARD_FAB2_LIB.BASEBOARD_FAB2(SCH_1):PAGE57
  J1G1  175  DQS2P SCONN288_H44441004_PIP-SCONN,HA    I66 @BASEBOARD_FAB2_LIB.BASEBOARD_FAB2(SCH_1):PAGE77
  J9T1  175  DQS2P SCONN288_H44441003_PIP-SCONN,HA   I120 @BASEBOARD_FAB2_LIB.BASEBOARD_FAB2(SCH_1):PAGE78

M_G_DQS_DP<3> @BASEBOARD_FAB2_LIB.BASEBOARD_FAB2(SCH_1):M_G_DQS_DP(3)
  U2D1  P75 DDR0_DQS_DP<3> SKX_EXT_B_BGA1-IC,TBD   I172 @BASEBOARD_FAB2_LIB.BASEBOARD_FAB2(SCH_1):PAGE57
  J1G1  186  DQS3P SCONN288_H44441004_PIP-SCONN,HA    I66 @BASEBOARD_FAB2_LIB.BASEBOARD_FAB2(SCH_1):PAGE77
  J9T1  186  DQS3P SCONN288_H44441003_PIP-SCONN,HA   I120 @BASEBOARD_FAB2_LIB.BASEBOARD_FAB2(SCH_1):PAGE78

M_G_DQS_DP<4> @BASEBOARD_FAB2_LIB.BASEBOARD_FAB2(SCH_1):M_G_DQS_DP(4)
  U2D1  E40 DDR0_DQS_DP<4> SKX_EXT_B_BGA1-IC,TBD   I172 @BASEBOARD_FAB2_LIB.BASEBOARD_FAB2(SCH_1):PAGE57
  J1G1  245  DQS4P SCONN288_H44441004_PIP-SCONN,HA    I66 @BASEBOARD_FAB2_LIB.BASEBOARD_FAB2(SCH_1):PAGE77
  J9T1  245  DQS4P SCONN288_H44441003_PIP-SCONN,HA   I120 @BASEBOARD_FAB2_LIB.BASEBOARD_FAB2(SCH_1):PAGE78

M_G_DQS_DP<5> @BASEBOARD_FAB2_LIB.BASEBOARD_FAB2(SCH_1):M_G_DQS_DP(5)
  U2D1  N36 DDR0_DQS_DP<5> SKX_EXT_B_BGA1-IC,TBD   I172 @BASEBOARD_FAB2_LIB.BASEBOARD_FAB2(SCH_1):PAGE57
  J1G1  256  DQS5P SCONN288_H44441004_PIP-SCONN,HA    I66 @BASEBOARD_FAB2_LIB.BASEBOARD_FAB2(SCH_1):PAGE77
  J9T1  256  DQS5P SCONN288_H44441003_PIP-SCONN,HA   I120 @BASEBOARD_FAB2_LIB.BASEBOARD_FAB2(SCH_1):PAGE78

M_G_DQS_DP<6> @BASEBOARD_FAB2_LIB.BASEBOARD_FAB2(SCH_1):M_G_DQS_DP(6)
  U2D1  N30 DDR0_DQS_DP<6> SKX_EXT_B_BGA1-IC,TBD   I172 @BASEBOARD_FAB2_LIB.BASEBOARD_FAB2(SCH_1):PAGE57
  J1G1  267  DQS6P SCONN288_H44441004_PIP-SCONN,HA    I66 @BASEBOARD_FAB2_LIB.BASEBOARD_FAB2(SCH_1):PAGE77
  J9T1  267  DQS6P SCONN288_H44441003_PIP-SCONN,HA   I120 @BASEBOARD_FAB2_LIB.BASEBOARD_FAB2(SCH_1):PAGE78

M_G_DQS_DP<7> @BASEBOARD_FAB2_LIB.BASEBOARD_FAB2(SCH_1):M_G_DQS_DP(7)
  U2D1  R24 DDR0_DQS_DP<7> SKX_EXT_B_BGA1-IC,TBD   I172 @BASEBOARD_FAB2_LIB.BASEBOARD_FAB2(SCH_1):PAGE57
  J1G1  278  DQS7P SCONN288_H44441004_PIP-SCONN,HA    I66 @BASEBOARD_FAB2_LIB.BASEBOARD_FAB2(SCH_1):PAGE77
  J9T1  278  DQS7P SCONN288_H44441003_PIP-SCONN,HA   I120 @BASEBOARD_FAB2_LIB.BASEBOARD_FAB2(SCH_1):PAGE78

M_G_DQS_DP<8> @BASEBOARD_FAB2_LIB.BASEBOARD_FAB2(SCH_1):M_G_DQS_DP(8)
  U2D1 AF67 DDR0_DQS_DP<8> SKX_EXT_B_BGA1-IC,TBD   I172 @BASEBOARD_FAB2_LIB.BASEBOARD_FAB2(SCH_1):PAGE57
  J1G1  197  DQS8P SCONN288_H44441004_PIP-SCONN,HA    I66 @BASEBOARD_FAB2_LIB.BASEBOARD_FAB2(SCH_1):PAGE77
  J9T1  197  DQS8P SCONN288_H44441003_PIP-SCONN,HA   I120 @BASEBOARD_FAB2_LIB.BASEBOARD_FAB2(SCH_1):PAGE78

M_G_DQS_DP<9> @BASEBOARD_FAB2_LIB.BASEBOARD_FAB2(SCH_1):M_G_DQS_DP(9)
  U2D1 AM85 DDR0_DQS_DP<9> SKX_EXT_B_BGA1-IC,TBD   I172 @BASEBOARD_FAB2_LIB.BASEBOARD_FAB2(SCH_1):PAGE57
  J1G1    7  DQS9P SCONN288_H44441004_PIP-SCONN,HA    I66 @BASEBOARD_FAB2_LIB.BASEBOARD_FAB2(SCH_1):PAGE77
  J9T1    7  DQS9P SCONN288_H44441003_PIP-SCONN,HA   I120 @BASEBOARD_FAB2_LIB.BASEBOARD_FAB2(SCH_1):PAGE78

M_G_ECC<0> @BASEBOARD_FAB2_LIB.BASEBOARD_FAB2(SCH_1):M_G_ECC(0)
  U2D1 AC68 DDR0_ECC<0> SKX_EXT_B_BGA1-IC,TBD   I172 @BASEBOARD_FAB2_LIB.BASEBOARD_FAB2(SCH_1):PAGE57
  J1G1  194  CB<1> SCONN288_H44441004_PIP-SCONN,HA   I111 @BASEBOARD_FAB2_LIB.BASEBOARD_FAB2(SCH_1):PAGE77
  J9T1   49  CB<0> SCONN288_H44441003_PIP-SCONN,HA    I13 @BASEBOARD_FAB2_LIB.BASEBOARD_FAB2(SCH_1):PAGE78

M_G_ECC<1> @BASEBOARD_FAB2_LIB.BASEBOARD_FAB2(SCH_1):M_G_ECC(1)
  U2D1 AG68 DDR0_ECC<1> SKX_EXT_B_BGA1-IC,TBD   I172 @BASEBOARD_FAB2_LIB.BASEBOARD_FAB2(SCH_1):PAGE57
  J1G1   49  CB<0> SCONN288_H44441004_PIP-SCONN,HA   I111 @BASEBOARD_FAB2_LIB.BASEBOARD_FAB2(SCH_1):PAGE77
  J9T1  194  CB<1> SCONN288_H44441003_PIP-SCONN,HA    I13 @BASEBOARD_FAB2_LIB.BASEBOARD_FAB2(SCH_1):PAGE78

M_G_ECC<2> @BASEBOARD_FAB2_LIB.BASEBOARD_FAB2(SCH_1):M_G_ECC(2)
  U2D1 AD65 DDR0_ECC<2> SKX_EXT_B_BGA1-IC,TBD   I172 @BASEBOARD_FAB2_LIB.BASEBOARD_FAB2(SCH_1):PAGE57
  J1G1  201  CB<3> SCONN288_H44441004_PIP-SCONN,HA   I111 @BASEBOARD_FAB2_LIB.BASEBOARD_FAB2(SCH_1):PAGE77
  J9T1   56  CB<2> SCONN288_H44441003_PIP-SCONN,HA    I13 @BASEBOARD_FAB2_LIB.BASEBOARD_FAB2(SCH_1):PAGE78

M_G_ECC<3> @BASEBOARD_FAB2_LIB.BASEBOARD_FAB2(SCH_1):M_G_ECC(3)
  U2D1 AF65 DDR0_ECC<3> SKX_EXT_B_BGA1-IC,TBD   I172 @BASEBOARD_FAB2_LIB.BASEBOARD_FAB2(SCH_1):PAGE57
  J1G1   56  CB<2> SCONN288_H44441004_PIP-SCONN,HA   I111 @BASEBOARD_FAB2_LIB.BASEBOARD_FAB2(SCH_1):PAGE77
  J9T1  201  CB<3> SCONN288_H44441003_PIP-SCONN,HA    I13 @BASEBOARD_FAB2_LIB.BASEBOARD_FAB2(SCH_1):PAGE78

M_G_ECC<4> @BASEBOARD_FAB2_LIB.BASEBOARD_FAB2(SCH_1):M_G_ECC(4)
  U2D1 AD69 DDR0_ECC<4> SKX_EXT_B_BGA1-IC,TBD   I172 @BASEBOARD_FAB2_LIB.BASEBOARD_FAB2(SCH_1):PAGE57
  J1G1  192  CB<5> SCONN288_H44441004_PIP-SCONN,HA   I111 @BASEBOARD_FAB2_LIB.BASEBOARD_FAB2(SCH_1):PAGE77
  J9T1   47  CB<4> SCONN288_H44441003_PIP-SCONN,HA    I13 @BASEBOARD_FAB2_LIB.BASEBOARD_FAB2(SCH_1):PAGE78

M_G_ECC<5> @BASEBOARD_FAB2_LIB.BASEBOARD_FAB2(SCH_1):M_G_ECC(5)
  U2D1 AF69 DDR0_ECC<5> SKX_EXT_B_BGA1-IC,TBD   I172 @BASEBOARD_FAB2_LIB.BASEBOARD_FAB2(SCH_1):PAGE57
  J1G1   47  CB<4> SCONN288_H44441004_PIP-SCONN,HA   I111 @BASEBOARD_FAB2_LIB.BASEBOARD_FAB2(SCH_1):PAGE77
  J9T1  192  CB<5> SCONN288_H44441003_PIP-SCONN,HA    I13 @BASEBOARD_FAB2_LIB.BASEBOARD_FAB2(SCH_1):PAGE78

M_G_ECC<6> @BASEBOARD_FAB2_LIB.BASEBOARD_FAB2(SCH_1):M_G_ECC(6)
  U2D1 AC66 DDR0_ECC<6> SKX_EXT_B_BGA1-IC,TBD   I172 @BASEBOARD_FAB2_LIB.BASEBOARD_FAB2(SCH_1):PAGE57
  J1G1  199  CB<7> SCONN288_H44441004_PIP-SCONN,HA   I111 @BASEBOARD_FAB2_LIB.BASEBOARD_FAB2(SCH_1):PAGE77
  J9T1   54  CB<6> SCONN288_H44441003_PIP-SCONN,HA    I13 @BASEBOARD_FAB2_LIB.BASEBOARD_FAB2(SCH_1):PAGE78

M_G_ECC<7> @BASEBOARD_FAB2_LIB.BASEBOARD_FAB2(SCH_1):M_G_ECC(7)
  U2D1 AG66 DDR0_ECC<7> SKX_EXT_B_BGA1-IC,TBD   I172 @BASEBOARD_FAB2_LIB.BASEBOARD_FAB2(SCH_1):PAGE57
  J1G1   54  CB<6> SCONN288_H44441004_PIP-SCONN,HA   I111 @BASEBOARD_FAB2_LIB.BASEBOARD_FAB2(SCH_1):PAGE77
  J9T1  199  CB<7> SCONN288_H44441003_PIP-SCONN,HA    I13 @BASEBOARD_FAB2_LIB.BASEBOARD_FAB2(SCH_1):PAGE78

M_G_MA<0> @BASEBOARD_FAB2_LIB.BASEBOARD_FAB2(SCH_1):M_G_MA(0)
  U2D1  F53 DDR0_MA<0> SKX_EXT_B_BGA1-IC,TBD   I172 @BASEBOARD_FAB2_LIB.BASEBOARD_FAB2(SCH_1):PAGE57
  J1G1   79     A0 SCONN288_H44441004_PIP-SCONN,HA   I111 @BASEBOARD_FAB2_LIB.BASEBOARD_FAB2(SCH_1):PAGE77
  J9T1   79     A0 SCONN288_H44441003_PIP-SCONN,HA    I13 @BASEBOARD_FAB2_LIB.BASEBOARD_FAB2(SCH_1):PAGE78

M_G_MA<10> @BASEBOARD_FAB2_LIB.BASEBOARD_FAB2(SCH_1):M_G_MA(10)
  U2D1  J54 DDR0_MA<10> SKX_EXT_B_BGA1-IC,TBD   I172 @BASEBOARD_FAB2_LIB.BASEBOARD_FAB2(SCH_1):PAGE57
  J1G1  225    A10 SCONN288_H44441004_PIP-SCONN,HA   I111 @BASEBOARD_FAB2_LIB.BASEBOARD_FAB2(SCH_1):PAGE77
  J9T1  225    A10 SCONN288_H44441003_PIP-SCONN,HA    I13 @BASEBOARD_FAB2_LIB.BASEBOARD_FAB2(SCH_1):PAGE78

M_G_MA<11> @BASEBOARD_FAB2_LIB.BASEBOARD_FAB2(SCH_1):M_G_MA(11)
  U2D1  G62 DDR0_MA<11> SKX_EXT_B_BGA1-IC,TBD   I172 @BASEBOARD_FAB2_LIB.BASEBOARD_FAB2(SCH_1):PAGE57
  J1G1  210    A11 SCONN288_H44441004_PIP-SCONN,HA   I111 @BASEBOARD_FAB2_LIB.BASEBOARD_FAB2(SCH_1):PAGE77
  J9T1  210    A11 SCONN288_H44441003_PIP-SCONN,HA    I13 @BASEBOARD_FAB2_LIB.BASEBOARD_FAB2(SCH_1):PAGE78

M_G_MA<12> @BASEBOARD_FAB2_LIB.BASEBOARD_FAB2(SCH_1):M_G_MA(12)
  U2D1  J64 DDR0_MA<12> SKX_EXT_B_BGA1-IC,TBD   I172 @BASEBOARD_FAB2_LIB.BASEBOARD_FAB2(SCH_1):PAGE57
  J1G1   65    A12 SCONN288_H44441004_PIP-SCONN,HA   I111 @BASEBOARD_FAB2_LIB.BASEBOARD_FAB2(SCH_1):PAGE77
  J9T1   65    A12 SCONN288_H44441003_PIP-SCONN,HA    I13 @BASEBOARD_FAB2_LIB.BASEBOARD_FAB2(SCH_1):PAGE78

M_G_MA<13> @BASEBOARD_FAB2_LIB.BASEBOARD_FAB2(SCH_1):M_G_MA(13)
  U2D1  J48 DDR0_MA<13> SKX_EXT_B_BGA1-IC,TBD   I172 @BASEBOARD_FAB2_LIB.BASEBOARD_FAB2(SCH_1):PAGE57
  J1G1  232    A13 SCONN288_H44441004_PIP-SCONN,HA   I111 @BASEBOARD_FAB2_LIB.BASEBOARD_FAB2(SCH_1):PAGE77
  J9T1  232    A13 SCONN288_H44441003_PIP-SCONN,HA    I13 @BASEBOARD_FAB2_LIB.BASEBOARD_FAB2(SCH_1):PAGE78

M_G_MA<14> @BASEBOARD_FAB2_LIB.BASEBOARD_FAB2(SCH_1):M_G_MA(14)
  U2D1  F51 DDR0_MA<14> SKX_EXT_B_BGA1-IC,TBD   I172 @BASEBOARD_FAB2_LIB.BASEBOARD_FAB2(SCH_1):PAGE57
  J1G1  228 A14_WE_N SCONN288_H44441004_PIP-SCONN,HA   I111 @BASEBOARD_FAB2_LIB.BASEBOARD_FAB2(SCH_1):PAGE77
  J9T1  228 A14_WE_N SCONN288_H44441003_PIP-SCONN,HA    I13 @BASEBOARD_FAB2_LIB.BASEBOARD_FAB2(SCH_1):PAGE78

M_G_MA<15> @BASEBOARD_FAB2_LIB.BASEBOARD_FAB2(SCH_1):M_G_MA(15)
  U2D1  K49 DDR0_MA<15> SKX_EXT_B_BGA1-IC,TBD   I172 @BASEBOARD_FAB2_LIB.BASEBOARD_FAB2(SCH_1):PAGE57
  J1G1   86 A15_CAS_N SCONN288_H44441004_PIP-SCONN,HA   I111 @BASEBOARD_FAB2_LIB.BASEBOARD_FAB2(SCH_1):PAGE77
  J9T1   86 A15_CAS_N SCONN288_H44441003_PIP-SCONN,HA    I13 @BASEBOARD_FAB2_LIB.BASEBOARD_FAB2(SCH_1):PAGE78

M_G_MA<16> @BASEBOARD_FAB2_LIB.BASEBOARD_FAB2(SCH_1):M_G_MA(16)
  U2D1  D51 DDR0_MA<16> SKX_EXT_B_BGA1-IC,TBD   I172 @BASEBOARD_FAB2_LIB.BASEBOARD_FAB2(SCH_1):PAGE57
  J1G1   82 A16_RAS_N SCONN288_H44441004_PIP-SCONN,HA   I111 @BASEBOARD_FAB2_LIB.BASEBOARD_FAB2(SCH_1):PAGE77
  J9T1   82 A16_RAS_N SCONN288_H44441003_PIP-SCONN,HA    I13 @BASEBOARD_FAB2_LIB.BASEBOARD_FAB2(SCH_1):PAGE78

M_G_MA<17> @BASEBOARD_FAB2_LIB.BASEBOARD_FAB2(SCH_1):M_G_MA(17)
  U2D1  K47 DDR0_MA<17> SKX_EXT_B_BGA1-IC,TBD   I172 @BASEBOARD_FAB2_LIB.BASEBOARD_FAB2(SCH_1):PAGE57
  J1G1  234    A17 SCONN288_H44441004_PIP-SCONN,HA   I111 @BASEBOARD_FAB2_LIB.BASEBOARD_FAB2(SCH_1):PAGE77
  J9T1  234    A17 SCONN288_H44441003_PIP-SCONN,HA    I13 @BASEBOARD_FAB2_LIB.BASEBOARD_FAB2(SCH_1):PAGE78

M_G_MA<1> @BASEBOARD_FAB2_LIB.BASEBOARD_FAB2(SCH_1):M_G_MA(1)
  U2D1  F57 DDR0_MA<1> SKX_EXT_B_BGA1-IC,TBD   I172 @BASEBOARD_FAB2_LIB.BASEBOARD_FAB2(SCH_1):PAGE57
  J1G1   72     A1 SCONN288_H44441004_PIP-SCONN,HA   I111 @BASEBOARD_FAB2_LIB.BASEBOARD_FAB2(SCH_1):PAGE77
  J9T1   72     A1 SCONN288_H44441003_PIP-SCONN,HA    I13 @BASEBOARD_FAB2_LIB.BASEBOARD_FAB2(SCH_1):PAGE78

M_G_MA<2> @BASEBOARD_FAB2_LIB.BASEBOARD_FAB2(SCH_1):M_G_MA(2)
  U2D1  D57 DDR0_MA<2> SKX_EXT_B_BGA1-IC,TBD   I172 @BASEBOARD_FAB2_LIB.BASEBOARD_FAB2(SCH_1):PAGE57
  J1G1  216     A2 SCONN288_H44441004_PIP-SCONN,HA   I111 @BASEBOARD_FAB2_LIB.BASEBOARD_FAB2(SCH_1):PAGE77
  J9T1  216     A2 SCONN288_H44441003_PIP-SCONN,HA    I13 @BASEBOARD_FAB2_LIB.BASEBOARD_FAB2(SCH_1):PAGE78

M_G_MA<3> @BASEBOARD_FAB2_LIB.BASEBOARD_FAB2(SCH_1):M_G_MA(3)
  U2D1  C58 DDR0_MA<3> SKX_EXT_B_BGA1-IC,TBD   I172 @BASEBOARD_FAB2_LIB.BASEBOARD_FAB2(SCH_1):PAGE57
  J1G1   71     A3 SCONN288_H44441004_PIP-SCONN,HA   I111 @BASEBOARD_FAB2_LIB.BASEBOARD_FAB2(SCH_1):PAGE77
  J9T1   71     A3 SCONN288_H44441003_PIP-SCONN,HA    I13 @BASEBOARD_FAB2_LIB.BASEBOARD_FAB2(SCH_1):PAGE78

M_G_MA<4> @BASEBOARD_FAB2_LIB.BASEBOARD_FAB2(SCH_1):M_G_MA(4)
  U2D1  G58 DDR0_MA<4> SKX_EXT_B_BGA1-IC,TBD   I172 @BASEBOARD_FAB2_LIB.BASEBOARD_FAB2(SCH_1):PAGE57
  J1G1  214     A4 SCONN288_H44441004_PIP-SCONN,HA   I111 @BASEBOARD_FAB2_LIB.BASEBOARD_FAB2(SCH_1):PAGE77
  J9T1  214     A4 SCONN288_H44441003_PIP-SCONN,HA    I13 @BASEBOARD_FAB2_LIB.BASEBOARD_FAB2(SCH_1):PAGE78

M_G_MA<5> @BASEBOARD_FAB2_LIB.BASEBOARD_FAB2(SCH_1):M_G_MA(5)
  U2D1  F59 DDR0_MA<5> SKX_EXT_B_BGA1-IC,TBD   I172 @BASEBOARD_FAB2_LIB.BASEBOARD_FAB2(SCH_1):PAGE57
  J1G1  213     A5 SCONN288_H44441004_PIP-SCONN,HA   I111 @BASEBOARD_FAB2_LIB.BASEBOARD_FAB2(SCH_1):PAGE77
  J9T1  213     A5 SCONN288_H44441003_PIP-SCONN,HA    I13 @BASEBOARD_FAB2_LIB.BASEBOARD_FAB2(SCH_1):PAGE78

M_G_MA<6> @BASEBOARD_FAB2_LIB.BASEBOARD_FAB2(SCH_1):M_G_MA(6)
  U2D1  D59 DDR0_MA<6> SKX_EXT_B_BGA1-IC,TBD   I172 @BASEBOARD_FAB2_LIB.BASEBOARD_FAB2(SCH_1):PAGE57
  J1G1   69     A6 SCONN288_H44441004_PIP-SCONN,HA   I111 @BASEBOARD_FAB2_LIB.BASEBOARD_FAB2(SCH_1):PAGE77
  J9T1   69     A6 SCONN288_H44441003_PIP-SCONN,HA    I13 @BASEBOARD_FAB2_LIB.BASEBOARD_FAB2(SCH_1):PAGE78

M_G_MA<7> @BASEBOARD_FAB2_LIB.BASEBOARD_FAB2(SCH_1):M_G_MA(7)
  U2D1  G60 DDR0_MA<7> SKX_EXT_B_BGA1-IC,TBD   I172 @BASEBOARD_FAB2_LIB.BASEBOARD_FAB2(SCH_1):PAGE57
  J1G1  211     A7 SCONN288_H44441004_PIP-SCONN,HA   I111 @BASEBOARD_FAB2_LIB.BASEBOARD_FAB2(SCH_1):PAGE77
  J9T1  211     A7 SCONN288_H44441003_PIP-SCONN,HA    I13 @BASEBOARD_FAB2_LIB.BASEBOARD_FAB2(SCH_1):PAGE78

M_G_MA<8> @BASEBOARD_FAB2_LIB.BASEBOARD_FAB2(SCH_1):M_G_MA(8)
  U2D1  C60 DDR0_MA<8> SKX_EXT_B_BGA1-IC,TBD   I172 @BASEBOARD_FAB2_LIB.BASEBOARD_FAB2(SCH_1):PAGE57
  J1G1   68     A8 SCONN288_H44441004_PIP-SCONN,HA   I111 @BASEBOARD_FAB2_LIB.BASEBOARD_FAB2(SCH_1):PAGE77
  J9T1   68     A8 SCONN288_H44441003_PIP-SCONN,HA    I13 @BASEBOARD_FAB2_LIB.BASEBOARD_FAB2(SCH_1):PAGE78

M_G_MA<9> @BASEBOARD_FAB2_LIB.BASEBOARD_FAB2(SCH_1):M_G_MA(9)
  U2D1  F61 DDR0_MA<9> SKX_EXT_B_BGA1-IC,TBD   I172 @BASEBOARD_FAB2_LIB.BASEBOARD_FAB2(SCH_1):PAGE57
  J1G1   66     A9 SCONN288_H44441004_PIP-SCONN,HA   I111 @BASEBOARD_FAB2_LIB.BASEBOARD_FAB2(SCH_1):PAGE77
  J9T1   66     A9 SCONN288_H44441003_PIP-SCONN,HA    I13 @BASEBOARD_FAB2_LIB.BASEBOARD_FAB2(SCH_1):PAGE78

M_G_ODT<0> @BASEBOARD_FAB2_LIB.BASEBOARD_FAB2(SCH_1):M_G_ODT(0)
  U2D1  C50 DDR0_ODT<0> SKX_EXT_B_BGA1-IC,TBD   I172 @BASEBOARD_FAB2_LIB.BASEBOARD_FAB2(SCH_1):PAGE57
  J1G1   87 ODT<0> SCONN288_H44441004_PIP-SCONN,HA   I111 @BASEBOARD_FAB2_LIB.BASEBOARD_FAB2(SCH_1):PAGE77

M_G_ODT<1> @BASEBOARD_FAB2_LIB.BASEBOARD_FAB2(SCH_1):M_G_ODT(1)
  U2D1  C48 DDR0_ODT<1> SKX_EXT_B_BGA1-IC,TBD   I172 @BASEBOARD_FAB2_LIB.BASEBOARD_FAB2(SCH_1):PAGE57
  J1G1   91 ODT<1> SCONN288_H44441004_PIP-SCONN,HA   I111 @BASEBOARD_FAB2_LIB.BASEBOARD_FAB2(SCH_1):PAGE77

M_G_ODT<2> @BASEBOARD_FAB2_LIB.BASEBOARD_FAB2(SCH_1):M_G_ODT(2)
  U2D1  G50 DDR0_ODT<2> SKX_EXT_B_BGA1-IC,TBD   I172 @BASEBOARD_FAB2_LIB.BASEBOARD_FAB2(SCH_1):PAGE57
  J9T1   87 ODT<0> SCONN288_H44441003_PIP-SCONN,HA    I13 @BASEBOARD_FAB2_LIB.BASEBOARD_FAB2(SCH_1):PAGE78

M_G_ODT<3> @BASEBOARD_FAB2_LIB.BASEBOARD_FAB2(SCH_1):M_G_ODT(3)
  U2D1  G48 DDR0_ODT<3> SKX_EXT_B_BGA1-IC,TBD   I172 @BASEBOARD_FAB2_LIB.BASEBOARD_FAB2(SCH_1):PAGE57
  J9T1   91 ODT<1> SCONN288_H44441003_PIP-SCONN,HA    I13 @BASEBOARD_FAB2_LIB.BASEBOARD_FAB2(SCH_1):PAGE78

M_G_PAR @BASEBOARD_FAB2_LIB.BASEBOARD_FAB2(SCH_1):M_G_PAR
  U2D1  D53 DDR0_PAR SKX_EXT_B_BGA1-IC,TBD   I172 @BASEBOARD_FAB2_LIB.BASEBOARD_FAB2(SCH_1):PAGE57
  J1G1  222    PAR SCONN288_H44441004_PIP-SCONN,HA   I111 @BASEBOARD_FAB2_LIB.BASEBOARD_FAB2(SCH_1):PAGE77
  J9T1  222    PAR SCONN288_H44441003_PIP-SCONN,HA    I13 @BASEBOARD_FAB2_LIB.BASEBOARD_FAB2(SCH_1):PAGE78

M_G_VREF @BASEBOARD_FAB2_LIB.BASEBOARD_FAB2(SCH_1):M_G_VREF
  J1G1  146 VREFCA SCONN288_H44441004_PIP-SCONN,HA   I111 @BASEBOARD_FAB2_LIB.BASEBOARD_FAB2(SCH_1):PAGE77
 C1F22    1      A CAP_A_0402V-0.01UF,25V,10%,X7RA   I181 @BASEBOARD_FAB2_LIB.BASEBOARD_FAB2(SCH_1):PAGE77
  C9T7    1      A CAP_A_0402V-0.01UF,25V,10%,X7RA     I2 @BASEBOARD_FAB2_LIB.BASEBOARD_FAB2(SCH_1):PAGE78
  J9T1  146 VREFCA SCONN288_H44441003_PIP-SCONN,HA    I13 @BASEBOARD_FAB2_LIB.BASEBOARD_FAB2(SCH_1):PAGE78
  R1F6    1      A RES_0402-1.00K,1%,1/16W,CHIP,GA     I2 @BASEBOARD_FAB2_LIB.BASEBOARD_FAB2(SCH_1):PAGE100
  R1F5    2      B RES_0402-1.00K,1%,1/16W,CHIP,GA     I6 @BASEBOARD_FAB2_LIB.BASEBOARD_FAB2(SCH_1):PAGE100
  R1F4    2      B RES_0402-2,1.0%,1/16W,CHIP,G21A     I7 @BASEBOARD_FAB2_LIB.BASEBOARD_FAB2(SCH_1):PAGE100

M_H_ACT_N @BASEBOARD_FAB2_LIB.BASEBOARD_FAB2(SCH_1):M_H_ACT_N
  U2D1  T63 DDR1_ACT_N SKX_EXT_B_BGA1-IC,TBD   I172 @BASEBOARD_FAB2_LIB.BASEBOARD_FAB2(SCH_1):PAGE58
  J1G2   62  ACT_N SCONN288_H44441004_PIP-SCONN,HA   I111 @BASEBOARD_FAB2_LIB.BASEBOARD_FAB2(SCH_1):PAGE79
  J9U1   62  ACT_N SCONN288_H44441003_PIP-SCONN,HA    I24 @BASEBOARD_FAB2_LIB.BASEBOARD_FAB2(SCH_1):PAGE80

M_H_ALERT_N @BASEBOARD_FAB2_LIB.BASEBOARD_FAB2(SCH_1):M_H_ALERT_N
  U2D1  W62 DDR1_ALERT_N SKX_EXT_B_BGA1-IC,TBD   I172 @BASEBOARD_FAB2_LIB.BASEBOARD_FAB2(SCH_1):PAGE58
  J1G2  208 ALERT_N SCONN288_H44441004_PIP-SCONN,HA   I111 @BASEBOARD_FAB2_LIB.BASEBOARD_FAB2(SCH_1):PAGE79
  J9U1  208 ALERT_N SCONN288_H44441003_PIP-SCONN,HA    I24 @BASEBOARD_FAB2_LIB.BASEBOARD_FAB2(SCH_1):PAGE80

M_H_BA<0> @BASEBOARD_FAB2_LIB.BASEBOARD_FAB2(SCH_1):M_H_BA(0)
  U2D1  T53 DDR1_BA<0> SKX_EXT_B_BGA1-IC,TBD   I172 @BASEBOARD_FAB2_LIB.BASEBOARD_FAB2(SCH_1):PAGE58
  J1G2   81  BA<0> SCONN288_H44441004_PIP-SCONN,HA   I111 @BASEBOARD_FAB2_LIB.BASEBOARD_FAB2(SCH_1):PAGE79
  J9U1   81  BA<0> SCONN288_H44441003_PIP-SCONN,HA    I24 @BASEBOARD_FAB2_LIB.BASEBOARD_FAB2(SCH_1):PAGE80

M_H_BA<1> @BASEBOARD_FAB2_LIB.BASEBOARD_FAB2(SCH_1):M_H_BA(1)
  U2D1  K55 DDR1_BA<1> SKX_EXT_B_BGA1-IC,TBD   I172 @BASEBOARD_FAB2_LIB.BASEBOARD_FAB2(SCH_1):PAGE58
  J1G2  224  BA<1> SCONN288_H44441004_PIP-SCONN,HA   I111 @BASEBOARD_FAB2_LIB.BASEBOARD_FAB2(SCH_1):PAGE79
  J9U1  224  BA<1> SCONN288_H44441003_PIP-SCONN,HA    I24 @BASEBOARD_FAB2_LIB.BASEBOARD_FAB2(SCH_1):PAGE80

M_H_BG<0> @BASEBOARD_FAB2_LIB.BASEBOARD_FAB2(SCH_1):M_H_BG(0)
  U2D1  M61 DDR1_BG<0> SKX_EXT_B_BGA1-IC,TBD   I172 @BASEBOARD_FAB2_LIB.BASEBOARD_FAB2(SCH_1):PAGE58
  J1G2   63  BG<0> SCONN288_H44441004_PIP-SCONN,HA   I111 @BASEBOARD_FAB2_LIB.BASEBOARD_FAB2(SCH_1):PAGE79
  J9U1   63  BG<0> SCONN288_H44441003_PIP-SCONN,HA    I24 @BASEBOARD_FAB2_LIB.BASEBOARD_FAB2(SCH_1):PAGE80

M_H_BG<1> @BASEBOARD_FAB2_LIB.BASEBOARD_FAB2(SCH_1):M_H_BG(1)
  U2D1  N60 DDR1_BG<1> SKX_EXT_B_BGA1-IC,TBD   I172 @BASEBOARD_FAB2_LIB.BASEBOARD_FAB2(SCH_1):PAGE58
  J1G2  207  BG<1> SCONN288_H44441004_PIP-SCONN,HA   I111 @BASEBOARD_FAB2_LIB.BASEBOARD_FAB2(SCH_1):PAGE79
  J9U1  207  BG<1> SCONN288_H44441003_PIP-SCONN,HA    I24 @BASEBOARD_FAB2_LIB.BASEBOARD_FAB2(SCH_1):PAGE80

M_H_C<2> @BASEBOARD_FAB2_LIB.BASEBOARD_FAB2(SCH_1):M_H_C(2)
  U2D1  M47 DDR1_CID<2> SKX_EXT_B_BGA1-IC,TBD   I172 @BASEBOARD_FAB2_LIB.BASEBOARD_FAB2(SCH_1):PAGE58
  J1G2  235   C<2> SCONN288_H44441004_PIP-SCONN,HA   I111 @BASEBOARD_FAB2_LIB.BASEBOARD_FAB2(SCH_1):PAGE79
  J9U1  235   C<2> SCONN288_H44441003_PIP-SCONN,HA    I24 @BASEBOARD_FAB2_LIB.BASEBOARD_FAB2(SCH_1):PAGE80

M_H_CKE<0> @BASEBOARD_FAB2_LIB.BASEBOARD_FAB2(SCH_1):M_H_CKE(0)
  U2D1  N62 DDR1_CKE<0> SKX_EXT_B_BGA1-IC,TBD   I172 @BASEBOARD_FAB2_LIB.BASEBOARD_FAB2(SCH_1):PAGE58
  J1G2   60 CKE<0> SCONN288_H44441004_PIP-SCONN,HA   I111 @BASEBOARD_FAB2_LIB.BASEBOARD_FAB2(SCH_1):PAGE79

M_H_CKE<1> @BASEBOARD_FAB2_LIB.BASEBOARD_FAB2(SCH_1):M_H_CKE(1)
  U2D1  R64 DDR1_CKE<1> SKX_EXT_B_BGA1-IC,TBD   I172 @BASEBOARD_FAB2_LIB.BASEBOARD_FAB2(SCH_1):PAGE58
  J1G2  203 CKE<1> SCONN288_H44441004_PIP-SCONN,HA   I111 @BASEBOARD_FAB2_LIB.BASEBOARD_FAB2(SCH_1):PAGE79

M_H_CKE<2> @BASEBOARD_FAB2_LIB.BASEBOARD_FAB2(SCH_1):M_H_CKE(2)
  U2D1  K63 DDR1_CKE<2> SKX_EXT_B_BGA1-IC,TBD   I172 @BASEBOARD_FAB2_LIB.BASEBOARD_FAB2(SCH_1):PAGE58
  J9U1   60 CKE<0> SCONN288_H44441003_PIP-SCONN,HA    I24 @BASEBOARD_FAB2_LIB.BASEBOARD_FAB2(SCH_1):PAGE80

M_H_CKE<3> @BASEBOARD_FAB2_LIB.BASEBOARD_FAB2(SCH_1):M_H_CKE(3)
  U2D1  L64 DDR1_CKE<3> SKX_EXT_B_BGA1-IC,TBD   I172 @BASEBOARD_FAB2_LIB.BASEBOARD_FAB2(SCH_1):PAGE58
  J9U1  203 CKE<1> SCONN288_H44441003_PIP-SCONN,HA    I24 @BASEBOARD_FAB2_LIB.BASEBOARD_FAB2(SCH_1):PAGE80

M_H_CLK_DN<0> @BASEBOARD_FAB2_LIB.BASEBOARD_FAB2(SCH_1):M_H_CLK_DN(0)
  U2D1  M53 DDR1_CLK_DN<0> SKX_EXT_B_BGA1-IC,TBD   I172 @BASEBOARD_FAB2_LIB.BASEBOARD_FAB2(SCH_1):PAGE58
  J1G2   75   CK0N SCONN288_H44441004_PIP-SCONN,HA   I111 @BASEBOARD_FAB2_LIB.BASEBOARD_FAB2(SCH_1):PAGE79

M_H_CLK_DN<1> @BASEBOARD_FAB2_LIB.BASEBOARD_FAB2(SCH_1):M_H_CLK_DN(1)
  U2D1  R54 DDR1_CLK_DN<1> SKX_EXT_B_BGA1-IC,TBD   I172 @BASEBOARD_FAB2_LIB.BASEBOARD_FAB2(SCH_1):PAGE58
  J1G2  219   CK1N SCONN288_H44441004_PIP-SCONN,HA   I111 @BASEBOARD_FAB2_LIB.BASEBOARD_FAB2(SCH_1):PAGE79

M_H_CLK_DN<2> @BASEBOARD_FAB2_LIB.BASEBOARD_FAB2(SCH_1):M_H_CLK_DN(2)
  U2D1  N56 DDR1_CLK_DN<2> SKX_EXT_B_BGA1-IC,TBD   I172 @BASEBOARD_FAB2_LIB.BASEBOARD_FAB2(SCH_1):PAGE58
  J9U1   75   CK0N SCONN288_H44441003_PIP-SCONN,HA    I24 @BASEBOARD_FAB2_LIB.BASEBOARD_FAB2(SCH_1):PAGE80

M_H_CLK_DN<3> @BASEBOARD_FAB2_LIB.BASEBOARD_FAB2(SCH_1):M_H_CLK_DN(3)
  U2D1  R56 DDR1_CLK_DN<3> SKX_EXT_B_BGA1-IC,TBD   I172 @BASEBOARD_FAB2_LIB.BASEBOARD_FAB2(SCH_1):PAGE58
  J9U1  219   CK1N SCONN288_H44441003_PIP-SCONN,HA    I24 @BASEBOARD_FAB2_LIB.BASEBOARD_FAB2(SCH_1):PAGE80

M_H_CLK_DP<0> @BASEBOARD_FAB2_LIB.BASEBOARD_FAB2(SCH_1):M_H_CLK_DP(0)
  U2D1  N54 DDR1_CLK_DP<0> SKX_EXT_B_BGA1-IC,TBD   I172 @BASEBOARD_FAB2_LIB.BASEBOARD_FAB2(SCH_1):PAGE58
  J1G2   74   CK0P SCONN288_H44441004_PIP-SCONN,HA   I111 @BASEBOARD_FAB2_LIB.BASEBOARD_FAB2(SCH_1):PAGE79

M_H_CLK_DP<1> @BASEBOARD_FAB2_LIB.BASEBOARD_FAB2(SCH_1):M_H_CLK_DP(1)
  U2D1  T55 DDR1_CLK_DP<1> SKX_EXT_B_BGA1-IC,TBD   I172 @BASEBOARD_FAB2_LIB.BASEBOARD_FAB2(SCH_1):PAGE58
  J1G2  218   CK1P SCONN288_H44441004_PIP-SCONN,HA   I111 @BASEBOARD_FAB2_LIB.BASEBOARD_FAB2(SCH_1):PAGE79

M_H_CLK_DP<2> @BASEBOARD_FAB2_LIB.BASEBOARD_FAB2(SCH_1):M_H_CLK_DP(2)
  U2D1  M57 DDR1_CLK_DP<2> SKX_EXT_B_BGA1-IC,TBD   I172 @BASEBOARD_FAB2_LIB.BASEBOARD_FAB2(SCH_1):PAGE58
  J9U1   74   CK0P SCONN288_H44441003_PIP-SCONN,HA    I24 @BASEBOARD_FAB2_LIB.BASEBOARD_FAB2(SCH_1):PAGE80

M_H_CLK_DP<3> @BASEBOARD_FAB2_LIB.BASEBOARD_FAB2(SCH_1):M_H_CLK_DP(3)
  U2D1  T57 DDR1_CLK_DP<3> SKX_EXT_B_BGA1-IC,TBD   I172 @BASEBOARD_FAB2_LIB.BASEBOARD_FAB2(SCH_1):PAGE58
  J9U1  218   CK1P SCONN288_H44441003_PIP-SCONN,HA    I24 @BASEBOARD_FAB2_LIB.BASEBOARD_FAB2(SCH_1):PAGE80

M_H_CPU_VREF @BASEBOARD_FAB2_LIB.BASEBOARD_FAB2(SCH_1):M_H_CPU_VREF
  U2D1 AK63 DDR1_CAVREF SKX_EXT_B_BGA1-IC,TBD   I172 @BASEBOARD_FAB2_LIB.BASEBOARD_FAB2(SCH_1):PAGE55
  R1G1    1      A RES_0402-2,1.0%,1/16W,CHIP,G21A    I25 @BASEBOARD_FAB2_LIB.BASEBOARD_FAB2(SCH_1):PAGE100
  C1G8    1      A CAP_A_0402V-0.01UF,25V,10%,X7RA    I26 @BASEBOARD_FAB2_LIB.BASEBOARD_FAB2(SCH_1):PAGE100

M_H_CS_N<0> @BASEBOARD_FAB2_LIB.BASEBOARD_FAB2(SCH_1):M_H_CS_N(0)
  U2D1  K51 DDR1_CS_N<0> SKX_EXT_B_BGA1-IC,TBD   I172 @BASEBOARD_FAB2_LIB.BASEBOARD_FAB2(SCH_1):PAGE58
  J1G2   84   S0_N SCONN288_H44441004_PIP-SCONN,HA   I111 @BASEBOARD_FAB2_LIB.BASEBOARD_FAB2(SCH_1):PAGE79

M_H_CS_N<1> @BASEBOARD_FAB2_LIB.BASEBOARD_FAB2(SCH_1):M_H_CS_N(1)
  U2D1  R50 DDR1_CS_N<1> SKX_EXT_B_BGA1-IC,TBD   I172 @BASEBOARD_FAB2_LIB.BASEBOARD_FAB2(SCH_1):PAGE58
  J1G2   89   S1_N SCONN288_H44441004_PIP-SCONN,HA   I111 @BASEBOARD_FAB2_LIB.BASEBOARD_FAB2(SCH_1):PAGE79

M_H_CS_N<2> @BASEBOARD_FAB2_LIB.BASEBOARD_FAB2(SCH_1):M_H_CS_N(2)
  U2D1  N46 DDR1_CS_N<2> SKX_EXT_B_BGA1-IC,TBD   I172 @BASEBOARD_FAB2_LIB.BASEBOARD_FAB2(SCH_1):PAGE58
  J1G2   93 S2_N_C<0> SCONN288_H44441004_PIP-SCONN,HA   I111 @BASEBOARD_FAB2_LIB.BASEBOARD_FAB2(SCH_1):PAGE79

M_H_CS_N<3> @BASEBOARD_FAB2_LIB.BASEBOARD_FAB2(SCH_1):M_H_CS_N(3)
  U2D1  V47 DDR1_CS_N<3> SKX_EXT_B_BGA1-IC,TBD   I172 @BASEBOARD_FAB2_LIB.BASEBOARD_FAB2(SCH_1):PAGE58
  J1G2  237 S3_N_C<1> SCONN288_H44441004_PIP-SCONN,HA   I111 @BASEBOARD_FAB2_LIB.BASEBOARD_FAB2(SCH_1):PAGE79

M_H_CS_N<4> @BASEBOARD_FAB2_LIB.BASEBOARD_FAB2(SCH_1):M_H_CS_N(4)
  U2D1  J50 DDR1_CS_N<4> SKX_EXT_B_BGA1-IC,TBD   I172 @BASEBOARD_FAB2_LIB.BASEBOARD_FAB2(SCH_1):PAGE58
  J9U1   84   S0_N SCONN288_H44441003_PIP-SCONN,HA    I24 @BASEBOARD_FAB2_LIB.BASEBOARD_FAB2(SCH_1):PAGE80

M_H_CS_N<5> @BASEBOARD_FAB2_LIB.BASEBOARD_FAB2(SCH_1):M_H_CS_N(5)
  U2D1  T49 DDR1_CS_N<5> SKX_EXT_B_BGA1-IC,TBD   I172 @BASEBOARD_FAB2_LIB.BASEBOARD_FAB2(SCH_1):PAGE58
  J9U1   89   S1_N SCONN288_H44441003_PIP-SCONN,HA    I24 @BASEBOARD_FAB2_LIB.BASEBOARD_FAB2(SCH_1):PAGE80

M_H_CS_N<6> @BASEBOARD_FAB2_LIB.BASEBOARD_FAB2(SCH_1):M_H_CS_N(6)
  U2D1  M45 DDR1_CS_N<6> SKX_EXT_B_BGA1-IC,TBD   I172 @BASEBOARD_FAB2_LIB.BASEBOARD_FAB2(SCH_1):PAGE58
  J9U1   93 S2_N_C<0> SCONN288_H44441003_PIP-SCONN,HA    I24 @BASEBOARD_FAB2_LIB.BASEBOARD_FAB2(SCH_1):PAGE80

M_H_CS_N<7> @BASEBOARD_FAB2_LIB.BASEBOARD_FAB2(SCH_1):M_H_CS_N(7)
  U2D1  R46 DDR1_CS_N<7> SKX_EXT_B_BGA1-IC,TBD   I172 @BASEBOARD_FAB2_LIB.BASEBOARD_FAB2(SCH_1):PAGE58
  J9U1  237 S3_N_C<1> SCONN288_H44441003_PIP-SCONN,HA    I24 @BASEBOARD_FAB2_LIB.BASEBOARD_FAB2(SCH_1):PAGE80

M_H_DQ<0> @BASEBOARD_FAB2_LIB.BASEBOARD_FAB2(SCH_1):M_H_DQ(0)
  U2D1 AV81 DDR1_DQ<0> SKX_EXT_B_BGA1-IC,TBD   I172 @BASEBOARD_FAB2_LIB.BASEBOARD_FAB2(SCH_1):PAGE58
  J1G2  150  DQ<1> SCONN288_H44441004_PIP-SCONN,HA   I111 @BASEBOARD_FAB2_LIB.BASEBOARD_FAB2(SCH_1):PAGE79
  J9U1    5  DQ<0> SCONN288_H44441003_PIP-SCONN,HA    I24 @BASEBOARD_FAB2_LIB.BASEBOARD_FAB2(SCH_1):PAGE80

M_H_DQ<10> @BASEBOARD_FAB2_LIB.BASEBOARD_FAB2(SCH_1):M_H_DQ(10)
  U2D1 AC82 DDR1_DQ<10> SKX_EXT_B_BGA1-IC,TBD   I172 @BASEBOARD_FAB2_LIB.BASEBOARD_FAB2(SCH_1):PAGE58
  J1G2  168 DQ<11> SCONN288_H44441004_PIP-SCONN,HA   I111 @BASEBOARD_FAB2_LIB.BASEBOARD_FAB2(SCH_1):PAGE79
  J9U1   23 DQ<10> SCONN288_H44441003_PIP-SCONN,HA    I24 @BASEBOARD_FAB2_LIB.BASEBOARD_FAB2(SCH_1):PAGE80

M_H_DQ<11> @BASEBOARD_FAB2_LIB.BASEBOARD_FAB2(SCH_1):M_H_DQ(11)
  U2D1 AB81 DDR1_DQ<11> SKX_EXT_B_BGA1-IC,TBD   I172 @BASEBOARD_FAB2_LIB.BASEBOARD_FAB2(SCH_1):PAGE58
  J1G2   23 DQ<10> SCONN288_H44441004_PIP-SCONN,HA   I111 @BASEBOARD_FAB2_LIB.BASEBOARD_FAB2(SCH_1):PAGE79
  J9U1  168 DQ<11> SCONN288_H44441003_PIP-SCONN,HA    I24 @BASEBOARD_FAB2_LIB.BASEBOARD_FAB2(SCH_1):PAGE80

M_H_DQ<12> @BASEBOARD_FAB2_LIB.BASEBOARD_FAB2(SCH_1):M_H_DQ(12)
  U2D1 AJ80 DDR1_DQ<12> SKX_EXT_B_BGA1-IC,TBD   I172 @BASEBOARD_FAB2_LIB.BASEBOARD_FAB2(SCH_1):PAGE58
  J1G2  159 DQ<13> SCONN288_H44441004_PIP-SCONN,HA   I111 @BASEBOARD_FAB2_LIB.BASEBOARD_FAB2(SCH_1):PAGE79
  J9U1   14 DQ<12> SCONN288_H44441003_PIP-SCONN,HA    I24 @BASEBOARD_FAB2_LIB.BASEBOARD_FAB2(SCH_1):PAGE80

M_H_DQ<13> @BASEBOARD_FAB2_LIB.BASEBOARD_FAB2(SCH_1):M_H_DQ(13)
  U2D1 AH79 DDR1_DQ<13> SKX_EXT_B_BGA1-IC,TBD   I172 @BASEBOARD_FAB2_LIB.BASEBOARD_FAB2(SCH_1):PAGE58
  J1G2   14 DQ<12> SCONN288_H44441004_PIP-SCONN,HA   I111 @BASEBOARD_FAB2_LIB.BASEBOARD_FAB2(SCH_1):PAGE79
  J9U1  159 DQ<13> SCONN288_H44441003_PIP-SCONN,HA    I24 @BASEBOARD_FAB2_LIB.BASEBOARD_FAB2(SCH_1):PAGE80

M_H_DQ<14> @BASEBOARD_FAB2_LIB.BASEBOARD_FAB2(SCH_1):M_H_DQ(14)
  U2D1 AE82 DDR1_DQ<14> SKX_EXT_B_BGA1-IC,TBD   I172 @BASEBOARD_FAB2_LIB.BASEBOARD_FAB2(SCH_1):PAGE58
  J1G2  166 DQ<15> SCONN288_H44441004_PIP-SCONN,HA   I111 @BASEBOARD_FAB2_LIB.BASEBOARD_FAB2(SCH_1):PAGE79
  J9U1   21 DQ<14> SCONN288_H44441003_PIP-SCONN,HA    I24 @BASEBOARD_FAB2_LIB.BASEBOARD_FAB2(SCH_1):PAGE80

M_H_DQ<15> @BASEBOARD_FAB2_LIB.BASEBOARD_FAB2(SCH_1):M_H_DQ(15)
  U2D1 AC80 DDR1_DQ<15> SKX_EXT_B_BGA1-IC,TBD   I172 @BASEBOARD_FAB2_LIB.BASEBOARD_FAB2(SCH_1):PAGE58
  J1G2   21 DQ<14> SCONN288_H44441004_PIP-SCONN,HA   I111 @BASEBOARD_FAB2_LIB.BASEBOARD_FAB2(SCH_1):PAGE79
  J9U1  166 DQ<15> SCONN288_H44441003_PIP-SCONN,HA    I24 @BASEBOARD_FAB2_LIB.BASEBOARD_FAB2(SCH_1):PAGE80

M_H_DQ<16> @BASEBOARD_FAB2_LIB.BASEBOARD_FAB2(SCH_1):M_H_DQ(16)
  U2D1  E80 DDR1_DQ<16> SKX_EXT_B_BGA1-IC,TBD   I172 @BASEBOARD_FAB2_LIB.BASEBOARD_FAB2(SCH_1):PAGE58
  J1G2  172 DQ<17> SCONN288_H44441004_PIP-SCONN,HA   I111 @BASEBOARD_FAB2_LIB.BASEBOARD_FAB2(SCH_1):PAGE79
  J9U1   27 DQ<16> SCONN288_H44441003_PIP-SCONN,HA    I24 @BASEBOARD_FAB2_LIB.BASEBOARD_FAB2(SCH_1):PAGE80

M_H_DQ<17> @BASEBOARD_FAB2_LIB.BASEBOARD_FAB2(SCH_1):M_H_DQ(17)
  U2D1  J80 DDR1_DQ<17> SKX_EXT_B_BGA1-IC,TBD   I172 @BASEBOARD_FAB2_LIB.BASEBOARD_FAB2(SCH_1):PAGE58
  J1G2   27 DQ<16> SCONN288_H44441004_PIP-SCONN,HA   I111 @BASEBOARD_FAB2_LIB.BASEBOARD_FAB2(SCH_1):PAGE79
  J9U1  172 DQ<17> SCONN288_H44441003_PIP-SCONN,HA    I24 @BASEBOARD_FAB2_LIB.BASEBOARD_FAB2(SCH_1):PAGE80

M_H_DQ<18> @BASEBOARD_FAB2_LIB.BASEBOARD_FAB2(SCH_1):M_H_DQ(18)
  U2D1  F77 DDR1_DQ<18> SKX_EXT_B_BGA1-IC,TBD   I172 @BASEBOARD_FAB2_LIB.BASEBOARD_FAB2(SCH_1):PAGE58
  J1G2  179 DQ<19> SCONN288_H44441004_PIP-SCONN,HA   I111 @BASEBOARD_FAB2_LIB.BASEBOARD_FAB2(SCH_1):PAGE79
  J9U1   34 DQ<18> SCONN288_H44441003_PIP-SCONN,HA    I24 @BASEBOARD_FAB2_LIB.BASEBOARD_FAB2(SCH_1):PAGE80

M_H_DQ<19> @BASEBOARD_FAB2_LIB.BASEBOARD_FAB2(SCH_1):M_H_DQ(19)
  U2D1  H77 DDR1_DQ<19> SKX_EXT_B_BGA1-IC,TBD   I172 @BASEBOARD_FAB2_LIB.BASEBOARD_FAB2(SCH_1):PAGE58
  J1G2   34 DQ<18> SCONN288_H44441004_PIP-SCONN,HA   I111 @BASEBOARD_FAB2_LIB.BASEBOARD_FAB2(SCH_1):PAGE79
  J9U1  179 DQ<19> SCONN288_H44441003_PIP-SCONN,HA    I24 @BASEBOARD_FAB2_LIB.BASEBOARD_FAB2(SCH_1):PAGE80

M_H_DQ<1> @BASEBOARD_FAB2_LIB.BASEBOARD_FAB2(SCH_1):M_H_DQ(1)
  U2D1 AT79 DDR1_DQ<1> SKX_EXT_B_BGA1-IC,TBD   I172 @BASEBOARD_FAB2_LIB.BASEBOARD_FAB2(SCH_1):PAGE58
  J1G2    5  DQ<0> SCONN288_H44441004_PIP-SCONN,HA   I111 @BASEBOARD_FAB2_LIB.BASEBOARD_FAB2(SCH_1):PAGE79
  J9U1  150  DQ<1> SCONN288_H44441003_PIP-SCONN,HA    I24 @BASEBOARD_FAB2_LIB.BASEBOARD_FAB2(SCH_1):PAGE80

M_H_DQ<20> @BASEBOARD_FAB2_LIB.BASEBOARD_FAB2(SCH_1):M_H_DQ(20)
  U2D1  F81 DDR1_DQ<20> SKX_EXT_B_BGA1-IC,TBD   I172 @BASEBOARD_FAB2_LIB.BASEBOARD_FAB2(SCH_1):PAGE58
  J1G2  170 DQ<21> SCONN288_H44441004_PIP-SCONN,HA   I111 @BASEBOARD_FAB2_LIB.BASEBOARD_FAB2(SCH_1):PAGE79
  J9U1   25 DQ<20> SCONN288_H44441003_PIP-SCONN,HA    I24 @BASEBOARD_FAB2_LIB.BASEBOARD_FAB2(SCH_1):PAGE80

M_H_DQ<21> @BASEBOARD_FAB2_LIB.BASEBOARD_FAB2(SCH_1):M_H_DQ(21)
  U2D1  H81 DDR1_DQ<21> SKX_EXT_B_BGA1-IC,TBD   I172 @BASEBOARD_FAB2_LIB.BASEBOARD_FAB2(SCH_1):PAGE58
  J1G2   25 DQ<20> SCONN288_H44441004_PIP-SCONN,HA   I111 @BASEBOARD_FAB2_LIB.BASEBOARD_FAB2(SCH_1):PAGE79
  J9U1  170 DQ<21> SCONN288_H44441003_PIP-SCONN,HA    I24 @BASEBOARD_FAB2_LIB.BASEBOARD_FAB2(SCH_1):PAGE80

M_H_DQ<22> @BASEBOARD_FAB2_LIB.BASEBOARD_FAB2(SCH_1):M_H_DQ(22)
  U2D1  E78 DDR1_DQ<22> SKX_EXT_B_BGA1-IC,TBD   I172 @BASEBOARD_FAB2_LIB.BASEBOARD_FAB2(SCH_1):PAGE58
  J1G2  177 DQ<23> SCONN288_H44441004_PIP-SCONN,HA   I111 @BASEBOARD_FAB2_LIB.BASEBOARD_FAB2(SCH_1):PAGE79
  J9U1   32 DQ<22> SCONN288_H44441003_PIP-SCONN,HA    I24 @BASEBOARD_FAB2_LIB.BASEBOARD_FAB2(SCH_1):PAGE80

M_H_DQ<23> @BASEBOARD_FAB2_LIB.BASEBOARD_FAB2(SCH_1):M_H_DQ(23)
  U2D1  J78 DDR1_DQ<23> SKX_EXT_B_BGA1-IC,TBD   I172 @BASEBOARD_FAB2_LIB.BASEBOARD_FAB2(SCH_1):PAGE58
  J1G2   32 DQ<22> SCONN288_H44441004_PIP-SCONN,HA   I111 @BASEBOARD_FAB2_LIB.BASEBOARD_FAB2(SCH_1):PAGE79
  J9U1  177 DQ<23> SCONN288_H44441003_PIP-SCONN,HA    I24 @BASEBOARD_FAB2_LIB.BASEBOARD_FAB2(SCH_1):PAGE80

M_H_DQ<24> @BASEBOARD_FAB2_LIB.BASEBOARD_FAB2(SCH_1):M_H_DQ(24)
  U2D1  D75 DDR1_DQ<24> SKX_EXT_B_BGA1-IC,TBD   I172 @BASEBOARD_FAB2_LIB.BASEBOARD_FAB2(SCH_1):PAGE58
  J1G2  183 DQ<25> SCONN288_H44441004_PIP-SCONN,HA   I111 @BASEBOARD_FAB2_LIB.BASEBOARD_FAB2(SCH_1):PAGE79
  J9U1   38 DQ<24> SCONN288_H44441003_PIP-SCONN,HA    I24 @BASEBOARD_FAB2_LIB.BASEBOARD_FAB2(SCH_1):PAGE80

M_H_DQ<25> @BASEBOARD_FAB2_LIB.BASEBOARD_FAB2(SCH_1):M_H_DQ(25)
  U2D1  C74 DDR1_DQ<25> SKX_EXT_B_BGA1-IC,TBD   I172 @BASEBOARD_FAB2_LIB.BASEBOARD_FAB2(SCH_1):PAGE58
  J1G2   38 DQ<24> SCONN288_H44441004_PIP-SCONN,HA   I111 @BASEBOARD_FAB2_LIB.BASEBOARD_FAB2(SCH_1):PAGE79
  J9U1  183 DQ<25> SCONN288_H44441003_PIP-SCONN,HA    I24 @BASEBOARD_FAB2_LIB.BASEBOARD_FAB2(SCH_1):PAGE80

M_H_DQ<26> @BASEBOARD_FAB2_LIB.BASEBOARD_FAB2(SCH_1):M_H_DQ(26)
  U2D1  D71 DDR1_DQ<26> SKX_EXT_B_BGA1-IC,TBD   I172 @BASEBOARD_FAB2_LIB.BASEBOARD_FAB2(SCH_1):PAGE58
  J1G2  190 DQ<27> SCONN288_H44441004_PIP-SCONN,HA   I111 @BASEBOARD_FAB2_LIB.BASEBOARD_FAB2(SCH_1):PAGE79
  J9U1   45 DQ<26> SCONN288_H44441003_PIP-SCONN,HA    I24 @BASEBOARD_FAB2_LIB.BASEBOARD_FAB2(SCH_1):PAGE80

M_H_DQ<27> @BASEBOARD_FAB2_LIB.BASEBOARD_FAB2(SCH_1):M_H_DQ(27)
  U2D1  F71 DDR1_DQ<27> SKX_EXT_B_BGA1-IC,TBD   I172 @BASEBOARD_FAB2_LIB.BASEBOARD_FAB2(SCH_1):PAGE58
  J1G2   45 DQ<26> SCONN288_H44441004_PIP-SCONN,HA   I111 @BASEBOARD_FAB2_LIB.BASEBOARD_FAB2(SCH_1):PAGE79
  J9U1  190 DQ<27> SCONN288_H44441003_PIP-SCONN,HA    I24 @BASEBOARD_FAB2_LIB.BASEBOARD_FAB2(SCH_1):PAGE80

M_H_DQ<28> @BASEBOARD_FAB2_LIB.BASEBOARD_FAB2(SCH_1):M_H_DQ(28)
  U2D1  F75 DDR1_DQ<28> SKX_EXT_B_BGA1-IC,TBD   I172 @BASEBOARD_FAB2_LIB.BASEBOARD_FAB2(SCH_1):PAGE58
  J1G2  181 DQ<29> SCONN288_H44441004_PIP-SCONN,HA   I111 @BASEBOARD_FAB2_LIB.BASEBOARD_FAB2(SCH_1):PAGE79
  J9U1   36 DQ<28> SCONN288_H44441003_PIP-SCONN,HA    I24 @BASEBOARD_FAB2_LIB.BASEBOARD_FAB2(SCH_1):PAGE80

M_H_DQ<29> @BASEBOARD_FAB2_LIB.BASEBOARD_FAB2(SCH_1):M_H_DQ(29)
  U2D1  G74 DDR1_DQ<29> SKX_EXT_B_BGA1-IC,TBD   I172 @BASEBOARD_FAB2_LIB.BASEBOARD_FAB2(SCH_1):PAGE58
  J1G2   36 DQ<28> SCONN288_H44441004_PIP-SCONN,HA   I111 @BASEBOARD_FAB2_LIB.BASEBOARD_FAB2(SCH_1):PAGE79
  J9U1  181 DQ<29> SCONN288_H44441003_PIP-SCONN,HA    I24 @BASEBOARD_FAB2_LIB.BASEBOARD_FAB2(SCH_1):PAGE80

M_H_DQ<2> @BASEBOARD_FAB2_LIB.BASEBOARD_FAB2(SCH_1):M_H_DQ(2)
  U2D1 AN82 DDR1_DQ<2> SKX_EXT_B_BGA1-IC,TBD   I172 @BASEBOARD_FAB2_LIB.BASEBOARD_FAB2(SCH_1):PAGE58
  J1G2  157  DQ<3> SCONN288_H44441004_PIP-SCONN,HA   I111 @BASEBOARD_FAB2_LIB.BASEBOARD_FAB2(SCH_1):PAGE79
  J9U1   12  DQ<2> SCONN288_H44441003_PIP-SCONN,HA    I24 @BASEBOARD_FAB2_LIB.BASEBOARD_FAB2(SCH_1):PAGE80

M_H_DQ<30> @BASEBOARD_FAB2_LIB.BASEBOARD_FAB2(SCH_1):M_H_DQ(30)
  U2D1  C72 DDR1_DQ<30> SKX_EXT_B_BGA1-IC,TBD   I172 @BASEBOARD_FAB2_LIB.BASEBOARD_FAB2(SCH_1):PAGE58
  J1G2  188 DQ<31> SCONN288_H44441004_PIP-SCONN,HA   I111 @BASEBOARD_FAB2_LIB.BASEBOARD_FAB2(SCH_1):PAGE79
  J9U1   43 DQ<30> SCONN288_H44441003_PIP-SCONN,HA    I24 @BASEBOARD_FAB2_LIB.BASEBOARD_FAB2(SCH_1):PAGE80

M_H_DQ<31> @BASEBOARD_FAB2_LIB.BASEBOARD_FAB2(SCH_1):M_H_DQ(31)
  U2D1  G72 DDR1_DQ<31> SKX_EXT_B_BGA1-IC,TBD   I172 @BASEBOARD_FAB2_LIB.BASEBOARD_FAB2(SCH_1):PAGE58
  J1G2   43 DQ<30> SCONN288_H44441004_PIP-SCONN,HA   I111 @BASEBOARD_FAB2_LIB.BASEBOARD_FAB2(SCH_1):PAGE79
  J9U1  188 DQ<31> SCONN288_H44441003_PIP-SCONN,HA    I24 @BASEBOARD_FAB2_LIB.BASEBOARD_FAB2(SCH_1):PAGE80

M_H_DQ<32> @BASEBOARD_FAB2_LIB.BASEBOARD_FAB2(SCH_1):M_H_DQ(32)
  U2D1  K43 DDR1_DQ<32> SKX_EXT_B_BGA1-IC,TBD   I172 @BASEBOARD_FAB2_LIB.BASEBOARD_FAB2(SCH_1):PAGE58
  J1G2  242 DQ<33> SCONN288_H44441004_PIP-SCONN,HA   I111 @BASEBOARD_FAB2_LIB.BASEBOARD_FAB2(SCH_1):PAGE79
  J9U1   97 DQ<32> SCONN288_H44441003_PIP-SCONN,HA    I24 @BASEBOARD_FAB2_LIB.BASEBOARD_FAB2(SCH_1):PAGE80

M_H_DQ<33> @BASEBOARD_FAB2_LIB.BASEBOARD_FAB2(SCH_1):M_H_DQ(33)
  U2D1  H43 DDR1_DQ<33> SKX_EXT_B_BGA1-IC,TBD   I172 @BASEBOARD_FAB2_LIB.BASEBOARD_FAB2(SCH_1):PAGE58
  J1G2   97 DQ<32> SCONN288_H44441004_PIP-SCONN,HA   I111 @BASEBOARD_FAB2_LIB.BASEBOARD_FAB2(SCH_1):PAGE79
  J9U1  242 DQ<33> SCONN288_H44441003_PIP-SCONN,HA    I24 @BASEBOARD_FAB2_LIB.BASEBOARD_FAB2(SCH_1):PAGE80

M_H_DQ<34> @BASEBOARD_FAB2_LIB.BASEBOARD_FAB2(SCH_1):M_H_DQ(34)
  U2D1  L40 DDR1_DQ<34> SKX_EXT_B_BGA1-IC,TBD   I172 @BASEBOARD_FAB2_LIB.BASEBOARD_FAB2(SCH_1):PAGE58
  J1G2  249 DQ<35> SCONN288_H44441004_PIP-SCONN,HA   I111 @BASEBOARD_FAB2_LIB.BASEBOARD_FAB2(SCH_1):PAGE79
  J9U1  104 DQ<34> SCONN288_H44441003_PIP-SCONN,HA    I24 @BASEBOARD_FAB2_LIB.BASEBOARD_FAB2(SCH_1):PAGE80

M_H_DQ<35> @BASEBOARD_FAB2_LIB.BASEBOARD_FAB2(SCH_1):M_H_DQ(35)
  U2D1  N40 DDR1_DQ<35> SKX_EXT_B_BGA1-IC,TBD   I172 @BASEBOARD_FAB2_LIB.BASEBOARD_FAB2(SCH_1):PAGE58
  J1G2  104 DQ<34> SCONN288_H44441004_PIP-SCONN,HA   I111 @BASEBOARD_FAB2_LIB.BASEBOARD_FAB2(SCH_1):PAGE79
  J9U1  249 DQ<35> SCONN288_H44441003_PIP-SCONN,HA    I24 @BASEBOARD_FAB2_LIB.BASEBOARD_FAB2(SCH_1):PAGE80

M_H_DQ<36> @BASEBOARD_FAB2_LIB.BASEBOARD_FAB2(SCH_1):M_H_DQ(36)
  U2D1  P43 DDR1_DQ<36> SKX_EXT_B_BGA1-IC,TBD   I172 @BASEBOARD_FAB2_LIB.BASEBOARD_FAB2(SCH_1):PAGE58
  J1G2  240 DQ<37> SCONN288_H44441004_PIP-SCONN,HA   I111 @BASEBOARD_FAB2_LIB.BASEBOARD_FAB2(SCH_1):PAGE79
  J9U1   95 DQ<36> SCONN288_H44441003_PIP-SCONN,HA    I24 @BASEBOARD_FAB2_LIB.BASEBOARD_FAB2(SCH_1):PAGE80

M_H_DQ<37> @BASEBOARD_FAB2_LIB.BASEBOARD_FAB2(SCH_1):M_H_DQ(37)
  U2D1  T43 DDR1_DQ<37> SKX_EXT_B_BGA1-IC,TBD   I172 @BASEBOARD_FAB2_LIB.BASEBOARD_FAB2(SCH_1):PAGE58
  J1G2   95 DQ<36> SCONN288_H44441004_PIP-SCONN,HA   I111 @BASEBOARD_FAB2_LIB.BASEBOARD_FAB2(SCH_1):PAGE79
  J9U1  240 DQ<37> SCONN288_H44441003_PIP-SCONN,HA    I24 @BASEBOARD_FAB2_LIB.BASEBOARD_FAB2(SCH_1):PAGE80

M_H_DQ<38> @BASEBOARD_FAB2_LIB.BASEBOARD_FAB2(SCH_1):M_H_DQ(38)
  U2D1  K41 DDR1_DQ<38> SKX_EXT_B_BGA1-IC,TBD   I172 @BASEBOARD_FAB2_LIB.BASEBOARD_FAB2(SCH_1):PAGE58
  J1G2  247 DQ<39> SCONN288_H44441004_PIP-SCONN,HA   I111 @BASEBOARD_FAB2_LIB.BASEBOARD_FAB2(SCH_1):PAGE79
  J9U1  102 DQ<38> SCONN288_H44441003_PIP-SCONN,HA    I24 @BASEBOARD_FAB2_LIB.BASEBOARD_FAB2(SCH_1):PAGE80

M_H_DQ<39> @BASEBOARD_FAB2_LIB.BASEBOARD_FAB2(SCH_1):M_H_DQ(39)
  U2D1  P41 DDR1_DQ<39> SKX_EXT_B_BGA1-IC,TBD   I172 @BASEBOARD_FAB2_LIB.BASEBOARD_FAB2(SCH_1):PAGE58
  J1G2  102 DQ<38> SCONN288_H44441004_PIP-SCONN,HA   I111 @BASEBOARD_FAB2_LIB.BASEBOARD_FAB2(SCH_1):PAGE79
  J9U1  247 DQ<39> SCONN288_H44441003_PIP-SCONN,HA    I24 @BASEBOARD_FAB2_LIB.BASEBOARD_FAB2(SCH_1):PAGE80

M_H_DQ<3> @BASEBOARD_FAB2_LIB.BASEBOARD_FAB2(SCH_1):M_H_DQ(3)
  U2D1 AM81 DDR1_DQ<3> SKX_EXT_B_BGA1-IC,TBD   I172 @BASEBOARD_FAB2_LIB.BASEBOARD_FAB2(SCH_1):PAGE58
  J1G2   12  DQ<2> SCONN288_H44441004_PIP-SCONN,HA   I111 @BASEBOARD_FAB2_LIB.BASEBOARD_FAB2(SCH_1):PAGE79
  J9U1  157  DQ<3> SCONN288_H44441003_PIP-SCONN,HA    I24 @BASEBOARD_FAB2_LIB.BASEBOARD_FAB2(SCH_1):PAGE80

M_H_DQ<40> @BASEBOARD_FAB2_LIB.BASEBOARD_FAB2(SCH_1):M_H_DQ(40)
  U2D1  C36 DDR1_DQ<40> SKX_EXT_B_BGA1-IC,TBD   I172 @BASEBOARD_FAB2_LIB.BASEBOARD_FAB2(SCH_1):PAGE58
  J1G2  253 DQ<41> SCONN288_H44441004_PIP-SCONN,HA   I111 @BASEBOARD_FAB2_LIB.BASEBOARD_FAB2(SCH_1):PAGE79
  J9U1  108 DQ<40> SCONN288_H44441003_PIP-SCONN,HA    I24 @BASEBOARD_FAB2_LIB.BASEBOARD_FAB2(SCH_1):PAGE80

M_H_DQ<41> @BASEBOARD_FAB2_LIB.BASEBOARD_FAB2(SCH_1):M_H_DQ(41)
  U2D1  B35 DDR1_DQ<41> SKX_EXT_B_BGA1-IC,TBD   I172 @BASEBOARD_FAB2_LIB.BASEBOARD_FAB2(SCH_1):PAGE58
  J1G2  108 DQ<40> SCONN288_H44441004_PIP-SCONN,HA   I111 @BASEBOARD_FAB2_LIB.BASEBOARD_FAB2(SCH_1):PAGE79
  J9U1  253 DQ<41> SCONN288_H44441003_PIP-SCONN,HA    I24 @BASEBOARD_FAB2_LIB.BASEBOARD_FAB2(SCH_1):PAGE80

M_H_DQ<42> @BASEBOARD_FAB2_LIB.BASEBOARD_FAB2(SCH_1):M_H_DQ(42)
  U2D1  C32 DDR1_DQ<42> SKX_EXT_B_BGA1-IC,TBD   I172 @BASEBOARD_FAB2_LIB.BASEBOARD_FAB2(SCH_1):PAGE58
  J1G2  260 DQ<43> SCONN288_H44441004_PIP-SCONN,HA   I111 @BASEBOARD_FAB2_LIB.BASEBOARD_FAB2(SCH_1):PAGE79
  J9U1  115 DQ<42> SCONN288_H44441003_PIP-SCONN,HA    I24 @BASEBOARD_FAB2_LIB.BASEBOARD_FAB2(SCH_1):PAGE80

M_H_DQ<43> @BASEBOARD_FAB2_LIB.BASEBOARD_FAB2(SCH_1):M_H_DQ(43)
  U2D1  E32 DDR1_DQ<43> SKX_EXT_B_BGA1-IC,TBD   I172 @BASEBOARD_FAB2_LIB.BASEBOARD_FAB2(SCH_1):PAGE58
  J1G2  115 DQ<42> SCONN288_H44441004_PIP-SCONN,HA   I111 @BASEBOARD_FAB2_LIB.BASEBOARD_FAB2(SCH_1):PAGE79
  J9U1  260 DQ<43> SCONN288_H44441003_PIP-SCONN,HA    I24 @BASEBOARD_FAB2_LIB.BASEBOARD_FAB2(SCH_1):PAGE80

M_H_DQ<44> @BASEBOARD_FAB2_LIB.BASEBOARD_FAB2(SCH_1):M_H_DQ(44)
  U2D1  E36 DDR1_DQ<44> SKX_EXT_B_BGA1-IC,TBD   I172 @BASEBOARD_FAB2_LIB.BASEBOARD_FAB2(SCH_1):PAGE58
  J1G2  251 DQ<45> SCONN288_H44441004_PIP-SCONN,HA   I111 @BASEBOARD_FAB2_LIB.BASEBOARD_FAB2(SCH_1):PAGE79
  J9U1  106 DQ<44> SCONN288_H44441003_PIP-SCONN,HA    I24 @BASEBOARD_FAB2_LIB.BASEBOARD_FAB2(SCH_1):PAGE80

M_H_DQ<45> @BASEBOARD_FAB2_LIB.BASEBOARD_FAB2(SCH_1):M_H_DQ(45)
  U2D1  F35 DDR1_DQ<45> SKX_EXT_B_BGA1-IC,TBD   I172 @BASEBOARD_FAB2_LIB.BASEBOARD_FAB2(SCH_1):PAGE58
  J1G2  106 DQ<44> SCONN288_H44441004_PIP-SCONN,HA   I111 @BASEBOARD_FAB2_LIB.BASEBOARD_FAB2(SCH_1):PAGE79
  J9U1  251 DQ<45> SCONN288_H44441003_PIP-SCONN,HA    I24 @BASEBOARD_FAB2_LIB.BASEBOARD_FAB2(SCH_1):PAGE80

M_H_DQ<46> @BASEBOARD_FAB2_LIB.BASEBOARD_FAB2(SCH_1):M_H_DQ(46)
  U2D1  B33 DDR1_DQ<46> SKX_EXT_B_BGA1-IC,TBD   I172 @BASEBOARD_FAB2_LIB.BASEBOARD_FAB2(SCH_1):PAGE58
  J1G2  258 DQ<47> SCONN288_H44441004_PIP-SCONN,HA   I111 @BASEBOARD_FAB2_LIB.BASEBOARD_FAB2(SCH_1):PAGE79
  J9U1  113 DQ<46> SCONN288_H44441003_PIP-SCONN,HA    I24 @BASEBOARD_FAB2_LIB.BASEBOARD_FAB2(SCH_1):PAGE80

M_H_DQ<47> @BASEBOARD_FAB2_LIB.BASEBOARD_FAB2(SCH_1):M_H_DQ(47)
  U2D1  F33 DDR1_DQ<47> SKX_EXT_B_BGA1-IC,TBD   I172 @BASEBOARD_FAB2_LIB.BASEBOARD_FAB2(SCH_1):PAGE58
  J1G2  113 DQ<46> SCONN288_H44441004_PIP-SCONN,HA   I111 @BASEBOARD_FAB2_LIB.BASEBOARD_FAB2(SCH_1):PAGE79
  J9U1  258 DQ<47> SCONN288_H44441003_PIP-SCONN,HA    I24 @BASEBOARD_FAB2_LIB.BASEBOARD_FAB2(SCH_1):PAGE80

M_H_DQ<48> @BASEBOARD_FAB2_LIB.BASEBOARD_FAB2(SCH_1):M_H_DQ(48)
  U2D1  C30 DDR1_DQ<48> SKX_EXT_B_BGA1-IC,TBD   I172 @BASEBOARD_FAB2_LIB.BASEBOARD_FAB2(SCH_1):PAGE58
  J1G2  264 DQ<49> SCONN288_H44441004_PIP-SCONN,HA   I111 @BASEBOARD_FAB2_LIB.BASEBOARD_FAB2(SCH_1):PAGE79
  J9U1  119 DQ<48> SCONN288_H44441003_PIP-SCONN,HA    I24 @BASEBOARD_FAB2_LIB.BASEBOARD_FAB2(SCH_1):PAGE80

M_H_DQ<49> @BASEBOARD_FAB2_LIB.BASEBOARD_FAB2(SCH_1):M_H_DQ(49)
  U2D1  B29 DDR1_DQ<49> SKX_EXT_B_BGA1-IC,TBD   I172 @BASEBOARD_FAB2_LIB.BASEBOARD_FAB2(SCH_1):PAGE58
  J1G2  119 DQ<48> SCONN288_H44441004_PIP-SCONN,HA   I111 @BASEBOARD_FAB2_LIB.BASEBOARD_FAB2(SCH_1):PAGE79
  J9U1  264 DQ<49> SCONN288_H44441003_PIP-SCONN,HA    I24 @BASEBOARD_FAB2_LIB.BASEBOARD_FAB2(SCH_1):PAGE80

M_H_DQ<4> @BASEBOARD_FAB2_LIB.BASEBOARD_FAB2(SCH_1):M_H_DQ(4)
  U2D1 AW80 DDR1_DQ<4> SKX_EXT_B_BGA1-IC,TBD   I172 @BASEBOARD_FAB2_LIB.BASEBOARD_FAB2(SCH_1):PAGE58
  J1G2  148  DQ<5> SCONN288_H44441004_PIP-SCONN,HA   I111 @BASEBOARD_FAB2_LIB.BASEBOARD_FAB2(SCH_1):PAGE79
  J9U1    3  DQ<4> SCONN288_H44441003_PIP-SCONN,HA    I24 @BASEBOARD_FAB2_LIB.BASEBOARD_FAB2(SCH_1):PAGE80

M_H_DQ<50> @BASEBOARD_FAB2_LIB.BASEBOARD_FAB2(SCH_1):M_H_DQ(50)
  U2D1  C26 DDR1_DQ<50> SKX_EXT_B_BGA1-IC,TBD   I172 @BASEBOARD_FAB2_LIB.BASEBOARD_FAB2(SCH_1):PAGE58
  J1G2  271 DQ<51> SCONN288_H44441004_PIP-SCONN,HA   I111 @BASEBOARD_FAB2_LIB.BASEBOARD_FAB2(SCH_1):PAGE79
  J9U1  126 DQ<50> SCONN288_H44441003_PIP-SCONN,HA    I24 @BASEBOARD_FAB2_LIB.BASEBOARD_FAB2(SCH_1):PAGE80

M_H_DQ<51> @BASEBOARD_FAB2_LIB.BASEBOARD_FAB2(SCH_1):M_H_DQ(51)
  U2D1  E26 DDR1_DQ<51> SKX_EXT_B_BGA1-IC,TBD   I172 @BASEBOARD_FAB2_LIB.BASEBOARD_FAB2(SCH_1):PAGE58
  J1G2  126 DQ<50> SCONN288_H44441004_PIP-SCONN,HA   I111 @BASEBOARD_FAB2_LIB.BASEBOARD_FAB2(SCH_1):PAGE79
  J9U1  271 DQ<51> SCONN288_H44441003_PIP-SCONN,HA    I24 @BASEBOARD_FAB2_LIB.BASEBOARD_FAB2(SCH_1):PAGE80

M_H_DQ<52> @BASEBOARD_FAB2_LIB.BASEBOARD_FAB2(SCH_1):M_H_DQ(52)
  U2D1  E30 DDR1_DQ<52> SKX_EXT_B_BGA1-IC,TBD   I172 @BASEBOARD_FAB2_LIB.BASEBOARD_FAB2(SCH_1):PAGE58
  J1G2  262 DQ<53> SCONN288_H44441004_PIP-SCONN,HA   I111 @BASEBOARD_FAB2_LIB.BASEBOARD_FAB2(SCH_1):PAGE79
  J9U1  117 DQ<52> SCONN288_H44441003_PIP-SCONN,HA    I24 @BASEBOARD_FAB2_LIB.BASEBOARD_FAB2(SCH_1):PAGE80

M_H_DQ<53> @BASEBOARD_FAB2_LIB.BASEBOARD_FAB2(SCH_1):M_H_DQ(53)
  U2D1  F29 DDR1_DQ<53> SKX_EXT_B_BGA1-IC,TBD   I172 @BASEBOARD_FAB2_LIB.BASEBOARD_FAB2(SCH_1):PAGE58
  J1G2  117 DQ<52> SCONN288_H44441004_PIP-SCONN,HA   I111 @BASEBOARD_FAB2_LIB.BASEBOARD_FAB2(SCH_1):PAGE79
  J9U1  262 DQ<53> SCONN288_H44441003_PIP-SCONN,HA    I24 @BASEBOARD_FAB2_LIB.BASEBOARD_FAB2(SCH_1):PAGE80

M_H_DQ<54> @BASEBOARD_FAB2_LIB.BASEBOARD_FAB2(SCH_1):M_H_DQ(54)
  U2D1  B27 DDR1_DQ<54> SKX_EXT_B_BGA1-IC,TBD   I172 @BASEBOARD_FAB2_LIB.BASEBOARD_FAB2(SCH_1):PAGE58
  J1G2  269 DQ<55> SCONN288_H44441004_PIP-SCONN,HA   I111 @BASEBOARD_FAB2_LIB.BASEBOARD_FAB2(SCH_1):PAGE79
  J9U1  124 DQ<54> SCONN288_H44441003_PIP-SCONN,HA    I24 @BASEBOARD_FAB2_LIB.BASEBOARD_FAB2(SCH_1):PAGE80

M_H_DQ<55> @BASEBOARD_FAB2_LIB.BASEBOARD_FAB2(SCH_1):M_H_DQ(55)
  U2D1  F27 DDR1_DQ<55> SKX_EXT_B_BGA1-IC,TBD   I172 @BASEBOARD_FAB2_LIB.BASEBOARD_FAB2(SCH_1):PAGE58
  J1G2  124 DQ<54> SCONN288_H44441004_PIP-SCONN,HA   I111 @BASEBOARD_FAB2_LIB.BASEBOARD_FAB2(SCH_1):PAGE79
  J9U1  269 DQ<55> SCONN288_H44441003_PIP-SCONN,HA    I24 @BASEBOARD_FAB2_LIB.BASEBOARD_FAB2(SCH_1):PAGE80

M_H_DQ<56> @BASEBOARD_FAB2_LIB.BASEBOARD_FAB2(SCH_1):M_H_DQ(56)
  U2D1  U28 DDR1_DQ<56> SKX_EXT_B_BGA1-IC,TBD   I172 @BASEBOARD_FAB2_LIB.BASEBOARD_FAB2(SCH_1):PAGE58
  J1G2  275 DQ<57> SCONN288_H44441004_PIP-SCONN,HA   I111 @BASEBOARD_FAB2_LIB.BASEBOARD_FAB2(SCH_1):PAGE79
  J9U1  130 DQ<56> SCONN288_H44441003_PIP-SCONN,HA    I24 @BASEBOARD_FAB2_LIB.BASEBOARD_FAB2(SCH_1):PAGE80

M_H_DQ<57> @BASEBOARD_FAB2_LIB.BASEBOARD_FAB2(SCH_1):M_H_DQ(57)
  U2D1 AA28 DDR1_DQ<57> SKX_EXT_B_BGA1-IC,TBD   I172 @BASEBOARD_FAB2_LIB.BASEBOARD_FAB2(SCH_1):PAGE58
  J1G2  130 DQ<56> SCONN288_H44441004_PIP-SCONN,HA   I111 @BASEBOARD_FAB2_LIB.BASEBOARD_FAB2(SCH_1):PAGE79
  J9U1  275 DQ<57> SCONN288_H44441003_PIP-SCONN,HA    I24 @BASEBOARD_FAB2_LIB.BASEBOARD_FAB2(SCH_1):PAGE80

M_H_DQ<58> @BASEBOARD_FAB2_LIB.BASEBOARD_FAB2(SCH_1):M_H_DQ(58)
  U2D1  V25 DDR1_DQ<58> SKX_EXT_B_BGA1-IC,TBD   I172 @BASEBOARD_FAB2_LIB.BASEBOARD_FAB2(SCH_1):PAGE58
  J1G2  282 DQ<59> SCONN288_H44441004_PIP-SCONN,HA   I111 @BASEBOARD_FAB2_LIB.BASEBOARD_FAB2(SCH_1):PAGE79
  J9U1  137 DQ<58> SCONN288_H44441003_PIP-SCONN,HA    I24 @BASEBOARD_FAB2_LIB.BASEBOARD_FAB2(SCH_1):PAGE80

M_H_DQ<59> @BASEBOARD_FAB2_LIB.BASEBOARD_FAB2(SCH_1):M_H_DQ(59)
  U2D1  Y25 DDR1_DQ<59> SKX_EXT_B_BGA1-IC,TBD   I172 @BASEBOARD_FAB2_LIB.BASEBOARD_FAB2(SCH_1):PAGE58
  J1G2  137 DQ<58> SCONN288_H44441004_PIP-SCONN,HA   I111 @BASEBOARD_FAB2_LIB.BASEBOARD_FAB2(SCH_1):PAGE79
  J9U1  282 DQ<59> SCONN288_H44441003_PIP-SCONN,HA    I24 @BASEBOARD_FAB2_LIB.BASEBOARD_FAB2(SCH_1):PAGE80

M_H_DQ<5> @BASEBOARD_FAB2_LIB.BASEBOARD_FAB2(SCH_1):M_H_DQ(5)
  U2D1 AV79 DDR1_DQ<5> SKX_EXT_B_BGA1-IC,TBD   I172 @BASEBOARD_FAB2_LIB.BASEBOARD_FAB2(SCH_1):PAGE58
  J1G2    3  DQ<4> SCONN288_H44441004_PIP-SCONN,HA   I111 @BASEBOARD_FAB2_LIB.BASEBOARD_FAB2(SCH_1):PAGE79
  J9U1  148  DQ<5> SCONN288_H44441003_PIP-SCONN,HA    I24 @BASEBOARD_FAB2_LIB.BASEBOARD_FAB2(SCH_1):PAGE80

M_H_DQ<60> @BASEBOARD_FAB2_LIB.BASEBOARD_FAB2(SCH_1):M_H_DQ(60)
  U2D1  V29 DDR1_DQ<60> SKX_EXT_B_BGA1-IC,TBD   I172 @BASEBOARD_FAB2_LIB.BASEBOARD_FAB2(SCH_1):PAGE58
  J1G2  273 DQ<61> SCONN288_H44441004_PIP-SCONN,HA   I111 @BASEBOARD_FAB2_LIB.BASEBOARD_FAB2(SCH_1):PAGE79
  J9U1  128 DQ<60> SCONN288_H44441003_PIP-SCONN,HA    I24 @BASEBOARD_FAB2_LIB.BASEBOARD_FAB2(SCH_1):PAGE80

M_H_DQ<61> @BASEBOARD_FAB2_LIB.BASEBOARD_FAB2(SCH_1):M_H_DQ(61)
  U2D1  Y29 DDR1_DQ<61> SKX_EXT_B_BGA1-IC,TBD   I172 @BASEBOARD_FAB2_LIB.BASEBOARD_FAB2(SCH_1):PAGE58
  J1G2  128 DQ<60> SCONN288_H44441004_PIP-SCONN,HA   I111 @BASEBOARD_FAB2_LIB.BASEBOARD_FAB2(SCH_1):PAGE79
  J9U1  273 DQ<61> SCONN288_H44441003_PIP-SCONN,HA    I24 @BASEBOARD_FAB2_LIB.BASEBOARD_FAB2(SCH_1):PAGE80

M_H_DQ<62> @BASEBOARD_FAB2_LIB.BASEBOARD_FAB2(SCH_1):M_H_DQ(62)
  U2D1  U26 DDR1_DQ<62> SKX_EXT_B_BGA1-IC,TBD   I172 @BASEBOARD_FAB2_LIB.BASEBOARD_FAB2(SCH_1):PAGE58
  J1G2  280 DQ<63> SCONN288_H44441004_PIP-SCONN,HA   I111 @BASEBOARD_FAB2_LIB.BASEBOARD_FAB2(SCH_1):PAGE79
  J9U1  135 DQ<62> SCONN288_H44441003_PIP-SCONN,HA    I24 @BASEBOARD_FAB2_LIB.BASEBOARD_FAB2(SCH_1):PAGE80

M_H_DQ<63> @BASEBOARD_FAB2_LIB.BASEBOARD_FAB2(SCH_1):M_H_DQ(63)
  U2D1 AA26 DDR1_DQ<63> SKX_EXT_B_BGA1-IC,TBD   I172 @BASEBOARD_FAB2_LIB.BASEBOARD_FAB2(SCH_1):PAGE58
  J1G2  135 DQ<62> SCONN288_H44441004_PIP-SCONN,HA   I111 @BASEBOARD_FAB2_LIB.BASEBOARD_FAB2(SCH_1):PAGE79
  J9U1  280 DQ<63> SCONN288_H44441003_PIP-SCONN,HA    I24 @BASEBOARD_FAB2_LIB.BASEBOARD_FAB2(SCH_1):PAGE80

M_H_DQ<6> @BASEBOARD_FAB2_LIB.BASEBOARD_FAB2(SCH_1):M_H_DQ(6)
  U2D1 AR82 DDR1_DQ<6> SKX_EXT_B_BGA1-IC,TBD   I172 @BASEBOARD_FAB2_LIB.BASEBOARD_FAB2(SCH_1):PAGE58
  J1G2  155  DQ<7> SCONN288_H44441004_PIP-SCONN,HA   I111 @BASEBOARD_FAB2_LIB.BASEBOARD_FAB2(SCH_1):PAGE79
  J9U1   10  DQ<6> SCONN288_H44441003_PIP-SCONN,HA    I24 @BASEBOARD_FAB2_LIB.BASEBOARD_FAB2(SCH_1):PAGE80

M_H_DQ<7> @BASEBOARD_FAB2_LIB.BASEBOARD_FAB2(SCH_1):M_H_DQ(7)
  U2D1 AN80 DDR1_DQ<7> SKX_EXT_B_BGA1-IC,TBD   I172 @BASEBOARD_FAB2_LIB.BASEBOARD_FAB2(SCH_1):PAGE58
  J1G2   10  DQ<6> SCONN288_H44441004_PIP-SCONN,HA   I111 @BASEBOARD_FAB2_LIB.BASEBOARD_FAB2(SCH_1):PAGE79
  J9U1  155  DQ<7> SCONN288_H44441003_PIP-SCONN,HA    I24 @BASEBOARD_FAB2_LIB.BASEBOARD_FAB2(SCH_1):PAGE80

M_H_DQ<8> @BASEBOARD_FAB2_LIB.BASEBOARD_FAB2(SCH_1):M_H_DQ(8)
  U2D1 AH81 DDR1_DQ<8> SKX_EXT_B_BGA1-IC,TBD   I172 @BASEBOARD_FAB2_LIB.BASEBOARD_FAB2(SCH_1):PAGE58
  J1G2  161  DQ<9> SCONN288_H44441004_PIP-SCONN,HA   I111 @BASEBOARD_FAB2_LIB.BASEBOARD_FAB2(SCH_1):PAGE79
  J9U1   16  DQ<8> SCONN288_H44441003_PIP-SCONN,HA    I24 @BASEBOARD_FAB2_LIB.BASEBOARD_FAB2(SCH_1):PAGE80

M_H_DQ<9> @BASEBOARD_FAB2_LIB.BASEBOARD_FAB2(SCH_1):M_H_DQ(9)
  U2D1 AF79 DDR1_DQ<9> SKX_EXT_B_BGA1-IC,TBD   I172 @BASEBOARD_FAB2_LIB.BASEBOARD_FAB2(SCH_1):PAGE58
  J1G2   16  DQ<8> SCONN288_H44441004_PIP-SCONN,HA   I111 @BASEBOARD_FAB2_LIB.BASEBOARD_FAB2(SCH_1):PAGE79
  J9U1  161  DQ<9> SCONN288_H44441003_PIP-SCONN,HA    I24 @BASEBOARD_FAB2_LIB.BASEBOARD_FAB2(SCH_1):PAGE80

M_H_DQS_DN<0> @BASEBOARD_FAB2_LIB.BASEBOARD_FAB2(SCH_1):M_H_DQS_DN(0)
  U2D1 AP79 DDR1_DQS_DN<0> SKX_EXT_B_BGA1-IC,TBD   I172 @BASEBOARD_FAB2_LIB.BASEBOARD_FAB2(SCH_1):PAGE58
  J1G2  152  DQS0N SCONN288_H44441004_PIP-SCONN,HA    I64 @BASEBOARD_FAB2_LIB.BASEBOARD_FAB2(SCH_1):PAGE79
  J9U1  152  DQS0N SCONN288_H44441003_PIP-SCONN,HA   I101 @BASEBOARD_FAB2_LIB.BASEBOARD_FAB2(SCH_1):PAGE80

M_H_DQS_DN<10> @BASEBOARD_FAB2_LIB.BASEBOARD_FAB2(SCH_1):M_H_DQS_DN(10)
  U2D1 AG82 DDR1_DQS_DN<10> SKX_EXT_B_BGA1-IC,TBD   I172 @BASEBOARD_FAB2_LIB.BASEBOARD_FAB2(SCH_1):PAGE58
  J1G2   19 DQS10N SCONN288_H44441004_PIP-SCONN,HA    I64 @BASEBOARD_FAB2_LIB.BASEBOARD_FAB2(SCH_1):PAGE79
  J9U1   19 DQS10N SCONN288_H44441003_PIP-SCONN,HA   I101 @BASEBOARD_FAB2_LIB.BASEBOARD_FAB2(SCH_1):PAGE80

M_H_DQS_DN<11> @BASEBOARD_FAB2_LIB.BASEBOARD_FAB2(SCH_1):M_H_DQS_DN(11)
  U2D1  D79 DDR1_DQS_DN<11> SKX_EXT_B_BGA1-IC,TBD   I172 @BASEBOARD_FAB2_LIB.BASEBOARD_FAB2(SCH_1):PAGE58
  J1G2   30 DQS11N SCONN288_H44441004_PIP-SCONN,HA    I64 @BASEBOARD_FAB2_LIB.BASEBOARD_FAB2(SCH_1):PAGE79
  J9U1   30 DQS11N SCONN288_H44441003_PIP-SCONN,HA   I101 @BASEBOARD_FAB2_LIB.BASEBOARD_FAB2(SCH_1):PAGE80

M_H_DQS_DN<12> @BASEBOARD_FAB2_LIB.BASEBOARD_FAB2(SCH_1):M_H_DQS_DN(12)
  U2D1  B73 DDR1_DQS_DN<12> SKX_EXT_B_BGA1-IC,TBD   I172 @BASEBOARD_FAB2_LIB.BASEBOARD_FAB2(SCH_1):PAGE58
  J1G2   41 DQS12N SCONN288_H44441004_PIP-SCONN,HA    I64 @BASEBOARD_FAB2_LIB.BASEBOARD_FAB2(SCH_1):PAGE79
  J9U1   41 DQS12N SCONN288_H44441003_PIP-SCONN,HA   I101 @BASEBOARD_FAB2_LIB.BASEBOARD_FAB2(SCH_1):PAGE80

M_H_DQS_DN<13> @BASEBOARD_FAB2_LIB.BASEBOARD_FAB2(SCH_1):M_H_DQS_DN(13)
  U2D1  J42 DDR1_DQS_DN<13> SKX_EXT_B_BGA1-IC,TBD   I172 @BASEBOARD_FAB2_LIB.BASEBOARD_FAB2(SCH_1):PAGE58
  J1G2  100 DQS13N SCONN288_H44441004_PIP-SCONN,HA    I64 @BASEBOARD_FAB2_LIB.BASEBOARD_FAB2(SCH_1):PAGE79
  J9U1  100 DQS13N SCONN288_H44441003_PIP-SCONN,HA   I101 @BASEBOARD_FAB2_LIB.BASEBOARD_FAB2(SCH_1):PAGE80

M_H_DQS_DN<14> @BASEBOARD_FAB2_LIB.BASEBOARD_FAB2(SCH_1):M_H_DQS_DN(14)
  U2D1  A34 DDR1_DQS_DN<14> SKX_EXT_B_BGA1-IC,TBD   I172 @BASEBOARD_FAB2_LIB.BASEBOARD_FAB2(SCH_1):PAGE58
  J1G2  111 DQS14N SCONN288_H44441004_PIP-SCONN,HA    I64 @BASEBOARD_FAB2_LIB.BASEBOARD_FAB2(SCH_1):PAGE79
  J9U1  111 DQS14N SCONN288_H44441003_PIP-SCONN,HA   I101 @BASEBOARD_FAB2_LIB.BASEBOARD_FAB2(SCH_1):PAGE80

M_H_DQS_DN<15> @BASEBOARD_FAB2_LIB.BASEBOARD_FAB2(SCH_1):M_H_DQS_DN(15)
  U2D1  A28 DDR1_DQS_DN<15> SKX_EXT_B_BGA1-IC,TBD   I172 @BASEBOARD_FAB2_LIB.BASEBOARD_FAB2(SCH_1):PAGE58
  J1G2  122 DQS15N SCONN288_H44441004_PIP-SCONN,HA    I64 @BASEBOARD_FAB2_LIB.BASEBOARD_FAB2(SCH_1):PAGE79
  J9U1  122 DQS15N SCONN288_H44441003_PIP-SCONN,HA   I101 @BASEBOARD_FAB2_LIB.BASEBOARD_FAB2(SCH_1):PAGE80

M_H_DQS_DN<16> @BASEBOARD_FAB2_LIB.BASEBOARD_FAB2(SCH_1):M_H_DQS_DN(16)
  U2D1  T27 DDR1_DQS_DN<16> SKX_EXT_B_BGA1-IC,TBD   I172 @BASEBOARD_FAB2_LIB.BASEBOARD_FAB2(SCH_1):PAGE58
  J1G2  133 DQS16N SCONN288_H44441004_PIP-SCONN,HA    I64 @BASEBOARD_FAB2_LIB.BASEBOARD_FAB2(SCH_1):PAGE79
  J9U1  133 DQS16N SCONN288_H44441003_PIP-SCONN,HA   I101 @BASEBOARD_FAB2_LIB.BASEBOARD_FAB2(SCH_1):PAGE80

M_H_DQS_DN<17> @BASEBOARD_FAB2_LIB.BASEBOARD_FAB2(SCH_1):M_H_DQS_DN(17)
  U2D1  G68 DDR1_DQS_DN<17> SKX_EXT_B_BGA1-IC,TBD   I172 @BASEBOARD_FAB2_LIB.BASEBOARD_FAB2(SCH_1):PAGE58
  J1G2   52 DQS17N SCONN288_H44441004_PIP-SCONN,HA    I64 @BASEBOARD_FAB2_LIB.BASEBOARD_FAB2(SCH_1):PAGE79
  J9U1   52 DQS17N SCONN288_H44441003_PIP-SCONN,HA   I101 @BASEBOARD_FAB2_LIB.BASEBOARD_FAB2(SCH_1):PAGE80

M_H_DQS_DN<1> @BASEBOARD_FAB2_LIB.BASEBOARD_FAB2(SCH_1):M_H_DQS_DN(1)
  U2D1 AD79 DDR1_DQS_DN<1> SKX_EXT_B_BGA1-IC,TBD   I172 @BASEBOARD_FAB2_LIB.BASEBOARD_FAB2(SCH_1):PAGE58
  J1G2  163  DQS1N SCONN288_H44441004_PIP-SCONN,HA    I64 @BASEBOARD_FAB2_LIB.BASEBOARD_FAB2(SCH_1):PAGE79
  J9U1  163  DQS1N SCONN288_H44441003_PIP-SCONN,HA   I101 @BASEBOARD_FAB2_LIB.BASEBOARD_FAB2(SCH_1):PAGE80

M_H_DQS_DN<2> @BASEBOARD_FAB2_LIB.BASEBOARD_FAB2(SCH_1):M_H_DQS_DN(2)
  U2D1  K79 DDR1_DQS_DN<2> SKX_EXT_B_BGA1-IC,TBD   I172 @BASEBOARD_FAB2_LIB.BASEBOARD_FAB2(SCH_1):PAGE58
  J1G2  174  DQS2N SCONN288_H44441004_PIP-SCONN,HA    I64 @BASEBOARD_FAB2_LIB.BASEBOARD_FAB2(SCH_1):PAGE79
  J9U1  174  DQS2N SCONN288_H44441003_PIP-SCONN,HA   I101 @BASEBOARD_FAB2_LIB.BASEBOARD_FAB2(SCH_1):PAGE80

M_H_DQS_DN<3> @BASEBOARD_FAB2_LIB.BASEBOARD_FAB2(SCH_1):M_H_DQS_DN(3)
  U2D1  H73 DDR1_DQS_DN<3> SKX_EXT_B_BGA1-IC,TBD   I172 @BASEBOARD_FAB2_LIB.BASEBOARD_FAB2(SCH_1):PAGE58
  J1G2  185  DQS3N SCONN288_H44441004_PIP-SCONN,HA    I64 @BASEBOARD_FAB2_LIB.BASEBOARD_FAB2(SCH_1):PAGE79
  J9U1  185  DQS3N SCONN288_H44441003_PIP-SCONN,HA   I101 @BASEBOARD_FAB2_LIB.BASEBOARD_FAB2(SCH_1):PAGE80

M_H_DQS_DN<4> @BASEBOARD_FAB2_LIB.BASEBOARD_FAB2(SCH_1):M_H_DQS_DN(4)
  U2D1  N42 DDR1_DQS_DN<4> SKX_EXT_B_BGA1-IC,TBD   I172 @BASEBOARD_FAB2_LIB.BASEBOARD_FAB2(SCH_1):PAGE58
  J1G2  244  DQS4N SCONN288_H44441004_PIP-SCONN,HA    I64 @BASEBOARD_FAB2_LIB.BASEBOARD_FAB2(SCH_1):PAGE79
  J9U1  244  DQS4N SCONN288_H44441003_PIP-SCONN,HA   I101 @BASEBOARD_FAB2_LIB.BASEBOARD_FAB2(SCH_1):PAGE80

M_H_DQS_DN<5> @BASEBOARD_FAB2_LIB.BASEBOARD_FAB2(SCH_1):M_H_DQS_DN(5)
  U2D1  G34 DDR1_DQS_DN<5> SKX_EXT_B_BGA1-IC,TBD   I172 @BASEBOARD_FAB2_LIB.BASEBOARD_FAB2(SCH_1):PAGE58
  J1G2  255  DQS5N SCONN288_H44441004_PIP-SCONN,HA    I64 @BASEBOARD_FAB2_LIB.BASEBOARD_FAB2(SCH_1):PAGE79
  J9U1  255  DQS5N SCONN288_H44441003_PIP-SCONN,HA   I101 @BASEBOARD_FAB2_LIB.BASEBOARD_FAB2(SCH_1):PAGE80

M_H_DQS_DN<6> @BASEBOARD_FAB2_LIB.BASEBOARD_FAB2(SCH_1):M_H_DQS_DN(6)
  U2D1  G28 DDR1_DQS_DN<6> SKX_EXT_B_BGA1-IC,TBD   I172 @BASEBOARD_FAB2_LIB.BASEBOARD_FAB2(SCH_1):PAGE58
  J1G2  266  DQS6N SCONN288_H44441004_PIP-SCONN,HA    I64 @BASEBOARD_FAB2_LIB.BASEBOARD_FAB2(SCH_1):PAGE79
  J9U1  266  DQS6N SCONN288_H44441003_PIP-SCONN,HA   I101 @BASEBOARD_FAB2_LIB.BASEBOARD_FAB2(SCH_1):PAGE80

M_H_DQS_DN<7> @BASEBOARD_FAB2_LIB.BASEBOARD_FAB2(SCH_1):M_H_DQS_DN(7)
  U2D1 AB27 DDR1_DQS_DN<7> SKX_EXT_B_BGA1-IC,TBD   I172 @BASEBOARD_FAB2_LIB.BASEBOARD_FAB2(SCH_1):PAGE58
  J1G2  277  DQS7N SCONN288_H44441004_PIP-SCONN,HA    I64 @BASEBOARD_FAB2_LIB.BASEBOARD_FAB2(SCH_1):PAGE79
  J9U1  277  DQS7N SCONN288_H44441003_PIP-SCONN,HA   I101 @BASEBOARD_FAB2_LIB.BASEBOARD_FAB2(SCH_1):PAGE80

M_H_DQS_DN<8> @BASEBOARD_FAB2_LIB.BASEBOARD_FAB2(SCH_1):M_H_DQS_DN(8)
  U2D1  N68 DDR1_DQS_DN<8> SKX_EXT_B_BGA1-IC,TBD   I172 @BASEBOARD_FAB2_LIB.BASEBOARD_FAB2(SCH_1):PAGE58
  J1G2  196  DQS8N SCONN288_H44441004_PIP-SCONN,HA    I64 @BASEBOARD_FAB2_LIB.BASEBOARD_FAB2(SCH_1):PAGE79
  J9U1  196  DQS8N SCONN288_H44441003_PIP-SCONN,HA   I101 @BASEBOARD_FAB2_LIB.BASEBOARD_FAB2(SCH_1):PAGE80

M_H_DQS_DN<9> @BASEBOARD_FAB2_LIB.BASEBOARD_FAB2(SCH_1):M_H_DQS_DN(9)
  U2D1 AU82 DDR1_DQS_DN<9> SKX_EXT_B_BGA1-IC,TBD   I172 @BASEBOARD_FAB2_LIB.BASEBOARD_FAB2(SCH_1):PAGE58
  J1G2    8  DQS9N SCONN288_H44441004_PIP-SCONN,HA    I64 @BASEBOARD_FAB2_LIB.BASEBOARD_FAB2(SCH_1):PAGE79
  J9U1    8  DQS9N SCONN288_H44441003_PIP-SCONN,HA   I101 @BASEBOARD_FAB2_LIB.BASEBOARD_FAB2(SCH_1):PAGE80

M_H_DQS_DP<0> @BASEBOARD_FAB2_LIB.BASEBOARD_FAB2(SCH_1):M_H_DQS_DP(0)
  U2D1 AR80 DDR1_DQS_DP<0> SKX_EXT_B_BGA1-IC,TBD   I172 @BASEBOARD_FAB2_LIB.BASEBOARD_FAB2(SCH_1):PAGE58
  J1G2  153  DQS0P SCONN288_H44441004_PIP-SCONN,HA    I64 @BASEBOARD_FAB2_LIB.BASEBOARD_FAB2(SCH_1):PAGE79
  J9U1  153  DQS0P SCONN288_H44441003_PIP-SCONN,HA   I101 @BASEBOARD_FAB2_LIB.BASEBOARD_FAB2(SCH_1):PAGE80

M_H_DQS_DP<10> @BASEBOARD_FAB2_LIB.BASEBOARD_FAB2(SCH_1):M_H_DQS_DP(10)
  U2D1 AF81 DDR1_DQS_DP<10> SKX_EXT_B_BGA1-IC,TBD   I172 @BASEBOARD_FAB2_LIB.BASEBOARD_FAB2(SCH_1):PAGE58
  J1G2   18 DQS10P SCONN288_H44441004_PIP-SCONN,HA    I64 @BASEBOARD_FAB2_LIB.BASEBOARD_FAB2(SCH_1):PAGE79
  J9U1   18 DQS10P SCONN288_H44441003_PIP-SCONN,HA   I101 @BASEBOARD_FAB2_LIB.BASEBOARD_FAB2(SCH_1):PAGE80

M_H_DQS_DP<11> @BASEBOARD_FAB2_LIB.BASEBOARD_FAB2(SCH_1):M_H_DQS_DP(11)
  U2D1  F79 DDR1_DQS_DP<11> SKX_EXT_B_BGA1-IC,TBD   I172 @BASEBOARD_FAB2_LIB.BASEBOARD_FAB2(SCH_1):PAGE58
  J1G2   29 DQS11P SCONN288_H44441004_PIP-SCONN,HA    I64 @BASEBOARD_FAB2_LIB.BASEBOARD_FAB2(SCH_1):PAGE79
  J9U1   29 DQS11P SCONN288_H44441003_PIP-SCONN,HA   I101 @BASEBOARD_FAB2_LIB.BASEBOARD_FAB2(SCH_1):PAGE80

M_H_DQS_DP<12> @BASEBOARD_FAB2_LIB.BASEBOARD_FAB2(SCH_1):M_H_DQS_DP(12)
  U2D1  D73 DDR1_DQS_DP<12> SKX_EXT_B_BGA1-IC,TBD   I172 @BASEBOARD_FAB2_LIB.BASEBOARD_FAB2(SCH_1):PAGE58
  J1G2   40 DQS12P SCONN288_H44441004_PIP-SCONN,HA    I64 @BASEBOARD_FAB2_LIB.BASEBOARD_FAB2(SCH_1):PAGE79
  J9U1   40 DQS12P SCONN288_H44441003_PIP-SCONN,HA   I101 @BASEBOARD_FAB2_LIB.BASEBOARD_FAB2(SCH_1):PAGE80

M_H_DQS_DP<13> @BASEBOARD_FAB2_LIB.BASEBOARD_FAB2(SCH_1):M_H_DQS_DP(13)
  U2D1  L42 DDR1_DQS_DP<13> SKX_EXT_B_BGA1-IC,TBD   I172 @BASEBOARD_FAB2_LIB.BASEBOARD_FAB2(SCH_1):PAGE58
  J1G2   99 DQS13P SCONN288_H44441004_PIP-SCONN,HA    I64 @BASEBOARD_FAB2_LIB.BASEBOARD_FAB2(SCH_1):PAGE79
  J9U1   99 DQS13P SCONN288_H44441003_PIP-SCONN,HA   I101 @BASEBOARD_FAB2_LIB.BASEBOARD_FAB2(SCH_1):PAGE80

M_H_DQS_DP<14> @BASEBOARD_FAB2_LIB.BASEBOARD_FAB2(SCH_1):M_H_DQS_DP(14)
  U2D1  C34 DDR1_DQS_DP<14> SKX_EXT_B_BGA1-IC,TBD   I172 @BASEBOARD_FAB2_LIB.BASEBOARD_FAB2(SCH_1):PAGE58
  J1G2  110 DQS14P SCONN288_H44441004_PIP-SCONN,HA    I64 @BASEBOARD_FAB2_LIB.BASEBOARD_FAB2(SCH_1):PAGE79
  J9U1  110 DQS14P SCONN288_H44441003_PIP-SCONN,HA   I101 @BASEBOARD_FAB2_LIB.BASEBOARD_FAB2(SCH_1):PAGE80

M_H_DQS_DP<15> @BASEBOARD_FAB2_LIB.BASEBOARD_FAB2(SCH_1):M_H_DQS_DP(15)
  U2D1  C28 DDR1_DQS_DP<15> SKX_EXT_B_BGA1-IC,TBD   I172 @BASEBOARD_FAB2_LIB.BASEBOARD_FAB2(SCH_1):PAGE58
  J1G2  121 DQS15P SCONN288_H44441004_PIP-SCONN,HA    I64 @BASEBOARD_FAB2_LIB.BASEBOARD_FAB2(SCH_1):PAGE79
  J9U1  121 DQS15P SCONN288_H44441003_PIP-SCONN,HA   I101 @BASEBOARD_FAB2_LIB.BASEBOARD_FAB2(SCH_1):PAGE80

M_H_DQS_DP<16> @BASEBOARD_FAB2_LIB.BASEBOARD_FAB2(SCH_1):M_H_DQS_DP(16)
  U2D1  V27 DDR1_DQS_DP<16> SKX_EXT_B_BGA1-IC,TBD   I172 @BASEBOARD_FAB2_LIB.BASEBOARD_FAB2(SCH_1):PAGE58
  J1G2  132 DQS16P SCONN288_H44441004_PIP-SCONN,HA    I64 @BASEBOARD_FAB2_LIB.BASEBOARD_FAB2(SCH_1):PAGE79
  J9U1  132 DQS16P SCONN288_H44441003_PIP-SCONN,HA   I101 @BASEBOARD_FAB2_LIB.BASEBOARD_FAB2(SCH_1):PAGE80

M_H_DQS_DP<17> @BASEBOARD_FAB2_LIB.BASEBOARD_FAB2(SCH_1):M_H_DQS_DP(17)
  U2D1  J68 DDR1_DQS_DP<17> SKX_EXT_B_BGA1-IC,TBD   I172 @BASEBOARD_FAB2_LIB.BASEBOARD_FAB2(SCH_1):PAGE58
  J1G2   51 DQS17P SCONN288_H44441004_PIP-SCONN,HA    I64 @BASEBOARD_FAB2_LIB.BASEBOARD_FAB2(SCH_1):PAGE79
  J9U1   51 DQS17P SCONN288_H44441003_PIP-SCONN,HA   I101 @BASEBOARD_FAB2_LIB.BASEBOARD_FAB2(SCH_1):PAGE80

M_H_DQS_DP<1> @BASEBOARD_FAB2_LIB.BASEBOARD_FAB2(SCH_1):M_H_DQS_DP(1)
  U2D1 AE80 DDR1_DQS_DP<1> SKX_EXT_B_BGA1-IC,TBD   I172 @BASEBOARD_FAB2_LIB.BASEBOARD_FAB2(SCH_1):PAGE58
  J1G2  164  DQS1P SCONN288_H44441004_PIP-SCONN,HA    I64 @BASEBOARD_FAB2_LIB.BASEBOARD_FAB2(SCH_1):PAGE79
  J9U1  164  DQS1P SCONN288_H44441003_PIP-SCONN,HA   I101 @BASEBOARD_FAB2_LIB.BASEBOARD_FAB2(SCH_1):PAGE80

M_H_DQS_DP<2> @BASEBOARD_FAB2_LIB.BASEBOARD_FAB2(SCH_1):M_H_DQS_DP(2)
  U2D1  H79 DDR1_DQS_DP<2> SKX_EXT_B_BGA1-IC,TBD   I172 @BASEBOARD_FAB2_LIB.BASEBOARD_FAB2(SCH_1):PAGE58
  J1G2  175  DQS2P SCONN288_H44441004_PIP-SCONN,HA    I64 @BASEBOARD_FAB2_LIB.BASEBOARD_FAB2(SCH_1):PAGE79
  J9U1  175  DQS2P SCONN288_H44441003_PIP-SCONN,HA   I101 @BASEBOARD_FAB2_LIB.BASEBOARD_FAB2(SCH_1):PAGE80

M_H_DQS_DP<3> @BASEBOARD_FAB2_LIB.BASEBOARD_FAB2(SCH_1):M_H_DQS_DP(3)
  U2D1  F73 DDR1_DQS_DP<3> SKX_EXT_B_BGA1-IC,TBD   I172 @BASEBOARD_FAB2_LIB.BASEBOARD_FAB2(SCH_1):PAGE58
  J1G2  186  DQS3P SCONN288_H44441004_PIP-SCONN,HA    I64 @BASEBOARD_FAB2_LIB.BASEBOARD_FAB2(SCH_1):PAGE79
  J9U1  186  DQS3P SCONN288_H44441003_PIP-SCONN,HA   I101 @BASEBOARD_FAB2_LIB.BASEBOARD_FAB2(SCH_1):PAGE80

M_H_DQS_DP<4> @BASEBOARD_FAB2_LIB.BASEBOARD_FAB2(SCH_1):M_H_DQS_DP(4)
  U2D1  R42 DDR1_DQS_DP<4> SKX_EXT_B_BGA1-IC,TBD   I172 @BASEBOARD_FAB2_LIB.BASEBOARD_FAB2(SCH_1):PAGE58
  J1G2  245  DQS4P SCONN288_H44441004_PIP-SCONN,HA    I64 @BASEBOARD_FAB2_LIB.BASEBOARD_FAB2(SCH_1):PAGE79
  J9U1  245  DQS4P SCONN288_H44441003_PIP-SCONN,HA   I101 @BASEBOARD_FAB2_LIB.BASEBOARD_FAB2(SCH_1):PAGE80

M_H_DQS_DP<5> @BASEBOARD_FAB2_LIB.BASEBOARD_FAB2(SCH_1):M_H_DQS_DP(5)
  U2D1  E34 DDR1_DQS_DP<5> SKX_EXT_B_BGA1-IC,TBD   I172 @BASEBOARD_FAB2_LIB.BASEBOARD_FAB2(SCH_1):PAGE58
  J1G2  256  DQS5P SCONN288_H44441004_PIP-SCONN,HA    I64 @BASEBOARD_FAB2_LIB.BASEBOARD_FAB2(SCH_1):PAGE79
  J9U1  256  DQS5P SCONN288_H44441003_PIP-SCONN,HA   I101 @BASEBOARD_FAB2_LIB.BASEBOARD_FAB2(SCH_1):PAGE80

M_H_DQS_DP<6> @BASEBOARD_FAB2_LIB.BASEBOARD_FAB2(SCH_1):M_H_DQS_DP(6)
  U2D1  E28 DDR1_DQS_DP<6> SKX_EXT_B_BGA1-IC,TBD   I172 @BASEBOARD_FAB2_LIB.BASEBOARD_FAB2(SCH_1):PAGE58
  J1G2  267  DQS6P SCONN288_H44441004_PIP-SCONN,HA    I64 @BASEBOARD_FAB2_LIB.BASEBOARD_FAB2(SCH_1):PAGE79
  J9U1  267  DQS6P SCONN288_H44441003_PIP-SCONN,HA   I101 @BASEBOARD_FAB2_LIB.BASEBOARD_FAB2(SCH_1):PAGE80

M_H_DQS_DP<7> @BASEBOARD_FAB2_LIB.BASEBOARD_FAB2(SCH_1):M_H_DQS_DP(7)
  U2D1  Y27 DDR1_DQS_DP<7> SKX_EXT_B_BGA1-IC,TBD   I172 @BASEBOARD_FAB2_LIB.BASEBOARD_FAB2(SCH_1):PAGE58
  J1G2  278  DQS7P SCONN288_H44441004_PIP-SCONN,HA    I64 @BASEBOARD_FAB2_LIB.BASEBOARD_FAB2(SCH_1):PAGE79
  J9U1  278  DQS7P SCONN288_H44441003_PIP-SCONN,HA   I101 @BASEBOARD_FAB2_LIB.BASEBOARD_FAB2(SCH_1):PAGE80

M_H_DQS_DP<8> @BASEBOARD_FAB2_LIB.BASEBOARD_FAB2(SCH_1):M_H_DQS_DP(8)
  U2D1  L68 DDR1_DQS_DP<8> SKX_EXT_B_BGA1-IC,TBD   I172 @BASEBOARD_FAB2_LIB.BASEBOARD_FAB2(SCH_1):PAGE58
  J1G2  197  DQS8P SCONN288_H44441004_PIP-SCONN,HA    I64 @BASEBOARD_FAB2_LIB.BASEBOARD_FAB2(SCH_1):PAGE79
  J9U1  197  DQS8P SCONN288_H44441003_PIP-SCONN,HA   I101 @BASEBOARD_FAB2_LIB.BASEBOARD_FAB2(SCH_1):PAGE80

M_H_DQS_DP<9> @BASEBOARD_FAB2_LIB.BASEBOARD_FAB2(SCH_1):M_H_DQS_DP(9)
  U2D1 AT81 DDR1_DQS_DP<9> SKX_EXT_B_BGA1-IC,TBD   I172 @BASEBOARD_FAB2_LIB.BASEBOARD_FAB2(SCH_1):PAGE58
  J1G2    7  DQS9P SCONN288_H44441004_PIP-SCONN,HA    I64 @BASEBOARD_FAB2_LIB.BASEBOARD_FAB2(SCH_1):PAGE79
  J9U1    7  DQS9P SCONN288_H44441003_PIP-SCONN,HA   I101 @BASEBOARD_FAB2_LIB.BASEBOARD_FAB2(SCH_1):PAGE80

M_H_ECC<0> @BASEBOARD_FAB2_LIB.BASEBOARD_FAB2(SCH_1):M_H_ECC(0)
  U2D1  J70 DDR1_ECC<0> SKX_EXT_B_BGA1-IC,TBD   I172 @BASEBOARD_FAB2_LIB.BASEBOARD_FAB2(SCH_1):PAGE58
  J1G2  194  CB<1> SCONN288_H44441004_PIP-SCONN,HA   I111 @BASEBOARD_FAB2_LIB.BASEBOARD_FAB2(SCH_1):PAGE79
  J9U1   49  CB<0> SCONN288_H44441003_PIP-SCONN,HA    I24 @BASEBOARD_FAB2_LIB.BASEBOARD_FAB2(SCH_1):PAGE80

M_H_ECC<1> @BASEBOARD_FAB2_LIB.BASEBOARD_FAB2(SCH_1):M_H_ECC(1)
  U2D1  H69 DDR1_ECC<1> SKX_EXT_B_BGA1-IC,TBD   I172 @BASEBOARD_FAB2_LIB.BASEBOARD_FAB2(SCH_1):PAGE58
  J1G2   49  CB<0> SCONN288_H44441004_PIP-SCONN,HA   I111 @BASEBOARD_FAB2_LIB.BASEBOARD_FAB2(SCH_1):PAGE79
  J9U1  194  CB<1> SCONN288_H44441003_PIP-SCONN,HA    I24 @BASEBOARD_FAB2_LIB.BASEBOARD_FAB2(SCH_1):PAGE80

M_H_ECC<2> @BASEBOARD_FAB2_LIB.BASEBOARD_FAB2(SCH_1):M_H_ECC(2)
  U2D1  J66 DDR1_ECC<2> SKX_EXT_B_BGA1-IC,TBD   I172 @BASEBOARD_FAB2_LIB.BASEBOARD_FAB2(SCH_1):PAGE58
  J1G2  201  CB<3> SCONN288_H44441004_PIP-SCONN,HA   I111 @BASEBOARD_FAB2_LIB.BASEBOARD_FAB2(SCH_1):PAGE79
  J9U1   56  CB<2> SCONN288_H44441003_PIP-SCONN,HA    I24 @BASEBOARD_FAB2_LIB.BASEBOARD_FAB2(SCH_1):PAGE80

M_H_ECC<3> @BASEBOARD_FAB2_LIB.BASEBOARD_FAB2(SCH_1):M_H_ECC(3)
  U2D1  L66 DDR1_ECC<3> SKX_EXT_B_BGA1-IC,TBD   I172 @BASEBOARD_FAB2_LIB.BASEBOARD_FAB2(SCH_1):PAGE58
  J1G2   56  CB<2> SCONN288_H44441004_PIP-SCONN,HA   I111 @BASEBOARD_FAB2_LIB.BASEBOARD_FAB2(SCH_1):PAGE79
  J9U1  201  CB<3> SCONN288_H44441003_PIP-SCONN,HA    I24 @BASEBOARD_FAB2_LIB.BASEBOARD_FAB2(SCH_1):PAGE80

M_H_ECC<4> @BASEBOARD_FAB2_LIB.BASEBOARD_FAB2(SCH_1):M_H_ECC(4)
  U2D1  L70 DDR1_ECC<4> SKX_EXT_B_BGA1-IC,TBD   I172 @BASEBOARD_FAB2_LIB.BASEBOARD_FAB2(SCH_1):PAGE58
  J1G2  192  CB<5> SCONN288_H44441004_PIP-SCONN,HA   I111 @BASEBOARD_FAB2_LIB.BASEBOARD_FAB2(SCH_1):PAGE79
  J9U1   47  CB<4> SCONN288_H44441003_PIP-SCONN,HA    I24 @BASEBOARD_FAB2_LIB.BASEBOARD_FAB2(SCH_1):PAGE80

M_H_ECC<5> @BASEBOARD_FAB2_LIB.BASEBOARD_FAB2(SCH_1):M_H_ECC(5)
  U2D1  M69 DDR1_ECC<5> SKX_EXT_B_BGA1-IC,TBD   I172 @BASEBOARD_FAB2_LIB.BASEBOARD_FAB2(SCH_1):PAGE58
  J1G2   47  CB<4> SCONN288_H44441004_PIP-SCONN,HA   I111 @BASEBOARD_FAB2_LIB.BASEBOARD_FAB2(SCH_1):PAGE79
  J9U1  192  CB<5> SCONN288_H44441003_PIP-SCONN,HA    I24 @BASEBOARD_FAB2_LIB.BASEBOARD_FAB2(SCH_1):PAGE80

M_H_ECC<6> @BASEBOARD_FAB2_LIB.BASEBOARD_FAB2(SCH_1):M_H_ECC(6)
  U2D1  H67 DDR1_ECC<6> SKX_EXT_B_BGA1-IC,TBD   I172 @BASEBOARD_FAB2_LIB.BASEBOARD_FAB2(SCH_1):PAGE58
  J1G2  199  CB<7> SCONN288_H44441004_PIP-SCONN,HA   I111 @BASEBOARD_FAB2_LIB.BASEBOARD_FAB2(SCH_1):PAGE79
  J9U1   54  CB<6> SCONN288_H44441003_PIP-SCONN,HA    I24 @BASEBOARD_FAB2_LIB.BASEBOARD_FAB2(SCH_1):PAGE80

M_H_ECC<7> @BASEBOARD_FAB2_LIB.BASEBOARD_FAB2(SCH_1):M_H_ECC(7)
  U2D1  M67 DDR1_ECC<7> SKX_EXT_B_BGA1-IC,TBD   I172 @BASEBOARD_FAB2_LIB.BASEBOARD_FAB2(SCH_1):PAGE58
  J1G2   54  CB<6> SCONN288_H44441004_PIP-SCONN,HA   I111 @BASEBOARD_FAB2_LIB.BASEBOARD_FAB2(SCH_1):PAGE79
  J9U1  199  CB<7> SCONN288_H44441003_PIP-SCONN,HA    I24 @BASEBOARD_FAB2_LIB.BASEBOARD_FAB2(SCH_1):PAGE80

M_H_MA<0> @BASEBOARD_FAB2_LIB.BASEBOARD_FAB2(SCH_1):M_H_MA(0)
  U2D1  J52 DDR1_MA<0> SKX_EXT_B_BGA1-IC,TBD   I172 @BASEBOARD_FAB2_LIB.BASEBOARD_FAB2(SCH_1):PAGE58
  J1G2   79     A0 SCONN288_H44441004_PIP-SCONN,HA   I111 @BASEBOARD_FAB2_LIB.BASEBOARD_FAB2(SCH_1):PAGE79
  J9U1   79     A0 SCONN288_H44441003_PIP-SCONN,HA    I24 @BASEBOARD_FAB2_LIB.BASEBOARD_FAB2(SCH_1):PAGE80

M_H_MA<10> @BASEBOARD_FAB2_LIB.BASEBOARD_FAB2(SCH_1):M_H_MA(10)
  U2D1  M55 DDR1_MA<10> SKX_EXT_B_BGA1-IC,TBD   I172 @BASEBOARD_FAB2_LIB.BASEBOARD_FAB2(SCH_1):PAGE58
  J1G2  225    A10 SCONN288_H44441004_PIP-SCONN,HA   I111 @BASEBOARD_FAB2_LIB.BASEBOARD_FAB2(SCH_1):PAGE79
  J9U1  225    A10 SCONN288_H44441003_PIP-SCONN,HA    I24 @BASEBOARD_FAB2_LIB.BASEBOARD_FAB2(SCH_1):PAGE80

M_H_MA<11> @BASEBOARD_FAB2_LIB.BASEBOARD_FAB2(SCH_1):M_H_MA(11)
  U2D1  R60 DDR1_MA<11> SKX_EXT_B_BGA1-IC,TBD   I172 @BASEBOARD_FAB2_LIB.BASEBOARD_FAB2(SCH_1):PAGE58
  J1G2  210    A11 SCONN288_H44441004_PIP-SCONN,HA   I111 @BASEBOARD_FAB2_LIB.BASEBOARD_FAB2(SCH_1):PAGE79
  J9U1  210    A11 SCONN288_H44441003_PIP-SCONN,HA    I24 @BASEBOARD_FAB2_LIB.BASEBOARD_FAB2(SCH_1):PAGE80

M_H_MA<12> @BASEBOARD_FAB2_LIB.BASEBOARD_FAB2(SCH_1):M_H_MA(12)
  U2D1  T61 DDR1_MA<12> SKX_EXT_B_BGA1-IC,TBD   I172 @BASEBOARD_FAB2_LIB.BASEBOARD_FAB2(SCH_1):PAGE58
  J1G2   65    A12 SCONN288_H44441004_PIP-SCONN,HA   I111 @BASEBOARD_FAB2_LIB.BASEBOARD_FAB2(SCH_1):PAGE79
  J9U1   65    A12 SCONN288_H44441003_PIP-SCONN,HA    I24 @BASEBOARD_FAB2_LIB.BASEBOARD_FAB2(SCH_1):PAGE80

M_H_MA<13> @BASEBOARD_FAB2_LIB.BASEBOARD_FAB2(SCH_1):M_H_MA(13)
  U2D1  M51 DDR1_MA<13> SKX_EXT_B_BGA1-IC,TBD   I172 @BASEBOARD_FAB2_LIB.BASEBOARD_FAB2(SCH_1):PAGE58
  J1G2  232    A13 SCONN288_H44441004_PIP-SCONN,HA   I111 @BASEBOARD_FAB2_LIB.BASEBOARD_FAB2(SCH_1):PAGE79
  J9U1  232    A13 SCONN288_H44441003_PIP-SCONN,HA    I24 @BASEBOARD_FAB2_LIB.BASEBOARD_FAB2(SCH_1):PAGE80

M_H_MA<14> @BASEBOARD_FAB2_LIB.BASEBOARD_FAB2(SCH_1):M_H_MA(14)
  U2D1  T51 DDR1_MA<14> SKX_EXT_B_BGA1-IC,TBD   I172 @BASEBOARD_FAB2_LIB.BASEBOARD_FAB2(SCH_1):PAGE58
  J1G2  228 A14_WE_N SCONN288_H44441004_PIP-SCONN,HA   I111 @BASEBOARD_FAB2_LIB.BASEBOARD_FAB2(SCH_1):PAGE79
  J9U1  228 A14_WE_N SCONN288_H44441003_PIP-SCONN,HA    I24 @BASEBOARD_FAB2_LIB.BASEBOARD_FAB2(SCH_1):PAGE80

M_H_MA<15> @BASEBOARD_FAB2_LIB.BASEBOARD_FAB2(SCH_1):M_H_MA(15)
  U2D1  N52 DDR1_MA<15> SKX_EXT_B_BGA1-IC,TBD   I172 @BASEBOARD_FAB2_LIB.BASEBOARD_FAB2(SCH_1):PAGE58
  J1G2   86 A15_CAS_N SCONN288_H44441004_PIP-SCONN,HA   I111 @BASEBOARD_FAB2_LIB.BASEBOARD_FAB2(SCH_1):PAGE79
  J9U1   86 A15_CAS_N SCONN288_H44441003_PIP-SCONN,HA    I24 @BASEBOARD_FAB2_LIB.BASEBOARD_FAB2(SCH_1):PAGE80

M_H_MA<16> @BASEBOARD_FAB2_LIB.BASEBOARD_FAB2(SCH_1):M_H_MA(16)
  U2D1  R52 DDR1_MA<16> SKX_EXT_B_BGA1-IC,TBD   I172 @BASEBOARD_FAB2_LIB.BASEBOARD_FAB2(SCH_1):PAGE58
  J1G2   82 A16_RAS_N SCONN288_H44441004_PIP-SCONN,HA   I111 @BASEBOARD_FAB2_LIB.BASEBOARD_FAB2(SCH_1):PAGE79
  J9U1   82 A16_RAS_N SCONN288_H44441003_PIP-SCONN,HA    I24 @BASEBOARD_FAB2_LIB.BASEBOARD_FAB2(SCH_1):PAGE80

M_H_MA<17> @BASEBOARD_FAB2_LIB.BASEBOARD_FAB2(SCH_1):M_H_MA(17)
  U2D1  N48 DDR1_MA<17> SKX_EXT_B_BGA1-IC,TBD   I172 @BASEBOARD_FAB2_LIB.BASEBOARD_FAB2(SCH_1):PAGE58
  J1G2  234    A17 SCONN288_H44441004_PIP-SCONN,HA   I111 @BASEBOARD_FAB2_LIB.BASEBOARD_FAB2(SCH_1):PAGE79
  J9U1  234    A17 SCONN288_H44441003_PIP-SCONN,HA    I24 @BASEBOARD_FAB2_LIB.BASEBOARD_FAB2(SCH_1):PAGE80

M_H_MA<1> @BASEBOARD_FAB2_LIB.BASEBOARD_FAB2(SCH_1):M_H_MA(1)
  U2D1  J58 DDR1_MA<1> SKX_EXT_B_BGA1-IC,TBD   I172 @BASEBOARD_FAB2_LIB.BASEBOARD_FAB2(SCH_1):PAGE58
  J1G2   72     A1 SCONN288_H44441004_PIP-SCONN,HA   I111 @BASEBOARD_FAB2_LIB.BASEBOARD_FAB2(SCH_1):PAGE79
  J9U1   72     A1 SCONN288_H44441003_PIP-SCONN,HA    I24 @BASEBOARD_FAB2_LIB.BASEBOARD_FAB2(SCH_1):PAGE80

M_H_MA<2> @BASEBOARD_FAB2_LIB.BASEBOARD_FAB2(SCH_1):M_H_MA(2)
  U2D1  K57 DDR1_MA<2> SKX_EXT_B_BGA1-IC,TBD   I172 @BASEBOARD_FAB2_LIB.BASEBOARD_FAB2(SCH_1):PAGE58
  J1G2  216     A2 SCONN288_H44441004_PIP-SCONN,HA   I111 @BASEBOARD_FAB2_LIB.BASEBOARD_FAB2(SCH_1):PAGE79
  J9U1  216     A2 SCONN288_H44441003_PIP-SCONN,HA    I24 @BASEBOARD_FAB2_LIB.BASEBOARD_FAB2(SCH_1):PAGE80

M_H_MA<3> @BASEBOARD_FAB2_LIB.BASEBOARD_FAB2(SCH_1):M_H_MA(3)
  U2D1  N58 DDR1_MA<3> SKX_EXT_B_BGA1-IC,TBD   I172 @BASEBOARD_FAB2_LIB.BASEBOARD_FAB2(SCH_1):PAGE58
  J1G2   71     A3 SCONN288_H44441004_PIP-SCONN,HA   I111 @BASEBOARD_FAB2_LIB.BASEBOARD_FAB2(SCH_1):PAGE79
  J9U1   71     A3 SCONN288_H44441003_PIP-SCONN,HA    I24 @BASEBOARD_FAB2_LIB.BASEBOARD_FAB2(SCH_1):PAGE80

M_H_MA<4> @BASEBOARD_FAB2_LIB.BASEBOARD_FAB2(SCH_1):M_H_MA(4)
  U2D1  M59 DDR1_MA<4> SKX_EXT_B_BGA1-IC,TBD   I172 @BASEBOARD_FAB2_LIB.BASEBOARD_FAB2(SCH_1):PAGE58
  J1G2  214     A4 SCONN288_H44441004_PIP-SCONN,HA   I111 @BASEBOARD_FAB2_LIB.BASEBOARD_FAB2(SCH_1):PAGE79
  J9U1  214     A4 SCONN288_H44441003_PIP-SCONN,HA    I24 @BASEBOARD_FAB2_LIB.BASEBOARD_FAB2(SCH_1):PAGE80

M_H_MA<5> @BASEBOARD_FAB2_LIB.BASEBOARD_FAB2(SCH_1):M_H_MA(5)
  U2D1  R58 DDR1_MA<5> SKX_EXT_B_BGA1-IC,TBD   I172 @BASEBOARD_FAB2_LIB.BASEBOARD_FAB2(SCH_1):PAGE58
  J1G2  213     A5 SCONN288_H44441004_PIP-SCONN,HA   I111 @BASEBOARD_FAB2_LIB.BASEBOARD_FAB2(SCH_1):PAGE79
  J9U1  213     A5 SCONN288_H44441003_PIP-SCONN,HA    I24 @BASEBOARD_FAB2_LIB.BASEBOARD_FAB2(SCH_1):PAGE80

M_H_MA<6> @BASEBOARD_FAB2_LIB.BASEBOARD_FAB2(SCH_1):M_H_MA(6)
  U2D1  T59 DDR1_MA<6> SKX_EXT_B_BGA1-IC,TBD   I172 @BASEBOARD_FAB2_LIB.BASEBOARD_FAB2(SCH_1):PAGE58
  J1G2   69     A6 SCONN288_H44441004_PIP-SCONN,HA   I111 @BASEBOARD_FAB2_LIB.BASEBOARD_FAB2(SCH_1):PAGE79
  J9U1   69     A6 SCONN288_H44441003_PIP-SCONN,HA    I24 @BASEBOARD_FAB2_LIB.BASEBOARD_FAB2(SCH_1):PAGE80

M_H_MA<7> @BASEBOARD_FAB2_LIB.BASEBOARD_FAB2(SCH_1):M_H_MA(7)
  U2D1  V61 DDR1_MA<7> SKX_EXT_B_BGA1-IC,TBD   I172 @BASEBOARD_FAB2_LIB.BASEBOARD_FAB2(SCH_1):PAGE58
  J1G2  211     A7 SCONN288_H44441004_PIP-SCONN,HA   I111 @BASEBOARD_FAB2_LIB.BASEBOARD_FAB2(SCH_1):PAGE79
  J9U1  211     A7 SCONN288_H44441003_PIP-SCONN,HA    I24 @BASEBOARD_FAB2_LIB.BASEBOARD_FAB2(SCH_1):PAGE80

M_H_MA<8> @BASEBOARD_FAB2_LIB.BASEBOARD_FAB2(SCH_1):M_H_MA(8)
  U2D1  W60 DDR1_MA<8> SKX_EXT_B_BGA1-IC,TBD   I172 @BASEBOARD_FAB2_LIB.BASEBOARD_FAB2(SCH_1):PAGE58
  J1G2   68     A8 SCONN288_H44441004_PIP-SCONN,HA   I111 @BASEBOARD_FAB2_LIB.BASEBOARD_FAB2(SCH_1):PAGE79
  J9U1   68     A8 SCONN288_H44441003_PIP-SCONN,HA    I24 @BASEBOARD_FAB2_LIB.BASEBOARD_FAB2(SCH_1):PAGE80

M_H_MA<9> @BASEBOARD_FAB2_LIB.BASEBOARD_FAB2(SCH_1):M_H_MA(9)
  U2D1  K59 DDR1_MA<9> SKX_EXT_B_BGA1-IC,TBD   I172 @BASEBOARD_FAB2_LIB.BASEBOARD_FAB2(SCH_1):PAGE58
  J1G2   66     A9 SCONN288_H44441004_PIP-SCONN,HA   I111 @BASEBOARD_FAB2_LIB.BASEBOARD_FAB2(SCH_1):PAGE79
  J9U1   66     A9 SCONN288_H44441003_PIP-SCONN,HA    I24 @BASEBOARD_FAB2_LIB.BASEBOARD_FAB2(SCH_1):PAGE80

M_H_ODT<0> @BASEBOARD_FAB2_LIB.BASEBOARD_FAB2(SCH_1):M_H_ODT(0)
  U2D1  N50 DDR1_ODT<0> SKX_EXT_B_BGA1-IC,TBD   I172 @BASEBOARD_FAB2_LIB.BASEBOARD_FAB2(SCH_1):PAGE58
  J1G2   87 ODT<0> SCONN288_H44441004_PIP-SCONN,HA   I111 @BASEBOARD_FAB2_LIB.BASEBOARD_FAB2(SCH_1):PAGE79

M_H_ODT<1> @BASEBOARD_FAB2_LIB.BASEBOARD_FAB2(SCH_1):M_H_ODT(1)
  U2D1  R48 DDR1_ODT<1> SKX_EXT_B_BGA1-IC,TBD   I172 @BASEBOARD_FAB2_LIB.BASEBOARD_FAB2(SCH_1):PAGE58
  J1G2   91 ODT<1> SCONN288_H44441004_PIP-SCONN,HA   I111 @BASEBOARD_FAB2_LIB.BASEBOARD_FAB2(SCH_1):PAGE79

M_H_ODT<2> @BASEBOARD_FAB2_LIB.BASEBOARD_FAB2(SCH_1):M_H_ODT(2)
  U2D1  M49 DDR1_ODT<2> SKX_EXT_B_BGA1-IC,TBD   I172 @BASEBOARD_FAB2_LIB.BASEBOARD_FAB2(SCH_1):PAGE58
  J9U1   87 ODT<0> SCONN288_H44441003_PIP-SCONN,HA    I24 @BASEBOARD_FAB2_LIB.BASEBOARD_FAB2(SCH_1):PAGE80

M_H_ODT<3> @BASEBOARD_FAB2_LIB.BASEBOARD_FAB2(SCH_1):M_H_ODT(3)
  U2D1  T47 DDR1_ODT<3> SKX_EXT_B_BGA1-IC,TBD   I172 @BASEBOARD_FAB2_LIB.BASEBOARD_FAB2(SCH_1):PAGE58
  J9U1   91 ODT<1> SCONN288_H44441003_PIP-SCONN,HA    I24 @BASEBOARD_FAB2_LIB.BASEBOARD_FAB2(SCH_1):PAGE80

M_H_PAR @BASEBOARD_FAB2_LIB.BASEBOARD_FAB2(SCH_1):M_H_PAR
  U2D1  K53 DDR1_PAR SKX_EXT_B_BGA1-IC,TBD   I172 @BASEBOARD_FAB2_LIB.BASEBOARD_FAB2(SCH_1):PAGE58
  J1G2  222    PAR SCONN288_H44441004_PIP-SCONN,HA   I111 @BASEBOARD_FAB2_LIB.BASEBOARD_FAB2(SCH_1):PAGE79
  J9U1  222    PAR SCONN288_H44441003_PIP-SCONN,HA    I24 @BASEBOARD_FAB2_LIB.BASEBOARD_FAB2(SCH_1):PAGE80

M_H_VREF @BASEBOARD_FAB2_LIB.BASEBOARD_FAB2(SCH_1):M_H_VREF
  J1G2  146 VREFCA SCONN288_H44441004_PIP-SCONN,HA   I111 @BASEBOARD_FAB2_LIB.BASEBOARD_FAB2(SCH_1):PAGE79
  C9U7    1      A CAP_A_0402V-0.01UF,25V,10%,X7RA   I178 @BASEBOARD_FAB2_LIB.BASEBOARD_FAB2(SCH_1):PAGE79
 C1G10    1      A CAP_A_0402V-0.01UF,25V,10%,X7RA     I3 @BASEBOARD_FAB2_LIB.BASEBOARD_FAB2(SCH_1):PAGE80
  J9U1  146 VREFCA SCONN288_H44441003_PIP-SCONN,HA    I24 @BASEBOARD_FAB2_LIB.BASEBOARD_FAB2(SCH_1):PAGE80
  R1G2    2      B RES_0402-1.00K,1%,1/16W,CHIP,GA    I19 @BASEBOARD_FAB2_LIB.BASEBOARD_FAB2(SCH_1):PAGE100
  R1G3    1      A RES_0402-1.00K,1%,1/16W,CHIP,GA    I20 @BASEBOARD_FAB2_LIB.BASEBOARD_FAB2(SCH_1):PAGE100
  R1G1    2      B RES_0402-2,1.0%,1/16W,CHIP,G21A    I25 @BASEBOARD_FAB2_LIB.BASEBOARD_FAB2(SCH_1):PAGE100

M_J_ACT_N @BASEBOARD_FAB2_LIB.BASEBOARD_FAB2(SCH_1):M_J_ACT_N
  U2D1 AB61 DDR2_ACT_N SKX_EXT_B_BGA1-IC,TBD   I172 @BASEBOARD_FAB2_LIB.BASEBOARD_FAB2(SCH_1):PAGE59
  J1G3   62  ACT_N SCONN288_H44441004_PIP-SCONN,HA   I186 @BASEBOARD_FAB2_LIB.BASEBOARD_FAB2(SCH_1):PAGE81
  J9U2   62  ACT_N SCONN288_H44441003_PIP-SCONN,HA   I187 @BASEBOARD_FAB2_LIB.BASEBOARD_FAB2(SCH_1):PAGE82

M_J_ALERT_N @BASEBOARD_FAB2_LIB.BASEBOARD_FAB2(SCH_1):M_J_ALERT_N
  U2D1 AD61 DDR2_ALERT_N SKX_EXT_B_BGA1-IC,TBD   I172 @BASEBOARD_FAB2_LIB.BASEBOARD_FAB2(SCH_1):PAGE59
  J1G3  208 ALERT_N SCONN288_H44441004_PIP-SCONN,HA   I186 @BASEBOARD_FAB2_LIB.BASEBOARD_FAB2(SCH_1):PAGE81
  J9U2  208 ALERT_N SCONN288_H44441003_PIP-SCONN,HA   I187 @BASEBOARD_FAB2_LIB.BASEBOARD_FAB2(SCH_1):PAGE82

M_J_BA<0> @BASEBOARD_FAB2_LIB.BASEBOARD_FAB2(SCH_1):M_J_BA(0)
  U2D1  W52 DDR2_BA<0> SKX_EXT_B_BGA1-IC,TBD   I172 @BASEBOARD_FAB2_LIB.BASEBOARD_FAB2(SCH_1):PAGE59
  J1G3   81  BA<0> SCONN288_H44441004_PIP-SCONN,HA   I186 @BASEBOARD_FAB2_LIB.BASEBOARD_FAB2(SCH_1):PAGE81
  J9U2   81  BA<0> SCONN288_H44441003_PIP-SCONN,HA   I187 @BASEBOARD_FAB2_LIB.BASEBOARD_FAB2(SCH_1):PAGE82

M_J_BA<1> @BASEBOARD_FAB2_LIB.BASEBOARD_FAB2(SCH_1):M_J_BA(1)
  U2D1 AE56 DDR2_BA<1> SKX_EXT_B_BGA1-IC,TBD   I172 @BASEBOARD_FAB2_LIB.BASEBOARD_FAB2(SCH_1):PAGE59
  J1G3  224  BA<1> SCONN288_H44441004_PIP-SCONN,HA   I186 @BASEBOARD_FAB2_LIB.BASEBOARD_FAB2(SCH_1):PAGE81
  J9U2  224  BA<1> SCONN288_H44441003_PIP-SCONN,HA   I187 @BASEBOARD_FAB2_LIB.BASEBOARD_FAB2(SCH_1):PAGE82

M_J_BG<0> @BASEBOARD_FAB2_LIB.BASEBOARD_FAB2(SCH_1):M_J_BG(0)
  U2D1 AA60 DDR2_BG<0> SKX_EXT_B_BGA1-IC,TBD   I172 @BASEBOARD_FAB2_LIB.BASEBOARD_FAB2(SCH_1):PAGE59
  J1G3   63  BG<0> SCONN288_H44441004_PIP-SCONN,HA   I186 @BASEBOARD_FAB2_LIB.BASEBOARD_FAB2(SCH_1):PAGE81
  J9U2   63  BG<0> SCONN288_H44441003_PIP-SCONN,HA   I187 @BASEBOARD_FAB2_LIB.BASEBOARD_FAB2(SCH_1):PAGE82

M_J_BG<1> @BASEBOARD_FAB2_LIB.BASEBOARD_FAB2(SCH_1):M_J_BG(1)
  U2D1 AE62 DDR2_BG<1> SKX_EXT_B_BGA1-IC,TBD   I172 @BASEBOARD_FAB2_LIB.BASEBOARD_FAB2(SCH_1):PAGE59
  J1G3  207  BG<1> SCONN288_H44441004_PIP-SCONN,HA   I186 @BASEBOARD_FAB2_LIB.BASEBOARD_FAB2(SCH_1):PAGE81
  J9U2  207  BG<1> SCONN288_H44441003_PIP-SCONN,HA   I187 @BASEBOARD_FAB2_LIB.BASEBOARD_FAB2(SCH_1):PAGE82

M_J_C<2> @BASEBOARD_FAB2_LIB.BASEBOARD_FAB2(SCH_1):M_J_C(2)
  U2D1 AB45 DDR2_CID<2> SKX_EXT_B_BGA1-IC,TBD   I172 @BASEBOARD_FAB2_LIB.BASEBOARD_FAB2(SCH_1):PAGE59
  J1G3  235   C<2> SCONN288_H44441004_PIP-SCONN,HA   I186 @BASEBOARD_FAB2_LIB.BASEBOARD_FAB2(SCH_1):PAGE81
  J9U2  235   C<2> SCONN288_H44441003_PIP-SCONN,HA   I187 @BASEBOARD_FAB2_LIB.BASEBOARD_FAB2(SCH_1):PAGE82

M_J_CKE<0> @BASEBOARD_FAB2_LIB.BASEBOARD_FAB2(SCH_1):M_J_CKE(0)
  U2D1 AA62 DDR2_CKE<0> SKX_EXT_B_BGA1-IC,TBD   I172 @BASEBOARD_FAB2_LIB.BASEBOARD_FAB2(SCH_1):PAGE59
  J1G3   60 CKE<0> SCONN288_H44441004_PIP-SCONN,HA   I186 @BASEBOARD_FAB2_LIB.BASEBOARD_FAB2(SCH_1):PAGE81

M_J_CKE<1> @BASEBOARD_FAB2_LIB.BASEBOARD_FAB2(SCH_1):M_J_CKE(1)
  U2D1 AD63 DDR2_CKE<1> SKX_EXT_B_BGA1-IC,TBD   I172 @BASEBOARD_FAB2_LIB.BASEBOARD_FAB2(SCH_1):PAGE59
  J1G3  203 CKE<1> SCONN288_H44441004_PIP-SCONN,HA   I186 @BASEBOARD_FAB2_LIB.BASEBOARD_FAB2(SCH_1):PAGE81

M_J_CKE<2> @BASEBOARD_FAB2_LIB.BASEBOARD_FAB2(SCH_1):M_J_CKE(2)
  U2D1  V63 DDR2_CKE<2> SKX_EXT_B_BGA1-IC,TBD   I172 @BASEBOARD_FAB2_LIB.BASEBOARD_FAB2(SCH_1):PAGE59
  J9U2   60 CKE<0> SCONN288_H44441003_PIP-SCONN,HA   I187 @BASEBOARD_FAB2_LIB.BASEBOARD_FAB2(SCH_1):PAGE82

M_J_CKE<3> @BASEBOARD_FAB2_LIB.BASEBOARD_FAB2(SCH_1):M_J_CKE(3)
  U2D1 AB63 DDR2_CKE<3> SKX_EXT_B_BGA1-IC,TBD   I172 @BASEBOARD_FAB2_LIB.BASEBOARD_FAB2(SCH_1):PAGE59
  J9U2  203 CKE<1> SCONN288_H44441003_PIP-SCONN,HA   I187 @BASEBOARD_FAB2_LIB.BASEBOARD_FAB2(SCH_1):PAGE82

M_J_CLK_DN<0> @BASEBOARD_FAB2_LIB.BASEBOARD_FAB2(SCH_1):M_J_CLK_DN(0)
  U2D1 AA54 DDR2_CLK_DN<0> SKX_EXT_B_BGA1-IC,TBD   I172 @BASEBOARD_FAB2_LIB.BASEBOARD_FAB2(SCH_1):PAGE59
  J1G3   75   CK0N SCONN288_H44441004_PIP-SCONN,HA   I186 @BASEBOARD_FAB2_LIB.BASEBOARD_FAB2(SCH_1):PAGE81

M_J_CLK_DN<1> @BASEBOARD_FAB2_LIB.BASEBOARD_FAB2(SCH_1):M_J_CLK_DN(1)
  U2D1  W54 DDR2_CLK_DN<1> SKX_EXT_B_BGA1-IC,TBD   I172 @BASEBOARD_FAB2_LIB.BASEBOARD_FAB2(SCH_1):PAGE59
  J1G3  219   CK1N SCONN288_H44441004_PIP-SCONN,HA   I186 @BASEBOARD_FAB2_LIB.BASEBOARD_FAB2(SCH_1):PAGE81

M_J_CLK_DN<2> @BASEBOARD_FAB2_LIB.BASEBOARD_FAB2(SCH_1):M_J_CLK_DN(2)
  U2D1 AA56 DDR2_CLK_DN<2> SKX_EXT_B_BGA1-IC,TBD   I172 @BASEBOARD_FAB2_LIB.BASEBOARD_FAB2(SCH_1):PAGE59
  J9U2   75   CK0N SCONN288_H44441003_PIP-SCONN,HA   I187 @BASEBOARD_FAB2_LIB.BASEBOARD_FAB2(SCH_1):PAGE82

M_J_CLK_DN<3> @BASEBOARD_FAB2_LIB.BASEBOARD_FAB2(SCH_1):M_J_CLK_DN(3)
  U2D1  W56 DDR2_CLK_DN<3> SKX_EXT_B_BGA1-IC,TBD   I172 @BASEBOARD_FAB2_LIB.BASEBOARD_FAB2(SCH_1):PAGE59
  J9U2  219   CK1N SCONN288_H44441003_PIP-SCONN,HA   I187 @BASEBOARD_FAB2_LIB.BASEBOARD_FAB2(SCH_1):PAGE82

M_J_CLK_DP<0> @BASEBOARD_FAB2_LIB.BASEBOARD_FAB2(SCH_1):M_J_CLK_DP(0)
  U2D1 AB55 DDR2_CLK_DP<0> SKX_EXT_B_BGA1-IC,TBD   I172 @BASEBOARD_FAB2_LIB.BASEBOARD_FAB2(SCH_1):PAGE59
  J1G3   74   CK0P SCONN288_H44441004_PIP-SCONN,HA   I186 @BASEBOARD_FAB2_LIB.BASEBOARD_FAB2(SCH_1):PAGE81

M_J_CLK_DP<1> @BASEBOARD_FAB2_LIB.BASEBOARD_FAB2(SCH_1):M_J_CLK_DP(1)
  U2D1  V55 DDR2_CLK_DP<1> SKX_EXT_B_BGA1-IC,TBD   I172 @BASEBOARD_FAB2_LIB.BASEBOARD_FAB2(SCH_1):PAGE59
  J1G3  218   CK1P SCONN288_H44441004_PIP-SCONN,HA   I186 @BASEBOARD_FAB2_LIB.BASEBOARD_FAB2(SCH_1):PAGE81

M_J_CLK_DP<2> @BASEBOARD_FAB2_LIB.BASEBOARD_FAB2(SCH_1):M_J_CLK_DP(2)
  U2D1 AB57 DDR2_CLK_DP<2> SKX_EXT_B_BGA1-IC,TBD   I172 @BASEBOARD_FAB2_LIB.BASEBOARD_FAB2(SCH_1):PAGE59
  J9U2   74   CK0P SCONN288_H44441003_PIP-SCONN,HA   I187 @BASEBOARD_FAB2_LIB.BASEBOARD_FAB2(SCH_1):PAGE82

M_J_CLK_DP<3> @BASEBOARD_FAB2_LIB.BASEBOARD_FAB2(SCH_1):M_J_CLK_DP(3)
  U2D1  V57 DDR2_CLK_DP<3> SKX_EXT_B_BGA1-IC,TBD   I172 @BASEBOARD_FAB2_LIB.BASEBOARD_FAB2(SCH_1):PAGE59
  J9U2  218   CK1P SCONN288_H44441003_PIP-SCONN,HA   I187 @BASEBOARD_FAB2_LIB.BASEBOARD_FAB2(SCH_1):PAGE82

M_J_CPU_VREF @BASEBOARD_FAB2_LIB.BASEBOARD_FAB2(SCH_1):M_J_CPU_VREF
  U2D1 AH63 DDR2_CAVREF SKX_EXT_B_BGA1-IC,TBD   I172 @BASEBOARD_FAB2_LIB.BASEBOARD_FAB2(SCH_1):PAGE55
 R1G14    1      A RES_0402-2,1.0%,1/16W,CHIP,G21A    I41 @BASEBOARD_FAB2_LIB.BASEBOARD_FAB2(SCH_1):PAGE100
 C1G18    1      A CAP_A_0402V-0.01UF,25V,10%,X7RA    I42 @BASEBOARD_FAB2_LIB.BASEBOARD_FAB2(SCH_1):PAGE100

M_J_CS_N<0> @BASEBOARD_FAB2_LIB.BASEBOARD_FAB2(SCH_1):M_J_CS_N(0)
  U2D1  V51 DDR2_CS_N<0> SKX_EXT_B_BGA1-IC,TBD   I172 @BASEBOARD_FAB2_LIB.BASEBOARD_FAB2(SCH_1):PAGE59
  J1G3   84   S0_N SCONN288_H44441004_PIP-SCONN,HA   I186 @BASEBOARD_FAB2_LIB.BASEBOARD_FAB2(SCH_1):PAGE81

M_J_CS_N<1> @BASEBOARD_FAB2_LIB.BASEBOARD_FAB2(SCH_1):M_J_CS_N(1)
  U2D1 AB49 DDR2_CS_N<1> SKX_EXT_B_BGA1-IC,TBD   I172 @BASEBOARD_FAB2_LIB.BASEBOARD_FAB2(SCH_1):PAGE59
  J1G3   89   S1_N SCONN288_H44441004_PIP-SCONN,HA   I186 @BASEBOARD_FAB2_LIB.BASEBOARD_FAB2(SCH_1):PAGE81

M_J_CS_N<2> @BASEBOARD_FAB2_LIB.BASEBOARD_FAB2(SCH_1):M_J_CS_N(2)
  U2D1  W46 DDR2_CS_N<2> SKX_EXT_B_BGA1-IC,TBD   I172 @BASEBOARD_FAB2_LIB.BASEBOARD_FAB2(SCH_1):PAGE59
  J1G3   93 S2_N_C<0> SCONN288_H44441004_PIP-SCONN,HA   I186 @BASEBOARD_FAB2_LIB.BASEBOARD_FAB2(SCH_1):PAGE81

M_J_CS_N<3> @BASEBOARD_FAB2_LIB.BASEBOARD_FAB2(SCH_1):M_J_CS_N(3)
  U2D1 AA46 DDR2_CS_N<3> SKX_EXT_B_BGA1-IC,TBD   I172 @BASEBOARD_FAB2_LIB.BASEBOARD_FAB2(SCH_1):PAGE59
  J1G3  237 S3_N_C<1> SCONN288_H44441004_PIP-SCONN,HA   I186 @BASEBOARD_FAB2_LIB.BASEBOARD_FAB2(SCH_1):PAGE81

M_J_CS_N<4> @BASEBOARD_FAB2_LIB.BASEBOARD_FAB2(SCH_1):M_J_CS_N(4)
  U2D1 AB51 DDR2_CS_N<4> SKX_EXT_B_BGA1-IC,TBD   I172 @BASEBOARD_FAB2_LIB.BASEBOARD_FAB2(SCH_1):PAGE59
  J9U2   84   S0_N SCONN288_H44441003_PIP-SCONN,HA   I187 @BASEBOARD_FAB2_LIB.BASEBOARD_FAB2(SCH_1):PAGE82

M_J_CS_N<5> @BASEBOARD_FAB2_LIB.BASEBOARD_FAB2(SCH_1):M_J_CS_N(5)
  U2D1  W48 DDR2_CS_N<5> SKX_EXT_B_BGA1-IC,TBD   I172 @BASEBOARD_FAB2_LIB.BASEBOARD_FAB2(SCH_1):PAGE59
  J9U2   89   S1_N SCONN288_H44441003_PIP-SCONN,HA   I187 @BASEBOARD_FAB2_LIB.BASEBOARD_FAB2(SCH_1):PAGE82

M_J_CS_N<6> @BASEBOARD_FAB2_LIB.BASEBOARD_FAB2(SCH_1):M_J_CS_N(6)
  U2D1  T45 DDR2_CS_N<6> SKX_EXT_B_BGA1-IC,TBD   I172 @BASEBOARD_FAB2_LIB.BASEBOARD_FAB2(SCH_1):PAGE59
  J9U2   93 S2_N_C<0> SCONN288_H44441003_PIP-SCONN,HA   I187 @BASEBOARD_FAB2_LIB.BASEBOARD_FAB2(SCH_1):PAGE82

M_J_CS_N<7> @BASEBOARD_FAB2_LIB.BASEBOARD_FAB2(SCH_1):M_J_CS_N(7)
  U2D1  V45 DDR2_CS_N<7> SKX_EXT_B_BGA1-IC,TBD   I172 @BASEBOARD_FAB2_LIB.BASEBOARD_FAB2(SCH_1):PAGE59
  J9U2  237 S3_N_C<1> SCONN288_H44441003_PIP-SCONN,HA   I187 @BASEBOARD_FAB2_LIB.BASEBOARD_FAB2(SCH_1):PAGE82

M_J_DQ<0> @BASEBOARD_FAB2_LIB.BASEBOARD_FAB2(SCH_1):M_J_DQ(0)
  U2D1 AR76 DDR2_DQ<0> SKX_EXT_B_BGA1-IC,TBD   I172 @BASEBOARD_FAB2_LIB.BASEBOARD_FAB2(SCH_1):PAGE59
  J1G3  150  DQ<1> SCONN288_H44441004_PIP-SCONN,HA   I186 @BASEBOARD_FAB2_LIB.BASEBOARD_FAB2(SCH_1):PAGE81
  J9U2    5  DQ<0> SCONN288_H44441003_PIP-SCONN,HA   I187 @BASEBOARD_FAB2_LIB.BASEBOARD_FAB2(SCH_1):PAGE82

M_J_DQ<10> @BASEBOARD_FAB2_LIB.BASEBOARD_FAB2(SCH_1):M_J_DQ(10)
  U2D1  Y77 DDR2_DQ<10> SKX_EXT_B_BGA1-IC,TBD   I172 @BASEBOARD_FAB2_LIB.BASEBOARD_FAB2(SCH_1):PAGE59
  J1G3  168 DQ<11> SCONN288_H44441004_PIP-SCONN,HA   I186 @BASEBOARD_FAB2_LIB.BASEBOARD_FAB2(SCH_1):PAGE81
  J9U2   23 DQ<10> SCONN288_H44441003_PIP-SCONN,HA   I187 @BASEBOARD_FAB2_LIB.BASEBOARD_FAB2(SCH_1):PAGE82

M_J_DQ<11> @BASEBOARD_FAB2_LIB.BASEBOARD_FAB2(SCH_1):M_J_DQ(11)
  U2D1  W76 DDR2_DQ<11> SKX_EXT_B_BGA1-IC,TBD   I172 @BASEBOARD_FAB2_LIB.BASEBOARD_FAB2(SCH_1):PAGE59
  J1G3   23 DQ<10> SCONN288_H44441004_PIP-SCONN,HA   I186 @BASEBOARD_FAB2_LIB.BASEBOARD_FAB2(SCH_1):PAGE81
  J9U2  168 DQ<11> SCONN288_H44441003_PIP-SCONN,HA   I187 @BASEBOARD_FAB2_LIB.BASEBOARD_FAB2(SCH_1):PAGE82

M_J_DQ<12> @BASEBOARD_FAB2_LIB.BASEBOARD_FAB2(SCH_1):M_J_DQ(12)
  U2D1 AF75 DDR2_DQ<12> SKX_EXT_B_BGA1-IC,TBD   I172 @BASEBOARD_FAB2_LIB.BASEBOARD_FAB2(SCH_1):PAGE59
  J1G3  159 DQ<13> SCONN288_H44441004_PIP-SCONN,HA   I186 @BASEBOARD_FAB2_LIB.BASEBOARD_FAB2(SCH_1):PAGE81
  J9U2   14 DQ<12> SCONN288_H44441003_PIP-SCONN,HA   I187 @BASEBOARD_FAB2_LIB.BASEBOARD_FAB2(SCH_1):PAGE82

M_J_DQ<13> @BASEBOARD_FAB2_LIB.BASEBOARD_FAB2(SCH_1):M_J_DQ(13)
  U2D1 AE74 DDR2_DQ<13> SKX_EXT_B_BGA1-IC,TBD   I172 @BASEBOARD_FAB2_LIB.BASEBOARD_FAB2(SCH_1):PAGE59
  J1G3   14 DQ<12> SCONN288_H44441004_PIP-SCONN,HA   I186 @BASEBOARD_FAB2_LIB.BASEBOARD_FAB2(SCH_1):PAGE81
  J9U2  159 DQ<13> SCONN288_H44441003_PIP-SCONN,HA   I187 @BASEBOARD_FAB2_LIB.BASEBOARD_FAB2(SCH_1):PAGE82

M_J_DQ<14> @BASEBOARD_FAB2_LIB.BASEBOARD_FAB2(SCH_1):M_J_DQ(14)
  U2D1 AB77 DDR2_DQ<14> SKX_EXT_B_BGA1-IC,TBD   I172 @BASEBOARD_FAB2_LIB.BASEBOARD_FAB2(SCH_1):PAGE59
  J1G3  166 DQ<15> SCONN288_H44441004_PIP-SCONN,HA   I186 @BASEBOARD_FAB2_LIB.BASEBOARD_FAB2(SCH_1):PAGE81
  J9U2   21 DQ<14> SCONN288_H44441003_PIP-SCONN,HA   I187 @BASEBOARD_FAB2_LIB.BASEBOARD_FAB2(SCH_1):PAGE82

M_J_DQ<15> @BASEBOARD_FAB2_LIB.BASEBOARD_FAB2(SCH_1):M_J_DQ(15)
  U2D1  Y75 DDR2_DQ<15> SKX_EXT_B_BGA1-IC,TBD   I172 @BASEBOARD_FAB2_LIB.BASEBOARD_FAB2(SCH_1):PAGE59
  J1G3   21 DQ<14> SCONN288_H44441004_PIP-SCONN,HA   I186 @BASEBOARD_FAB2_LIB.BASEBOARD_FAB2(SCH_1):PAGE81
  J9U2  166 DQ<15> SCONN288_H44441003_PIP-SCONN,HA   I187 @BASEBOARD_FAB2_LIB.BASEBOARD_FAB2(SCH_1):PAGE82

M_J_DQ<16> @BASEBOARD_FAB2_LIB.BASEBOARD_FAB2(SCH_1):M_J_DQ(16)
  U2D1  W72 DDR2_DQ<16> SKX_EXT_B_BGA1-IC,TBD   I172 @BASEBOARD_FAB2_LIB.BASEBOARD_FAB2(SCH_1):PAGE59
  J1G3  172 DQ<17> SCONN288_H44441004_PIP-SCONN,HA   I186 @BASEBOARD_FAB2_LIB.BASEBOARD_FAB2(SCH_1):PAGE81
  J9U2   27 DQ<16> SCONN288_H44441003_PIP-SCONN,HA   I187 @BASEBOARD_FAB2_LIB.BASEBOARD_FAB2(SCH_1):PAGE82

M_J_DQ<17> @BASEBOARD_FAB2_LIB.BASEBOARD_FAB2(SCH_1):M_J_DQ(17)
  U2D1 AA70 DDR2_DQ<17> SKX_EXT_B_BGA1-IC,TBD   I172 @BASEBOARD_FAB2_LIB.BASEBOARD_FAB2(SCH_1):PAGE59
  J1G3   27 DQ<16> SCONN288_H44441004_PIP-SCONN,HA   I186 @BASEBOARD_FAB2_LIB.BASEBOARD_FAB2(SCH_1):PAGE81
  J9U2  172 DQ<17> SCONN288_H44441003_PIP-SCONN,HA   I187 @BASEBOARD_FAB2_LIB.BASEBOARD_FAB2(SCH_1):PAGE82

M_J_DQ<18> @BASEBOARD_FAB2_LIB.BASEBOARD_FAB2(SCH_1):M_J_DQ(18)
  U2D1  R70 DDR2_DQ<18> SKX_EXT_B_BGA1-IC,TBD   I172 @BASEBOARD_FAB2_LIB.BASEBOARD_FAB2(SCH_1):PAGE59
  J1G3  179 DQ<19> SCONN288_H44441004_PIP-SCONN,HA   I186 @BASEBOARD_FAB2_LIB.BASEBOARD_FAB2(SCH_1):PAGE81
  J9U2   34 DQ<18> SCONN288_H44441003_PIP-SCONN,HA   I187 @BASEBOARD_FAB2_LIB.BASEBOARD_FAB2(SCH_1):PAGE82

M_J_DQ<19> @BASEBOARD_FAB2_LIB.BASEBOARD_FAB2(SCH_1):M_J_DQ(19)
  U2D1  T69 DDR2_DQ<19> SKX_EXT_B_BGA1-IC,TBD   I172 @BASEBOARD_FAB2_LIB.BASEBOARD_FAB2(SCH_1):PAGE59
  J1G3   34 DQ<18> SCONN288_H44441004_PIP-SCONN,HA   I186 @BASEBOARD_FAB2_LIB.BASEBOARD_FAB2(SCH_1):PAGE81
  J9U2  179 DQ<19> SCONN288_H44441003_PIP-SCONN,HA   I187 @BASEBOARD_FAB2_LIB.BASEBOARD_FAB2(SCH_1):PAGE82

M_J_DQ<1> @BASEBOARD_FAB2_LIB.BASEBOARD_FAB2(SCH_1):M_J_DQ(1)
  U2D1 AN74 DDR2_DQ<1> SKX_EXT_B_BGA1-IC,TBD   I172 @BASEBOARD_FAB2_LIB.BASEBOARD_FAB2(SCH_1):PAGE59
  J1G3    5  DQ<0> SCONN288_H44441004_PIP-SCONN,HA   I186 @BASEBOARD_FAB2_LIB.BASEBOARD_FAB2(SCH_1):PAGE81
  J9U2  150  DQ<1> SCONN288_H44441003_PIP-SCONN,HA   I187 @BASEBOARD_FAB2_LIB.BASEBOARD_FAB2(SCH_1):PAGE82

M_J_DQ<20> @BASEBOARD_FAB2_LIB.BASEBOARD_FAB2(SCH_1):M_J_DQ(20)
  U2D1 AA72 DDR2_DQ<20> SKX_EXT_B_BGA1-IC,TBD   I172 @BASEBOARD_FAB2_LIB.BASEBOARD_FAB2(SCH_1):PAGE59
  J1G3  170 DQ<21> SCONN288_H44441004_PIP-SCONN,HA   I186 @BASEBOARD_FAB2_LIB.BASEBOARD_FAB2(SCH_1):PAGE81
  J9U2   25 DQ<20> SCONN288_H44441003_PIP-SCONN,HA   I187 @BASEBOARD_FAB2_LIB.BASEBOARD_FAB2(SCH_1):PAGE82

M_J_DQ<21> @BASEBOARD_FAB2_LIB.BASEBOARD_FAB2(SCH_1):M_J_DQ(21)
  U2D1 AB71 DDR2_DQ<21> SKX_EXT_B_BGA1-IC,TBD   I172 @BASEBOARD_FAB2_LIB.BASEBOARD_FAB2(SCH_1):PAGE59
  J1G3   25 DQ<20> SCONN288_H44441004_PIP-SCONN,HA   I186 @BASEBOARD_FAB2_LIB.BASEBOARD_FAB2(SCH_1):PAGE81
  J9U2  170 DQ<21> SCONN288_H44441003_PIP-SCONN,HA   I187 @BASEBOARD_FAB2_LIB.BASEBOARD_FAB2(SCH_1):PAGE82

M_J_DQ<22> @BASEBOARD_FAB2_LIB.BASEBOARD_FAB2(SCH_1):M_J_DQ(22)
  U2D1  T71 DDR2_DQ<22> SKX_EXT_B_BGA1-IC,TBD   I172 @BASEBOARD_FAB2_LIB.BASEBOARD_FAB2(SCH_1):PAGE59
  J1G3  177 DQ<23> SCONN288_H44441004_PIP-SCONN,HA   I186 @BASEBOARD_FAB2_LIB.BASEBOARD_FAB2(SCH_1):PAGE81
  J9U2   32 DQ<22> SCONN288_H44441003_PIP-SCONN,HA   I187 @BASEBOARD_FAB2_LIB.BASEBOARD_FAB2(SCH_1):PAGE82

M_J_DQ<23> @BASEBOARD_FAB2_LIB.BASEBOARD_FAB2(SCH_1):M_J_DQ(23)
  U2D1  V69 DDR2_DQ<23> SKX_EXT_B_BGA1-IC,TBD   I172 @BASEBOARD_FAB2_LIB.BASEBOARD_FAB2(SCH_1):PAGE59
  J1G3   32 DQ<22> SCONN288_H44441004_PIP-SCONN,HA   I186 @BASEBOARD_FAB2_LIB.BASEBOARD_FAB2(SCH_1):PAGE81
  J9U2  177 DQ<23> SCONN288_H44441003_PIP-SCONN,HA   I187 @BASEBOARD_FAB2_LIB.BASEBOARD_FAB2(SCH_1):PAGE82

M_J_DQ<24> @BASEBOARD_FAB2_LIB.BASEBOARD_FAB2(SCH_1):M_J_DQ(24)
  U2D1 AM67 DDR2_DQ<24> SKX_EXT_B_BGA1-IC,TBD   I172 @BASEBOARD_FAB2_LIB.BASEBOARD_FAB2(SCH_1):PAGE59
  J1G3  183 DQ<25> SCONN288_H44441004_PIP-SCONN,HA   I186 @BASEBOARD_FAB2_LIB.BASEBOARD_FAB2(SCH_1):PAGE81
  J9U2   38 DQ<24> SCONN288_H44441003_PIP-SCONN,HA   I187 @BASEBOARD_FAB2_LIB.BASEBOARD_FAB2(SCH_1):PAGE82

M_J_DQ<25> @BASEBOARD_FAB2_LIB.BASEBOARD_FAB2(SCH_1):M_J_DQ(25)
  U2D1 AT67 DDR2_DQ<25> SKX_EXT_B_BGA1-IC,TBD   I172 @BASEBOARD_FAB2_LIB.BASEBOARD_FAB2(SCH_1):PAGE59
  J1G3   38 DQ<24> SCONN288_H44441004_PIP-SCONN,HA   I186 @BASEBOARD_FAB2_LIB.BASEBOARD_FAB2(SCH_1):PAGE81
  J9U2  183 DQ<25> SCONN288_H44441003_PIP-SCONN,HA   I187 @BASEBOARD_FAB2_LIB.BASEBOARD_FAB2(SCH_1):PAGE82

M_J_DQ<26> @BASEBOARD_FAB2_LIB.BASEBOARD_FAB2(SCH_1):M_J_DQ(26)
  U2D1 AN64 DDR2_DQ<26> SKX_EXT_B_BGA1-IC,TBD   I172 @BASEBOARD_FAB2_LIB.BASEBOARD_FAB2(SCH_1):PAGE59
  J1G3  190 DQ<27> SCONN288_H44441004_PIP-SCONN,HA   I186 @BASEBOARD_FAB2_LIB.BASEBOARD_FAB2(SCH_1):PAGE81
  J9U2   45 DQ<26> SCONN288_H44441003_PIP-SCONN,HA   I187 @BASEBOARD_FAB2_LIB.BASEBOARD_FAB2(SCH_1):PAGE82

M_J_DQ<27> @BASEBOARD_FAB2_LIB.BASEBOARD_FAB2(SCH_1):M_J_DQ(27)
  U2D1 AR64 DDR2_DQ<27> SKX_EXT_B_BGA1-IC,TBD   I172 @BASEBOARD_FAB2_LIB.BASEBOARD_FAB2(SCH_1):PAGE59
  J1G3   45 DQ<26> SCONN288_H44441004_PIP-SCONN,HA   I186 @BASEBOARD_FAB2_LIB.BASEBOARD_FAB2(SCH_1):PAGE81
  J9U2  190 DQ<27> SCONN288_H44441003_PIP-SCONN,HA   I187 @BASEBOARD_FAB2_LIB.BASEBOARD_FAB2(SCH_1):PAGE82

M_J_DQ<28> @BASEBOARD_FAB2_LIB.BASEBOARD_FAB2(SCH_1):M_J_DQ(28)
  U2D1 AN68 DDR2_DQ<28> SKX_EXT_B_BGA1-IC,TBD   I172 @BASEBOARD_FAB2_LIB.BASEBOARD_FAB2(SCH_1):PAGE59
  J1G3  181 DQ<29> SCONN288_H44441004_PIP-SCONN,HA   I186 @BASEBOARD_FAB2_LIB.BASEBOARD_FAB2(SCH_1):PAGE81
  J9U2   36 DQ<28> SCONN288_H44441003_PIP-SCONN,HA   I187 @BASEBOARD_FAB2_LIB.BASEBOARD_FAB2(SCH_1):PAGE82

M_J_DQ<29> @BASEBOARD_FAB2_LIB.BASEBOARD_FAB2(SCH_1):M_J_DQ(29)
  U2D1 AR68 DDR2_DQ<29> SKX_EXT_B_BGA1-IC,TBD   I172 @BASEBOARD_FAB2_LIB.BASEBOARD_FAB2(SCH_1):PAGE59
  J1G3   36 DQ<28> SCONN288_H44441004_PIP-SCONN,HA   I186 @BASEBOARD_FAB2_LIB.BASEBOARD_FAB2(SCH_1):PAGE81
  J9U2  181 DQ<29> SCONN288_H44441003_PIP-SCONN,HA   I187 @BASEBOARD_FAB2_LIB.BASEBOARD_FAB2(SCH_1):PAGE82

M_J_DQ<2> @BASEBOARD_FAB2_LIB.BASEBOARD_FAB2(SCH_1):M_J_DQ(2)
  U2D1 AK77 DDR2_DQ<2> SKX_EXT_B_BGA1-IC,TBD   I172 @BASEBOARD_FAB2_LIB.BASEBOARD_FAB2(SCH_1):PAGE59
  J1G3  157  DQ<3> SCONN288_H44441004_PIP-SCONN,HA   I186 @BASEBOARD_FAB2_LIB.BASEBOARD_FAB2(SCH_1):PAGE81
  J9U2   12  DQ<2> SCONN288_H44441003_PIP-SCONN,HA   I187 @BASEBOARD_FAB2_LIB.BASEBOARD_FAB2(SCH_1):PAGE82

M_J_DQ<30> @BASEBOARD_FAB2_LIB.BASEBOARD_FAB2(SCH_1):M_J_DQ(30)
  U2D1 AM65 DDR2_DQ<30> SKX_EXT_B_BGA1-IC,TBD   I172 @BASEBOARD_FAB2_LIB.BASEBOARD_FAB2(SCH_1):PAGE59
  J1G3  188 DQ<31> SCONN288_H44441004_PIP-SCONN,HA   I186 @BASEBOARD_FAB2_LIB.BASEBOARD_FAB2(SCH_1):PAGE81
  J9U2   43 DQ<30> SCONN288_H44441003_PIP-SCONN,HA   I187 @BASEBOARD_FAB2_LIB.BASEBOARD_FAB2(SCH_1):PAGE82

M_J_DQ<31> @BASEBOARD_FAB2_LIB.BASEBOARD_FAB2(SCH_1):M_J_DQ(31)
  U2D1 AT65 DDR2_DQ<31> SKX_EXT_B_BGA1-IC,TBD   I172 @BASEBOARD_FAB2_LIB.BASEBOARD_FAB2(SCH_1):PAGE59
  J1G3   43 DQ<30> SCONN288_H44441004_PIP-SCONN,HA   I186 @BASEBOARD_FAB2_LIB.BASEBOARD_FAB2(SCH_1):PAGE81
  J9U2  188 DQ<31> SCONN288_H44441003_PIP-SCONN,HA   I187 @BASEBOARD_FAB2_LIB.BASEBOARD_FAB2(SCH_1):PAGE82

M_J_DQ<32> @BASEBOARD_FAB2_LIB.BASEBOARD_FAB2(SCH_1):M_J_DQ(32)
  U2D1  U40 DDR2_DQ<32> SKX_EXT_B_BGA1-IC,TBD   I172 @BASEBOARD_FAB2_LIB.BASEBOARD_FAB2(SCH_1):PAGE59
  J1G3  242 DQ<33> SCONN288_H44441004_PIP-SCONN,HA   I186 @BASEBOARD_FAB2_LIB.BASEBOARD_FAB2(SCH_1):PAGE81
  J9U2   97 DQ<32> SCONN288_H44441003_PIP-SCONN,HA   I187 @BASEBOARD_FAB2_LIB.BASEBOARD_FAB2(SCH_1):PAGE82

M_J_DQ<33> @BASEBOARD_FAB2_LIB.BASEBOARD_FAB2(SCH_1):M_J_DQ(33)
  U2D1 AA40 DDR2_DQ<33> SKX_EXT_B_BGA1-IC,TBD   I172 @BASEBOARD_FAB2_LIB.BASEBOARD_FAB2(SCH_1):PAGE59
  J1G3   97 DQ<32> SCONN288_H44441004_PIP-SCONN,HA   I186 @BASEBOARD_FAB2_LIB.BASEBOARD_FAB2(SCH_1):PAGE81
  J9U2  242 DQ<33> SCONN288_H44441003_PIP-SCONN,HA   I187 @BASEBOARD_FAB2_LIB.BASEBOARD_FAB2(SCH_1):PAGE82

M_J_DQ<34> @BASEBOARD_FAB2_LIB.BASEBOARD_FAB2(SCH_1):M_J_DQ(34)
  U2D1  V37 DDR2_DQ<34> SKX_EXT_B_BGA1-IC,TBD   I172 @BASEBOARD_FAB2_LIB.BASEBOARD_FAB2(SCH_1):PAGE59
  J1G3  249 DQ<35> SCONN288_H44441004_PIP-SCONN,HA   I186 @BASEBOARD_FAB2_LIB.BASEBOARD_FAB2(SCH_1):PAGE81
  J9U2  104 DQ<34> SCONN288_H44441003_PIP-SCONN,HA   I187 @BASEBOARD_FAB2_LIB.BASEBOARD_FAB2(SCH_1):PAGE82

M_J_DQ<35> @BASEBOARD_FAB2_LIB.BASEBOARD_FAB2(SCH_1):M_J_DQ(35)
  U2D1  Y37 DDR2_DQ<35> SKX_EXT_B_BGA1-IC,TBD   I172 @BASEBOARD_FAB2_LIB.BASEBOARD_FAB2(SCH_1):PAGE59
  J1G3  104 DQ<34> SCONN288_H44441004_PIP-SCONN,HA   I186 @BASEBOARD_FAB2_LIB.BASEBOARD_FAB2(SCH_1):PAGE81
  J9U2  249 DQ<35> SCONN288_H44441003_PIP-SCONN,HA   I187 @BASEBOARD_FAB2_LIB.BASEBOARD_FAB2(SCH_1):PAGE82

M_J_DQ<36> @BASEBOARD_FAB2_LIB.BASEBOARD_FAB2(SCH_1):M_J_DQ(36)
  U2D1  V41 DDR2_DQ<36> SKX_EXT_B_BGA1-IC,TBD   I172 @BASEBOARD_FAB2_LIB.BASEBOARD_FAB2(SCH_1):PAGE59
  J1G3  240 DQ<37> SCONN288_H44441004_PIP-SCONN,HA   I186 @BASEBOARD_FAB2_LIB.BASEBOARD_FAB2(SCH_1):PAGE81
  J9U2   95 DQ<36> SCONN288_H44441003_PIP-SCONN,HA   I187 @BASEBOARD_FAB2_LIB.BASEBOARD_FAB2(SCH_1):PAGE82

M_J_DQ<37> @BASEBOARD_FAB2_LIB.BASEBOARD_FAB2(SCH_1):M_J_DQ(37)
  U2D1  Y41 DDR2_DQ<37> SKX_EXT_B_BGA1-IC,TBD   I172 @BASEBOARD_FAB2_LIB.BASEBOARD_FAB2(SCH_1):PAGE59
  J1G3   95 DQ<36> SCONN288_H44441004_PIP-SCONN,HA   I186 @BASEBOARD_FAB2_LIB.BASEBOARD_FAB2(SCH_1):PAGE81
  J9U2  240 DQ<37> SCONN288_H44441003_PIP-SCONN,HA   I187 @BASEBOARD_FAB2_LIB.BASEBOARD_FAB2(SCH_1):PAGE82

M_J_DQ<38> @BASEBOARD_FAB2_LIB.BASEBOARD_FAB2(SCH_1):M_J_DQ(38)
  U2D1  U38 DDR2_DQ<38> SKX_EXT_B_BGA1-IC,TBD   I172 @BASEBOARD_FAB2_LIB.BASEBOARD_FAB2(SCH_1):PAGE59
  J1G3  247 DQ<39> SCONN288_H44441004_PIP-SCONN,HA   I186 @BASEBOARD_FAB2_LIB.BASEBOARD_FAB2(SCH_1):PAGE81
  J9U2  102 DQ<38> SCONN288_H44441003_PIP-SCONN,HA   I187 @BASEBOARD_FAB2_LIB.BASEBOARD_FAB2(SCH_1):PAGE82

M_J_DQ<39> @BASEBOARD_FAB2_LIB.BASEBOARD_FAB2(SCH_1):M_J_DQ(39)
  U2D1 AA38 DDR2_DQ<39> SKX_EXT_B_BGA1-IC,TBD   I172 @BASEBOARD_FAB2_LIB.BASEBOARD_FAB2(SCH_1):PAGE59
  J1G3  102 DQ<38> SCONN288_H44441004_PIP-SCONN,HA   I186 @BASEBOARD_FAB2_LIB.BASEBOARD_FAB2(SCH_1):PAGE81
  J9U2  247 DQ<39> SCONN288_H44441003_PIP-SCONN,HA   I187 @BASEBOARD_FAB2_LIB.BASEBOARD_FAB2(SCH_1):PAGE82

M_J_DQ<3> @BASEBOARD_FAB2_LIB.BASEBOARD_FAB2(SCH_1):M_J_DQ(3)
  U2D1 AJ76 DDR2_DQ<3> SKX_EXT_B_BGA1-IC,TBD   I172 @BASEBOARD_FAB2_LIB.BASEBOARD_FAB2(SCH_1):PAGE59
  J1G3   12  DQ<2> SCONN288_H44441004_PIP-SCONN,HA   I186 @BASEBOARD_FAB2_LIB.BASEBOARD_FAB2(SCH_1):PAGE81
  J9U2  157  DQ<3> SCONN288_H44441003_PIP-SCONN,HA   I187 @BASEBOARD_FAB2_LIB.BASEBOARD_FAB2(SCH_1):PAGE82

M_J_DQ<40> @BASEBOARD_FAB2_LIB.BASEBOARD_FAB2(SCH_1):M_J_DQ(40)
  U2D1  U34 DDR2_DQ<40> SKX_EXT_B_BGA1-IC,TBD   I172 @BASEBOARD_FAB2_LIB.BASEBOARD_FAB2(SCH_1):PAGE59
  J1G3  253 DQ<41> SCONN288_H44441004_PIP-SCONN,HA   I186 @BASEBOARD_FAB2_LIB.BASEBOARD_FAB2(SCH_1):PAGE81
  J9U2  108 DQ<40> SCONN288_H44441003_PIP-SCONN,HA   I187 @BASEBOARD_FAB2_LIB.BASEBOARD_FAB2(SCH_1):PAGE82

M_J_DQ<41> @BASEBOARD_FAB2_LIB.BASEBOARD_FAB2(SCH_1):M_J_DQ(41)
  U2D1 AA34 DDR2_DQ<41> SKX_EXT_B_BGA1-IC,TBD   I172 @BASEBOARD_FAB2_LIB.BASEBOARD_FAB2(SCH_1):PAGE59
  J1G3  108 DQ<40> SCONN288_H44441004_PIP-SCONN,HA   I186 @BASEBOARD_FAB2_LIB.BASEBOARD_FAB2(SCH_1):PAGE81
  J9U2  253 DQ<41> SCONN288_H44441003_PIP-SCONN,HA   I187 @BASEBOARD_FAB2_LIB.BASEBOARD_FAB2(SCH_1):PAGE82

M_J_DQ<42> @BASEBOARD_FAB2_LIB.BASEBOARD_FAB2(SCH_1):M_J_DQ(42)
  U2D1  V31 DDR2_DQ<42> SKX_EXT_B_BGA1-IC,TBD   I172 @BASEBOARD_FAB2_LIB.BASEBOARD_FAB2(SCH_1):PAGE59
  J1G3  260 DQ<43> SCONN288_H44441004_PIP-SCONN,HA   I186 @BASEBOARD_FAB2_LIB.BASEBOARD_FAB2(SCH_1):PAGE81
  J9U2  115 DQ<42> SCONN288_H44441003_PIP-SCONN,HA   I187 @BASEBOARD_FAB2_LIB.BASEBOARD_FAB2(SCH_1):PAGE82

M_J_DQ<43> @BASEBOARD_FAB2_LIB.BASEBOARD_FAB2(SCH_1):M_J_DQ(43)
  U2D1  Y31 DDR2_DQ<43> SKX_EXT_B_BGA1-IC,TBD   I172 @BASEBOARD_FAB2_LIB.BASEBOARD_FAB2(SCH_1):PAGE59
  J1G3  115 DQ<42> SCONN288_H44441004_PIP-SCONN,HA   I186 @BASEBOARD_FAB2_LIB.BASEBOARD_FAB2(SCH_1):PAGE81
  J9U2  260 DQ<43> SCONN288_H44441003_PIP-SCONN,HA   I187 @BASEBOARD_FAB2_LIB.BASEBOARD_FAB2(SCH_1):PAGE82

M_J_DQ<44> @BASEBOARD_FAB2_LIB.BASEBOARD_FAB2(SCH_1):M_J_DQ(44)
  U2D1  V35 DDR2_DQ<44> SKX_EXT_B_BGA1-IC,TBD   I172 @BASEBOARD_FAB2_LIB.BASEBOARD_FAB2(SCH_1):PAGE59
  J1G3  251 DQ<45> SCONN288_H44441004_PIP-SCONN,HA   I186 @BASEBOARD_FAB2_LIB.BASEBOARD_FAB2(SCH_1):PAGE81
  J9U2  106 DQ<44> SCONN288_H44441003_PIP-SCONN,HA   I187 @BASEBOARD_FAB2_LIB.BASEBOARD_FAB2(SCH_1):PAGE82

M_J_DQ<45> @BASEBOARD_FAB2_LIB.BASEBOARD_FAB2(SCH_1):M_J_DQ(45)
  U2D1  Y35 DDR2_DQ<45> SKX_EXT_B_BGA1-IC,TBD   I172 @BASEBOARD_FAB2_LIB.BASEBOARD_FAB2(SCH_1):PAGE59
  J1G3  106 DQ<44> SCONN288_H44441004_PIP-SCONN,HA   I186 @BASEBOARD_FAB2_LIB.BASEBOARD_FAB2(SCH_1):PAGE81
  J9U2  251 DQ<45> SCONN288_H44441003_PIP-SCONN,HA   I187 @BASEBOARD_FAB2_LIB.BASEBOARD_FAB2(SCH_1):PAGE82

M_J_DQ<46> @BASEBOARD_FAB2_LIB.BASEBOARD_FAB2(SCH_1):M_J_DQ(46)
  U2D1  U32 DDR2_DQ<46> SKX_EXT_B_BGA1-IC,TBD   I172 @BASEBOARD_FAB2_LIB.BASEBOARD_FAB2(SCH_1):PAGE59
  J1G3  258 DQ<47> SCONN288_H44441004_PIP-SCONN,HA   I186 @BASEBOARD_FAB2_LIB.BASEBOARD_FAB2(SCH_1):PAGE81
  J9U2  113 DQ<46> SCONN288_H44441003_PIP-SCONN,HA   I187 @BASEBOARD_FAB2_LIB.BASEBOARD_FAB2(SCH_1):PAGE82

M_J_DQ<47> @BASEBOARD_FAB2_LIB.BASEBOARD_FAB2(SCH_1):M_J_DQ(47)
  U2D1 AA32 DDR2_DQ<47> SKX_EXT_B_BGA1-IC,TBD   I172 @BASEBOARD_FAB2_LIB.BASEBOARD_FAB2(SCH_1):PAGE59
  J1G3  113 DQ<46> SCONN288_H44441004_PIP-SCONN,HA   I186 @BASEBOARD_FAB2_LIB.BASEBOARD_FAB2(SCH_1):PAGE81
  J9U2  258 DQ<47> SCONN288_H44441003_PIP-SCONN,HA   I187 @BASEBOARD_FAB2_LIB.BASEBOARD_FAB2(SCH_1):PAGE82

M_J_DQ<48> @BASEBOARD_FAB2_LIB.BASEBOARD_FAB2(SCH_1):M_J_DQ(48)
  U2D1 AD31 DDR2_DQ<48> SKX_EXT_B_BGA1-IC,TBD   I172 @BASEBOARD_FAB2_LIB.BASEBOARD_FAB2(SCH_1):PAGE59
  J1G3  264 DQ<49> SCONN288_H44441004_PIP-SCONN,HA   I186 @BASEBOARD_FAB2_LIB.BASEBOARD_FAB2(SCH_1):PAGE81
  J9U2  119 DQ<48> SCONN288_H44441003_PIP-SCONN,HA   I187 @BASEBOARD_FAB2_LIB.BASEBOARD_FAB2(SCH_1):PAGE82

M_J_DQ<49> @BASEBOARD_FAB2_LIB.BASEBOARD_FAB2(SCH_1):M_J_DQ(49)
  U2D1 AH31 DDR2_DQ<49> SKX_EXT_B_BGA1-IC,TBD   I172 @BASEBOARD_FAB2_LIB.BASEBOARD_FAB2(SCH_1):PAGE59
  J1G3  119 DQ<48> SCONN288_H44441004_PIP-SCONN,HA   I186 @BASEBOARD_FAB2_LIB.BASEBOARD_FAB2(SCH_1):PAGE81
  J9U2  264 DQ<49> SCONN288_H44441003_PIP-SCONN,HA   I187 @BASEBOARD_FAB2_LIB.BASEBOARD_FAB2(SCH_1):PAGE82

M_J_DQ<4> @BASEBOARD_FAB2_LIB.BASEBOARD_FAB2(SCH_1):M_J_DQ(4)
  U2D1 AT75 DDR2_DQ<4> SKX_EXT_B_BGA1-IC,TBD   I172 @BASEBOARD_FAB2_LIB.BASEBOARD_FAB2(SCH_1):PAGE59
  J1G3  148  DQ<5> SCONN288_H44441004_PIP-SCONN,HA   I186 @BASEBOARD_FAB2_LIB.BASEBOARD_FAB2(SCH_1):PAGE81
  J9U2    3  DQ<4> SCONN288_H44441003_PIP-SCONN,HA   I187 @BASEBOARD_FAB2_LIB.BASEBOARD_FAB2(SCH_1):PAGE82

M_J_DQ<50> @BASEBOARD_FAB2_LIB.BASEBOARD_FAB2(SCH_1):M_J_DQ(50)
  U2D1 AE28 DDR2_DQ<50> SKX_EXT_B_BGA1-IC,TBD   I172 @BASEBOARD_FAB2_LIB.BASEBOARD_FAB2(SCH_1):PAGE59
  J1G3  271 DQ<51> SCONN288_H44441004_PIP-SCONN,HA   I186 @BASEBOARD_FAB2_LIB.BASEBOARD_FAB2(SCH_1):PAGE81
  J9U2  126 DQ<50> SCONN288_H44441003_PIP-SCONN,HA   I187 @BASEBOARD_FAB2_LIB.BASEBOARD_FAB2(SCH_1):PAGE82

M_J_DQ<51> @BASEBOARD_FAB2_LIB.BASEBOARD_FAB2(SCH_1):M_J_DQ(51)
  U2D1 AG28 DDR2_DQ<51> SKX_EXT_B_BGA1-IC,TBD   I172 @BASEBOARD_FAB2_LIB.BASEBOARD_FAB2(SCH_1):PAGE59
  J1G3  126 DQ<50> SCONN288_H44441004_PIP-SCONN,HA   I186 @BASEBOARD_FAB2_LIB.BASEBOARD_FAB2(SCH_1):PAGE81
  J9U2  271 DQ<51> SCONN288_H44441003_PIP-SCONN,HA   I187 @BASEBOARD_FAB2_LIB.BASEBOARD_FAB2(SCH_1):PAGE82

M_J_DQ<52> @BASEBOARD_FAB2_LIB.BASEBOARD_FAB2(SCH_1):M_J_DQ(52)
  U2D1 AE32 DDR2_DQ<52> SKX_EXT_B_BGA1-IC,TBD   I172 @BASEBOARD_FAB2_LIB.BASEBOARD_FAB2(SCH_1):PAGE59
  J1G3  262 DQ<53> SCONN288_H44441004_PIP-SCONN,HA   I186 @BASEBOARD_FAB2_LIB.BASEBOARD_FAB2(SCH_1):PAGE81
  J9U2  117 DQ<52> SCONN288_H44441003_PIP-SCONN,HA   I187 @BASEBOARD_FAB2_LIB.BASEBOARD_FAB2(SCH_1):PAGE82

M_J_DQ<53> @BASEBOARD_FAB2_LIB.BASEBOARD_FAB2(SCH_1):M_J_DQ(53)
  U2D1 AG32 DDR2_DQ<53> SKX_EXT_B_BGA1-IC,TBD   I172 @BASEBOARD_FAB2_LIB.BASEBOARD_FAB2(SCH_1):PAGE59
  J1G3  117 DQ<52> SCONN288_H44441004_PIP-SCONN,HA   I186 @BASEBOARD_FAB2_LIB.BASEBOARD_FAB2(SCH_1):PAGE81
  J9U2  262 DQ<53> SCONN288_H44441003_PIP-SCONN,HA   I187 @BASEBOARD_FAB2_LIB.BASEBOARD_FAB2(SCH_1):PAGE82

M_J_DQ<54> @BASEBOARD_FAB2_LIB.BASEBOARD_FAB2(SCH_1):M_J_DQ(54)
  U2D1 AD29 DDR2_DQ<54> SKX_EXT_B_BGA1-IC,TBD   I172 @BASEBOARD_FAB2_LIB.BASEBOARD_FAB2(SCH_1):PAGE59
  J1G3  269 DQ<55> SCONN288_H44441004_PIP-SCONN,HA   I186 @BASEBOARD_FAB2_LIB.BASEBOARD_FAB2(SCH_1):PAGE81
  J9U2  124 DQ<54> SCONN288_H44441003_PIP-SCONN,HA   I187 @BASEBOARD_FAB2_LIB.BASEBOARD_FAB2(SCH_1):PAGE82

M_J_DQ<55> @BASEBOARD_FAB2_LIB.BASEBOARD_FAB2(SCH_1):M_J_DQ(55)
  U2D1 AH29 DDR2_DQ<55> SKX_EXT_B_BGA1-IC,TBD   I172 @BASEBOARD_FAB2_LIB.BASEBOARD_FAB2(SCH_1):PAGE59
  J1G3  124 DQ<54> SCONN288_H44441004_PIP-SCONN,HA   I186 @BASEBOARD_FAB2_LIB.BASEBOARD_FAB2(SCH_1):PAGE81
  J9U2  269 DQ<55> SCONN288_H44441003_PIP-SCONN,HA   I187 @BASEBOARD_FAB2_LIB.BASEBOARD_FAB2(SCH_1):PAGE82

M_J_DQ<56> @BASEBOARD_FAB2_LIB.BASEBOARD_FAB2(SCH_1):M_J_DQ(56)
  U2D1 AD25 DDR2_DQ<56> SKX_EXT_B_BGA1-IC,TBD   I172 @BASEBOARD_FAB2_LIB.BASEBOARD_FAB2(SCH_1):PAGE59
  J1G3  275 DQ<57> SCONN288_H44441004_PIP-SCONN,HA   I186 @BASEBOARD_FAB2_LIB.BASEBOARD_FAB2(SCH_1):PAGE81
  J9U2  130 DQ<56> SCONN288_H44441003_PIP-SCONN,HA   I187 @BASEBOARD_FAB2_LIB.BASEBOARD_FAB2(SCH_1):PAGE82

M_J_DQ<57> @BASEBOARD_FAB2_LIB.BASEBOARD_FAB2(SCH_1):M_J_DQ(57)
  U2D1 AH25 DDR2_DQ<57> SKX_EXT_B_BGA1-IC,TBD   I172 @BASEBOARD_FAB2_LIB.BASEBOARD_FAB2(SCH_1):PAGE59
  J1G3  130 DQ<56> SCONN288_H44441004_PIP-SCONN,HA   I186 @BASEBOARD_FAB2_LIB.BASEBOARD_FAB2(SCH_1):PAGE81
  J9U2  275 DQ<57> SCONN288_H44441003_PIP-SCONN,HA   I187 @BASEBOARD_FAB2_LIB.BASEBOARD_FAB2(SCH_1):PAGE82

M_J_DQ<58> @BASEBOARD_FAB2_LIB.BASEBOARD_FAB2(SCH_1):M_J_DQ(58)
  U2D1 AE22 DDR2_DQ<58> SKX_EXT_B_BGA1-IC,TBD   I172 @BASEBOARD_FAB2_LIB.BASEBOARD_FAB2(SCH_1):PAGE59
  J1G3  282 DQ<59> SCONN288_H44441004_PIP-SCONN,HA   I186 @BASEBOARD_FAB2_LIB.BASEBOARD_FAB2(SCH_1):PAGE81
  J9U2  137 DQ<58> SCONN288_H44441003_PIP-SCONN,HA   I187 @BASEBOARD_FAB2_LIB.BASEBOARD_FAB2(SCH_1):PAGE82

M_J_DQ<59> @BASEBOARD_FAB2_LIB.BASEBOARD_FAB2(SCH_1):M_J_DQ(59)
  U2D1 AG22 DDR2_DQ<59> SKX_EXT_B_BGA1-IC,TBD   I172 @BASEBOARD_FAB2_LIB.BASEBOARD_FAB2(SCH_1):PAGE59
  J1G3  137 DQ<58> SCONN288_H44441004_PIP-SCONN,HA   I186 @BASEBOARD_FAB2_LIB.BASEBOARD_FAB2(SCH_1):PAGE81
  J9U2  282 DQ<59> SCONN288_H44441003_PIP-SCONN,HA   I187 @BASEBOARD_FAB2_LIB.BASEBOARD_FAB2(SCH_1):PAGE82

M_J_DQ<5> @BASEBOARD_FAB2_LIB.BASEBOARD_FAB2(SCH_1):M_J_DQ(5)
  U2D1 AR74 DDR2_DQ<5> SKX_EXT_B_BGA1-IC,TBD   I172 @BASEBOARD_FAB2_LIB.BASEBOARD_FAB2(SCH_1):PAGE59
  J1G3    3  DQ<4> SCONN288_H44441004_PIP-SCONN,HA   I186 @BASEBOARD_FAB2_LIB.BASEBOARD_FAB2(SCH_1):PAGE81
  J9U2  148  DQ<5> SCONN288_H44441003_PIP-SCONN,HA   I187 @BASEBOARD_FAB2_LIB.BASEBOARD_FAB2(SCH_1):PAGE82

M_J_DQ<60> @BASEBOARD_FAB2_LIB.BASEBOARD_FAB2(SCH_1):M_J_DQ(60)
  U2D1 AE26 DDR2_DQ<60> SKX_EXT_B_BGA1-IC,TBD   I172 @BASEBOARD_FAB2_LIB.BASEBOARD_FAB2(SCH_1):PAGE59
  J1G3  273 DQ<61> SCONN288_H44441004_PIP-SCONN,HA   I186 @BASEBOARD_FAB2_LIB.BASEBOARD_FAB2(SCH_1):PAGE81
  J9U2  128 DQ<60> SCONN288_H44441003_PIP-SCONN,HA   I187 @BASEBOARD_FAB2_LIB.BASEBOARD_FAB2(SCH_1):PAGE82

M_J_DQ<61> @BASEBOARD_FAB2_LIB.BASEBOARD_FAB2(SCH_1):M_J_DQ(61)
  U2D1 AG26 DDR2_DQ<61> SKX_EXT_B_BGA1-IC,TBD   I172 @BASEBOARD_FAB2_LIB.BASEBOARD_FAB2(SCH_1):PAGE59
  J1G3  128 DQ<60> SCONN288_H44441004_PIP-SCONN,HA   I186 @BASEBOARD_FAB2_LIB.BASEBOARD_FAB2(SCH_1):PAGE81
  J9U2  273 DQ<61> SCONN288_H44441003_PIP-SCONN,HA   I187 @BASEBOARD_FAB2_LIB.BASEBOARD_FAB2(SCH_1):PAGE82

M_J_DQ<62> @BASEBOARD_FAB2_LIB.BASEBOARD_FAB2(SCH_1):M_J_DQ(62)
  U2D1 AD23 DDR2_DQ<62> SKX_EXT_B_BGA1-IC,TBD   I172 @BASEBOARD_FAB2_LIB.BASEBOARD_FAB2(SCH_1):PAGE59
  J1G3  280 DQ<63> SCONN288_H44441004_PIP-SCONN,HA   I186 @BASEBOARD_FAB2_LIB.BASEBOARD_FAB2(SCH_1):PAGE81
  J9U2  135 DQ<62> SCONN288_H44441003_PIP-SCONN,HA   I187 @BASEBOARD_FAB2_LIB.BASEBOARD_FAB2(SCH_1):PAGE82

M_J_DQ<63> @BASEBOARD_FAB2_LIB.BASEBOARD_FAB2(SCH_1):M_J_DQ(63)
  U2D1 AH23 DDR2_DQ<63> SKX_EXT_B_BGA1-IC,TBD   I172 @BASEBOARD_FAB2_LIB.BASEBOARD_FAB2(SCH_1):PAGE59
  J1G3  135 DQ<62> SCONN288_H44441004_PIP-SCONN,HA   I186 @BASEBOARD_FAB2_LIB.BASEBOARD_FAB2(SCH_1):PAGE81
  J9U2  280 DQ<63> SCONN288_H44441003_PIP-SCONN,HA   I187 @BASEBOARD_FAB2_LIB.BASEBOARD_FAB2(SCH_1):PAGE82

M_J_DQ<6> @BASEBOARD_FAB2_LIB.BASEBOARD_FAB2(SCH_1):M_J_DQ(6)
  U2D1 AM77 DDR2_DQ<6> SKX_EXT_B_BGA1-IC,TBD   I172 @BASEBOARD_FAB2_LIB.BASEBOARD_FAB2(SCH_1):PAGE59
  J1G3  155  DQ<7> SCONN288_H44441004_PIP-SCONN,HA   I186 @BASEBOARD_FAB2_LIB.BASEBOARD_FAB2(SCH_1):PAGE81
  J9U2   10  DQ<6> SCONN288_H44441003_PIP-SCONN,HA   I187 @BASEBOARD_FAB2_LIB.BASEBOARD_FAB2(SCH_1):PAGE82

M_J_DQ<7> @BASEBOARD_FAB2_LIB.BASEBOARD_FAB2(SCH_1):M_J_DQ(7)
  U2D1 AK75 DDR2_DQ<7> SKX_EXT_B_BGA1-IC,TBD   I172 @BASEBOARD_FAB2_LIB.BASEBOARD_FAB2(SCH_1):PAGE59
  J1G3   10  DQ<6> SCONN288_H44441004_PIP-SCONN,HA   I186 @BASEBOARD_FAB2_LIB.BASEBOARD_FAB2(SCH_1):PAGE81
  J9U2  155  DQ<7> SCONN288_H44441003_PIP-SCONN,HA   I187 @BASEBOARD_FAB2_LIB.BASEBOARD_FAB2(SCH_1):PAGE82

M_J_DQ<8> @BASEBOARD_FAB2_LIB.BASEBOARD_FAB2(SCH_1):M_J_DQ(8)
  U2D1 AE76 DDR2_DQ<8> SKX_EXT_B_BGA1-IC,TBD   I172 @BASEBOARD_FAB2_LIB.BASEBOARD_FAB2(SCH_1):PAGE59
  J1G3  161  DQ<9> SCONN288_H44441004_PIP-SCONN,HA   I186 @BASEBOARD_FAB2_LIB.BASEBOARD_FAB2(SCH_1):PAGE81
  J9U2   16  DQ<8> SCONN288_H44441003_PIP-SCONN,HA   I187 @BASEBOARD_FAB2_LIB.BASEBOARD_FAB2(SCH_1):PAGE82

M_J_DQ<9> @BASEBOARD_FAB2_LIB.BASEBOARD_FAB2(SCH_1):M_J_DQ(9)
  U2D1 AC74 DDR2_DQ<9> SKX_EXT_B_BGA1-IC,TBD   I172 @BASEBOARD_FAB2_LIB.BASEBOARD_FAB2(SCH_1):PAGE59
  J1G3   16  DQ<8> SCONN288_H44441004_PIP-SCONN,HA   I186 @BASEBOARD_FAB2_LIB.BASEBOARD_FAB2(SCH_1):PAGE81
  J9U2  161  DQ<9> SCONN288_H44441003_PIP-SCONN,HA   I187 @BASEBOARD_FAB2_LIB.BASEBOARD_FAB2(SCH_1):PAGE82

M_J_DQS_DN<0> @BASEBOARD_FAB2_LIB.BASEBOARD_FAB2(SCH_1):M_J_DQS_DN(0)
  U2D1 AL74 DDR2_DQS_DN<0> SKX_EXT_B_BGA1-IC,TBD   I172 @BASEBOARD_FAB2_LIB.BASEBOARD_FAB2(SCH_1):PAGE59
  J1G3  152  DQS0N SCONN288_H44441004_PIP-SCONN,HA    I67 @BASEBOARD_FAB2_LIB.BASEBOARD_FAB2(SCH_1):PAGE81
  J9U2  152  DQS0N SCONN288_H44441003_PIP-SCONN,HA    I64 @BASEBOARD_FAB2_LIB.BASEBOARD_FAB2(SCH_1):PAGE82

M_J_DQS_DN<10> @BASEBOARD_FAB2_LIB.BASEBOARD_FAB2(SCH_1):M_J_DQS_DN(10)
  U2D1 AD77 DDR2_DQS_DN<10> SKX_EXT_B_BGA1-IC,TBD   I172 @BASEBOARD_FAB2_LIB.BASEBOARD_FAB2(SCH_1):PAGE59
  J1G3   19 DQS10N SCONN288_H44441004_PIP-SCONN,HA    I67 @BASEBOARD_FAB2_LIB.BASEBOARD_FAB2(SCH_1):PAGE81
  J9U2   19 DQS10N SCONN288_H44441003_PIP-SCONN,HA    I64 @BASEBOARD_FAB2_LIB.BASEBOARD_FAB2(SCH_1):PAGE82

M_J_DQS_DN<11> @BASEBOARD_FAB2_LIB.BASEBOARD_FAB2(SCH_1):M_J_DQS_DN(11)
  U2D1  U72 DDR2_DQS_DN<11> SKX_EXT_B_BGA1-IC,TBD   I172 @BASEBOARD_FAB2_LIB.BASEBOARD_FAB2(SCH_1):PAGE59
  J1G3   30 DQS11N SCONN288_H44441004_PIP-SCONN,HA    I67 @BASEBOARD_FAB2_LIB.BASEBOARD_FAB2(SCH_1):PAGE81
  J9U2   30 DQS11N SCONN288_H44441003_PIP-SCONN,HA    I64 @BASEBOARD_FAB2_LIB.BASEBOARD_FAB2(SCH_1):PAGE82

M_J_DQS_DN<12> @BASEBOARD_FAB2_LIB.BASEBOARD_FAB2(SCH_1):M_J_DQS_DN(12)
  U2D1 AL66 DDR2_DQS_DN<12> SKX_EXT_B_BGA1-IC,TBD   I172 @BASEBOARD_FAB2_LIB.BASEBOARD_FAB2(SCH_1):PAGE59
  J1G3   41 DQS12N SCONN288_H44441004_PIP-SCONN,HA    I67 @BASEBOARD_FAB2_LIB.BASEBOARD_FAB2(SCH_1):PAGE81
  J9U2   41 DQS12N SCONN288_H44441003_PIP-SCONN,HA    I64 @BASEBOARD_FAB2_LIB.BASEBOARD_FAB2(SCH_1):PAGE82

M_J_DQS_DN<13> @BASEBOARD_FAB2_LIB.BASEBOARD_FAB2(SCH_1):M_J_DQS_DN(13)
  U2D1  T39 DDR2_DQS_DN<13> SKX_EXT_B_BGA1-IC,TBD   I172 @BASEBOARD_FAB2_LIB.BASEBOARD_FAB2(SCH_1):PAGE59
  J1G3  100 DQS13N SCONN288_H44441004_PIP-SCONN,HA    I67 @BASEBOARD_FAB2_LIB.BASEBOARD_FAB2(SCH_1):PAGE81
  J9U2  100 DQS13N SCONN288_H44441003_PIP-SCONN,HA    I64 @BASEBOARD_FAB2_LIB.BASEBOARD_FAB2(SCH_1):PAGE82

M_J_DQS_DN<14> @BASEBOARD_FAB2_LIB.BASEBOARD_FAB2(SCH_1):M_J_DQS_DN(14)
  U2D1  T33 DDR2_DQS_DN<14> SKX_EXT_B_BGA1-IC,TBD   I172 @BASEBOARD_FAB2_LIB.BASEBOARD_FAB2(SCH_1):PAGE59
  J1G3  111 DQS14N SCONN288_H44441004_PIP-SCONN,HA    I67 @BASEBOARD_FAB2_LIB.BASEBOARD_FAB2(SCH_1):PAGE81
  J9U2  111 DQS14N SCONN288_H44441003_PIP-SCONN,HA    I64 @BASEBOARD_FAB2_LIB.BASEBOARD_FAB2(SCH_1):PAGE82

M_J_DQS_DN<15> @BASEBOARD_FAB2_LIB.BASEBOARD_FAB2(SCH_1):M_J_DQS_DN(15)
  U2D1 AC30 DDR2_DQS_DN<15> SKX_EXT_B_BGA1-IC,TBD   I172 @BASEBOARD_FAB2_LIB.BASEBOARD_FAB2(SCH_1):PAGE59
  J1G3  122 DQS15N SCONN288_H44441004_PIP-SCONN,HA    I67 @BASEBOARD_FAB2_LIB.BASEBOARD_FAB2(SCH_1):PAGE81
  J9U2  122 DQS15N SCONN288_H44441003_PIP-SCONN,HA    I64 @BASEBOARD_FAB2_LIB.BASEBOARD_FAB2(SCH_1):PAGE82

M_J_DQS_DN<16> @BASEBOARD_FAB2_LIB.BASEBOARD_FAB2(SCH_1):M_J_DQS_DN(16)
  U2D1 AC24 DDR2_DQS_DN<16> SKX_EXT_B_BGA1-IC,TBD   I172 @BASEBOARD_FAB2_LIB.BASEBOARD_FAB2(SCH_1):PAGE59
  J1G3  133 DQS16N SCONN288_H44441004_PIP-SCONN,HA    I67 @BASEBOARD_FAB2_LIB.BASEBOARD_FAB2(SCH_1):PAGE81
  J9U2  133 DQS16N SCONN288_H44441003_PIP-SCONN,HA    I64 @BASEBOARD_FAB2_LIB.BASEBOARD_FAB2(SCH_1):PAGE82

M_J_DQS_DN<17> @BASEBOARD_FAB2_LIB.BASEBOARD_FAB2(SCH_1):M_J_DQS_DN(17)
  U2D1 AT71 DDR2_DQS_DN<17> SKX_EXT_B_BGA1-IC,TBD   I172 @BASEBOARD_FAB2_LIB.BASEBOARD_FAB2(SCH_1):PAGE59
  J1G3   52 DQS17N SCONN288_H44441004_PIP-SCONN,HA    I67 @BASEBOARD_FAB2_LIB.BASEBOARD_FAB2(SCH_1):PAGE81
  J9U2   52 DQS17N SCONN288_H44441003_PIP-SCONN,HA    I64 @BASEBOARD_FAB2_LIB.BASEBOARD_FAB2(SCH_1):PAGE82

M_J_DQS_DN<1> @BASEBOARD_FAB2_LIB.BASEBOARD_FAB2(SCH_1):M_J_DQS_DN(1)
  U2D1 AA74 DDR2_DQS_DN<1> SKX_EXT_B_BGA1-IC,TBD   I172 @BASEBOARD_FAB2_LIB.BASEBOARD_FAB2(SCH_1):PAGE59
  J1G3  163  DQS1N SCONN288_H44441004_PIP-SCONN,HA    I67 @BASEBOARD_FAB2_LIB.BASEBOARD_FAB2(SCH_1):PAGE81
  J9U2  163  DQS1N SCONN288_H44441003_PIP-SCONN,HA    I64 @BASEBOARD_FAB2_LIB.BASEBOARD_FAB2(SCH_1):PAGE82

M_J_DQS_DN<2> @BASEBOARD_FAB2_LIB.BASEBOARD_FAB2(SCH_1):M_J_DQS_DN(2)
  U2D1  Y69 DDR2_DQS_DN<2> SKX_EXT_B_BGA1-IC,TBD   I172 @BASEBOARD_FAB2_LIB.BASEBOARD_FAB2(SCH_1):PAGE59
  J1G3  174  DQS2N SCONN288_H44441004_PIP-SCONN,HA    I67 @BASEBOARD_FAB2_LIB.BASEBOARD_FAB2(SCH_1):PAGE81
  J9U2  174  DQS2N SCONN288_H44441003_PIP-SCONN,HA    I64 @BASEBOARD_FAB2_LIB.BASEBOARD_FAB2(SCH_1):PAGE82

M_J_DQS_DN<3> @BASEBOARD_FAB2_LIB.BASEBOARD_FAB2(SCH_1):M_J_DQS_DN(3)
  U2D1 AU66 DDR2_DQS_DN<3> SKX_EXT_B_BGA1-IC,TBD   I172 @BASEBOARD_FAB2_LIB.BASEBOARD_FAB2(SCH_1):PAGE59
  J1G3  185  DQS3N SCONN288_H44441004_PIP-SCONN,HA    I67 @BASEBOARD_FAB2_LIB.BASEBOARD_FAB2(SCH_1):PAGE81
  J9U2  185  DQS3N SCONN288_H44441003_PIP-SCONN,HA    I64 @BASEBOARD_FAB2_LIB.BASEBOARD_FAB2(SCH_1):PAGE82

M_J_DQS_DN<4> @BASEBOARD_FAB2_LIB.BASEBOARD_FAB2(SCH_1):M_J_DQS_DN(4)
  U2D1 AB39 DDR2_DQS_DN<4> SKX_EXT_B_BGA1-IC,TBD   I172 @BASEBOARD_FAB2_LIB.BASEBOARD_FAB2(SCH_1):PAGE59
  J1G3  244  DQS4N SCONN288_H44441004_PIP-SCONN,HA    I67 @BASEBOARD_FAB2_LIB.BASEBOARD_FAB2(SCH_1):PAGE81
  J9U2  244  DQS4N SCONN288_H44441003_PIP-SCONN,HA    I64 @BASEBOARD_FAB2_LIB.BASEBOARD_FAB2(SCH_1):PAGE82

M_J_DQS_DN<5> @BASEBOARD_FAB2_LIB.BASEBOARD_FAB2(SCH_1):M_J_DQS_DN(5)
  U2D1 AB33 DDR2_DQS_DN<5> SKX_EXT_B_BGA1-IC,TBD   I172 @BASEBOARD_FAB2_LIB.BASEBOARD_FAB2(SCH_1):PAGE59
  J1G3  255  DQS5N SCONN288_H44441004_PIP-SCONN,HA    I67 @BASEBOARD_FAB2_LIB.BASEBOARD_FAB2(SCH_1):PAGE81
  J9U2  255  DQS5N SCONN288_H44441003_PIP-SCONN,HA    I64 @BASEBOARD_FAB2_LIB.BASEBOARD_FAB2(SCH_1):PAGE82

M_J_DQS_DN<6> @BASEBOARD_FAB2_LIB.BASEBOARD_FAB2(SCH_1):M_J_DQS_DN(6)
  U2D1 AJ30 DDR2_DQS_DN<6> SKX_EXT_B_BGA1-IC,TBD   I172 @BASEBOARD_FAB2_LIB.BASEBOARD_FAB2(SCH_1):PAGE59
  J1G3  266  DQS6N SCONN288_H44441004_PIP-SCONN,HA    I67 @BASEBOARD_FAB2_LIB.BASEBOARD_FAB2(SCH_1):PAGE81
  J9U2  266  DQS6N SCONN288_H44441003_PIP-SCONN,HA    I64 @BASEBOARD_FAB2_LIB.BASEBOARD_FAB2(SCH_1):PAGE82

M_J_DQS_DN<7> @BASEBOARD_FAB2_LIB.BASEBOARD_FAB2(SCH_1):M_J_DQS_DN(7)
  U2D1 AJ24 DDR2_DQS_DN<7> SKX_EXT_B_BGA1-IC,TBD   I172 @BASEBOARD_FAB2_LIB.BASEBOARD_FAB2(SCH_1):PAGE59
  J1G3  277  DQS7N SCONN288_H44441004_PIP-SCONN,HA    I67 @BASEBOARD_FAB2_LIB.BASEBOARD_FAB2(SCH_1):PAGE81
  J9U2  277  DQS7N SCONN288_H44441003_PIP-SCONN,HA    I64 @BASEBOARD_FAB2_LIB.BASEBOARD_FAB2(SCH_1):PAGE82

M_J_DQS_DN<8> @BASEBOARD_FAB2_LIB.BASEBOARD_FAB2(SCH_1):M_J_DQS_DN(8)
  U2D1 BB71 DDR2_DQS_DN<8> SKX_EXT_B_BGA1-IC,TBD   I172 @BASEBOARD_FAB2_LIB.BASEBOARD_FAB2(SCH_1):PAGE59
  J1G3  196  DQS8N SCONN288_H44441004_PIP-SCONN,HA    I67 @BASEBOARD_FAB2_LIB.BASEBOARD_FAB2(SCH_1):PAGE81
  J9U2  196  DQS8N SCONN288_H44441003_PIP-SCONN,HA    I64 @BASEBOARD_FAB2_LIB.BASEBOARD_FAB2(SCH_1):PAGE82

M_J_DQS_DN<9> @BASEBOARD_FAB2_LIB.BASEBOARD_FAB2(SCH_1):M_J_DQS_DN(9)
  U2D1 AP77 DDR2_DQS_DN<9> SKX_EXT_B_BGA1-IC,TBD   I172 @BASEBOARD_FAB2_LIB.BASEBOARD_FAB2(SCH_1):PAGE59
  J1G3    8  DQS9N SCONN288_H44441004_PIP-SCONN,HA    I67 @BASEBOARD_FAB2_LIB.BASEBOARD_FAB2(SCH_1):PAGE81
  J9U2    8  DQS9N SCONN288_H44441003_PIP-SCONN,HA    I64 @BASEBOARD_FAB2_LIB.BASEBOARD_FAB2(SCH_1):PAGE82

M_J_DQS_DP<0> @BASEBOARD_FAB2_LIB.BASEBOARD_FAB2(SCH_1):M_J_DQS_DP(0)
  U2D1 AM75 DDR2_DQS_DP<0> SKX_EXT_B_BGA1-IC,TBD   I172 @BASEBOARD_FAB2_LIB.BASEBOARD_FAB2(SCH_1):PAGE59
  J1G3  153  DQS0P SCONN288_H44441004_PIP-SCONN,HA    I67 @BASEBOARD_FAB2_LIB.BASEBOARD_FAB2(SCH_1):PAGE81
  J9U2  153  DQS0P SCONN288_H44441003_PIP-SCONN,HA    I64 @BASEBOARD_FAB2_LIB.BASEBOARD_FAB2(SCH_1):PAGE82

M_J_DQS_DP<10> @BASEBOARD_FAB2_LIB.BASEBOARD_FAB2(SCH_1):M_J_DQS_DP(10)
  U2D1 AC76 DDR2_DQS_DP<10> SKX_EXT_B_BGA1-IC,TBD   I172 @BASEBOARD_FAB2_LIB.BASEBOARD_FAB2(SCH_1):PAGE59
  J1G3   18 DQS10P SCONN288_H44441004_PIP-SCONN,HA    I67 @BASEBOARD_FAB2_LIB.BASEBOARD_FAB2(SCH_1):PAGE81
  J9U2   18 DQS10P SCONN288_H44441003_PIP-SCONN,HA    I64 @BASEBOARD_FAB2_LIB.BASEBOARD_FAB2(SCH_1):PAGE82

M_J_DQS_DP<11> @BASEBOARD_FAB2_LIB.BASEBOARD_FAB2(SCH_1):M_J_DQS_DP(11)
  U2D1  V71 DDR2_DQS_DP<11> SKX_EXT_B_BGA1-IC,TBD   I172 @BASEBOARD_FAB2_LIB.BASEBOARD_FAB2(SCH_1):PAGE59
  J1G3   29 DQS11P SCONN288_H44441004_PIP-SCONN,HA    I67 @BASEBOARD_FAB2_LIB.BASEBOARD_FAB2(SCH_1):PAGE81
  J9U2   29 DQS11P SCONN288_H44441003_PIP-SCONN,HA    I64 @BASEBOARD_FAB2_LIB.BASEBOARD_FAB2(SCH_1):PAGE82

M_J_DQS_DP<12> @BASEBOARD_FAB2_LIB.BASEBOARD_FAB2(SCH_1):M_J_DQS_DP(12)
  U2D1 AN66 DDR2_DQS_DP<12> SKX_EXT_B_BGA1-IC,TBD   I172 @BASEBOARD_FAB2_LIB.BASEBOARD_FAB2(SCH_1):PAGE59
  J1G3   40 DQS12P SCONN288_H44441004_PIP-SCONN,HA    I67 @BASEBOARD_FAB2_LIB.BASEBOARD_FAB2(SCH_1):PAGE81
  J9U2   40 DQS12P SCONN288_H44441003_PIP-SCONN,HA    I64 @BASEBOARD_FAB2_LIB.BASEBOARD_FAB2(SCH_1):PAGE82

M_J_DQS_DP<13> @BASEBOARD_FAB2_LIB.BASEBOARD_FAB2(SCH_1):M_J_DQS_DP(13)
  U2D1  V39 DDR2_DQS_DP<13> SKX_EXT_B_BGA1-IC,TBD   I172 @BASEBOARD_FAB2_LIB.BASEBOARD_FAB2(SCH_1):PAGE59
  J1G3   99 DQS13P SCONN288_H44441004_PIP-SCONN,HA    I67 @BASEBOARD_FAB2_LIB.BASEBOARD_FAB2(SCH_1):PAGE81
  J9U2   99 DQS13P SCONN288_H44441003_PIP-SCONN,HA    I64 @BASEBOARD_FAB2_LIB.BASEBOARD_FAB2(SCH_1):PAGE82

M_J_DQS_DP<14> @BASEBOARD_FAB2_LIB.BASEBOARD_FAB2(SCH_1):M_J_DQS_DP(14)
  U2D1  V33 DDR2_DQS_DP<14> SKX_EXT_B_BGA1-IC,TBD   I172 @BASEBOARD_FAB2_LIB.BASEBOARD_FAB2(SCH_1):PAGE59
  J1G3  110 DQS14P SCONN288_H44441004_PIP-SCONN,HA    I67 @BASEBOARD_FAB2_LIB.BASEBOARD_FAB2(SCH_1):PAGE81
  J9U2  110 DQS14P SCONN288_H44441003_PIP-SCONN,HA    I64 @BASEBOARD_FAB2_LIB.BASEBOARD_FAB2(SCH_1):PAGE82

M_J_DQS_DP<15> @BASEBOARD_FAB2_LIB.BASEBOARD_FAB2(SCH_1):M_J_DQS_DP(15)
  U2D1 AE30 DDR2_DQS_DP<15> SKX_EXT_B_BGA1-IC,TBD   I172 @BASEBOARD_FAB2_LIB.BASEBOARD_FAB2(SCH_1):PAGE59
  J1G3  121 DQS15P SCONN288_H44441004_PIP-SCONN,HA    I67 @BASEBOARD_FAB2_LIB.BASEBOARD_FAB2(SCH_1):PAGE81
  J9U2  121 DQS15P SCONN288_H44441003_PIP-SCONN,HA    I64 @BASEBOARD_FAB2_LIB.BASEBOARD_FAB2(SCH_1):PAGE82

M_J_DQS_DP<16> @BASEBOARD_FAB2_LIB.BASEBOARD_FAB2(SCH_1):M_J_DQS_DP(16)
  U2D1 AE24 DDR2_DQS_DP<16> SKX_EXT_B_BGA1-IC,TBD   I172 @BASEBOARD_FAB2_LIB.BASEBOARD_FAB2(SCH_1):PAGE59
  J1G3  132 DQS16P SCONN288_H44441004_PIP-SCONN,HA    I67 @BASEBOARD_FAB2_LIB.BASEBOARD_FAB2(SCH_1):PAGE81
  J9U2  132 DQS16P SCONN288_H44441003_PIP-SCONN,HA    I64 @BASEBOARD_FAB2_LIB.BASEBOARD_FAB2(SCH_1):PAGE82

M_J_DQS_DP<17> @BASEBOARD_FAB2_LIB.BASEBOARD_FAB2(SCH_1):M_J_DQS_DP(17)
  U2D1 AV71 DDR2_DQS_DP<17> SKX_EXT_B_BGA1-IC,TBD   I172 @BASEBOARD_FAB2_LIB.BASEBOARD_FAB2(SCH_1):PAGE59
  J1G3   51 DQS17P SCONN288_H44441004_PIP-SCONN,HA    I67 @BASEBOARD_FAB2_LIB.BASEBOARD_FAB2(SCH_1):PAGE81
  J9U2   51 DQS17P SCONN288_H44441003_PIP-SCONN,HA    I64 @BASEBOARD_FAB2_LIB.BASEBOARD_FAB2(SCH_1):PAGE82

M_J_DQS_DP<1> @BASEBOARD_FAB2_LIB.BASEBOARD_FAB2(SCH_1):M_J_DQS_DP(1)
  U2D1 AB75 DDR2_DQS_DP<1> SKX_EXT_B_BGA1-IC,TBD   I172 @BASEBOARD_FAB2_LIB.BASEBOARD_FAB2(SCH_1):PAGE59
  J1G3  164  DQS1P SCONN288_H44441004_PIP-SCONN,HA    I67 @BASEBOARD_FAB2_LIB.BASEBOARD_FAB2(SCH_1):PAGE81
  J9U2  164  DQS1P SCONN288_H44441003_PIP-SCONN,HA    I64 @BASEBOARD_FAB2_LIB.BASEBOARD_FAB2(SCH_1):PAGE82

M_J_DQS_DP<2> @BASEBOARD_FAB2_LIB.BASEBOARD_FAB2(SCH_1):M_J_DQS_DP(2)
  U2D1  W70 DDR2_DQS_DP<2> SKX_EXT_B_BGA1-IC,TBD   I172 @BASEBOARD_FAB2_LIB.BASEBOARD_FAB2(SCH_1):PAGE59
  J1G3  175  DQS2P SCONN288_H44441004_PIP-SCONN,HA    I67 @BASEBOARD_FAB2_LIB.BASEBOARD_FAB2(SCH_1):PAGE81
  J9U2  175  DQS2P SCONN288_H44441003_PIP-SCONN,HA    I64 @BASEBOARD_FAB2_LIB.BASEBOARD_FAB2(SCH_1):PAGE82

M_J_DQS_DP<3> @BASEBOARD_FAB2_LIB.BASEBOARD_FAB2(SCH_1):M_J_DQS_DP(3)
  U2D1 AR66 DDR2_DQS_DP<3> SKX_EXT_B_BGA1-IC,TBD   I172 @BASEBOARD_FAB2_LIB.BASEBOARD_FAB2(SCH_1):PAGE59
  J1G3  186  DQS3P SCONN288_H44441004_PIP-SCONN,HA    I67 @BASEBOARD_FAB2_LIB.BASEBOARD_FAB2(SCH_1):PAGE81
  J9U2  186  DQS3P SCONN288_H44441003_PIP-SCONN,HA    I64 @BASEBOARD_FAB2_LIB.BASEBOARD_FAB2(SCH_1):PAGE82

M_J_DQS_DP<4> @BASEBOARD_FAB2_LIB.BASEBOARD_FAB2(SCH_1):M_J_DQS_DP(4)
  U2D1  Y39 DDR2_DQS_DP<4> SKX_EXT_B_BGA1-IC,TBD   I172 @BASEBOARD_FAB2_LIB.BASEBOARD_FAB2(SCH_1):PAGE59
  J1G3  245  DQS4P SCONN288_H44441004_PIP-SCONN,HA    I67 @BASEBOARD_FAB2_LIB.BASEBOARD_FAB2(SCH_1):PAGE81
  J9U2  245  DQS4P SCONN288_H44441003_PIP-SCONN,HA    I64 @BASEBOARD_FAB2_LIB.BASEBOARD_FAB2(SCH_1):PAGE82

M_J_DQS_DP<5> @BASEBOARD_FAB2_LIB.BASEBOARD_FAB2(SCH_1):M_J_DQS_DP(5)
  U2D1  Y33 DDR2_DQS_DP<5> SKX_EXT_B_BGA1-IC,TBD   I172 @BASEBOARD_FAB2_LIB.BASEBOARD_FAB2(SCH_1):PAGE59
  J1G3  256  DQS5P SCONN288_H44441004_PIP-SCONN,HA    I67 @BASEBOARD_FAB2_LIB.BASEBOARD_FAB2(SCH_1):PAGE81
  J9U2  256  DQS5P SCONN288_H44441003_PIP-SCONN,HA    I64 @BASEBOARD_FAB2_LIB.BASEBOARD_FAB2(SCH_1):PAGE82

M_J_DQS_DP<6> @BASEBOARD_FAB2_LIB.BASEBOARD_FAB2(SCH_1):M_J_DQS_DP(6)
  U2D1 AG30 DDR2_DQS_DP<6> SKX_EXT_B_BGA1-IC,TBD   I172 @BASEBOARD_FAB2_LIB.BASEBOARD_FAB2(SCH_1):PAGE59
  J1G3  267  DQS6P SCONN288_H44441004_PIP-SCONN,HA    I67 @BASEBOARD_FAB2_LIB.BASEBOARD_FAB2(SCH_1):PAGE81
  J9U2  267  DQS6P SCONN288_H44441003_PIP-SCONN,HA    I64 @BASEBOARD_FAB2_LIB.BASEBOARD_FAB2(SCH_1):PAGE82

M_J_DQS_DP<7> @BASEBOARD_FAB2_LIB.BASEBOARD_FAB2(SCH_1):M_J_DQS_DP(7)
  U2D1 AG24 DDR2_DQS_DP<7> SKX_EXT_B_BGA1-IC,TBD   I172 @BASEBOARD_FAB2_LIB.BASEBOARD_FAB2(SCH_1):PAGE59
  J1G3  278  DQS7P SCONN288_H44441004_PIP-SCONN,HA    I67 @BASEBOARD_FAB2_LIB.BASEBOARD_FAB2(SCH_1):PAGE81
  J9U2  278  DQS7P SCONN288_H44441003_PIP-SCONN,HA    I64 @BASEBOARD_FAB2_LIB.BASEBOARD_FAB2(SCH_1):PAGE82

M_J_DQS_DP<8> @BASEBOARD_FAB2_LIB.BASEBOARD_FAB2(SCH_1):M_J_DQS_DP(8)
  U2D1 AY71 DDR2_DQS_DP<8> SKX_EXT_B_BGA1-IC,TBD   I172 @BASEBOARD_FAB2_LIB.BASEBOARD_FAB2(SCH_1):PAGE59
  J1G3  197  DQS8P SCONN288_H44441004_PIP-SCONN,HA    I67 @BASEBOARD_FAB2_LIB.BASEBOARD_FAB2(SCH_1):PAGE81
  J9U2  197  DQS8P SCONN288_H44441003_PIP-SCONN,HA    I64 @BASEBOARD_FAB2_LIB.BASEBOARD_FAB2(SCH_1):PAGE82

M_J_DQS_DP<9> @BASEBOARD_FAB2_LIB.BASEBOARD_FAB2(SCH_1):M_J_DQS_DP(9)
  U2D1 AN76 DDR2_DQS_DP<9> SKX_EXT_B_BGA1-IC,TBD   I172 @BASEBOARD_FAB2_LIB.BASEBOARD_FAB2(SCH_1):PAGE59
  J1G3    7  DQS9P SCONN288_H44441004_PIP-SCONN,HA    I67 @BASEBOARD_FAB2_LIB.BASEBOARD_FAB2(SCH_1):PAGE81
  J9U2    7  DQS9P SCONN288_H44441003_PIP-SCONN,HA    I64 @BASEBOARD_FAB2_LIB.BASEBOARD_FAB2(SCH_1):PAGE82

M_J_ECC<0> @BASEBOARD_FAB2_LIB.BASEBOARD_FAB2(SCH_1):M_J_ECC(0)
  U2D1 AU72 DDR2_ECC<0> SKX_EXT_B_BGA1-IC,TBD   I172 @BASEBOARD_FAB2_LIB.BASEBOARD_FAB2(SCH_1):PAGE59
  J1G3  194  CB<1> SCONN288_H44441004_PIP-SCONN,HA   I186 @BASEBOARD_FAB2_LIB.BASEBOARD_FAB2(SCH_1):PAGE81
  J9U2   49  CB<0> SCONN288_H44441003_PIP-SCONN,HA   I187 @BASEBOARD_FAB2_LIB.BASEBOARD_FAB2(SCH_1):PAGE82

M_J_ECC<1> @BASEBOARD_FAB2_LIB.BASEBOARD_FAB2(SCH_1):M_J_ECC(1)
  U2D1 BA72 DDR2_ECC<1> SKX_EXT_B_BGA1-IC,TBD   I172 @BASEBOARD_FAB2_LIB.BASEBOARD_FAB2(SCH_1):PAGE59
  J1G3   49  CB<0> SCONN288_H44441004_PIP-SCONN,HA   I186 @BASEBOARD_FAB2_LIB.BASEBOARD_FAB2(SCH_1):PAGE81
  J9U2  194  CB<1> SCONN288_H44441003_PIP-SCONN,HA   I187 @BASEBOARD_FAB2_LIB.BASEBOARD_FAB2(SCH_1):PAGE82

M_J_ECC<2> @BASEBOARD_FAB2_LIB.BASEBOARD_FAB2(SCH_1):M_J_ECC(2)
  U2D1 AV69 DDR2_ECC<2> SKX_EXT_B_BGA1-IC,TBD   I172 @BASEBOARD_FAB2_LIB.BASEBOARD_FAB2(SCH_1):PAGE59
  J1G3  201  CB<3> SCONN288_H44441004_PIP-SCONN,HA   I186 @BASEBOARD_FAB2_LIB.BASEBOARD_FAB2(SCH_1):PAGE81
  J9U2   56  CB<2> SCONN288_H44441003_PIP-SCONN,HA   I187 @BASEBOARD_FAB2_LIB.BASEBOARD_FAB2(SCH_1):PAGE82

M_J_ECC<3> @BASEBOARD_FAB2_LIB.BASEBOARD_FAB2(SCH_1):M_J_ECC(3)
  U2D1 AY69 DDR2_ECC<3> SKX_EXT_B_BGA1-IC,TBD   I172 @BASEBOARD_FAB2_LIB.BASEBOARD_FAB2(SCH_1):PAGE59
  J1G3   56  CB<2> SCONN288_H44441004_PIP-SCONN,HA   I186 @BASEBOARD_FAB2_LIB.BASEBOARD_FAB2(SCH_1):PAGE81
  J9U2  201  CB<3> SCONN288_H44441003_PIP-SCONN,HA   I187 @BASEBOARD_FAB2_LIB.BASEBOARD_FAB2(SCH_1):PAGE82

M_J_ECC<4> @BASEBOARD_FAB2_LIB.BASEBOARD_FAB2(SCH_1):M_J_ECC(4)
  U2D1 AV73 DDR2_ECC<4> SKX_EXT_B_BGA1-IC,TBD   I172 @BASEBOARD_FAB2_LIB.BASEBOARD_FAB2(SCH_1):PAGE59
  J1G3  192  CB<5> SCONN288_H44441004_PIP-SCONN,HA   I186 @BASEBOARD_FAB2_LIB.BASEBOARD_FAB2(SCH_1):PAGE81
  J9U2   47  CB<4> SCONN288_H44441003_PIP-SCONN,HA   I187 @BASEBOARD_FAB2_LIB.BASEBOARD_FAB2(SCH_1):PAGE82

M_J_ECC<5> @BASEBOARD_FAB2_LIB.BASEBOARD_FAB2(SCH_1):M_J_ECC(5)
  U2D1 AY73 DDR2_ECC<5> SKX_EXT_B_BGA1-IC,TBD   I172 @BASEBOARD_FAB2_LIB.BASEBOARD_FAB2(SCH_1):PAGE59
  J1G3   47  CB<4> SCONN288_H44441004_PIP-SCONN,HA   I186 @BASEBOARD_FAB2_LIB.BASEBOARD_FAB2(SCH_1):PAGE81
  J9U2  192  CB<5> SCONN288_H44441003_PIP-SCONN,HA   I187 @BASEBOARD_FAB2_LIB.BASEBOARD_FAB2(SCH_1):PAGE82

M_J_ECC<6> @BASEBOARD_FAB2_LIB.BASEBOARD_FAB2(SCH_1):M_J_ECC(6)
  U2D1 AU70 DDR2_ECC<6> SKX_EXT_B_BGA1-IC,TBD   I172 @BASEBOARD_FAB2_LIB.BASEBOARD_FAB2(SCH_1):PAGE59
  J1G3  199  CB<7> SCONN288_H44441004_PIP-SCONN,HA   I186 @BASEBOARD_FAB2_LIB.BASEBOARD_FAB2(SCH_1):PAGE81
  J9U2   54  CB<6> SCONN288_H44441003_PIP-SCONN,HA   I187 @BASEBOARD_FAB2_LIB.BASEBOARD_FAB2(SCH_1):PAGE82

M_J_ECC<7> @BASEBOARD_FAB2_LIB.BASEBOARD_FAB2(SCH_1):M_J_ECC(7)
  U2D1 BA70 DDR2_ECC<7> SKX_EXT_B_BGA1-IC,TBD   I172 @BASEBOARD_FAB2_LIB.BASEBOARD_FAB2(SCH_1):PAGE59
  J1G3   54  CB<6> SCONN288_H44441004_PIP-SCONN,HA   I186 @BASEBOARD_FAB2_LIB.BASEBOARD_FAB2(SCH_1):PAGE81
  J9U2  199  CB<7> SCONN288_H44441003_PIP-SCONN,HA   I187 @BASEBOARD_FAB2_LIB.BASEBOARD_FAB2(SCH_1):PAGE82

M_J_MA<0> @BASEBOARD_FAB2_LIB.BASEBOARD_FAB2(SCH_1):M_J_MA(0)
  U2D1 AB53 DDR2_MA<0> SKX_EXT_B_BGA1-IC,TBD   I172 @BASEBOARD_FAB2_LIB.BASEBOARD_FAB2(SCH_1):PAGE59
  J1G3   79     A0 SCONN288_H44441004_PIP-SCONN,HA   I186 @BASEBOARD_FAB2_LIB.BASEBOARD_FAB2(SCH_1):PAGE81
  J9U2   79     A0 SCONN288_H44441003_PIP-SCONN,HA   I187 @BASEBOARD_FAB2_LIB.BASEBOARD_FAB2(SCH_1):PAGE82

M_J_MA<10> @BASEBOARD_FAB2_LIB.BASEBOARD_FAB2(SCH_1):M_J_MA(10)
  U2D1 AD55 DDR2_MA<10> SKX_EXT_B_BGA1-IC,TBD   I172 @BASEBOARD_FAB2_LIB.BASEBOARD_FAB2(SCH_1):PAGE59
  J1G3  225    A10 SCONN288_H44441004_PIP-SCONN,HA   I186 @BASEBOARD_FAB2_LIB.BASEBOARD_FAB2(SCH_1):PAGE81
  J9U2  225    A10 SCONN288_H44441003_PIP-SCONN,HA   I187 @BASEBOARD_FAB2_LIB.BASEBOARD_FAB2(SCH_1):PAGE82

M_J_MA<11> @BASEBOARD_FAB2_LIB.BASEBOARD_FAB2(SCH_1):M_J_MA(11)
  U2D1 AG60 DDR2_MA<11> SKX_EXT_B_BGA1-IC,TBD   I172 @BASEBOARD_FAB2_LIB.BASEBOARD_FAB2(SCH_1):PAGE59
  J1G3  210    A11 SCONN288_H44441004_PIP-SCONN,HA   I186 @BASEBOARD_FAB2_LIB.BASEBOARD_FAB2(SCH_1):PAGE81
  J9U2  210    A11 SCONN288_H44441003_PIP-SCONN,HA   I187 @BASEBOARD_FAB2_LIB.BASEBOARD_FAB2(SCH_1):PAGE82

M_J_MA<12> @BASEBOARD_FAB2_LIB.BASEBOARD_FAB2(SCH_1):M_J_MA(12)
  U2D1 AG62 DDR2_MA<12> SKX_EXT_B_BGA1-IC,TBD   I172 @BASEBOARD_FAB2_LIB.BASEBOARD_FAB2(SCH_1):PAGE59
  J1G3   65    A12 SCONN288_H44441004_PIP-SCONN,HA   I186 @BASEBOARD_FAB2_LIB.BASEBOARD_FAB2(SCH_1):PAGE81
  J9U2   65    A12 SCONN288_H44441003_PIP-SCONN,HA   I187 @BASEBOARD_FAB2_LIB.BASEBOARD_FAB2(SCH_1):PAGE82

M_J_MA<13> @BASEBOARD_FAB2_LIB.BASEBOARD_FAB2(SCH_1):M_J_MA(13)
  U2D1 AD53 DDR2_MA<13> SKX_EXT_B_BGA1-IC,TBD   I172 @BASEBOARD_FAB2_LIB.BASEBOARD_FAB2(SCH_1):PAGE59
  J1G3  232    A13 SCONN288_H44441004_PIP-SCONN,HA   I186 @BASEBOARD_FAB2_LIB.BASEBOARD_FAB2(SCH_1):PAGE81
  J9U2  232    A13 SCONN288_H44441003_PIP-SCONN,HA   I187 @BASEBOARD_FAB2_LIB.BASEBOARD_FAB2(SCH_1):PAGE82

M_J_MA<14> @BASEBOARD_FAB2_LIB.BASEBOARD_FAB2(SCH_1):M_J_MA(14)
  U2D1  W50 DDR2_MA<14> SKX_EXT_B_BGA1-IC,TBD   I172 @BASEBOARD_FAB2_LIB.BASEBOARD_FAB2(SCH_1):PAGE59
  J1G3  228 A14_WE_N SCONN288_H44441004_PIP-SCONN,HA   I186 @BASEBOARD_FAB2_LIB.BASEBOARD_FAB2(SCH_1):PAGE81
  J9U2  228 A14_WE_N SCONN288_H44441003_PIP-SCONN,HA   I187 @BASEBOARD_FAB2_LIB.BASEBOARD_FAB2(SCH_1):PAGE82

M_J_MA<15> @BASEBOARD_FAB2_LIB.BASEBOARD_FAB2(SCH_1):M_J_MA(15)
  U2D1 AE54 DDR2_MA<15> SKX_EXT_B_BGA1-IC,TBD   I172 @BASEBOARD_FAB2_LIB.BASEBOARD_FAB2(SCH_1):PAGE59
  J1G3   86 A15_CAS_N SCONN288_H44441004_PIP-SCONN,HA   I186 @BASEBOARD_FAB2_LIB.BASEBOARD_FAB2(SCH_1):PAGE81
  J9U2   86 A15_CAS_N SCONN288_H44441003_PIP-SCONN,HA   I187 @BASEBOARD_FAB2_LIB.BASEBOARD_FAB2(SCH_1):PAGE82

M_J_MA<16> @BASEBOARD_FAB2_LIB.BASEBOARD_FAB2(SCH_1):M_J_MA(16)
  U2D1 AA52 DDR2_MA<16> SKX_EXT_B_BGA1-IC,TBD   I172 @BASEBOARD_FAB2_LIB.BASEBOARD_FAB2(SCH_1):PAGE59
  J1G3   82 A16_RAS_N SCONN288_H44441004_PIP-SCONN,HA   I186 @BASEBOARD_FAB2_LIB.BASEBOARD_FAB2(SCH_1):PAGE81
  J9U2   82 A16_RAS_N SCONN288_H44441003_PIP-SCONN,HA   I187 @BASEBOARD_FAB2_LIB.BASEBOARD_FAB2(SCH_1):PAGE82

M_J_MA<17> @BASEBOARD_FAB2_LIB.BASEBOARD_FAB2(SCH_1):M_J_MA(17)
  U2D1 AC46 DDR2_MA<17> SKX_EXT_B_BGA1-IC,TBD   I172 @BASEBOARD_FAB2_LIB.BASEBOARD_FAB2(SCH_1):PAGE59
  J1G3  234    A17 SCONN288_H44441004_PIP-SCONN,HA   I186 @BASEBOARD_FAB2_LIB.BASEBOARD_FAB2(SCH_1):PAGE81
  J9U2  234    A17 SCONN288_H44441003_PIP-SCONN,HA   I187 @BASEBOARD_FAB2_LIB.BASEBOARD_FAB2(SCH_1):PAGE82

M_J_MA<1> @BASEBOARD_FAB2_LIB.BASEBOARD_FAB2(SCH_1):M_J_MA(1)
  U2D1 AE58 DDR2_MA<1> SKX_EXT_B_BGA1-IC,TBD   I172 @BASEBOARD_FAB2_LIB.BASEBOARD_FAB2(SCH_1):PAGE59
  J1G3   72     A1 SCONN288_H44441004_PIP-SCONN,HA   I186 @BASEBOARD_FAB2_LIB.BASEBOARD_FAB2(SCH_1):PAGE81
  J9U2   72     A1 SCONN288_H44441003_PIP-SCONN,HA   I187 @BASEBOARD_FAB2_LIB.BASEBOARD_FAB2(SCH_1):PAGE82

M_J_MA<2> @BASEBOARD_FAB2_LIB.BASEBOARD_FAB2(SCH_1):M_J_MA(2)
  U2D1 AD57 DDR2_MA<2> SKX_EXT_B_BGA1-IC,TBD   I172 @BASEBOARD_FAB2_LIB.BASEBOARD_FAB2(SCH_1):PAGE59
  J1G3  216     A2 SCONN288_H44441004_PIP-SCONN,HA   I186 @BASEBOARD_FAB2_LIB.BASEBOARD_FAB2(SCH_1):PAGE81
  J9U2  216     A2 SCONN288_H44441003_PIP-SCONN,HA   I187 @BASEBOARD_FAB2_LIB.BASEBOARD_FAB2(SCH_1):PAGE82

M_J_MA<3> @BASEBOARD_FAB2_LIB.BASEBOARD_FAB2(SCH_1):M_J_MA(3)
  U2D1  W58 DDR2_MA<3> SKX_EXT_B_BGA1-IC,TBD   I172 @BASEBOARD_FAB2_LIB.BASEBOARD_FAB2(SCH_1):PAGE59
  J1G3   71     A3 SCONN288_H44441004_PIP-SCONN,HA   I186 @BASEBOARD_FAB2_LIB.BASEBOARD_FAB2(SCH_1):PAGE81
  J9U2   71     A3 SCONN288_H44441003_PIP-SCONN,HA   I187 @BASEBOARD_FAB2_LIB.BASEBOARD_FAB2(SCH_1):PAGE82

M_J_MA<4> @BASEBOARD_FAB2_LIB.BASEBOARD_FAB2(SCH_1):M_J_MA(4)
  U2D1 AA58 DDR2_MA<4> SKX_EXT_B_BGA1-IC,TBD   I172 @BASEBOARD_FAB2_LIB.BASEBOARD_FAB2(SCH_1):PAGE59
  J1G3  214     A4 SCONN288_H44441004_PIP-SCONN,HA   I186 @BASEBOARD_FAB2_LIB.BASEBOARD_FAB2(SCH_1):PAGE81
  J9U2  214     A4 SCONN288_H44441003_PIP-SCONN,HA   I187 @BASEBOARD_FAB2_LIB.BASEBOARD_FAB2(SCH_1):PAGE82

M_J_MA<5> @BASEBOARD_FAB2_LIB.BASEBOARD_FAB2(SCH_1):M_J_MA(5)
  U2D1  V59 DDR2_MA<5> SKX_EXT_B_BGA1-IC,TBD   I172 @BASEBOARD_FAB2_LIB.BASEBOARD_FAB2(SCH_1):PAGE59
  J1G3  213     A5 SCONN288_H44441004_PIP-SCONN,HA   I186 @BASEBOARD_FAB2_LIB.BASEBOARD_FAB2(SCH_1):PAGE81
  J9U2  213     A5 SCONN288_H44441003_PIP-SCONN,HA   I187 @BASEBOARD_FAB2_LIB.BASEBOARD_FAB2(SCH_1):PAGE82

M_J_MA<6> @BASEBOARD_FAB2_LIB.BASEBOARD_FAB2(SCH_1):M_J_MA(6)
  U2D1 AB59 DDR2_MA<6> SKX_EXT_B_BGA1-IC,TBD   I172 @BASEBOARD_FAB2_LIB.BASEBOARD_FAB2(SCH_1):PAGE59
  J1G3   69     A6 SCONN288_H44441004_PIP-SCONN,HA   I186 @BASEBOARD_FAB2_LIB.BASEBOARD_FAB2(SCH_1):PAGE81
  J9U2   69     A6 SCONN288_H44441003_PIP-SCONN,HA   I187 @BASEBOARD_FAB2_LIB.BASEBOARD_FAB2(SCH_1):PAGE82

M_J_MA<7> @BASEBOARD_FAB2_LIB.BASEBOARD_FAB2(SCH_1):M_J_MA(7)
  U2D1 AE60 DDR2_MA<7> SKX_EXT_B_BGA1-IC,TBD   I172 @BASEBOARD_FAB2_LIB.BASEBOARD_FAB2(SCH_1):PAGE59
  J1G3  211     A7 SCONN288_H44441004_PIP-SCONN,HA   I186 @BASEBOARD_FAB2_LIB.BASEBOARD_FAB2(SCH_1):PAGE81
  J9U2  211     A7 SCONN288_H44441003_PIP-SCONN,HA   I187 @BASEBOARD_FAB2_LIB.BASEBOARD_FAB2(SCH_1):PAGE82

M_J_MA<8> @BASEBOARD_FAB2_LIB.BASEBOARD_FAB2(SCH_1):M_J_MA(8)
  U2D1 AD59 DDR2_MA<8> SKX_EXT_B_BGA1-IC,TBD   I172 @BASEBOARD_FAB2_LIB.BASEBOARD_FAB2(SCH_1):PAGE59
  J1G3   68     A8 SCONN288_H44441004_PIP-SCONN,HA   I186 @BASEBOARD_FAB2_LIB.BASEBOARD_FAB2(SCH_1):PAGE81
  J9U2   68     A8 SCONN288_H44441003_PIP-SCONN,HA   I187 @BASEBOARD_FAB2_LIB.BASEBOARD_FAB2(SCH_1):PAGE82

M_J_MA<9> @BASEBOARD_FAB2_LIB.BASEBOARD_FAB2(SCH_1):M_J_MA(9)
  U2D1 AG58 DDR2_MA<9> SKX_EXT_B_BGA1-IC,TBD   I172 @BASEBOARD_FAB2_LIB.BASEBOARD_FAB2(SCH_1):PAGE59
  J1G3   66     A9 SCONN288_H44441004_PIP-SCONN,HA   I186 @BASEBOARD_FAB2_LIB.BASEBOARD_FAB2(SCH_1):PAGE81
  J9U2   66     A9 SCONN288_H44441003_PIP-SCONN,HA   I187 @BASEBOARD_FAB2_LIB.BASEBOARD_FAB2(SCH_1):PAGE82

M_J_ODT<0> @BASEBOARD_FAB2_LIB.BASEBOARD_FAB2(SCH_1):M_J_ODT(0)
  U2D1 AA50 DDR2_ODT<0> SKX_EXT_B_BGA1-IC,TBD   I172 @BASEBOARD_FAB2_LIB.BASEBOARD_FAB2(SCH_1):PAGE59
  J1G3   87 ODT<0> SCONN288_H44441004_PIP-SCONN,HA   I186 @BASEBOARD_FAB2_LIB.BASEBOARD_FAB2(SCH_1):PAGE81

M_J_ODT<1> @BASEBOARD_FAB2_LIB.BASEBOARD_FAB2(SCH_1):M_J_ODT(1)
  U2D1 AA48 DDR2_ODT<1> SKX_EXT_B_BGA1-IC,TBD   I172 @BASEBOARD_FAB2_LIB.BASEBOARD_FAB2(SCH_1):PAGE59
  J1G3   91 ODT<1> SCONN288_H44441004_PIP-SCONN,HA   I186 @BASEBOARD_FAB2_LIB.BASEBOARD_FAB2(SCH_1):PAGE81

M_J_ODT<2> @BASEBOARD_FAB2_LIB.BASEBOARD_FAB2(SCH_1):M_J_ODT(2)
  U2D1  V49 DDR2_ODT<2> SKX_EXT_B_BGA1-IC,TBD   I172 @BASEBOARD_FAB2_LIB.BASEBOARD_FAB2(SCH_1):PAGE59
  J9U2   87 ODT<0> SCONN288_H44441003_PIP-SCONN,HA   I187 @BASEBOARD_FAB2_LIB.BASEBOARD_FAB2(SCH_1):PAGE82

M_J_ODT<3> @BASEBOARD_FAB2_LIB.BASEBOARD_FAB2(SCH_1):M_J_ODT(3)
  U2D1 AB47 DDR2_ODT<3> SKX_EXT_B_BGA1-IC,TBD   I172 @BASEBOARD_FAB2_LIB.BASEBOARD_FAB2(SCH_1):PAGE59
  J9U2   91 ODT<1> SCONN288_H44441003_PIP-SCONN,HA   I187 @BASEBOARD_FAB2_LIB.BASEBOARD_FAB2(SCH_1):PAGE82

M_J_PAR @BASEBOARD_FAB2_LIB.BASEBOARD_FAB2(SCH_1):M_J_PAR
  U2D1  V53 DDR2_PAR SKX_EXT_B_BGA1-IC,TBD   I172 @BASEBOARD_FAB2_LIB.BASEBOARD_FAB2(SCH_1):PAGE59
  J1G3  222    PAR SCONN288_H44441004_PIP-SCONN,HA   I186 @BASEBOARD_FAB2_LIB.BASEBOARD_FAB2(SCH_1):PAGE81
  J9U2  222    PAR SCONN288_H44441003_PIP-SCONN,HA   I187 @BASEBOARD_FAB2_LIB.BASEBOARD_FAB2(SCH_1):PAGE82

M_J_VREF @BASEBOARD_FAB2_LIB.BASEBOARD_FAB2(SCH_1):M_J_VREF
 C9U10    1      A CAP_A_0402V-0.01UF,25V,10%,X7RA   I178 @BASEBOARD_FAB2_LIB.BASEBOARD_FAB2(SCH_1):PAGE81
  J1G3  146 VREFCA SCONN288_H44441004_PIP-SCONN,HA   I186 @BASEBOARD_FAB2_LIB.BASEBOARD_FAB2(SCH_1):PAGE81
 C1G19    1      A CAP_A_0402V-0.01UF,25V,10%,X7RA   I180 @BASEBOARD_FAB2_LIB.BASEBOARD_FAB2(SCH_1):PAGE82
  J9U2  146 VREFCA SCONN288_H44441003_PIP-SCONN,HA   I187 @BASEBOARD_FAB2_LIB.BASEBOARD_FAB2(SCH_1):PAGE82
 R1G15    2      B RES_0402-1.00K,1%,1/16W,CHIP,GA    I35 @BASEBOARD_FAB2_LIB.BASEBOARD_FAB2(SCH_1):PAGE100
 R1G17    1      A RES_0402-1.00K,1%,1/16W,CHIP,GA    I36 @BASEBOARD_FAB2_LIB.BASEBOARD_FAB2(SCH_1):PAGE100
 R1G14    2      B RES_0402-2,1.0%,1/16W,CHIP,G21A    I41 @BASEBOARD_FAB2_LIB.BASEBOARD_FAB2(SCH_1):PAGE100

M_KLM_RST_N @BASEBOARD_FAB2_LIB.BASEBOARD_FAB2(SCH_1):M_KLM_RST_N
  U2D1 DV63 DDR345_RESET_N SKX_EXT_B_BGA1-IC,TBD   I172 @BASEBOARD_FAB2_LIB.BASEBOARD_FAB2(SCH_1):PAGE55
  J1B1   58 RESET_N SCONN288_H44441004_PIP-SCONN,HA   I111 @BASEBOARD_FAB2_LIB.BASEBOARD_FAB2(SCH_1):PAGE83
  J9M1   58 RESET_N SCONN288_H44441003_PIP-SCONN,HA    I14 @BASEBOARD_FAB2_LIB.BASEBOARD_FAB2(SCH_1):PAGE84
  J1A2   58 RESET_N SCONN288_H44441004_PIP-SCONN,HA   I111 @BASEBOARD_FAB2_LIB.BASEBOARD_FAB2(SCH_1):PAGE85
  J9L2   58 RESET_N SCONN288_H44441003_PIP-SCONN,HA    I12 @BASEBOARD_FAB2_LIB.BASEBOARD_FAB2(SCH_1):PAGE86
  J1A1   58 RESET_N SCONN288_H44441004_PIP-SCONN,HA   I186 @BASEBOARD_FAB2_LIB.BASEBOARD_FAB2(SCH_1):PAGE87
  J9L1   58 RESET_N SCONN288_H44441003_PIP-SCONN,HA   I111 @BASEBOARD_FAB2_LIB.BASEBOARD_FAB2(SCH_1):PAGE88

M_K_ACT_N @BASEBOARD_FAB2_LIB.BASEBOARD_FAB2(SCH_1):M_K_ACT_N
  U2D1 DW60 DDR3_ACT_N SKX_EXT_B_BGA1-IC,TBD   I172 @BASEBOARD_FAB2_LIB.BASEBOARD_FAB2(SCH_1):PAGE60
  J1B1   62  ACT_N SCONN288_H44441004_PIP-SCONN,HA   I111 @BASEBOARD_FAB2_LIB.BASEBOARD_FAB2(SCH_1):PAGE83
  J9M1   62  ACT_N SCONN288_H44441003_PIP-SCONN,HA    I14 @BASEBOARD_FAB2_LIB.BASEBOARD_FAB2(SCH_1):PAGE84

M_K_ALERT_N @BASEBOARD_FAB2_LIB.BASEBOARD_FAB2(SCH_1):M_K_ALERT_N
  U2D1 ED63 DDR3_ALERT_N SKX_EXT_B_BGA1-IC,TBD   I172 @BASEBOARD_FAB2_LIB.BASEBOARD_FAB2(SCH_1):PAGE60
  J1B1  208 ALERT_N SCONN288_H44441004_PIP-SCONN,HA   I111 @BASEBOARD_FAB2_LIB.BASEBOARD_FAB2(SCH_1):PAGE83
  J9M1  208 ALERT_N SCONN288_H44441003_PIP-SCONN,HA    I14 @BASEBOARD_FAB2_LIB.BASEBOARD_FAB2(SCH_1):PAGE84

M_K_BA<0> @BASEBOARD_FAB2_LIB.BASEBOARD_FAB2(SCH_1):M_K_BA(0)
  U2D1 EE52 DDR3_BA<0> SKX_EXT_B_BGA1-IC,TBD   I172 @BASEBOARD_FAB2_LIB.BASEBOARD_FAB2(SCH_1):PAGE60
  J1B1   81  BA<0> SCONN288_H44441004_PIP-SCONN,HA   I111 @BASEBOARD_FAB2_LIB.BASEBOARD_FAB2(SCH_1):PAGE83
  J9M1   81  BA<0> SCONN288_H44441003_PIP-SCONN,HA    I14 @BASEBOARD_FAB2_LIB.BASEBOARD_FAB2(SCH_1):PAGE84

M_K_BA<1> @BASEBOARD_FAB2_LIB.BASEBOARD_FAB2(SCH_1):M_K_BA(1)
  U2D1 EA54 DDR3_BA<1> SKX_EXT_B_BGA1-IC,TBD   I172 @BASEBOARD_FAB2_LIB.BASEBOARD_FAB2(SCH_1):PAGE60
  J1B1  224  BA<1> SCONN288_H44441004_PIP-SCONN,HA   I111 @BASEBOARD_FAB2_LIB.BASEBOARD_FAB2(SCH_1):PAGE83
  J9M1  224  BA<1> SCONN288_H44441003_PIP-SCONN,HA    I14 @BASEBOARD_FAB2_LIB.BASEBOARD_FAB2(SCH_1):PAGE84

M_K_BG<0> @BASEBOARD_FAB2_LIB.BASEBOARD_FAB2(SCH_1):M_K_BG(0)
  U2D1 ED61 DDR3_BG<0> SKX_EXT_B_BGA1-IC,TBD   I172 @BASEBOARD_FAB2_LIB.BASEBOARD_FAB2(SCH_1):PAGE60
  J1B1   63  BG<0> SCONN288_H44441004_PIP-SCONN,HA   I111 @BASEBOARD_FAB2_LIB.BASEBOARD_FAB2(SCH_1):PAGE83
  J9M1   63  BG<0> SCONN288_H44441003_PIP-SCONN,HA    I14 @BASEBOARD_FAB2_LIB.BASEBOARD_FAB2(SCH_1):PAGE84

M_K_BG<1> @BASEBOARD_FAB2_LIB.BASEBOARD_FAB2(SCH_1):M_K_BG(1)
  U2D1 DW62 DDR3_BG<1> SKX_EXT_B_BGA1-IC,TBD   I172 @BASEBOARD_FAB2_LIB.BASEBOARD_FAB2(SCH_1):PAGE60
  J1B1  207  BG<1> SCONN288_H44441004_PIP-SCONN,HA   I111 @BASEBOARD_FAB2_LIB.BASEBOARD_FAB2(SCH_1):PAGE83
  J9M1  207  BG<1> SCONN288_H44441003_PIP-SCONN,HA    I14 @BASEBOARD_FAB2_LIB.BASEBOARD_FAB2(SCH_1):PAGE84

M_K_C<2> @BASEBOARD_FAB2_LIB.BASEBOARD_FAB2(SCH_1):M_K_C(2)
  U2D1 DV47 DDR3_CID<2> SKX_EXT_B_BGA1-IC,TBD   I172 @BASEBOARD_FAB2_LIB.BASEBOARD_FAB2(SCH_1):PAGE60
  J1B1  235   C<2> SCONN288_H44441004_PIP-SCONN,HA   I111 @BASEBOARD_FAB2_LIB.BASEBOARD_FAB2(SCH_1):PAGE83
  J9M1  235   C<2> SCONN288_H44441003_PIP-SCONN,HA    I14 @BASEBOARD_FAB2_LIB.BASEBOARD_FAB2(SCH_1):PAGE84

M_K_CKE<0> @BASEBOARD_FAB2_LIB.BASEBOARD_FAB2(SCH_1):M_K_CKE(0)
  U2D1 EE62 DDR3_CKE<0> SKX_EXT_B_BGA1-IC,TBD   I172 @BASEBOARD_FAB2_LIB.BASEBOARD_FAB2(SCH_1):PAGE60
  J1B1   60 CKE<0> SCONN288_H44441004_PIP-SCONN,HA   I111 @BASEBOARD_FAB2_LIB.BASEBOARD_FAB2(SCH_1):PAGE83

M_K_CKE<1> @BASEBOARD_FAB2_LIB.BASEBOARD_FAB2(SCH_1):M_K_CKE(1)
  U2D1 EF63 DDR3_CKE<1> SKX_EXT_B_BGA1-IC,TBD   I172 @BASEBOARD_FAB2_LIB.BASEBOARD_FAB2(SCH_1):PAGE60
  J1B1  203 CKE<1> SCONN288_H44441004_PIP-SCONN,HA   I111 @BASEBOARD_FAB2_LIB.BASEBOARD_FAB2(SCH_1):PAGE83

M_K_CKE<2> @BASEBOARD_FAB2_LIB.BASEBOARD_FAB2(SCH_1):M_K_CKE(2)
  U2D1 EA62 DDR3_CKE<2> SKX_EXT_B_BGA1-IC,TBD   I172 @BASEBOARD_FAB2_LIB.BASEBOARD_FAB2(SCH_1):PAGE60
  J9M1   60 CKE<0> SCONN288_H44441003_PIP-SCONN,HA    I14 @BASEBOARD_FAB2_LIB.BASEBOARD_FAB2(SCH_1):PAGE84

M_K_CKE<3> @BASEBOARD_FAB2_LIB.BASEBOARD_FAB2(SCH_1):M_K_CKE(3)
  U2D1 EB63 DDR3_CKE<3> SKX_EXT_B_BGA1-IC,TBD   I172 @BASEBOARD_FAB2_LIB.BASEBOARD_FAB2(SCH_1):PAGE60
  J9M1  203 CKE<1> SCONN288_H44441003_PIP-SCONN,HA    I14 @BASEBOARD_FAB2_LIB.BASEBOARD_FAB2(SCH_1):PAGE84

M_K_CLK_DN<0> @BASEBOARD_FAB2_LIB.BASEBOARD_FAB2(SCH_1):M_K_CLK_DN(0)
  U2D1 ED55 DDR3_CLK_DN<0> SKX_EXT_B_BGA1-IC,TBD   I172 @BASEBOARD_FAB2_LIB.BASEBOARD_FAB2(SCH_1):PAGE60
  J1B1   75   CK0N SCONN288_H44441004_PIP-SCONN,HA   I111 @BASEBOARD_FAB2_LIB.BASEBOARD_FAB2(SCH_1):PAGE83

M_K_CLK_DN<1> @BASEBOARD_FAB2_LIB.BASEBOARD_FAB2(SCH_1):M_K_CLK_DN(1)
  U2D1 EF55 DDR3_CLK_DN<1> SKX_EXT_B_BGA1-IC,TBD   I172 @BASEBOARD_FAB2_LIB.BASEBOARD_FAB2(SCH_1):PAGE60
  J1B1  219   CK1N SCONN288_H44441004_PIP-SCONN,HA   I111 @BASEBOARD_FAB2_LIB.BASEBOARD_FAB2(SCH_1):PAGE83

M_K_CLK_DN<2> @BASEBOARD_FAB2_LIB.BASEBOARD_FAB2(SCH_1):M_K_CLK_DN(2)
  U2D1 DW56 DDR3_CLK_DN<2> SKX_EXT_B_BGA1-IC,TBD   I172 @BASEBOARD_FAB2_LIB.BASEBOARD_FAB2(SCH_1):PAGE60
  J9M1   75   CK0N SCONN288_H44441003_PIP-SCONN,HA    I14 @BASEBOARD_FAB2_LIB.BASEBOARD_FAB2(SCH_1):PAGE84

M_K_CLK_DN<3> @BASEBOARD_FAB2_LIB.BASEBOARD_FAB2(SCH_1):M_K_CLK_DN(3)
  U2D1 EF57 DDR3_CLK_DN<3> SKX_EXT_B_BGA1-IC,TBD   I172 @BASEBOARD_FAB2_LIB.BASEBOARD_FAB2(SCH_1):PAGE60
  J9M1  219   CK1N SCONN288_H44441003_PIP-SCONN,HA    I14 @BASEBOARD_FAB2_LIB.BASEBOARD_FAB2(SCH_1):PAGE84

M_K_CLK_DP<0> @BASEBOARD_FAB2_LIB.BASEBOARD_FAB2(SCH_1):M_K_CLK_DP(0)
  U2D1 EB55 DDR3_CLK_DP<0> SKX_EXT_B_BGA1-IC,TBD   I172 @BASEBOARD_FAB2_LIB.BASEBOARD_FAB2(SCH_1):PAGE60
  J1B1   74   CK0P SCONN288_H44441004_PIP-SCONN,HA   I111 @BASEBOARD_FAB2_LIB.BASEBOARD_FAB2(SCH_1):PAGE83

M_K_CLK_DP<1> @BASEBOARD_FAB2_LIB.BASEBOARD_FAB2(SCH_1):M_K_CLK_DP(1)
  U2D1 EE54 DDR3_CLK_DP<1> SKX_EXT_B_BGA1-IC,TBD   I172 @BASEBOARD_FAB2_LIB.BASEBOARD_FAB2(SCH_1):PAGE60
  J1B1  218   CK1P SCONN288_H44441004_PIP-SCONN,HA   I111 @BASEBOARD_FAB2_LIB.BASEBOARD_FAB2(SCH_1):PAGE83

M_K_CLK_DP<2> @BASEBOARD_FAB2_LIB.BASEBOARD_FAB2(SCH_1):M_K_CLK_DP(2)
  U2D1 EA56 DDR3_CLK_DP<2> SKX_EXT_B_BGA1-IC,TBD   I172 @BASEBOARD_FAB2_LIB.BASEBOARD_FAB2(SCH_1):PAGE60
  J9M1   74   CK0P SCONN288_H44441003_PIP-SCONN,HA    I14 @BASEBOARD_FAB2_LIB.BASEBOARD_FAB2(SCH_1):PAGE84

M_K_CLK_DP<3> @BASEBOARD_FAB2_LIB.BASEBOARD_FAB2(SCH_1):M_K_CLK_DP(3)
  U2D1 EE56 DDR3_CLK_DP<3> SKX_EXT_B_BGA1-IC,TBD   I172 @BASEBOARD_FAB2_LIB.BASEBOARD_FAB2(SCH_1):PAGE60
  J9M1  218   CK1P SCONN288_H44441003_PIP-SCONN,HA    I14 @BASEBOARD_FAB2_LIB.BASEBOARD_FAB2(SCH_1):PAGE84

M_K_CPU_VREF @BASEBOARD_FAB2_LIB.BASEBOARD_FAB2(SCH_1):M_K_CPU_VREF
  U2D1 CP61 DDR3_CAVREF SKX_EXT_B_BGA1-IC,TBD   I172 @BASEBOARD_FAB2_LIB.BASEBOARD_FAB2(SCH_1):PAGE55
  R9M2    1      A RES_0402-2,1.0%,1/16W,CHIP,G21A    I13 @BASEBOARD_FAB2_LIB.BASEBOARD_FAB2(SCH_1):PAGE100
  C9M2    1      A CAP_A_0402V-0.01UF,25V,10%,X7RA    I15 @BASEBOARD_FAB2_LIB.BASEBOARD_FAB2(SCH_1):PAGE100

M_K_CS_N<0> @BASEBOARD_FAB2_LIB.BASEBOARD_FAB2(SCH_1):M_K_CS_N(0)
  U2D1 EF51 DDR3_CS_N<0> SKX_EXT_B_BGA1-IC,TBD   I172 @BASEBOARD_FAB2_LIB.BASEBOARD_FAB2(SCH_1):PAGE60
  J1B1   84   S0_N SCONN288_H44441004_PIP-SCONN,HA   I111 @BASEBOARD_FAB2_LIB.BASEBOARD_FAB2(SCH_1):PAGE83

M_K_CS_N<1> @BASEBOARD_FAB2_LIB.BASEBOARD_FAB2(SCH_1):M_K_CS_N(1)
  U2D1 ED49 DDR3_CS_N<1> SKX_EXT_B_BGA1-IC,TBD   I172 @BASEBOARD_FAB2_LIB.BASEBOARD_FAB2(SCH_1):PAGE60
  J1B1   89   S1_N SCONN288_H44441004_PIP-SCONN,HA   I111 @BASEBOARD_FAB2_LIB.BASEBOARD_FAB2(SCH_1):PAGE83

M_K_CS_N<2> @BASEBOARD_FAB2_LIB.BASEBOARD_FAB2(SCH_1):M_K_CS_N(2)
  U2D1 ED47 DDR3_CS_N<2> SKX_EXT_B_BGA1-IC,TBD   I172 @BASEBOARD_FAB2_LIB.BASEBOARD_FAB2(SCH_1):PAGE60
  J1B1   93 S2_N_C<0> SCONN288_H44441004_PIP-SCONN,HA   I111 @BASEBOARD_FAB2_LIB.BASEBOARD_FAB2(SCH_1):PAGE83

M_K_CS_N<3> @BASEBOARD_FAB2_LIB.BASEBOARD_FAB2(SCH_1):M_K_CS_N(3)
  U2D1 EB47 DDR3_CS_N<3> SKX_EXT_B_BGA1-IC,TBD   I172 @BASEBOARD_FAB2_LIB.BASEBOARD_FAB2(SCH_1):PAGE60
  J1B1  237 S3_N_C<1> SCONN288_H44441004_PIP-SCONN,HA   I111 @BASEBOARD_FAB2_LIB.BASEBOARD_FAB2(SCH_1):PAGE83

M_K_CS_N<4> @BASEBOARD_FAB2_LIB.BASEBOARD_FAB2(SCH_1):M_K_CS_N(4)
  U2D1 EB51 DDR3_CS_N<4> SKX_EXT_B_BGA1-IC,TBD   I172 @BASEBOARD_FAB2_LIB.BASEBOARD_FAB2(SCH_1):PAGE60
  J9M1   84   S0_N SCONN288_H44441003_PIP-SCONN,HA    I14 @BASEBOARD_FAB2_LIB.BASEBOARD_FAB2(SCH_1):PAGE84

M_K_CS_N<5> @BASEBOARD_FAB2_LIB.BASEBOARD_FAB2(SCH_1):M_K_CS_N(5)
  U2D1 EB49 DDR3_CS_N<5> SKX_EXT_B_BGA1-IC,TBD   I172 @BASEBOARD_FAB2_LIB.BASEBOARD_FAB2(SCH_1):PAGE60
  J9M1   89   S1_N SCONN288_H44441003_PIP-SCONN,HA    I14 @BASEBOARD_FAB2_LIB.BASEBOARD_FAB2(SCH_1):PAGE84

M_K_CS_N<6> @BASEBOARD_FAB2_LIB.BASEBOARD_FAB2(SCH_1):M_K_CS_N(6)
  U2D1 DV45 DDR3_CS_N<6> SKX_EXT_B_BGA1-IC,TBD   I172 @BASEBOARD_FAB2_LIB.BASEBOARD_FAB2(SCH_1):PAGE60
  J9M1   93 S2_N_C<0> SCONN288_H44441003_PIP-SCONN,HA    I14 @BASEBOARD_FAB2_LIB.BASEBOARD_FAB2(SCH_1):PAGE84

M_K_CS_N<7> @BASEBOARD_FAB2_LIB.BASEBOARD_FAB2(SCH_1):M_K_CS_N(7)
  U2D1 EB45 DDR3_CS_N<7> SKX_EXT_B_BGA1-IC,TBD   I172 @BASEBOARD_FAB2_LIB.BASEBOARD_FAB2(SCH_1):PAGE60
  J9M1  237 S3_N_C<1> SCONN288_H44441003_PIP-SCONN,HA    I14 @BASEBOARD_FAB2_LIB.BASEBOARD_FAB2(SCH_1):PAGE84

M_K_DQ<0> @BASEBOARD_FAB2_LIB.BASEBOARD_FAB2(SCH_1):M_K_DQ(0)
  U2D1 CN84 DDR3_DQ<0> SKX_EXT_B_BGA1-IC,TBD   I172 @BASEBOARD_FAB2_LIB.BASEBOARD_FAB2(SCH_1):PAGE60
  J1B1  150  DQ<1> SCONN288_H44441004_PIP-SCONN,HA   I111 @BASEBOARD_FAB2_LIB.BASEBOARD_FAB2(SCH_1):PAGE83
  J9M1    5  DQ<0> SCONN288_H44441003_PIP-SCONN,HA    I14 @BASEBOARD_FAB2_LIB.BASEBOARD_FAB2(SCH_1):PAGE84

M_K_DQ<10> @BASEBOARD_FAB2_LIB.BASEBOARD_FAB2(SCH_1):M_K_DQ(10)
  U2D1 DV83 DDR3_DQ<10> SKX_EXT_B_BGA1-IC,TBD   I172 @BASEBOARD_FAB2_LIB.BASEBOARD_FAB2(SCH_1):PAGE60
  J1B1  168 DQ<11> SCONN288_H44441004_PIP-SCONN,HA   I111 @BASEBOARD_FAB2_LIB.BASEBOARD_FAB2(SCH_1):PAGE83
  J9M1   23 DQ<10> SCONN288_H44441003_PIP-SCONN,HA    I14 @BASEBOARD_FAB2_LIB.BASEBOARD_FAB2(SCH_1):PAGE84

M_K_DQ<11> @BASEBOARD_FAB2_LIB.BASEBOARD_FAB2(SCH_1):M_K_DQ(11)
  U2D1 DY83 DDR3_DQ<11> SKX_EXT_B_BGA1-IC,TBD   I172 @BASEBOARD_FAB2_LIB.BASEBOARD_FAB2(SCH_1):PAGE60
  J1B1   23 DQ<10> SCONN288_H44441004_PIP-SCONN,HA   I111 @BASEBOARD_FAB2_LIB.BASEBOARD_FAB2(SCH_1):PAGE83
  J9M1  168 DQ<11> SCONN288_H44441003_PIP-SCONN,HA    I14 @BASEBOARD_FAB2_LIB.BASEBOARD_FAB2(SCH_1):PAGE84

M_K_DQ<12> @BASEBOARD_FAB2_LIB.BASEBOARD_FAB2(SCH_1):M_K_DQ(12)
  U2D1 DD85 DDR3_DQ<12> SKX_EXT_B_BGA1-IC,TBD   I172 @BASEBOARD_FAB2_LIB.BASEBOARD_FAB2(SCH_1):PAGE60
  J1B1  159 DQ<13> SCONN288_H44441004_PIP-SCONN,HA   I111 @BASEBOARD_FAB2_LIB.BASEBOARD_FAB2(SCH_1):PAGE83
  J9M1   14 DQ<12> SCONN288_H44441003_PIP-SCONN,HA    I14 @BASEBOARD_FAB2_LIB.BASEBOARD_FAB2(SCH_1):PAGE84

M_K_DQ<13> @BASEBOARD_FAB2_LIB.BASEBOARD_FAB2(SCH_1):M_K_DQ(13)
  U2D1 DE84 DDR3_DQ<13> SKX_EXT_B_BGA1-IC,TBD   I172 @BASEBOARD_FAB2_LIB.BASEBOARD_FAB2(SCH_1):PAGE60
  J1B1   14 DQ<12> SCONN288_H44441004_PIP-SCONN,HA   I111 @BASEBOARD_FAB2_LIB.BASEBOARD_FAB2(SCH_1):PAGE83
  J9M1  159 DQ<13> SCONN288_H44441003_PIP-SCONN,HA    I14 @BASEBOARD_FAB2_LIB.BASEBOARD_FAB2(SCH_1):PAGE84

M_K_DQ<14> @BASEBOARD_FAB2_LIB.BASEBOARD_FAB2(SCH_1):M_K_DQ(14)
  U2D1 DR84 DDR3_DQ<14> SKX_EXT_B_BGA1-IC,TBD   I172 @BASEBOARD_FAB2_LIB.BASEBOARD_FAB2(SCH_1):PAGE60
  J1B1  166 DQ<15> SCONN288_H44441004_PIP-SCONN,HA   I111 @BASEBOARD_FAB2_LIB.BASEBOARD_FAB2(SCH_1):PAGE83
  J9M1   21 DQ<14> SCONN288_H44441003_PIP-SCONN,HA    I14 @BASEBOARD_FAB2_LIB.BASEBOARD_FAB2(SCH_1):PAGE84

M_K_DQ<15> @BASEBOARD_FAB2_LIB.BASEBOARD_FAB2(SCH_1):M_K_DQ(15)
  U2D1 DV85 DDR3_DQ<15> SKX_EXT_B_BGA1-IC,TBD   I172 @BASEBOARD_FAB2_LIB.BASEBOARD_FAB2(SCH_1):PAGE60
  J1B1   21 DQ<14> SCONN288_H44441004_PIP-SCONN,HA   I111 @BASEBOARD_FAB2_LIB.BASEBOARD_FAB2(SCH_1):PAGE83
  J9M1  166 DQ<15> SCONN288_H44441003_PIP-SCONN,HA    I14 @BASEBOARD_FAB2_LIB.BASEBOARD_FAB2(SCH_1):PAGE84

M_K_DQ<16> @BASEBOARD_FAB2_LIB.BASEBOARD_FAB2(SCH_1):M_K_DQ(16)
  U2D1 DM79 DDR3_DQ<16> SKX_EXT_B_BGA1-IC,TBD   I172 @BASEBOARD_FAB2_LIB.BASEBOARD_FAB2(SCH_1):PAGE60
  J1B1  172 DQ<17> SCONN288_H44441004_PIP-SCONN,HA   I111 @BASEBOARD_FAB2_LIB.BASEBOARD_FAB2(SCH_1):PAGE83
  J9M1   27 DQ<16> SCONN288_H44441003_PIP-SCONN,HA    I14 @BASEBOARD_FAB2_LIB.BASEBOARD_FAB2(SCH_1):PAGE84

M_K_DQ<17> @BASEBOARD_FAB2_LIB.BASEBOARD_FAB2(SCH_1):M_K_DQ(17)
  U2D1 DK81 DDR3_DQ<17> SKX_EXT_B_BGA1-IC,TBD   I172 @BASEBOARD_FAB2_LIB.BASEBOARD_FAB2(SCH_1):PAGE60
  J1B1   27 DQ<16> SCONN288_H44441004_PIP-SCONN,HA   I111 @BASEBOARD_FAB2_LIB.BASEBOARD_FAB2(SCH_1):PAGE83
  J9M1  172 DQ<17> SCONN288_H44441003_PIP-SCONN,HA    I14 @BASEBOARD_FAB2_LIB.BASEBOARD_FAB2(SCH_1):PAGE84

M_K_DQ<18> @BASEBOARD_FAB2_LIB.BASEBOARD_FAB2(SCH_1):M_K_DQ(18)
  U2D1 DT81 DDR3_DQ<18> SKX_EXT_B_BGA1-IC,TBD   I172 @BASEBOARD_FAB2_LIB.BASEBOARD_FAB2(SCH_1):PAGE60
  J1B1  179 DQ<19> SCONN288_H44441004_PIP-SCONN,HA   I111 @BASEBOARD_FAB2_LIB.BASEBOARD_FAB2(SCH_1):PAGE83
  J9M1   34 DQ<18> SCONN288_H44441003_PIP-SCONN,HA    I14 @BASEBOARD_FAB2_LIB.BASEBOARD_FAB2(SCH_1):PAGE84

M_K_DQ<19> @BASEBOARD_FAB2_LIB.BASEBOARD_FAB2(SCH_1):M_K_DQ(19)
  U2D1 DR82 DDR3_DQ<19> SKX_EXT_B_BGA1-IC,TBD   I172 @BASEBOARD_FAB2_LIB.BASEBOARD_FAB2(SCH_1):PAGE60
  J1B1   34 DQ<18> SCONN288_H44441004_PIP-SCONN,HA   I111 @BASEBOARD_FAB2_LIB.BASEBOARD_FAB2(SCH_1):PAGE83
  J9M1  179 DQ<19> SCONN288_H44441003_PIP-SCONN,HA    I14 @BASEBOARD_FAB2_LIB.BASEBOARD_FAB2(SCH_1):PAGE84

M_K_DQ<1> @BASEBOARD_FAB2_LIB.BASEBOARD_FAB2(SCH_1):M_K_DQ(1)
  U2D1 CN86 DDR3_DQ<1> SKX_EXT_B_BGA1-IC,TBD   I172 @BASEBOARD_FAB2_LIB.BASEBOARD_FAB2(SCH_1):PAGE60
  J1B1    5  DQ<0> SCONN288_H44441004_PIP-SCONN,HA   I111 @BASEBOARD_FAB2_LIB.BASEBOARD_FAB2(SCH_1):PAGE83
  J9M1  150  DQ<1> SCONN288_H44441003_PIP-SCONN,HA    I14 @BASEBOARD_FAB2_LIB.BASEBOARD_FAB2(SCH_1):PAGE84

M_K_DQ<20> @BASEBOARD_FAB2_LIB.BASEBOARD_FAB2(SCH_1):M_K_DQ(20)
  U2D1 DK79 DDR3_DQ<20> SKX_EXT_B_BGA1-IC,TBD   I172 @BASEBOARD_FAB2_LIB.BASEBOARD_FAB2(SCH_1):PAGE60
  J1B1  170 DQ<21> SCONN288_H44441004_PIP-SCONN,HA   I111 @BASEBOARD_FAB2_LIB.BASEBOARD_FAB2(SCH_1):PAGE83
  J9M1   25 DQ<20> SCONN288_H44441003_PIP-SCONN,HA    I14 @BASEBOARD_FAB2_LIB.BASEBOARD_FAB2(SCH_1):PAGE84

M_K_DQ<21> @BASEBOARD_FAB2_LIB.BASEBOARD_FAB2(SCH_1):M_K_DQ(21)
  U2D1 DJ80 DDR3_DQ<21> SKX_EXT_B_BGA1-IC,TBD   I172 @BASEBOARD_FAB2_LIB.BASEBOARD_FAB2(SCH_1):PAGE60
  J1B1   25 DQ<20> SCONN288_H44441004_PIP-SCONN,HA   I111 @BASEBOARD_FAB2_LIB.BASEBOARD_FAB2(SCH_1):PAGE83
  J9M1  170 DQ<21> SCONN288_H44441003_PIP-SCONN,HA    I14 @BASEBOARD_FAB2_LIB.BASEBOARD_FAB2(SCH_1):PAGE84

M_K_DQ<22> @BASEBOARD_FAB2_LIB.BASEBOARD_FAB2(SCH_1):M_K_DQ(22)
  U2D1 DR80 DDR3_DQ<22> SKX_EXT_B_BGA1-IC,TBD   I172 @BASEBOARD_FAB2_LIB.BASEBOARD_FAB2(SCH_1):PAGE60
  J1B1  177 DQ<23> SCONN288_H44441004_PIP-SCONN,HA   I111 @BASEBOARD_FAB2_LIB.BASEBOARD_FAB2(SCH_1):PAGE83
  J9M1   32 DQ<22> SCONN288_H44441003_PIP-SCONN,HA    I14 @BASEBOARD_FAB2_LIB.BASEBOARD_FAB2(SCH_1):PAGE84

M_K_DQ<23> @BASEBOARD_FAB2_LIB.BASEBOARD_FAB2(SCH_1):M_K_DQ(23)
  U2D1 DN82 DDR3_DQ<23> SKX_EXT_B_BGA1-IC,TBD   I172 @BASEBOARD_FAB2_LIB.BASEBOARD_FAB2(SCH_1):PAGE60
  J1B1   32 DQ<22> SCONN288_H44441004_PIP-SCONN,HA   I111 @BASEBOARD_FAB2_LIB.BASEBOARD_FAB2(SCH_1):PAGE83
  J9M1  177 DQ<23> SCONN288_H44441003_PIP-SCONN,HA    I14 @BASEBOARD_FAB2_LIB.BASEBOARD_FAB2(SCH_1):PAGE84

M_K_DQ<24> @BASEBOARD_FAB2_LIB.BASEBOARD_FAB2(SCH_1):M_K_DQ(24)
  U2D1 DN76 DDR3_DQ<24> SKX_EXT_B_BGA1-IC,TBD   I172 @BASEBOARD_FAB2_LIB.BASEBOARD_FAB2(SCH_1):PAGE60
  J1B1  183 DQ<25> SCONN288_H44441004_PIP-SCONN,HA   I111 @BASEBOARD_FAB2_LIB.BASEBOARD_FAB2(SCH_1):PAGE83
  J9M1   38 DQ<24> SCONN288_H44441003_PIP-SCONN,HA    I14 @BASEBOARD_FAB2_LIB.BASEBOARD_FAB2(SCH_1):PAGE84

M_K_DQ<25> @BASEBOARD_FAB2_LIB.BASEBOARD_FAB2(SCH_1):M_K_DQ(25)
  U2D1 DU76 DDR3_DQ<25> SKX_EXT_B_BGA1-IC,TBD   I172 @BASEBOARD_FAB2_LIB.BASEBOARD_FAB2(SCH_1):PAGE60
  J1B1   38 DQ<24> SCONN288_H44441004_PIP-SCONN,HA   I111 @BASEBOARD_FAB2_LIB.BASEBOARD_FAB2(SCH_1):PAGE83
  J9M1  183 DQ<25> SCONN288_H44441003_PIP-SCONN,HA    I14 @BASEBOARD_FAB2_LIB.BASEBOARD_FAB2(SCH_1):PAGE84

M_K_DQ<26> @BASEBOARD_FAB2_LIB.BASEBOARD_FAB2(SCH_1):M_K_DQ(26)
  U2D1 DP73 DDR3_DQ<26> SKX_EXT_B_BGA1-IC,TBD   I172 @BASEBOARD_FAB2_LIB.BASEBOARD_FAB2(SCH_1):PAGE60
  J1B1  190 DQ<27> SCONN288_H44441004_PIP-SCONN,HA   I111 @BASEBOARD_FAB2_LIB.BASEBOARD_FAB2(SCH_1):PAGE83
  J9M1   45 DQ<26> SCONN288_H44441003_PIP-SCONN,HA    I14 @BASEBOARD_FAB2_LIB.BASEBOARD_FAB2(SCH_1):PAGE84

M_K_DQ<27> @BASEBOARD_FAB2_LIB.BASEBOARD_FAB2(SCH_1):M_K_DQ(27)
  U2D1 DT73 DDR3_DQ<27> SKX_EXT_B_BGA1-IC,TBD   I172 @BASEBOARD_FAB2_LIB.BASEBOARD_FAB2(SCH_1):PAGE60
  J1B1   45 DQ<26> SCONN288_H44441004_PIP-SCONN,HA   I111 @BASEBOARD_FAB2_LIB.BASEBOARD_FAB2(SCH_1):PAGE83
  J9M1  190 DQ<27> SCONN288_H44441003_PIP-SCONN,HA    I14 @BASEBOARD_FAB2_LIB.BASEBOARD_FAB2(SCH_1):PAGE84

M_K_DQ<28> @BASEBOARD_FAB2_LIB.BASEBOARD_FAB2(SCH_1):M_K_DQ(28)
  U2D1 DP77 DDR3_DQ<28> SKX_EXT_B_BGA1-IC,TBD   I172 @BASEBOARD_FAB2_LIB.BASEBOARD_FAB2(SCH_1):PAGE60
  J1B1  181 DQ<29> SCONN288_H44441004_PIP-SCONN,HA   I111 @BASEBOARD_FAB2_LIB.BASEBOARD_FAB2(SCH_1):PAGE83
  J9M1   36 DQ<28> SCONN288_H44441003_PIP-SCONN,HA    I14 @BASEBOARD_FAB2_LIB.BASEBOARD_FAB2(SCH_1):PAGE84

M_K_DQ<29> @BASEBOARD_FAB2_LIB.BASEBOARD_FAB2(SCH_1):M_K_DQ(29)
  U2D1 DT77 DDR3_DQ<29> SKX_EXT_B_BGA1-IC,TBD   I172 @BASEBOARD_FAB2_LIB.BASEBOARD_FAB2(SCH_1):PAGE60
  J1B1   36 DQ<28> SCONN288_H44441004_PIP-SCONN,HA   I111 @BASEBOARD_FAB2_LIB.BASEBOARD_FAB2(SCH_1):PAGE83
  J9M1  181 DQ<29> SCONN288_H44441003_PIP-SCONN,HA    I14 @BASEBOARD_FAB2_LIB.BASEBOARD_FAB2(SCH_1):PAGE84

M_K_DQ<2> @BASEBOARD_FAB2_LIB.BASEBOARD_FAB2(SCH_1):M_K_DQ(2)
  U2D1 DA86 DDR3_DQ<2> SKX_EXT_B_BGA1-IC,TBD   I172 @BASEBOARD_FAB2_LIB.BASEBOARD_FAB2(SCH_1):PAGE60
  J1B1  157  DQ<3> SCONN288_H44441004_PIP-SCONN,HA   I111 @BASEBOARD_FAB2_LIB.BASEBOARD_FAB2(SCH_1):PAGE83
  J9M1   12  DQ<2> SCONN288_H44441003_PIP-SCONN,HA    I14 @BASEBOARD_FAB2_LIB.BASEBOARD_FAB2(SCH_1):PAGE84

M_K_DQ<30> @BASEBOARD_FAB2_LIB.BASEBOARD_FAB2(SCH_1):M_K_DQ(30)
  U2D1 DN74 DDR3_DQ<30> SKX_EXT_B_BGA1-IC,TBD   I172 @BASEBOARD_FAB2_LIB.BASEBOARD_FAB2(SCH_1):PAGE60
  J1B1  188 DQ<31> SCONN288_H44441004_PIP-SCONN,HA   I111 @BASEBOARD_FAB2_LIB.BASEBOARD_FAB2(SCH_1):PAGE83
  J9M1   43 DQ<30> SCONN288_H44441003_PIP-SCONN,HA    I14 @BASEBOARD_FAB2_LIB.BASEBOARD_FAB2(SCH_1):PAGE84

M_K_DQ<31> @BASEBOARD_FAB2_LIB.BASEBOARD_FAB2(SCH_1):M_K_DQ(31)
  U2D1 DU74 DDR3_DQ<31> SKX_EXT_B_BGA1-IC,TBD   I172 @BASEBOARD_FAB2_LIB.BASEBOARD_FAB2(SCH_1):PAGE60
  J1B1   43 DQ<30> SCONN288_H44441004_PIP-SCONN,HA   I111 @BASEBOARD_FAB2_LIB.BASEBOARD_FAB2(SCH_1):PAGE83
  J9M1  188 DQ<31> SCONN288_H44441003_PIP-SCONN,HA    I14 @BASEBOARD_FAB2_LIB.BASEBOARD_FAB2(SCH_1):PAGE84

M_K_DQ<32> @BASEBOARD_FAB2_LIB.BASEBOARD_FAB2(SCH_1):M_K_DQ(32)
  U2D1 EC40 DDR3_DQ<32> SKX_EXT_B_BGA1-IC,TBD   I172 @BASEBOARD_FAB2_LIB.BASEBOARD_FAB2(SCH_1):PAGE60
  J1B1  242 DQ<33> SCONN288_H44441004_PIP-SCONN,HA   I111 @BASEBOARD_FAB2_LIB.BASEBOARD_FAB2(SCH_1):PAGE83
  J9M1   97 DQ<32> SCONN288_H44441003_PIP-SCONN,HA    I14 @BASEBOARD_FAB2_LIB.BASEBOARD_FAB2(SCH_1):PAGE84

M_K_DQ<33> @BASEBOARD_FAB2_LIB.BASEBOARD_FAB2(SCH_1):M_K_DQ(33)
  U2D1 ED39 DDR3_DQ<33> SKX_EXT_B_BGA1-IC,TBD   I172 @BASEBOARD_FAB2_LIB.BASEBOARD_FAB2(SCH_1):PAGE60
  J1B1   97 DQ<32> SCONN288_H44441004_PIP-SCONN,HA   I111 @BASEBOARD_FAB2_LIB.BASEBOARD_FAB2(SCH_1):PAGE83
  J9M1  242 DQ<33> SCONN288_H44441003_PIP-SCONN,HA    I14 @BASEBOARD_FAB2_LIB.BASEBOARD_FAB2(SCH_1):PAGE84

M_K_DQ<34> @BASEBOARD_FAB2_LIB.BASEBOARD_FAB2(SCH_1):M_K_DQ(34)
  U2D1 EA36 DDR3_DQ<34> SKX_EXT_B_BGA1-IC,TBD   I172 @BASEBOARD_FAB2_LIB.BASEBOARD_FAB2(SCH_1):PAGE60
  J1B1  249 DQ<35> SCONN288_H44441004_PIP-SCONN,HA   I111 @BASEBOARD_FAB2_LIB.BASEBOARD_FAB2(SCH_1):PAGE83
  J9M1  104 DQ<34> SCONN288_H44441003_PIP-SCONN,HA    I14 @BASEBOARD_FAB2_LIB.BASEBOARD_FAB2(SCH_1):PAGE84

M_K_DQ<35> @BASEBOARD_FAB2_LIB.BASEBOARD_FAB2(SCH_1):M_K_DQ(35)
  U2D1 EC36 DDR3_DQ<35> SKX_EXT_B_BGA1-IC,TBD   I172 @BASEBOARD_FAB2_LIB.BASEBOARD_FAB2(SCH_1):PAGE60
  J1B1  104 DQ<34> SCONN288_H44441004_PIP-SCONN,HA   I111 @BASEBOARD_FAB2_LIB.BASEBOARD_FAB2(SCH_1):PAGE83
  J9M1  249 DQ<35> SCONN288_H44441003_PIP-SCONN,HA    I14 @BASEBOARD_FAB2_LIB.BASEBOARD_FAB2(SCH_1):PAGE84

M_K_DQ<36> @BASEBOARD_FAB2_LIB.BASEBOARD_FAB2(SCH_1):M_K_DQ(36)
  U2D1 DY39 DDR3_DQ<36> SKX_EXT_B_BGA1-IC,TBD   I172 @BASEBOARD_FAB2_LIB.BASEBOARD_FAB2(SCH_1):PAGE60
  J1B1  240 DQ<37> SCONN288_H44441004_PIP-SCONN,HA   I111 @BASEBOARD_FAB2_LIB.BASEBOARD_FAB2(SCH_1):PAGE83
  J9M1   95 DQ<36> SCONN288_H44441003_PIP-SCONN,HA    I14 @BASEBOARD_FAB2_LIB.BASEBOARD_FAB2(SCH_1):PAGE84

M_K_DQ<37> @BASEBOARD_FAB2_LIB.BASEBOARD_FAB2(SCH_1):M_K_DQ(37)
  U2D1 EA40 DDR3_DQ<37> SKX_EXT_B_BGA1-IC,TBD   I172 @BASEBOARD_FAB2_LIB.BASEBOARD_FAB2(SCH_1):PAGE60
  J1B1   95 DQ<36> SCONN288_H44441004_PIP-SCONN,HA   I111 @BASEBOARD_FAB2_LIB.BASEBOARD_FAB2(SCH_1):PAGE83
  J9M1  240 DQ<37> SCONN288_H44441003_PIP-SCONN,HA    I14 @BASEBOARD_FAB2_LIB.BASEBOARD_FAB2(SCH_1):PAGE84

M_K_DQ<38> @BASEBOARD_FAB2_LIB.BASEBOARD_FAB2(SCH_1):M_K_DQ(38)
  U2D1 DY37 DDR3_DQ<38> SKX_EXT_B_BGA1-IC,TBD   I172 @BASEBOARD_FAB2_LIB.BASEBOARD_FAB2(SCH_1):PAGE60
  J1B1  247 DQ<39> SCONN288_H44441004_PIP-SCONN,HA   I111 @BASEBOARD_FAB2_LIB.BASEBOARD_FAB2(SCH_1):PAGE83
  J9M1  102 DQ<38> SCONN288_H44441003_PIP-SCONN,HA    I14 @BASEBOARD_FAB2_LIB.BASEBOARD_FAB2(SCH_1):PAGE84

M_K_DQ<39> @BASEBOARD_FAB2_LIB.BASEBOARD_FAB2(SCH_1):M_K_DQ(39)
  U2D1 ED37 DDR3_DQ<39> SKX_EXT_B_BGA1-IC,TBD   I172 @BASEBOARD_FAB2_LIB.BASEBOARD_FAB2(SCH_1):PAGE60
  J1B1  102 DQ<38> SCONN288_H44441004_PIP-SCONN,HA   I111 @BASEBOARD_FAB2_LIB.BASEBOARD_FAB2(SCH_1):PAGE83
  J9M1  247 DQ<39> SCONN288_H44441003_PIP-SCONN,HA    I14 @BASEBOARD_FAB2_LIB.BASEBOARD_FAB2(SCH_1):PAGE84

M_K_DQ<3> @BASEBOARD_FAB2_LIB.BASEBOARD_FAB2(SCH_1):M_K_DQ(3)
  U2D1 DA84 DDR3_DQ<3> SKX_EXT_B_BGA1-IC,TBD   I172 @BASEBOARD_FAB2_LIB.BASEBOARD_FAB2(SCH_1):PAGE60
  J1B1   12  DQ<2> SCONN288_H44441004_PIP-SCONN,HA   I111 @BASEBOARD_FAB2_LIB.BASEBOARD_FAB2(SCH_1):PAGE83
  J9M1  157  DQ<3> SCONN288_H44441003_PIP-SCONN,HA    I14 @BASEBOARD_FAB2_LIB.BASEBOARD_FAB2(SCH_1):PAGE84

M_K_DQ<40> @BASEBOARD_FAB2_LIB.BASEBOARD_FAB2(SCH_1):M_K_DQ(40)
  U2D1 DN36 DDR3_DQ<40> SKX_EXT_B_BGA1-IC,TBD   I172 @BASEBOARD_FAB2_LIB.BASEBOARD_FAB2(SCH_1):PAGE60
  J1B1  253 DQ<41> SCONN288_H44441004_PIP-SCONN,HA   I111 @BASEBOARD_FAB2_LIB.BASEBOARD_FAB2(SCH_1):PAGE83
  J9M1  108 DQ<40> SCONN288_H44441003_PIP-SCONN,HA    I14 @BASEBOARD_FAB2_LIB.BASEBOARD_FAB2(SCH_1):PAGE84

M_K_DQ<41> @BASEBOARD_FAB2_LIB.BASEBOARD_FAB2(SCH_1):M_K_DQ(41)
  U2D1 DU36 DDR3_DQ<41> SKX_EXT_B_BGA1-IC,TBD   I172 @BASEBOARD_FAB2_LIB.BASEBOARD_FAB2(SCH_1):PAGE60
  J1B1  108 DQ<40> SCONN288_H44441004_PIP-SCONN,HA   I111 @BASEBOARD_FAB2_LIB.BASEBOARD_FAB2(SCH_1):PAGE83
  J9M1  253 DQ<41> SCONN288_H44441003_PIP-SCONN,HA    I14 @BASEBOARD_FAB2_LIB.BASEBOARD_FAB2(SCH_1):PAGE84

M_K_DQ<42> @BASEBOARD_FAB2_LIB.BASEBOARD_FAB2(SCH_1):M_K_DQ(42)
  U2D1 DP33 DDR3_DQ<42> SKX_EXT_B_BGA1-IC,TBD   I172 @BASEBOARD_FAB2_LIB.BASEBOARD_FAB2(SCH_1):PAGE60
  J1B1  260 DQ<43> SCONN288_H44441004_PIP-SCONN,HA   I111 @BASEBOARD_FAB2_LIB.BASEBOARD_FAB2(SCH_1):PAGE83
  J9M1  115 DQ<42> SCONN288_H44441003_PIP-SCONN,HA    I14 @BASEBOARD_FAB2_LIB.BASEBOARD_FAB2(SCH_1):PAGE84

M_K_DQ<43> @BASEBOARD_FAB2_LIB.BASEBOARD_FAB2(SCH_1):M_K_DQ(43)
  U2D1 DT33 DDR3_DQ<43> SKX_EXT_B_BGA1-IC,TBD   I172 @BASEBOARD_FAB2_LIB.BASEBOARD_FAB2(SCH_1):PAGE60
  J1B1  115 DQ<42> SCONN288_H44441004_PIP-SCONN,HA   I111 @BASEBOARD_FAB2_LIB.BASEBOARD_FAB2(SCH_1):PAGE83
  J9M1  260 DQ<43> SCONN288_H44441003_PIP-SCONN,HA    I14 @BASEBOARD_FAB2_LIB.BASEBOARD_FAB2(SCH_1):PAGE84

M_K_DQ<44> @BASEBOARD_FAB2_LIB.BASEBOARD_FAB2(SCH_1):M_K_DQ(44)
  U2D1 DP37 DDR3_DQ<44> SKX_EXT_B_BGA1-IC,TBD   I172 @BASEBOARD_FAB2_LIB.BASEBOARD_FAB2(SCH_1):PAGE60
  J1B1  251 DQ<45> SCONN288_H44441004_PIP-SCONN,HA   I111 @BASEBOARD_FAB2_LIB.BASEBOARD_FAB2(SCH_1):PAGE83
  J9M1  106 DQ<44> SCONN288_H44441003_PIP-SCONN,HA    I14 @BASEBOARD_FAB2_LIB.BASEBOARD_FAB2(SCH_1):PAGE84

M_K_DQ<45> @BASEBOARD_FAB2_LIB.BASEBOARD_FAB2(SCH_1):M_K_DQ(45)
  U2D1 DT37 DDR3_DQ<45> SKX_EXT_B_BGA1-IC,TBD   I172 @BASEBOARD_FAB2_LIB.BASEBOARD_FAB2(SCH_1):PAGE60
  J1B1  106 DQ<44> SCONN288_H44441004_PIP-SCONN,HA   I111 @BASEBOARD_FAB2_LIB.BASEBOARD_FAB2(SCH_1):PAGE83
  J9M1  251 DQ<45> SCONN288_H44441003_PIP-SCONN,HA    I14 @BASEBOARD_FAB2_LIB.BASEBOARD_FAB2(SCH_1):PAGE84

M_K_DQ<46> @BASEBOARD_FAB2_LIB.BASEBOARD_FAB2(SCH_1):M_K_DQ(46)
  U2D1 DN34 DDR3_DQ<46> SKX_EXT_B_BGA1-IC,TBD   I172 @BASEBOARD_FAB2_LIB.BASEBOARD_FAB2(SCH_1):PAGE60
  J1B1  258 DQ<47> SCONN288_H44441004_PIP-SCONN,HA   I111 @BASEBOARD_FAB2_LIB.BASEBOARD_FAB2(SCH_1):PAGE83
  J9M1  113 DQ<46> SCONN288_H44441003_PIP-SCONN,HA    I14 @BASEBOARD_FAB2_LIB.BASEBOARD_FAB2(SCH_1):PAGE84

M_K_DQ<47> @BASEBOARD_FAB2_LIB.BASEBOARD_FAB2(SCH_1):M_K_DQ(47)
  U2D1 DU34 DDR3_DQ<47> SKX_EXT_B_BGA1-IC,TBD   I172 @BASEBOARD_FAB2_LIB.BASEBOARD_FAB2(SCH_1):PAGE60
  J1B1  113 DQ<46> SCONN288_H44441004_PIP-SCONN,HA   I111 @BASEBOARD_FAB2_LIB.BASEBOARD_FAB2(SCH_1):PAGE83
  J9M1  258 DQ<47> SCONN288_H44441003_PIP-SCONN,HA    I14 @BASEBOARD_FAB2_LIB.BASEBOARD_FAB2(SCH_1):PAGE84

M_K_DQ<48> @BASEBOARD_FAB2_LIB.BASEBOARD_FAB2(SCH_1):M_K_DQ(48)
  U2D1 DN30 DDR3_DQ<48> SKX_EXT_B_BGA1-IC,TBD   I172 @BASEBOARD_FAB2_LIB.BASEBOARD_FAB2(SCH_1):PAGE60
  J1B1  264 DQ<49> SCONN288_H44441004_PIP-SCONN,HA   I111 @BASEBOARD_FAB2_LIB.BASEBOARD_FAB2(SCH_1):PAGE83
  J9M1  119 DQ<48> SCONN288_H44441003_PIP-SCONN,HA    I14 @BASEBOARD_FAB2_LIB.BASEBOARD_FAB2(SCH_1):PAGE84

M_K_DQ<49> @BASEBOARD_FAB2_LIB.BASEBOARD_FAB2(SCH_1):M_K_DQ(49)
  U2D1 DU30 DDR3_DQ<49> SKX_EXT_B_BGA1-IC,TBD   I172 @BASEBOARD_FAB2_LIB.BASEBOARD_FAB2(SCH_1):PAGE60
  J1B1  119 DQ<48> SCONN288_H44441004_PIP-SCONN,HA   I111 @BASEBOARD_FAB2_LIB.BASEBOARD_FAB2(SCH_1):PAGE83
  J9M1  264 DQ<49> SCONN288_H44441003_PIP-SCONN,HA    I14 @BASEBOARD_FAB2_LIB.BASEBOARD_FAB2(SCH_1):PAGE84

M_K_DQ<4> @BASEBOARD_FAB2_LIB.BASEBOARD_FAB2(SCH_1):M_K_DQ(4)
  U2D1 CL84 DDR3_DQ<4> SKX_EXT_B_BGA1-IC,TBD   I172 @BASEBOARD_FAB2_LIB.BASEBOARD_FAB2(SCH_1):PAGE60
  J1B1  148  DQ<5> SCONN288_H44441004_PIP-SCONN,HA   I111 @BASEBOARD_FAB2_LIB.BASEBOARD_FAB2(SCH_1):PAGE83
  J9M1    3  DQ<4> SCONN288_H44441003_PIP-SCONN,HA    I14 @BASEBOARD_FAB2_LIB.BASEBOARD_FAB2(SCH_1):PAGE84

M_K_DQ<50> @BASEBOARD_FAB2_LIB.BASEBOARD_FAB2(SCH_1):M_K_DQ(50)
  U2D1 DP27 DDR3_DQ<50> SKX_EXT_B_BGA1-IC,TBD   I172 @BASEBOARD_FAB2_LIB.BASEBOARD_FAB2(SCH_1):PAGE60
  J1B1  271 DQ<51> SCONN288_H44441004_PIP-SCONN,HA   I111 @BASEBOARD_FAB2_LIB.BASEBOARD_FAB2(SCH_1):PAGE83
  J9M1  126 DQ<50> SCONN288_H44441003_PIP-SCONN,HA    I14 @BASEBOARD_FAB2_LIB.BASEBOARD_FAB2(SCH_1):PAGE84

M_K_DQ<51> @BASEBOARD_FAB2_LIB.BASEBOARD_FAB2(SCH_1):M_K_DQ(51)
  U2D1 DT27 DDR3_DQ<51> SKX_EXT_B_BGA1-IC,TBD   I172 @BASEBOARD_FAB2_LIB.BASEBOARD_FAB2(SCH_1):PAGE60
  J1B1  126 DQ<50> SCONN288_H44441004_PIP-SCONN,HA   I111 @BASEBOARD_FAB2_LIB.BASEBOARD_FAB2(SCH_1):PAGE83
  J9M1  271 DQ<51> SCONN288_H44441003_PIP-SCONN,HA    I14 @BASEBOARD_FAB2_LIB.BASEBOARD_FAB2(SCH_1):PAGE84

M_K_DQ<52> @BASEBOARD_FAB2_LIB.BASEBOARD_FAB2(SCH_1):M_K_DQ(52)
  U2D1 DP31 DDR3_DQ<52> SKX_EXT_B_BGA1-IC,TBD   I172 @BASEBOARD_FAB2_LIB.BASEBOARD_FAB2(SCH_1):PAGE60
  J1B1  262 DQ<53> SCONN288_H44441004_PIP-SCONN,HA   I111 @BASEBOARD_FAB2_LIB.BASEBOARD_FAB2(SCH_1):PAGE83
  J9M1  117 DQ<52> SCONN288_H44441003_PIP-SCONN,HA    I14 @BASEBOARD_FAB2_LIB.BASEBOARD_FAB2(SCH_1):PAGE84

M_K_DQ<53> @BASEBOARD_FAB2_LIB.BASEBOARD_FAB2(SCH_1):M_K_DQ(53)
  U2D1 DT31 DDR3_DQ<53> SKX_EXT_B_BGA1-IC,TBD   I172 @BASEBOARD_FAB2_LIB.BASEBOARD_FAB2(SCH_1):PAGE60
  J1B1  117 DQ<52> SCONN288_H44441004_PIP-SCONN,HA   I111 @BASEBOARD_FAB2_LIB.BASEBOARD_FAB2(SCH_1):PAGE83
  J9M1  262 DQ<53> SCONN288_H44441003_PIP-SCONN,HA    I14 @BASEBOARD_FAB2_LIB.BASEBOARD_FAB2(SCH_1):PAGE84

M_K_DQ<54> @BASEBOARD_FAB2_LIB.BASEBOARD_FAB2(SCH_1):M_K_DQ(54)
  U2D1 DN28 DDR3_DQ<54> SKX_EXT_B_BGA1-IC,TBD   I172 @BASEBOARD_FAB2_LIB.BASEBOARD_FAB2(SCH_1):PAGE60
  J1B1  269 DQ<55> SCONN288_H44441004_PIP-SCONN,HA   I111 @BASEBOARD_FAB2_LIB.BASEBOARD_FAB2(SCH_1):PAGE83
  J9M1  124 DQ<54> SCONN288_H44441003_PIP-SCONN,HA    I14 @BASEBOARD_FAB2_LIB.BASEBOARD_FAB2(SCH_1):PAGE84

M_K_DQ<55> @BASEBOARD_FAB2_LIB.BASEBOARD_FAB2(SCH_1):M_K_DQ(55)
  U2D1 DU28 DDR3_DQ<55> SKX_EXT_B_BGA1-IC,TBD   I172 @BASEBOARD_FAB2_LIB.BASEBOARD_FAB2(SCH_1):PAGE60
  J1B1  124 DQ<54> SCONN288_H44441004_PIP-SCONN,HA   I111 @BASEBOARD_FAB2_LIB.BASEBOARD_FAB2(SCH_1):PAGE83
  J9M1  269 DQ<55> SCONN288_H44441003_PIP-SCONN,HA    I14 @BASEBOARD_FAB2_LIB.BASEBOARD_FAB2(SCH_1):PAGE84

M_K_DQ<56> @BASEBOARD_FAB2_LIB.BASEBOARD_FAB2(SCH_1):M_K_DQ(56)
  U2D1 DN24 DDR3_DQ<56> SKX_EXT_B_BGA1-IC,TBD   I172 @BASEBOARD_FAB2_LIB.BASEBOARD_FAB2(SCH_1):PAGE60
  J1B1  275 DQ<57> SCONN288_H44441004_PIP-SCONN,HA   I111 @BASEBOARD_FAB2_LIB.BASEBOARD_FAB2(SCH_1):PAGE83
  J9M1  130 DQ<56> SCONN288_H44441003_PIP-SCONN,HA    I14 @BASEBOARD_FAB2_LIB.BASEBOARD_FAB2(SCH_1):PAGE84

M_K_DQ<57> @BASEBOARD_FAB2_LIB.BASEBOARD_FAB2(SCH_1):M_K_DQ(57)
  U2D1 DU24 DDR3_DQ<57> SKX_EXT_B_BGA1-IC,TBD   I172 @BASEBOARD_FAB2_LIB.BASEBOARD_FAB2(SCH_1):PAGE60
  J1B1  130 DQ<56> SCONN288_H44441004_PIP-SCONN,HA   I111 @BASEBOARD_FAB2_LIB.BASEBOARD_FAB2(SCH_1):PAGE83
  J9M1  275 DQ<57> SCONN288_H44441003_PIP-SCONN,HA    I14 @BASEBOARD_FAB2_LIB.BASEBOARD_FAB2(SCH_1):PAGE84

M_K_DQ<58> @BASEBOARD_FAB2_LIB.BASEBOARD_FAB2(SCH_1):M_K_DQ(58)
  U2D1 DY21 DDR3_DQ<58> SKX_EXT_B_BGA1-IC,TBD   I172 @BASEBOARD_FAB2_LIB.BASEBOARD_FAB2(SCH_1):PAGE60
  J1B1  282 DQ<59> SCONN288_H44441004_PIP-SCONN,HA   I111 @BASEBOARD_FAB2_LIB.BASEBOARD_FAB2(SCH_1):PAGE83
  J9M1  137 DQ<58> SCONN288_H44441003_PIP-SCONN,HA    I14 @BASEBOARD_FAB2_LIB.BASEBOARD_FAB2(SCH_1):PAGE84

M_K_DQ<59> @BASEBOARD_FAB2_LIB.BASEBOARD_FAB2(SCH_1):M_K_DQ(59)
  U2D1 EB21 DDR3_DQ<59> SKX_EXT_B_BGA1-IC,TBD   I172 @BASEBOARD_FAB2_LIB.BASEBOARD_FAB2(SCH_1):PAGE60
  J1B1  137 DQ<58> SCONN288_H44441004_PIP-SCONN,HA   I111 @BASEBOARD_FAB2_LIB.BASEBOARD_FAB2(SCH_1):PAGE83
  J9M1  282 DQ<59> SCONN288_H44441003_PIP-SCONN,HA    I14 @BASEBOARD_FAB2_LIB.BASEBOARD_FAB2(SCH_1):PAGE84

M_K_DQ<5> @BASEBOARD_FAB2_LIB.BASEBOARD_FAB2(SCH_1):M_K_DQ(5)
  U2D1 CL86 DDR3_DQ<5> SKX_EXT_B_BGA1-IC,TBD   I172 @BASEBOARD_FAB2_LIB.BASEBOARD_FAB2(SCH_1):PAGE60
  J1B1    3  DQ<4> SCONN288_H44441004_PIP-SCONN,HA   I111 @BASEBOARD_FAB2_LIB.BASEBOARD_FAB2(SCH_1):PAGE83
  J9M1  148  DQ<5> SCONN288_H44441003_PIP-SCONN,HA    I14 @BASEBOARD_FAB2_LIB.BASEBOARD_FAB2(SCH_1):PAGE84

M_K_DQ<60> @BASEBOARD_FAB2_LIB.BASEBOARD_FAB2(SCH_1):M_K_DQ(60)
  U2D1 DP25 DDR3_DQ<60> SKX_EXT_B_BGA1-IC,TBD   I172 @BASEBOARD_FAB2_LIB.BASEBOARD_FAB2(SCH_1):PAGE60
  J1B1  273 DQ<61> SCONN288_H44441004_PIP-SCONN,HA   I111 @BASEBOARD_FAB2_LIB.BASEBOARD_FAB2(SCH_1):PAGE83
  J9M1  128 DQ<60> SCONN288_H44441003_PIP-SCONN,HA    I14 @BASEBOARD_FAB2_LIB.BASEBOARD_FAB2(SCH_1):PAGE84

M_K_DQ<61> @BASEBOARD_FAB2_LIB.BASEBOARD_FAB2(SCH_1):M_K_DQ(61)
  U2D1 DT25 DDR3_DQ<61> SKX_EXT_B_BGA1-IC,TBD   I172 @BASEBOARD_FAB2_LIB.BASEBOARD_FAB2(SCH_1):PAGE60
  J1B1  128 DQ<60> SCONN288_H44441004_PIP-SCONN,HA   I111 @BASEBOARD_FAB2_LIB.BASEBOARD_FAB2(SCH_1):PAGE83
  J9M1  273 DQ<61> SCONN288_H44441003_PIP-SCONN,HA    I14 @BASEBOARD_FAB2_LIB.BASEBOARD_FAB2(SCH_1):PAGE84

M_K_DQ<62> @BASEBOARD_FAB2_LIB.BASEBOARD_FAB2(SCH_1):M_K_DQ(62)
  U2D1 EC22 DDR3_DQ<62> SKX_EXT_B_BGA1-IC,TBD   I172 @BASEBOARD_FAB2_LIB.BASEBOARD_FAB2(SCH_1):PAGE60
  J1B1  280 DQ<63> SCONN288_H44441004_PIP-SCONN,HA   I111 @BASEBOARD_FAB2_LIB.BASEBOARD_FAB2(SCH_1):PAGE83
  J9M1  135 DQ<62> SCONN288_H44441003_PIP-SCONN,HA    I14 @BASEBOARD_FAB2_LIB.BASEBOARD_FAB2(SCH_1):PAGE84

M_K_DQ<63> @BASEBOARD_FAB2_LIB.BASEBOARD_FAB2(SCH_1):M_K_DQ(63)
  U2D1 DW22 DDR3_DQ<63> SKX_EXT_B_BGA1-IC,TBD   I172 @BASEBOARD_FAB2_LIB.BASEBOARD_FAB2(SCH_1):PAGE60
  J1B1  135 DQ<62> SCONN288_H44441004_PIP-SCONN,HA   I111 @BASEBOARD_FAB2_LIB.BASEBOARD_FAB2(SCH_1):PAGE83
  J9M1  280 DQ<63> SCONN288_H44441003_PIP-SCONN,HA    I14 @BASEBOARD_FAB2_LIB.BASEBOARD_FAB2(SCH_1):PAGE84

M_K_DQ<6> @BASEBOARD_FAB2_LIB.BASEBOARD_FAB2(SCH_1):M_K_DQ(6)
  U2D1 CW86 DDR3_DQ<6> SKX_EXT_B_BGA1-IC,TBD   I172 @BASEBOARD_FAB2_LIB.BASEBOARD_FAB2(SCH_1):PAGE60
  J1B1  155  DQ<7> SCONN288_H44441004_PIP-SCONN,HA   I111 @BASEBOARD_FAB2_LIB.BASEBOARD_FAB2(SCH_1):PAGE83
  J9M1   10  DQ<6> SCONN288_H44441003_PIP-SCONN,HA    I14 @BASEBOARD_FAB2_LIB.BASEBOARD_FAB2(SCH_1):PAGE84

M_K_DQ<7> @BASEBOARD_FAB2_LIB.BASEBOARD_FAB2(SCH_1):M_K_DQ(7)
  U2D1 CW84 DDR3_DQ<7> SKX_EXT_B_BGA1-IC,TBD   I172 @BASEBOARD_FAB2_LIB.BASEBOARD_FAB2(SCH_1):PAGE60
  J1B1   10  DQ<6> SCONN288_H44441004_PIP-SCONN,HA   I111 @BASEBOARD_FAB2_LIB.BASEBOARD_FAB2(SCH_1):PAGE83
  J9M1  155  DQ<7> SCONN288_H44441003_PIP-SCONN,HA    I14 @BASEBOARD_FAB2_LIB.BASEBOARD_FAB2(SCH_1):PAGE84

M_K_DQ<8> @BASEBOARD_FAB2_LIB.BASEBOARD_FAB2(SCH_1):M_K_DQ(8)
  U2D1 DG84 DDR3_DQ<8> SKX_EXT_B_BGA1-IC,TBD   I172 @BASEBOARD_FAB2_LIB.BASEBOARD_FAB2(SCH_1):PAGE60
  J1B1  161  DQ<9> SCONN288_H44441004_PIP-SCONN,HA   I111 @BASEBOARD_FAB2_LIB.BASEBOARD_FAB2(SCH_1):PAGE83
  J9M1   16  DQ<8> SCONN288_H44441003_PIP-SCONN,HA    I14 @BASEBOARD_FAB2_LIB.BASEBOARD_FAB2(SCH_1):PAGE84

M_K_DQ<9> @BASEBOARD_FAB2_LIB.BASEBOARD_FAB2(SCH_1):M_K_DQ(9)
  U2D1 DH85 DDR3_DQ<9> SKX_EXT_B_BGA1-IC,TBD   I172 @BASEBOARD_FAB2_LIB.BASEBOARD_FAB2(SCH_1):PAGE60
  J1B1   16  DQ<8> SCONN288_H44441004_PIP-SCONN,HA   I111 @BASEBOARD_FAB2_LIB.BASEBOARD_FAB2(SCH_1):PAGE83
  J9M1  161  DQ<9> SCONN288_H44441003_PIP-SCONN,HA    I14 @BASEBOARD_FAB2_LIB.BASEBOARD_FAB2(SCH_1):PAGE84

M_K_DQS_DN<0> @BASEBOARD_FAB2_LIB.BASEBOARD_FAB2(SCH_1):M_K_DQS_DN(0)
  U2D1 CU84 DDR3_DQS_DN<0> SKX_EXT_B_BGA1-IC,TBD   I172 @BASEBOARD_FAB2_LIB.BASEBOARD_FAB2(SCH_1):PAGE60
  J1B1  152  DQS0N SCONN288_H44441004_PIP-SCONN,HA    I66 @BASEBOARD_FAB2_LIB.BASEBOARD_FAB2(SCH_1):PAGE83
  J9M1  152  DQS0N SCONN288_H44441003_PIP-SCONN,HA   I102 @BASEBOARD_FAB2_LIB.BASEBOARD_FAB2(SCH_1):PAGE84

M_K_DQS_DN<10> @BASEBOARD_FAB2_LIB.BASEBOARD_FAB2(SCH_1):M_K_DQS_DN(10)
  U2D1 DM85 DDR3_DQS_DN<10> SKX_EXT_B_BGA1-IC,TBD   I172 @BASEBOARD_FAB2_LIB.BASEBOARD_FAB2(SCH_1):PAGE60
  J1B1   19 DQS10N SCONN288_H44441004_PIP-SCONN,HA    I66 @BASEBOARD_FAB2_LIB.BASEBOARD_FAB2(SCH_1):PAGE83
  J9M1   19 DQS10N SCONN288_H44441003_PIP-SCONN,HA   I102 @BASEBOARD_FAB2_LIB.BASEBOARD_FAB2(SCH_1):PAGE84

M_K_DQS_DN<11> @BASEBOARD_FAB2_LIB.BASEBOARD_FAB2(SCH_1):M_K_DQS_DN(11)
  U2D1 DN80 DDR3_DQS_DN<11> SKX_EXT_B_BGA1-IC,TBD   I172 @BASEBOARD_FAB2_LIB.BASEBOARD_FAB2(SCH_1):PAGE60
  J1B1   30 DQS11N SCONN288_H44441004_PIP-SCONN,HA    I66 @BASEBOARD_FAB2_LIB.BASEBOARD_FAB2(SCH_1):PAGE83
  J9M1   30 DQS11N SCONN288_H44441003_PIP-SCONN,HA   I102 @BASEBOARD_FAB2_LIB.BASEBOARD_FAB2(SCH_1):PAGE84

M_K_DQS_DN<12> @BASEBOARD_FAB2_LIB.BASEBOARD_FAB2(SCH_1):M_K_DQS_DN(12)
  U2D1 DP75 DDR3_DQS_DN<12> SKX_EXT_B_BGA1-IC,TBD   I172 @BASEBOARD_FAB2_LIB.BASEBOARD_FAB2(SCH_1):PAGE60
  J1B1   41 DQS12N SCONN288_H44441004_PIP-SCONN,HA    I66 @BASEBOARD_FAB2_LIB.BASEBOARD_FAB2(SCH_1):PAGE83
  J9M1   41 DQS12N SCONN288_H44441003_PIP-SCONN,HA   I102 @BASEBOARD_FAB2_LIB.BASEBOARD_FAB2(SCH_1):PAGE84

M_K_DQS_DN<13> @BASEBOARD_FAB2_LIB.BASEBOARD_FAB2(SCH_1):M_K_DQS_DN(13)
  U2D1 EA38 DDR3_DQS_DN<13> SKX_EXT_B_BGA1-IC,TBD   I172 @BASEBOARD_FAB2_LIB.BASEBOARD_FAB2(SCH_1):PAGE60
  J1B1  100 DQS13N SCONN288_H44441004_PIP-SCONN,HA    I66 @BASEBOARD_FAB2_LIB.BASEBOARD_FAB2(SCH_1):PAGE83
  J9M1  100 DQS13N SCONN288_H44441003_PIP-SCONN,HA   I102 @BASEBOARD_FAB2_LIB.BASEBOARD_FAB2(SCH_1):PAGE84

M_K_DQS_DN<14> @BASEBOARD_FAB2_LIB.BASEBOARD_FAB2(SCH_1):M_K_DQS_DN(14)
  U2D1 DP35 DDR3_DQS_DN<14> SKX_EXT_B_BGA1-IC,TBD   I172 @BASEBOARD_FAB2_LIB.BASEBOARD_FAB2(SCH_1):PAGE60
  J1B1  111 DQS14N SCONN288_H44441004_PIP-SCONN,HA    I66 @BASEBOARD_FAB2_LIB.BASEBOARD_FAB2(SCH_1):PAGE83
  J9M1  111 DQS14N SCONN288_H44441003_PIP-SCONN,HA   I102 @BASEBOARD_FAB2_LIB.BASEBOARD_FAB2(SCH_1):PAGE84

M_K_DQS_DN<15> @BASEBOARD_FAB2_LIB.BASEBOARD_FAB2(SCH_1):M_K_DQS_DN(15)
  U2D1 DM29 DDR3_DQS_DN<15> SKX_EXT_B_BGA1-IC,TBD   I172 @BASEBOARD_FAB2_LIB.BASEBOARD_FAB2(SCH_1):PAGE60
  J1B1  122 DQS15N SCONN288_H44441004_PIP-SCONN,HA    I66 @BASEBOARD_FAB2_LIB.BASEBOARD_FAB2(SCH_1):PAGE83
  J9M1  122 DQS15N SCONN288_H44441003_PIP-SCONN,HA   I102 @BASEBOARD_FAB2_LIB.BASEBOARD_FAB2(SCH_1):PAGE84

M_K_DQS_DN<16> @BASEBOARD_FAB2_LIB.BASEBOARD_FAB2(SCH_1):M_K_DQS_DN(16)
  U2D1 DM23 DDR3_DQS_DN<16> SKX_EXT_B_BGA1-IC,TBD   I172 @BASEBOARD_FAB2_LIB.BASEBOARD_FAB2(SCH_1):PAGE60
  J1B1  133 DQS16N SCONN288_H44441004_PIP-SCONN,HA    I66 @BASEBOARD_FAB2_LIB.BASEBOARD_FAB2(SCH_1):PAGE83
  J9M1  133 DQS16N SCONN288_H44441003_PIP-SCONN,HA   I102 @BASEBOARD_FAB2_LIB.BASEBOARD_FAB2(SCH_1):PAGE84

M_K_DQS_DN<17> @BASEBOARD_FAB2_LIB.BASEBOARD_FAB2(SCH_1):M_K_DQS_DN(17)
  U2D1 DB67 DDR3_DQS_DN<17> SKX_EXT_B_BGA1-IC,TBD   I172 @BASEBOARD_FAB2_LIB.BASEBOARD_FAB2(SCH_1):PAGE60
  J1B1   52 DQS17N SCONN288_H44441004_PIP-SCONN,HA    I66 @BASEBOARD_FAB2_LIB.BASEBOARD_FAB2(SCH_1):PAGE83
  J9M1   52 DQS17N SCONN288_H44441003_PIP-SCONN,HA   I102 @BASEBOARD_FAB2_LIB.BASEBOARD_FAB2(SCH_1):PAGE84

M_K_DQS_DN<1> @BASEBOARD_FAB2_LIB.BASEBOARD_FAB2(SCH_1):M_K_DQS_DN(1)
  U2D1 DN84 DDR3_DQS_DN<1> SKX_EXT_B_BGA1-IC,TBD   I172 @BASEBOARD_FAB2_LIB.BASEBOARD_FAB2(SCH_1):PAGE60
  J1B1  163  DQS1N SCONN288_H44441004_PIP-SCONN,HA    I66 @BASEBOARD_FAB2_LIB.BASEBOARD_FAB2(SCH_1):PAGE83
  J9M1  163  DQS1N SCONN288_H44441003_PIP-SCONN,HA   I102 @BASEBOARD_FAB2_LIB.BASEBOARD_FAB2(SCH_1):PAGE84

M_K_DQS_DN<2> @BASEBOARD_FAB2_LIB.BASEBOARD_FAB2(SCH_1):M_K_DQS_DN(2)
  U2D1 DL82 DDR3_DQS_DN<2> SKX_EXT_B_BGA1-IC,TBD   I172 @BASEBOARD_FAB2_LIB.BASEBOARD_FAB2(SCH_1):PAGE60
  J1B1  174  DQS2N SCONN288_H44441004_PIP-SCONN,HA    I66 @BASEBOARD_FAB2_LIB.BASEBOARD_FAB2(SCH_1):PAGE83
  J9M1  174  DQS2N SCONN288_H44441003_PIP-SCONN,HA   I102 @BASEBOARD_FAB2_LIB.BASEBOARD_FAB2(SCH_1):PAGE84

M_K_DQS_DN<3> @BASEBOARD_FAB2_LIB.BASEBOARD_FAB2(SCH_1):M_K_DQS_DN(3)
  U2D1 DV75 DDR3_DQS_DN<3> SKX_EXT_B_BGA1-IC,TBD   I172 @BASEBOARD_FAB2_LIB.BASEBOARD_FAB2(SCH_1):PAGE60
  J1B1  185  DQS3N SCONN288_H44441004_PIP-SCONN,HA    I66 @BASEBOARD_FAB2_LIB.BASEBOARD_FAB2(SCH_1):PAGE83
  J9M1  185  DQS3N SCONN288_H44441003_PIP-SCONN,HA   I102 @BASEBOARD_FAB2_LIB.BASEBOARD_FAB2(SCH_1):PAGE84

M_K_DQS_DN<4> @BASEBOARD_FAB2_LIB.BASEBOARD_FAB2(SCH_1):M_K_DQS_DN(4)
  U2D1 EE38 DDR3_DQS_DN<4> SKX_EXT_B_BGA1-IC,TBD   I172 @BASEBOARD_FAB2_LIB.BASEBOARD_FAB2(SCH_1):PAGE60
  J1B1  244  DQS4N SCONN288_H44441004_PIP-SCONN,HA    I66 @BASEBOARD_FAB2_LIB.BASEBOARD_FAB2(SCH_1):PAGE83
  J9M1  244  DQS4N SCONN288_H44441003_PIP-SCONN,HA   I102 @BASEBOARD_FAB2_LIB.BASEBOARD_FAB2(SCH_1):PAGE84

M_K_DQS_DN<5> @BASEBOARD_FAB2_LIB.BASEBOARD_FAB2(SCH_1):M_K_DQS_DN(5)
  U2D1 DV35 DDR3_DQS_DN<5> SKX_EXT_B_BGA1-IC,TBD   I172 @BASEBOARD_FAB2_LIB.BASEBOARD_FAB2(SCH_1):PAGE60
  J1B1  255  DQS5N SCONN288_H44441004_PIP-SCONN,HA    I66 @BASEBOARD_FAB2_LIB.BASEBOARD_FAB2(SCH_1):PAGE83
  J9M1  255  DQS5N SCONN288_H44441003_PIP-SCONN,HA   I102 @BASEBOARD_FAB2_LIB.BASEBOARD_FAB2(SCH_1):PAGE84

M_K_DQS_DN<6> @BASEBOARD_FAB2_LIB.BASEBOARD_FAB2(SCH_1):M_K_DQS_DN(6)
  U2D1 DV29 DDR3_DQS_DN<6> SKX_EXT_B_BGA1-IC,TBD   I172 @BASEBOARD_FAB2_LIB.BASEBOARD_FAB2(SCH_1):PAGE60
  J1B1  266  DQS6N SCONN288_H44441004_PIP-SCONN,HA    I66 @BASEBOARD_FAB2_LIB.BASEBOARD_FAB2(SCH_1):PAGE83
  J9M1  266  DQS6N SCONN288_H44441003_PIP-SCONN,HA   I102 @BASEBOARD_FAB2_LIB.BASEBOARD_FAB2(SCH_1):PAGE84

M_K_DQS_DN<7> @BASEBOARD_FAB2_LIB.BASEBOARD_FAB2(SCH_1):M_K_DQS_DN(7)
  U2D1 DV23 DDR3_DQS_DN<7> SKX_EXT_B_BGA1-IC,TBD   I172 @BASEBOARD_FAB2_LIB.BASEBOARD_FAB2(SCH_1):PAGE60
  J1B1  277  DQS7N SCONN288_H44441004_PIP-SCONN,HA    I66 @BASEBOARD_FAB2_LIB.BASEBOARD_FAB2(SCH_1):PAGE83
  J9M1  277  DQS7N SCONN288_H44441003_PIP-SCONN,HA   I102 @BASEBOARD_FAB2_LIB.BASEBOARD_FAB2(SCH_1):PAGE84

M_K_DQS_DN<8> @BASEBOARD_FAB2_LIB.BASEBOARD_FAB2(SCH_1):M_K_DQS_DN(8)
  U2D1 DF67 DDR3_DQS_DN<8> SKX_EXT_B_BGA1-IC,TBD   I172 @BASEBOARD_FAB2_LIB.BASEBOARD_FAB2(SCH_1):PAGE60
  J1B1  196  DQS8N SCONN288_H44441004_PIP-SCONN,HA    I66 @BASEBOARD_FAB2_LIB.BASEBOARD_FAB2(SCH_1):PAGE83
  J9M1  196  DQS8N SCONN288_H44441003_PIP-SCONN,HA   I102 @BASEBOARD_FAB2_LIB.BASEBOARD_FAB2(SCH_1):PAGE84

M_K_DQS_DN<9> @BASEBOARD_FAB2_LIB.BASEBOARD_FAB2(SCH_1):M_K_DQS_DN(9)
  U2D1 CR84 DDR3_DQS_DN<9> SKX_EXT_B_BGA1-IC,TBD   I172 @BASEBOARD_FAB2_LIB.BASEBOARD_FAB2(SCH_1):PAGE60
  J1B1    8  DQS9N SCONN288_H44441004_PIP-SCONN,HA    I66 @BASEBOARD_FAB2_LIB.BASEBOARD_FAB2(SCH_1):PAGE83
  J9M1    8  DQS9N SCONN288_H44441003_PIP-SCONN,HA   I102 @BASEBOARD_FAB2_LIB.BASEBOARD_FAB2(SCH_1):PAGE84

M_K_DQS_DP<0> @BASEBOARD_FAB2_LIB.BASEBOARD_FAB2(SCH_1):M_K_DQS_DP(0)
  U2D1 CV85 DDR3_DQS_DP<0> SKX_EXT_B_BGA1-IC,TBD   I172 @BASEBOARD_FAB2_LIB.BASEBOARD_FAB2(SCH_1):PAGE60
  J1B1  153  DQS0P SCONN288_H44441004_PIP-SCONN,HA    I66 @BASEBOARD_FAB2_LIB.BASEBOARD_FAB2(SCH_1):PAGE83
  J9M1  153  DQS0P SCONN288_H44441003_PIP-SCONN,HA   I102 @BASEBOARD_FAB2_LIB.BASEBOARD_FAB2(SCH_1):PAGE84

M_K_DQS_DP<10> @BASEBOARD_FAB2_LIB.BASEBOARD_FAB2(SCH_1):M_K_DQS_DP(10)
  U2D1 DL84 DDR3_DQS_DP<10> SKX_EXT_B_BGA1-IC,TBD   I172 @BASEBOARD_FAB2_LIB.BASEBOARD_FAB2(SCH_1):PAGE60
  J1B1   18 DQS10P SCONN288_H44441004_PIP-SCONN,HA    I66 @BASEBOARD_FAB2_LIB.BASEBOARD_FAB2(SCH_1):PAGE83
  J9M1   18 DQS10P SCONN288_H44441003_PIP-SCONN,HA   I102 @BASEBOARD_FAB2_LIB.BASEBOARD_FAB2(SCH_1):PAGE84

M_K_DQS_DP<11> @BASEBOARD_FAB2_LIB.BASEBOARD_FAB2(SCH_1):M_K_DQS_DP(11)
  U2D1 DP79 DDR3_DQS_DP<11> SKX_EXT_B_BGA1-IC,TBD   I172 @BASEBOARD_FAB2_LIB.BASEBOARD_FAB2(SCH_1):PAGE60
  J1B1   29 DQS11P SCONN288_H44441004_PIP-SCONN,HA    I66 @BASEBOARD_FAB2_LIB.BASEBOARD_FAB2(SCH_1):PAGE83
  J9M1   29 DQS11P SCONN288_H44441003_PIP-SCONN,HA   I102 @BASEBOARD_FAB2_LIB.BASEBOARD_FAB2(SCH_1):PAGE84

M_K_DQS_DP<12> @BASEBOARD_FAB2_LIB.BASEBOARD_FAB2(SCH_1):M_K_DQS_DP(12)
  U2D1 DM75 DDR3_DQS_DP<12> SKX_EXT_B_BGA1-IC,TBD   I172 @BASEBOARD_FAB2_LIB.BASEBOARD_FAB2(SCH_1):PAGE60
  J1B1   40 DQS12P SCONN288_H44441004_PIP-SCONN,HA    I66 @BASEBOARD_FAB2_LIB.BASEBOARD_FAB2(SCH_1):PAGE83
  J9M1   40 DQS12P SCONN288_H44441003_PIP-SCONN,HA   I102 @BASEBOARD_FAB2_LIB.BASEBOARD_FAB2(SCH_1):PAGE84

M_K_DQS_DP<13> @BASEBOARD_FAB2_LIB.BASEBOARD_FAB2(SCH_1):M_K_DQS_DP(13)
  U2D1 DW38 DDR3_DQS_DP<13> SKX_EXT_B_BGA1-IC,TBD   I172 @BASEBOARD_FAB2_LIB.BASEBOARD_FAB2(SCH_1):PAGE60
  J1B1   99 DQS13P SCONN288_H44441004_PIP-SCONN,HA    I66 @BASEBOARD_FAB2_LIB.BASEBOARD_FAB2(SCH_1):PAGE83
  J9M1   99 DQS13P SCONN288_H44441003_PIP-SCONN,HA   I102 @BASEBOARD_FAB2_LIB.BASEBOARD_FAB2(SCH_1):PAGE84

M_K_DQS_DP<14> @BASEBOARD_FAB2_LIB.BASEBOARD_FAB2(SCH_1):M_K_DQS_DP(14)
  U2D1 DM35 DDR3_DQS_DP<14> SKX_EXT_B_BGA1-IC,TBD   I172 @BASEBOARD_FAB2_LIB.BASEBOARD_FAB2(SCH_1):PAGE60
  J1B1  110 DQS14P SCONN288_H44441004_PIP-SCONN,HA    I66 @BASEBOARD_FAB2_LIB.BASEBOARD_FAB2(SCH_1):PAGE83
  J9M1  110 DQS14P SCONN288_H44441003_PIP-SCONN,HA   I102 @BASEBOARD_FAB2_LIB.BASEBOARD_FAB2(SCH_1):PAGE84

M_K_DQS_DP<15> @BASEBOARD_FAB2_LIB.BASEBOARD_FAB2(SCH_1):M_K_DQS_DP(15)
  U2D1 DP29 DDR3_DQS_DP<15> SKX_EXT_B_BGA1-IC,TBD   I172 @BASEBOARD_FAB2_LIB.BASEBOARD_FAB2(SCH_1):PAGE60
  J1B1  121 DQS15P SCONN288_H44441004_PIP-SCONN,HA    I66 @BASEBOARD_FAB2_LIB.BASEBOARD_FAB2(SCH_1):PAGE83
  J9M1  121 DQS15P SCONN288_H44441003_PIP-SCONN,HA   I102 @BASEBOARD_FAB2_LIB.BASEBOARD_FAB2(SCH_1):PAGE84

M_K_DQS_DP<16> @BASEBOARD_FAB2_LIB.BASEBOARD_FAB2(SCH_1):M_K_DQS_DP(16)
  U2D1 DP23 DDR3_DQS_DP<16> SKX_EXT_B_BGA1-IC,TBD   I172 @BASEBOARD_FAB2_LIB.BASEBOARD_FAB2(SCH_1):PAGE60
  J1B1  132 DQS16P SCONN288_H44441004_PIP-SCONN,HA    I66 @BASEBOARD_FAB2_LIB.BASEBOARD_FAB2(SCH_1):PAGE83
  J9M1  132 DQS16P SCONN288_H44441003_PIP-SCONN,HA   I102 @BASEBOARD_FAB2_LIB.BASEBOARD_FAB2(SCH_1):PAGE84

M_K_DQS_DP<17> @BASEBOARD_FAB2_LIB.BASEBOARD_FAB2(SCH_1):M_K_DQS_DP(17)
  U2D1 CY67 DDR3_DQS_DP<17> SKX_EXT_B_BGA1-IC,TBD   I172 @BASEBOARD_FAB2_LIB.BASEBOARD_FAB2(SCH_1):PAGE60
  J1B1   51 DQS17P SCONN288_H44441004_PIP-SCONN,HA    I66 @BASEBOARD_FAB2_LIB.BASEBOARD_FAB2(SCH_1):PAGE83
  J9M1   51 DQS17P SCONN288_H44441003_PIP-SCONN,HA   I102 @BASEBOARD_FAB2_LIB.BASEBOARD_FAB2(SCH_1):PAGE84

M_K_DQS_DP<1> @BASEBOARD_FAB2_LIB.BASEBOARD_FAB2(SCH_1):M_K_DQS_DP(1)
  U2D1 DP85 DDR3_DQS_DP<1> SKX_EXT_B_BGA1-IC,TBD   I172 @BASEBOARD_FAB2_LIB.BASEBOARD_FAB2(SCH_1):PAGE60
  J1B1  164  DQS1P SCONN288_H44441004_PIP-SCONN,HA    I66 @BASEBOARD_FAB2_LIB.BASEBOARD_FAB2(SCH_1):PAGE83
  J9M1  164  DQS1P SCONN288_H44441003_PIP-SCONN,HA   I102 @BASEBOARD_FAB2_LIB.BASEBOARD_FAB2(SCH_1):PAGE84

M_K_DQS_DP<2> @BASEBOARD_FAB2_LIB.BASEBOARD_FAB2(SCH_1):M_K_DQS_DP(2)
  U2D1 DM81 DDR3_DQS_DP<2> SKX_EXT_B_BGA1-IC,TBD   I172 @BASEBOARD_FAB2_LIB.BASEBOARD_FAB2(SCH_1):PAGE60
  J1B1  175  DQS2P SCONN288_H44441004_PIP-SCONN,HA    I66 @BASEBOARD_FAB2_LIB.BASEBOARD_FAB2(SCH_1):PAGE83
  J9M1  175  DQS2P SCONN288_H44441003_PIP-SCONN,HA   I102 @BASEBOARD_FAB2_LIB.BASEBOARD_FAB2(SCH_1):PAGE84

M_K_DQS_DP<3> @BASEBOARD_FAB2_LIB.BASEBOARD_FAB2(SCH_1):M_K_DQS_DP(3)
  U2D1 DT75 DDR3_DQS_DP<3> SKX_EXT_B_BGA1-IC,TBD   I172 @BASEBOARD_FAB2_LIB.BASEBOARD_FAB2(SCH_1):PAGE60
  J1B1  186  DQS3P SCONN288_H44441004_PIP-SCONN,HA    I66 @BASEBOARD_FAB2_LIB.BASEBOARD_FAB2(SCH_1):PAGE83
  J9M1  186  DQS3P SCONN288_H44441003_PIP-SCONN,HA   I102 @BASEBOARD_FAB2_LIB.BASEBOARD_FAB2(SCH_1):PAGE84

M_K_DQS_DP<4> @BASEBOARD_FAB2_LIB.BASEBOARD_FAB2(SCH_1):M_K_DQS_DP(4)
  U2D1 EC38 DDR3_DQS_DP<4> SKX_EXT_B_BGA1-IC,TBD   I172 @BASEBOARD_FAB2_LIB.BASEBOARD_FAB2(SCH_1):PAGE60
  J1B1  245  DQS4P SCONN288_H44441004_PIP-SCONN,HA    I66 @BASEBOARD_FAB2_LIB.BASEBOARD_FAB2(SCH_1):PAGE83
  J9M1  245  DQS4P SCONN288_H44441003_PIP-SCONN,HA   I102 @BASEBOARD_FAB2_LIB.BASEBOARD_FAB2(SCH_1):PAGE84

M_K_DQS_DP<5> @BASEBOARD_FAB2_LIB.BASEBOARD_FAB2(SCH_1):M_K_DQS_DP(5)
  U2D1 DT35 DDR3_DQS_DP<5> SKX_EXT_B_BGA1-IC,TBD   I172 @BASEBOARD_FAB2_LIB.BASEBOARD_FAB2(SCH_1):PAGE60
  J1B1  256  DQS5P SCONN288_H44441004_PIP-SCONN,HA    I66 @BASEBOARD_FAB2_LIB.BASEBOARD_FAB2(SCH_1):PAGE83
  J9M1  256  DQS5P SCONN288_H44441003_PIP-SCONN,HA   I102 @BASEBOARD_FAB2_LIB.BASEBOARD_FAB2(SCH_1):PAGE84

M_K_DQS_DP<6> @BASEBOARD_FAB2_LIB.BASEBOARD_FAB2(SCH_1):M_K_DQS_DP(6)
  U2D1 DT29 DDR3_DQS_DP<6> SKX_EXT_B_BGA1-IC,TBD   I172 @BASEBOARD_FAB2_LIB.BASEBOARD_FAB2(SCH_1):PAGE60
  J1B1  267  DQS6P SCONN288_H44441004_PIP-SCONN,HA    I66 @BASEBOARD_FAB2_LIB.BASEBOARD_FAB2(SCH_1):PAGE83
  J9M1  267  DQS6P SCONN288_H44441003_PIP-SCONN,HA   I102 @BASEBOARD_FAB2_LIB.BASEBOARD_FAB2(SCH_1):PAGE84

M_K_DQS_DP<7> @BASEBOARD_FAB2_LIB.BASEBOARD_FAB2(SCH_1):M_K_DQS_DP(7)
  U2D1 DT23 DDR3_DQS_DP<7> SKX_EXT_B_BGA1-IC,TBD   I172 @BASEBOARD_FAB2_LIB.BASEBOARD_FAB2(SCH_1):PAGE60
  J1B1  278  DQS7P SCONN288_H44441004_PIP-SCONN,HA    I66 @BASEBOARD_FAB2_LIB.BASEBOARD_FAB2(SCH_1):PAGE83
  J9M1  278  DQS7P SCONN288_H44441003_PIP-SCONN,HA   I102 @BASEBOARD_FAB2_LIB.BASEBOARD_FAB2(SCH_1):PAGE84

M_K_DQS_DP<8> @BASEBOARD_FAB2_LIB.BASEBOARD_FAB2(SCH_1):M_K_DQS_DP(8)
  U2D1 DD67 DDR3_DQS_DP<8> SKX_EXT_B_BGA1-IC,TBD   I172 @BASEBOARD_FAB2_LIB.BASEBOARD_FAB2(SCH_1):PAGE60
  J1B1  197  DQS8P SCONN288_H44441004_PIP-SCONN,HA    I66 @BASEBOARD_FAB2_LIB.BASEBOARD_FAB2(SCH_1):PAGE83
  J9M1  197  DQS8P SCONN288_H44441003_PIP-SCONN,HA   I102 @BASEBOARD_FAB2_LIB.BASEBOARD_FAB2(SCH_1):PAGE84

M_K_DQS_DP<9> @BASEBOARD_FAB2_LIB.BASEBOARD_FAB2(SCH_1):M_K_DQS_DP(9)
  U2D1 CP85 DDR3_DQS_DP<9> SKX_EXT_B_BGA1-IC,TBD   I172 @BASEBOARD_FAB2_LIB.BASEBOARD_FAB2(SCH_1):PAGE60
  J1B1    7  DQS9P SCONN288_H44441004_PIP-SCONN,HA    I66 @BASEBOARD_FAB2_LIB.BASEBOARD_FAB2(SCH_1):PAGE83
  J9M1    7  DQS9P SCONN288_H44441003_PIP-SCONN,HA   I102 @BASEBOARD_FAB2_LIB.BASEBOARD_FAB2(SCH_1):PAGE84

M_K_ECC<0> @BASEBOARD_FAB2_LIB.BASEBOARD_FAB2(SCH_1):M_K_ECC(0)
  U2D1 DA68 DDR3_ECC<0> SKX_EXT_B_BGA1-IC,TBD   I172 @BASEBOARD_FAB2_LIB.BASEBOARD_FAB2(SCH_1):PAGE60
  J1B1  194  CB<1> SCONN288_H44441004_PIP-SCONN,HA   I111 @BASEBOARD_FAB2_LIB.BASEBOARD_FAB2(SCH_1):PAGE83
  J9M1   49  CB<0> SCONN288_H44441003_PIP-SCONN,HA    I14 @BASEBOARD_FAB2_LIB.BASEBOARD_FAB2(SCH_1):PAGE84

M_K_ECC<1> @BASEBOARD_FAB2_LIB.BASEBOARD_FAB2(SCH_1):M_K_ECC(1)
  U2D1 DE68 DDR3_ECC<1> SKX_EXT_B_BGA1-IC,TBD   I172 @BASEBOARD_FAB2_LIB.BASEBOARD_FAB2(SCH_1):PAGE60
  J1B1   49  CB<0> SCONN288_H44441004_PIP-SCONN,HA   I111 @BASEBOARD_FAB2_LIB.BASEBOARD_FAB2(SCH_1):PAGE83
  J9M1  194  CB<1> SCONN288_H44441003_PIP-SCONN,HA    I14 @BASEBOARD_FAB2_LIB.BASEBOARD_FAB2(SCH_1):PAGE84

M_K_ECC<2> @BASEBOARD_FAB2_LIB.BASEBOARD_FAB2(SCH_1):M_K_ECC(2)
  U2D1 DB65 DDR3_ECC<2> SKX_EXT_B_BGA1-IC,TBD   I172 @BASEBOARD_FAB2_LIB.BASEBOARD_FAB2(SCH_1):PAGE60
  J1B1  201  CB<3> SCONN288_H44441004_PIP-SCONN,HA   I111 @BASEBOARD_FAB2_LIB.BASEBOARD_FAB2(SCH_1):PAGE83
  J9M1   56  CB<2> SCONN288_H44441003_PIP-SCONN,HA    I14 @BASEBOARD_FAB2_LIB.BASEBOARD_FAB2(SCH_1):PAGE84

M_K_ECC<3> @BASEBOARD_FAB2_LIB.BASEBOARD_FAB2(SCH_1):M_K_ECC(3)
  U2D1 DD65 DDR3_ECC<3> SKX_EXT_B_BGA1-IC,TBD   I172 @BASEBOARD_FAB2_LIB.BASEBOARD_FAB2(SCH_1):PAGE60
  J1B1   56  CB<2> SCONN288_H44441004_PIP-SCONN,HA   I111 @BASEBOARD_FAB2_LIB.BASEBOARD_FAB2(SCH_1):PAGE83
  J9M1  201  CB<3> SCONN288_H44441003_PIP-SCONN,HA    I14 @BASEBOARD_FAB2_LIB.BASEBOARD_FAB2(SCH_1):PAGE84

M_K_ECC<4> @BASEBOARD_FAB2_LIB.BASEBOARD_FAB2(SCH_1):M_K_ECC(4)
  U2D1 DB69 DDR3_ECC<4> SKX_EXT_B_BGA1-IC,TBD   I172 @BASEBOARD_FAB2_LIB.BASEBOARD_FAB2(SCH_1):PAGE60
  J1B1  192  CB<5> SCONN288_H44441004_PIP-SCONN,HA   I111 @BASEBOARD_FAB2_LIB.BASEBOARD_FAB2(SCH_1):PAGE83
  J9M1   47  CB<4> SCONN288_H44441003_PIP-SCONN,HA    I14 @BASEBOARD_FAB2_LIB.BASEBOARD_FAB2(SCH_1):PAGE84

M_K_ECC<5> @BASEBOARD_FAB2_LIB.BASEBOARD_FAB2(SCH_1):M_K_ECC(5)
  U2D1 DD69 DDR3_ECC<5> SKX_EXT_B_BGA1-IC,TBD   I172 @BASEBOARD_FAB2_LIB.BASEBOARD_FAB2(SCH_1):PAGE60
  J1B1   47  CB<4> SCONN288_H44441004_PIP-SCONN,HA   I111 @BASEBOARD_FAB2_LIB.BASEBOARD_FAB2(SCH_1):PAGE83
  J9M1  192  CB<5> SCONN288_H44441003_PIP-SCONN,HA    I14 @BASEBOARD_FAB2_LIB.BASEBOARD_FAB2(SCH_1):PAGE84

M_K_ECC<6> @BASEBOARD_FAB2_LIB.BASEBOARD_FAB2(SCH_1):M_K_ECC(6)
  U2D1 DA66 DDR3_ECC<6> SKX_EXT_B_BGA1-IC,TBD   I172 @BASEBOARD_FAB2_LIB.BASEBOARD_FAB2(SCH_1):PAGE60
  J1B1  199  CB<7> SCONN288_H44441004_PIP-SCONN,HA   I111 @BASEBOARD_FAB2_LIB.BASEBOARD_FAB2(SCH_1):PAGE83
  J9M1   54  CB<6> SCONN288_H44441003_PIP-SCONN,HA    I14 @BASEBOARD_FAB2_LIB.BASEBOARD_FAB2(SCH_1):PAGE84

M_K_ECC<7> @BASEBOARD_FAB2_LIB.BASEBOARD_FAB2(SCH_1):M_K_ECC(7)
  U2D1 DE66 DDR3_ECC<7> SKX_EXT_B_BGA1-IC,TBD   I172 @BASEBOARD_FAB2_LIB.BASEBOARD_FAB2(SCH_1):PAGE60
  J1B1   54  CB<6> SCONN288_H44441004_PIP-SCONN,HA   I111 @BASEBOARD_FAB2_LIB.BASEBOARD_FAB2(SCH_1):PAGE83
  J9M1  199  CB<7> SCONN288_H44441003_PIP-SCONN,HA    I14 @BASEBOARD_FAB2_LIB.BASEBOARD_FAB2(SCH_1):PAGE84

M_K_MA<0> @BASEBOARD_FAB2_LIB.BASEBOARD_FAB2(SCH_1):M_K_MA(0)
  U2D1 EB53 DDR3_MA<0> SKX_EXT_B_BGA1-IC,TBD   I172 @BASEBOARD_FAB2_LIB.BASEBOARD_FAB2(SCH_1):PAGE60
  J1B1   79     A0 SCONN288_H44441004_PIP-SCONN,HA   I111 @BASEBOARD_FAB2_LIB.BASEBOARD_FAB2(SCH_1):PAGE83
  J9M1   79     A0 SCONN288_H44441003_PIP-SCONN,HA    I14 @BASEBOARD_FAB2_LIB.BASEBOARD_FAB2(SCH_1):PAGE84

M_K_MA<10> @BASEBOARD_FAB2_LIB.BASEBOARD_FAB2(SCH_1):M_K_MA(10)
  U2D1 DW54 DDR3_MA<10> SKX_EXT_B_BGA1-IC,TBD   I172 @BASEBOARD_FAB2_LIB.BASEBOARD_FAB2(SCH_1):PAGE60
  J1B1  225    A10 SCONN288_H44441004_PIP-SCONN,HA   I111 @BASEBOARD_FAB2_LIB.BASEBOARD_FAB2(SCH_1):PAGE83
  J9M1  225    A10 SCONN288_H44441003_PIP-SCONN,HA    I14 @BASEBOARD_FAB2_LIB.BASEBOARD_FAB2(SCH_1):PAGE84

M_K_MA<11> @BASEBOARD_FAB2_LIB.BASEBOARD_FAB2(SCH_1):M_K_MA(11)
  U2D1 EB61 DDR3_MA<11> SKX_EXT_B_BGA1-IC,TBD   I172 @BASEBOARD_FAB2_LIB.BASEBOARD_FAB2(SCH_1):PAGE60
  J1B1  210    A11 SCONN288_H44441004_PIP-SCONN,HA   I111 @BASEBOARD_FAB2_LIB.BASEBOARD_FAB2(SCH_1):PAGE83
  J9M1  210    A11 SCONN288_H44441003_PIP-SCONN,HA    I14 @BASEBOARD_FAB2_LIB.BASEBOARD_FAB2(SCH_1):PAGE84

M_K_MA<12> @BASEBOARD_FAB2_LIB.BASEBOARD_FAB2(SCH_1):M_K_MA(12)
  U2D1 DT63 DDR3_MA<12> SKX_EXT_B_BGA1-IC,TBD   I172 @BASEBOARD_FAB2_LIB.BASEBOARD_FAB2(SCH_1):PAGE60
  J1B1   65    A12 SCONN288_H44441004_PIP-SCONN,HA   I111 @BASEBOARD_FAB2_LIB.BASEBOARD_FAB2(SCH_1):PAGE83
  J9M1   65    A12 SCONN288_H44441003_PIP-SCONN,HA    I14 @BASEBOARD_FAB2_LIB.BASEBOARD_FAB2(SCH_1):PAGE84

M_K_MA<13> @BASEBOARD_FAB2_LIB.BASEBOARD_FAB2(SCH_1):M_K_MA(13)
  U2D1 DW48 DDR3_MA<13> SKX_EXT_B_BGA1-IC,TBD   I172 @BASEBOARD_FAB2_LIB.BASEBOARD_FAB2(SCH_1):PAGE60
  J1B1  232    A13 SCONN288_H44441004_PIP-SCONN,HA   I111 @BASEBOARD_FAB2_LIB.BASEBOARD_FAB2(SCH_1):PAGE83
  J9M1  232    A13 SCONN288_H44441003_PIP-SCONN,HA    I14 @BASEBOARD_FAB2_LIB.BASEBOARD_FAB2(SCH_1):PAGE84

M_K_MA<14> @BASEBOARD_FAB2_LIB.BASEBOARD_FAB2(SCH_1):M_K_MA(14)
  U2D1 ED51 DDR3_MA<14> SKX_EXT_B_BGA1-IC,TBD   I172 @BASEBOARD_FAB2_LIB.BASEBOARD_FAB2(SCH_1):PAGE60
  J1B1  228 A14_WE_N SCONN288_H44441004_PIP-SCONN,HA   I111 @BASEBOARD_FAB2_LIB.BASEBOARD_FAB2(SCH_1):PAGE83
  J9M1  228 A14_WE_N SCONN288_H44441003_PIP-SCONN,HA    I14 @BASEBOARD_FAB2_LIB.BASEBOARD_FAB2(SCH_1):PAGE84

M_K_MA<15> @BASEBOARD_FAB2_LIB.BASEBOARD_FAB2(SCH_1):M_K_MA(15)
  U2D1 DV49 DDR3_MA<15> SKX_EXT_B_BGA1-IC,TBD   I172 @BASEBOARD_FAB2_LIB.BASEBOARD_FAB2(SCH_1):PAGE60
  J1B1   86 A15_CAS_N SCONN288_H44441004_PIP-SCONN,HA   I111 @BASEBOARD_FAB2_LIB.BASEBOARD_FAB2(SCH_1):PAGE83
  J9M1   86 A15_CAS_N SCONN288_H44441003_PIP-SCONN,HA    I14 @BASEBOARD_FAB2_LIB.BASEBOARD_FAB2(SCH_1):PAGE84

M_K_MA<16> @BASEBOARD_FAB2_LIB.BASEBOARD_FAB2(SCH_1):M_K_MA(16)
  U2D1 EA52 DDR3_MA<16> SKX_EXT_B_BGA1-IC,TBD   I172 @BASEBOARD_FAB2_LIB.BASEBOARD_FAB2(SCH_1):PAGE60
  J1B1   82 A16_RAS_N SCONN288_H44441004_PIP-SCONN,HA   I111 @BASEBOARD_FAB2_LIB.BASEBOARD_FAB2(SCH_1):PAGE83
  J9M1   82 A16_RAS_N SCONN288_H44441003_PIP-SCONN,HA    I14 @BASEBOARD_FAB2_LIB.BASEBOARD_FAB2(SCH_1):PAGE84

M_K_MA<17> @BASEBOARD_FAB2_LIB.BASEBOARD_FAB2(SCH_1):M_K_MA(17)
  U2D1 EA46 DDR3_MA<17> SKX_EXT_B_BGA1-IC,TBD   I172 @BASEBOARD_FAB2_LIB.BASEBOARD_FAB2(SCH_1):PAGE60
  J1B1  234    A17 SCONN288_H44441004_PIP-SCONN,HA   I111 @BASEBOARD_FAB2_LIB.BASEBOARD_FAB2(SCH_1):PAGE83
  J9M1  234    A17 SCONN288_H44441003_PIP-SCONN,HA    I14 @BASEBOARD_FAB2_LIB.BASEBOARD_FAB2(SCH_1):PAGE84

M_K_MA<1> @BASEBOARD_FAB2_LIB.BASEBOARD_FAB2(SCH_1):M_K_MA(1)
  U2D1 ED57 DDR3_MA<1> SKX_EXT_B_BGA1-IC,TBD   I172 @BASEBOARD_FAB2_LIB.BASEBOARD_FAB2(SCH_1):PAGE60
  J1B1   72     A1 SCONN288_H44441004_PIP-SCONN,HA   I111 @BASEBOARD_FAB2_LIB.BASEBOARD_FAB2(SCH_1):PAGE83
  J9M1   72     A1 SCONN288_H44441003_PIP-SCONN,HA    I14 @BASEBOARD_FAB2_LIB.BASEBOARD_FAB2(SCH_1):PAGE84

M_K_MA<2> @BASEBOARD_FAB2_LIB.BASEBOARD_FAB2(SCH_1):M_K_MA(2)
  U2D1 EE58 DDR3_MA<2> SKX_EXT_B_BGA1-IC,TBD   I172 @BASEBOARD_FAB2_LIB.BASEBOARD_FAB2(SCH_1):PAGE60
  J1B1  216     A2 SCONN288_H44441004_PIP-SCONN,HA   I111 @BASEBOARD_FAB2_LIB.BASEBOARD_FAB2(SCH_1):PAGE83
  J9M1  216     A2 SCONN288_H44441003_PIP-SCONN,HA    I14 @BASEBOARD_FAB2_LIB.BASEBOARD_FAB2(SCH_1):PAGE84

M_K_MA<3> @BASEBOARD_FAB2_LIB.BASEBOARD_FAB2(SCH_1):M_K_MA(3)
  U2D1 EB57 DDR3_MA<3> SKX_EXT_B_BGA1-IC,TBD   I172 @BASEBOARD_FAB2_LIB.BASEBOARD_FAB2(SCH_1):PAGE60
  J1B1   71     A3 SCONN288_H44441004_PIP-SCONN,HA   I111 @BASEBOARD_FAB2_LIB.BASEBOARD_FAB2(SCH_1):PAGE83
  J9M1   71     A3 SCONN288_H44441003_PIP-SCONN,HA    I14 @BASEBOARD_FAB2_LIB.BASEBOARD_FAB2(SCH_1):PAGE84

M_K_MA<4> @BASEBOARD_FAB2_LIB.BASEBOARD_FAB2(SCH_1):M_K_MA(4)
  U2D1 ED59 DDR3_MA<4> SKX_EXT_B_BGA1-IC,TBD   I172 @BASEBOARD_FAB2_LIB.BASEBOARD_FAB2(SCH_1):PAGE60
  J1B1  214     A4 SCONN288_H44441004_PIP-SCONN,HA   I111 @BASEBOARD_FAB2_LIB.BASEBOARD_FAB2(SCH_1):PAGE83
  J9M1  214     A4 SCONN288_H44441003_PIP-SCONN,HA    I14 @BASEBOARD_FAB2_LIB.BASEBOARD_FAB2(SCH_1):PAGE84

M_K_MA<5> @BASEBOARD_FAB2_LIB.BASEBOARD_FAB2(SCH_1):M_K_MA(5)
  U2D1 EA58 DDR3_MA<5> SKX_EXT_B_BGA1-IC,TBD   I172 @BASEBOARD_FAB2_LIB.BASEBOARD_FAB2(SCH_1):PAGE60
  J1B1  213     A5 SCONN288_H44441004_PIP-SCONN,HA   I111 @BASEBOARD_FAB2_LIB.BASEBOARD_FAB2(SCH_1):PAGE83
  J9M1  213     A5 SCONN288_H44441003_PIP-SCONN,HA    I14 @BASEBOARD_FAB2_LIB.BASEBOARD_FAB2(SCH_1):PAGE84

M_K_MA<6> @BASEBOARD_FAB2_LIB.BASEBOARD_FAB2(SCH_1):M_K_MA(6)
  U2D1 EE60 DDR3_MA<6> SKX_EXT_B_BGA1-IC,TBD   I172 @BASEBOARD_FAB2_LIB.BASEBOARD_FAB2(SCH_1):PAGE60
  J1B1   69     A6 SCONN288_H44441004_PIP-SCONN,HA   I111 @BASEBOARD_FAB2_LIB.BASEBOARD_FAB2(SCH_1):PAGE83
  J9M1   69     A6 SCONN288_H44441003_PIP-SCONN,HA    I14 @BASEBOARD_FAB2_LIB.BASEBOARD_FAB2(SCH_1):PAGE84

M_K_MA<7> @BASEBOARD_FAB2_LIB.BASEBOARD_FAB2(SCH_1):M_K_MA(7)
  U2D1 EA60 DDR3_MA<7> SKX_EXT_B_BGA1-IC,TBD   I172 @BASEBOARD_FAB2_LIB.BASEBOARD_FAB2(SCH_1):PAGE60
  J1B1  211     A7 SCONN288_H44441004_PIP-SCONN,HA   I111 @BASEBOARD_FAB2_LIB.BASEBOARD_FAB2(SCH_1):PAGE83
  J9M1  211     A7 SCONN288_H44441003_PIP-SCONN,HA    I14 @BASEBOARD_FAB2_LIB.BASEBOARD_FAB2(SCH_1):PAGE84

M_K_MA<8> @BASEBOARD_FAB2_LIB.BASEBOARD_FAB2(SCH_1):M_K_MA(8)
  U2D1 EB59 DDR3_MA<8> SKX_EXT_B_BGA1-IC,TBD   I172 @BASEBOARD_FAB2_LIB.BASEBOARD_FAB2(SCH_1):PAGE60
  J1B1   68     A8 SCONN288_H44441004_PIP-SCONN,HA   I111 @BASEBOARD_FAB2_LIB.BASEBOARD_FAB2(SCH_1):PAGE83
  J9M1   68     A8 SCONN288_H44441003_PIP-SCONN,HA    I14 @BASEBOARD_FAB2_LIB.BASEBOARD_FAB2(SCH_1):PAGE84

M_K_MA<9> @BASEBOARD_FAB2_LIB.BASEBOARD_FAB2(SCH_1):M_K_MA(9)
  U2D1 EF61 DDR3_MA<9> SKX_EXT_B_BGA1-IC,TBD   I172 @BASEBOARD_FAB2_LIB.BASEBOARD_FAB2(SCH_1):PAGE60
  J1B1   66     A9 SCONN288_H44441004_PIP-SCONN,HA   I111 @BASEBOARD_FAB2_LIB.BASEBOARD_FAB2(SCH_1):PAGE83
  J9M1   66     A9 SCONN288_H44441003_PIP-SCONN,HA    I14 @BASEBOARD_FAB2_LIB.BASEBOARD_FAB2(SCH_1):PAGE84

M_K_ODT<0> @BASEBOARD_FAB2_LIB.BASEBOARD_FAB2(SCH_1):M_K_ODT(0)
  U2D1 EE50 DDR3_ODT<0> SKX_EXT_B_BGA1-IC,TBD   I172 @BASEBOARD_FAB2_LIB.BASEBOARD_FAB2(SCH_1):PAGE60
  J1B1   87 ODT<0> SCONN288_H44441004_PIP-SCONN,HA   I111 @BASEBOARD_FAB2_LIB.BASEBOARD_FAB2(SCH_1):PAGE83

M_K_ODT<1> @BASEBOARD_FAB2_LIB.BASEBOARD_FAB2(SCH_1):M_K_ODT(1)
  U2D1 EE48 DDR3_ODT<1> SKX_EXT_B_BGA1-IC,TBD   I172 @BASEBOARD_FAB2_LIB.BASEBOARD_FAB2(SCH_1):PAGE60
  J1B1   91 ODT<1> SCONN288_H44441004_PIP-SCONN,HA   I111 @BASEBOARD_FAB2_LIB.BASEBOARD_FAB2(SCH_1):PAGE83

M_K_ODT<2> @BASEBOARD_FAB2_LIB.BASEBOARD_FAB2(SCH_1):M_K_ODT(2)
  U2D1 EA50 DDR3_ODT<2> SKX_EXT_B_BGA1-IC,TBD   I172 @BASEBOARD_FAB2_LIB.BASEBOARD_FAB2(SCH_1):PAGE60
  J9M1   87 ODT<0> SCONN288_H44441003_PIP-SCONN,HA    I14 @BASEBOARD_FAB2_LIB.BASEBOARD_FAB2(SCH_1):PAGE84

M_K_ODT<3> @BASEBOARD_FAB2_LIB.BASEBOARD_FAB2(SCH_1):M_K_ODT(3)
  U2D1 EA48 DDR3_ODT<3> SKX_EXT_B_BGA1-IC,TBD   I172 @BASEBOARD_FAB2_LIB.BASEBOARD_FAB2(SCH_1):PAGE60
  J9M1   91 ODT<1> SCONN288_H44441003_PIP-SCONN,HA    I14 @BASEBOARD_FAB2_LIB.BASEBOARD_FAB2(SCH_1):PAGE84

M_K_PAR @BASEBOARD_FAB2_LIB.BASEBOARD_FAB2(SCH_1):M_K_PAR
  U2D1 ED53 DDR3_PAR SKX_EXT_B_BGA1-IC,TBD   I172 @BASEBOARD_FAB2_LIB.BASEBOARD_FAB2(SCH_1):PAGE60
  J1B1  222    PAR SCONN288_H44441004_PIP-SCONN,HA   I111 @BASEBOARD_FAB2_LIB.BASEBOARD_FAB2(SCH_1):PAGE83
  J9M1  222    PAR SCONN288_H44441003_PIP-SCONN,HA    I14 @BASEBOARD_FAB2_LIB.BASEBOARD_FAB2(SCH_1):PAGE84

M_K_VREF @BASEBOARD_FAB2_LIB.BASEBOARD_FAB2(SCH_1):M_K_VREF
  J1B1  146 VREFCA SCONN288_H44441004_PIP-SCONN,HA   I111 @BASEBOARD_FAB2_LIB.BASEBOARD_FAB2(SCH_1):PAGE83
  C1B9    1      A CAP_A_0402V-0.01UF,25V,10%,X7RA   I176 @BASEBOARD_FAB2_LIB.BASEBOARD_FAB2(SCH_1):PAGE83
  C9M1    1      A CAP_A_0402V-0.01UF,25V,10%,X7RA     I4 @BASEBOARD_FAB2_LIB.BASEBOARD_FAB2(SCH_1):PAGE84
  J9M1  146 VREFCA SCONN288_H44441003_PIP-SCONN,HA    I14 @BASEBOARD_FAB2_LIB.BASEBOARD_FAB2(SCH_1):PAGE84
 R9L11    1      A RES_0402-1.00K,1%,1/16W,CHIP,GA     I4 @BASEBOARD_FAB2_LIB.BASEBOARD_FAB2(SCH_1):PAGE100
  R9M1    2      B RES_0402-1.00K,1%,1/16W,CHIP,GA    I11 @BASEBOARD_FAB2_LIB.BASEBOARD_FAB2(SCH_1):PAGE100
  R9M2    2      B RES_0402-2,1.0%,1/16W,CHIP,G21A    I13 @BASEBOARD_FAB2_LIB.BASEBOARD_FAB2(SCH_1):PAGE100

M_L_ACT_N @BASEBOARD_FAB2_LIB.BASEBOARD_FAB2(SCH_1):M_L_ACT_N
  U2D1 DR62 DDR4_ACT_N SKX_EXT_B_BGA1-IC,TBD   I172 @BASEBOARD_FAB2_LIB.BASEBOARD_FAB2(SCH_1):PAGE61
  J1A2   62  ACT_N SCONN288_H44441004_PIP-SCONN,HA   I111 @BASEBOARD_FAB2_LIB.BASEBOARD_FAB2(SCH_1):PAGE85
  J9L2   62  ACT_N SCONN288_H44441003_PIP-SCONN,HA    I12 @BASEBOARD_FAB2_LIB.BASEBOARD_FAB2(SCH_1):PAGE86

M_L_ALERT_N @BASEBOARD_FAB2_LIB.BASEBOARD_FAB2(SCH_1):M_L_ALERT_N
  U2D1 DT61 DDR4_ALERT_N SKX_EXT_B_BGA1-IC,TBD   I172 @BASEBOARD_FAB2_LIB.BASEBOARD_FAB2(SCH_1):PAGE61
  J1A2  208 ALERT_N SCONN288_H44441004_PIP-SCONN,HA   I111 @BASEBOARD_FAB2_LIB.BASEBOARD_FAB2(SCH_1):PAGE85
  J9L2  208 ALERT_N SCONN288_H44441003_PIP-SCONN,HA    I12 @BASEBOARD_FAB2_LIB.BASEBOARD_FAB2(SCH_1):PAGE86

M_L_BA<0> @BASEBOARD_FAB2_LIB.BASEBOARD_FAB2(SCH_1):M_L_BA(0)
  U2D1 DM53 DDR4_BA<0> SKX_EXT_B_BGA1-IC,TBD   I172 @BASEBOARD_FAB2_LIB.BASEBOARD_FAB2(SCH_1):PAGE61
  J1A2   81  BA<0> SCONN288_H44441004_PIP-SCONN,HA   I111 @BASEBOARD_FAB2_LIB.BASEBOARD_FAB2(SCH_1):PAGE85
  J9L2   81  BA<0> SCONN288_H44441003_PIP-SCONN,HA    I12 @BASEBOARD_FAB2_LIB.BASEBOARD_FAB2(SCH_1):PAGE86

M_L_BA<1> @BASEBOARD_FAB2_LIB.BASEBOARD_FAB2(SCH_1):M_L_BA(1)
  U2D1 DV55 DDR4_BA<1> SKX_EXT_B_BGA1-IC,TBD   I172 @BASEBOARD_FAB2_LIB.BASEBOARD_FAB2(SCH_1):PAGE61
  J1A2  224  BA<1> SCONN288_H44441004_PIP-SCONN,HA   I111 @BASEBOARD_FAB2_LIB.BASEBOARD_FAB2(SCH_1):PAGE85
  J9L2  224  BA<1> SCONN288_H44441003_PIP-SCONN,HA    I12 @BASEBOARD_FAB2_LIB.BASEBOARD_FAB2(SCH_1):PAGE86

M_L_BG<0> @BASEBOARD_FAB2_LIB.BASEBOARD_FAB2(SCH_1):M_L_BG(0)
  U2D1 DJ62 DDR4_BG<0> SKX_EXT_B_BGA1-IC,TBD   I172 @BASEBOARD_FAB2_LIB.BASEBOARD_FAB2(SCH_1):PAGE61
  J1A2   63  BG<0> SCONN288_H44441004_PIP-SCONN,HA   I111 @BASEBOARD_FAB2_LIB.BASEBOARD_FAB2(SCH_1):PAGE85
  J9L2   63  BG<0> SCONN288_H44441003_PIP-SCONN,HA    I12 @BASEBOARD_FAB2_LIB.BASEBOARD_FAB2(SCH_1):PAGE86

M_L_BG<1> @BASEBOARD_FAB2_LIB.BASEBOARD_FAB2(SCH_1):M_L_BG(1)
  U2D1 DM61 DDR4_BG<1> SKX_EXT_B_BGA1-IC,TBD   I172 @BASEBOARD_FAB2_LIB.BASEBOARD_FAB2(SCH_1):PAGE61
  J1A2  207  BG<1> SCONN288_H44441004_PIP-SCONN,HA   I111 @BASEBOARD_FAB2_LIB.BASEBOARD_FAB2(SCH_1):PAGE85
  J9L2  207  BG<1> SCONN288_H44441003_PIP-SCONN,HA    I12 @BASEBOARD_FAB2_LIB.BASEBOARD_FAB2(SCH_1):PAGE86

M_L_C<2> @BASEBOARD_FAB2_LIB.BASEBOARD_FAB2(SCH_1):M_L_C(2)
  U2D1 DT47 DDR4_CID<2> SKX_EXT_B_BGA1-IC,TBD   I172 @BASEBOARD_FAB2_LIB.BASEBOARD_FAB2(SCH_1):PAGE61
  J1A2  235   C<2> SCONN288_H44441004_PIP-SCONN,HA   I111 @BASEBOARD_FAB2_LIB.BASEBOARD_FAB2(SCH_1):PAGE85
  J9L2  235   C<2> SCONN288_H44441003_PIP-SCONN,HA    I12 @BASEBOARD_FAB2_LIB.BASEBOARD_FAB2(SCH_1):PAGE86

M_L_CKE<0> @BASEBOARD_FAB2_LIB.BASEBOARD_FAB2(SCH_1):M_L_CKE(0)
  U2D1 DM63 DDR4_CKE<0> SKX_EXT_B_BGA1-IC,TBD   I172 @BASEBOARD_FAB2_LIB.BASEBOARD_FAB2(SCH_1):PAGE61
  J1A2   60 CKE<0> SCONN288_H44441004_PIP-SCONN,HA   I111 @BASEBOARD_FAB2_LIB.BASEBOARD_FAB2(SCH_1):PAGE85

M_L_CKE<1> @BASEBOARD_FAB2_LIB.BASEBOARD_FAB2(SCH_1):M_L_CKE(1)
  U2D1 DN64 DDR4_CKE<1> SKX_EXT_B_BGA1-IC,TBD   I172 @BASEBOARD_FAB2_LIB.BASEBOARD_FAB2(SCH_1):PAGE61
  J1A2  203 CKE<1> SCONN288_H44441004_PIP-SCONN,HA   I111 @BASEBOARD_FAB2_LIB.BASEBOARD_FAB2(SCH_1):PAGE85

M_L_CKE<2> @BASEBOARD_FAB2_LIB.BASEBOARD_FAB2(SCH_1):M_L_CKE(2)
  U2D1 DL64 DDR4_CKE<2> SKX_EXT_B_BGA1-IC,TBD   I172 @BASEBOARD_FAB2_LIB.BASEBOARD_FAB2(SCH_1):PAGE61
  J9L2   60 CKE<0> SCONN288_H44441003_PIP-SCONN,HA    I12 @BASEBOARD_FAB2_LIB.BASEBOARD_FAB2(SCH_1):PAGE86

M_L_CKE<3> @BASEBOARD_FAB2_LIB.BASEBOARD_FAB2(SCH_1):M_L_CKE(3)
  U2D1 DR64 DDR4_CKE<3> SKX_EXT_B_BGA1-IC,TBD   I172 @BASEBOARD_FAB2_LIB.BASEBOARD_FAB2(SCH_1):PAGE61
  J9L2  203 CKE<1> SCONN288_H44441003_PIP-SCONN,HA    I12 @BASEBOARD_FAB2_LIB.BASEBOARD_FAB2(SCH_1):PAGE86

M_L_CLK_DN<0> @BASEBOARD_FAB2_LIB.BASEBOARD_FAB2(SCH_1):M_L_CLK_DN(0)
  U2D1 DM55 DDR4_CLK_DN<0> SKX_EXT_B_BGA1-IC,TBD   I172 @BASEBOARD_FAB2_LIB.BASEBOARD_FAB2(SCH_1):PAGE61
  J1A2   75   CK0N SCONN288_H44441004_PIP-SCONN,HA   I111 @BASEBOARD_FAB2_LIB.BASEBOARD_FAB2(SCH_1):PAGE85

M_L_CLK_DN<1> @BASEBOARD_FAB2_LIB.BASEBOARD_FAB2(SCH_1):M_L_CLK_DN(1)
  U2D1 DR54 DDR4_CLK_DN<1> SKX_EXT_B_BGA1-IC,TBD   I172 @BASEBOARD_FAB2_LIB.BASEBOARD_FAB2(SCH_1):PAGE61
  J1A2  219   CK1N SCONN288_H44441004_PIP-SCONN,HA   I111 @BASEBOARD_FAB2_LIB.BASEBOARD_FAB2(SCH_1):PAGE85

M_L_CLK_DN<2> @BASEBOARD_FAB2_LIB.BASEBOARD_FAB2(SCH_1):M_L_CLK_DN(2)
  U2D1 DM57 DDR4_CLK_DN<2> SKX_EXT_B_BGA1-IC,TBD   I172 @BASEBOARD_FAB2_LIB.BASEBOARD_FAB2(SCH_1):PAGE61
  J9L2   75   CK0N SCONN288_H44441003_PIP-SCONN,HA    I12 @BASEBOARD_FAB2_LIB.BASEBOARD_FAB2(SCH_1):PAGE86

M_L_CLK_DN<3> @BASEBOARD_FAB2_LIB.BASEBOARD_FAB2(SCH_1):M_L_CLK_DN(3)
  U2D1 DT57 DDR4_CLK_DN<3> SKX_EXT_B_BGA1-IC,TBD   I172 @BASEBOARD_FAB2_LIB.BASEBOARD_FAB2(SCH_1):PAGE61
  J9L2  219   CK1N SCONN288_H44441003_PIP-SCONN,HA    I12 @BASEBOARD_FAB2_LIB.BASEBOARD_FAB2(SCH_1):PAGE86

M_L_CLK_DP<0> @BASEBOARD_FAB2_LIB.BASEBOARD_FAB2(SCH_1):M_L_CLK_DP(0)
  U2D1 DN54 DDR4_CLK_DP<0> SKX_EXT_B_BGA1-IC,TBD   I172 @BASEBOARD_FAB2_LIB.BASEBOARD_FAB2(SCH_1):PAGE61
  J1A2   74   CK0P SCONN288_H44441004_PIP-SCONN,HA   I111 @BASEBOARD_FAB2_LIB.BASEBOARD_FAB2(SCH_1):PAGE85

M_L_CLK_DP<1> @BASEBOARD_FAB2_LIB.BASEBOARD_FAB2(SCH_1):M_L_CLK_DP(1)
  U2D1 DT53 DDR4_CLK_DP<1> SKX_EXT_B_BGA1-IC,TBD   I172 @BASEBOARD_FAB2_LIB.BASEBOARD_FAB2(SCH_1):PAGE61
  J1A2  218   CK1P SCONN288_H44441004_PIP-SCONN,HA   I111 @BASEBOARD_FAB2_LIB.BASEBOARD_FAB2(SCH_1):PAGE85

M_L_CLK_DP<2> @BASEBOARD_FAB2_LIB.BASEBOARD_FAB2(SCH_1):M_L_CLK_DP(2)
  U2D1 DN56 DDR4_CLK_DP<2> SKX_EXT_B_BGA1-IC,TBD   I172 @BASEBOARD_FAB2_LIB.BASEBOARD_FAB2(SCH_1):PAGE61
  J9L2   74   CK0P SCONN288_H44441003_PIP-SCONN,HA    I12 @BASEBOARD_FAB2_LIB.BASEBOARD_FAB2(SCH_1):PAGE86

M_L_CLK_DP<3> @BASEBOARD_FAB2_LIB.BASEBOARD_FAB2(SCH_1):M_L_CLK_DP(3)
  U2D1 DR56 DDR4_CLK_DP<3> SKX_EXT_B_BGA1-IC,TBD   I172 @BASEBOARD_FAB2_LIB.BASEBOARD_FAB2(SCH_1):PAGE61
  J9L2  218   CK1P SCONN288_H44441003_PIP-SCONN,HA    I12 @BASEBOARD_FAB2_LIB.BASEBOARD_FAB2(SCH_1):PAGE86

M_L_CPU_VREF @BASEBOARD_FAB2_LIB.BASEBOARD_FAB2(SCH_1):M_L_CPU_VREF
  U2D1 CT61 DDR4_CAVREF SKX_EXT_B_BGA1-IC,TBD   I172 @BASEBOARD_FAB2_LIB.BASEBOARD_FAB2(SCH_1):PAGE55
  R9L8    1      A RES_0402-2,1.0%,1/16W,CHIP,G21A    I29 @BASEBOARD_FAB2_LIB.BASEBOARD_FAB2(SCH_1):PAGE100
  C9L8    1      A CAP_A_0402V-0.01UF,25V,10%,X7RA    I30 @BASEBOARD_FAB2_LIB.BASEBOARD_FAB2(SCH_1):PAGE100

M_L_CS_N<0> @BASEBOARD_FAB2_LIB.BASEBOARD_FAB2(SCH_1):M_L_CS_N(0)
  U2D1 DV51 DDR4_CS_N<0> SKX_EXT_B_BGA1-IC,TBD   I172 @BASEBOARD_FAB2_LIB.BASEBOARD_FAB2(SCH_1):PAGE61
  J1A2   84   S0_N SCONN288_H44441004_PIP-SCONN,HA   I111 @BASEBOARD_FAB2_LIB.BASEBOARD_FAB2(SCH_1):PAGE85

M_L_CS_N<1> @BASEBOARD_FAB2_LIB.BASEBOARD_FAB2(SCH_1):M_L_CS_N(1)
  U2D1 DN50 DDR4_CS_N<1> SKX_EXT_B_BGA1-IC,TBD   I172 @BASEBOARD_FAB2_LIB.BASEBOARD_FAB2(SCH_1):PAGE61
  J1A2   89   S1_N SCONN288_H44441004_PIP-SCONN,HA   I111 @BASEBOARD_FAB2_LIB.BASEBOARD_FAB2(SCH_1):PAGE85

M_L_CS_N<2> @BASEBOARD_FAB2_LIB.BASEBOARD_FAB2(SCH_1):M_L_CS_N(2)
  U2D1 DR46 DDR4_CS_N<2> SKX_EXT_B_BGA1-IC,TBD   I172 @BASEBOARD_FAB2_LIB.BASEBOARD_FAB2(SCH_1):PAGE61
  J1A2   93 S2_N_C<0> SCONN288_H44441004_PIP-SCONN,HA   I111 @BASEBOARD_FAB2_LIB.BASEBOARD_FAB2(SCH_1):PAGE85

M_L_CS_N<3> @BASEBOARD_FAB2_LIB.BASEBOARD_FAB2(SCH_1):M_L_CS_N(3)
  U2D1 DK47 DDR4_CS_N<3> SKX_EXT_B_BGA1-IC,TBD   I172 @BASEBOARD_FAB2_LIB.BASEBOARD_FAB2(SCH_1):PAGE61
  J1A2  237 S3_N_C<1> SCONN288_H44441004_PIP-SCONN,HA   I111 @BASEBOARD_FAB2_LIB.BASEBOARD_FAB2(SCH_1):PAGE85

M_L_CS_N<4> @BASEBOARD_FAB2_LIB.BASEBOARD_FAB2(SCH_1):M_L_CS_N(4)
  U2D1 DW50 DDR4_CS_N<4> SKX_EXT_B_BGA1-IC,TBD   I172 @BASEBOARD_FAB2_LIB.BASEBOARD_FAB2(SCH_1):PAGE61
  J9L2   84   S0_N SCONN288_H44441003_PIP-SCONN,HA    I12 @BASEBOARD_FAB2_LIB.BASEBOARD_FAB2(SCH_1):PAGE86

M_L_CS_N<5> @BASEBOARD_FAB2_LIB.BASEBOARD_FAB2(SCH_1):M_L_CS_N(5)
  U2D1 DM49 DDR4_CS_N<5> SKX_EXT_B_BGA1-IC,TBD   I172 @BASEBOARD_FAB2_LIB.BASEBOARD_FAB2(SCH_1):PAGE61
  J9L2   89   S1_N SCONN288_H44441003_PIP-SCONN,HA    I12 @BASEBOARD_FAB2_LIB.BASEBOARD_FAB2(SCH_1):PAGE86

M_L_CS_N<6> @BASEBOARD_FAB2_LIB.BASEBOARD_FAB2(SCH_1):M_L_CS_N(6)
  U2D1 DT45 DDR4_CS_N<6> SKX_EXT_B_BGA1-IC,TBD   I172 @BASEBOARD_FAB2_LIB.BASEBOARD_FAB2(SCH_1):PAGE61
  J9L2   93 S2_N_C<0> SCONN288_H44441003_PIP-SCONN,HA    I12 @BASEBOARD_FAB2_LIB.BASEBOARD_FAB2(SCH_1):PAGE86

M_L_CS_N<7> @BASEBOARD_FAB2_LIB.BASEBOARD_FAB2(SCH_1):M_L_CS_N(7)
  U2D1 DN46 DDR4_CS_N<7> SKX_EXT_B_BGA1-IC,TBD   I172 @BASEBOARD_FAB2_LIB.BASEBOARD_FAB2(SCH_1):PAGE61
  J9L2  237 S3_N_C<1> SCONN288_H44441003_PIP-SCONN,HA    I12 @BASEBOARD_FAB2_LIB.BASEBOARD_FAB2(SCH_1):PAGE86

M_L_DQ<0> @BASEBOARD_FAB2_LIB.BASEBOARD_FAB2(SCH_1):M_L_DQ(0)
  U2D1 CM79 DDR4_DQ<0> SKX_EXT_B_BGA1-IC,TBD   I172 @BASEBOARD_FAB2_LIB.BASEBOARD_FAB2(SCH_1):PAGE61
  J1A2  150  DQ<1> SCONN288_H44441004_PIP-SCONN,HA   I111 @BASEBOARD_FAB2_LIB.BASEBOARD_FAB2(SCH_1):PAGE85
  J9L2    5  DQ<0> SCONN288_H44441003_PIP-SCONN,HA    I12 @BASEBOARD_FAB2_LIB.BASEBOARD_FAB2(SCH_1):PAGE86

M_L_DQ<10> @BASEBOARD_FAB2_LIB.BASEBOARD_FAB2(SCH_1):M_L_DQ(10)
  U2D1 DE80 DDR4_DQ<10> SKX_EXT_B_BGA1-IC,TBD   I172 @BASEBOARD_FAB2_LIB.BASEBOARD_FAB2(SCH_1):PAGE61
  J1A2  168 DQ<11> SCONN288_H44441004_PIP-SCONN,HA   I111 @BASEBOARD_FAB2_LIB.BASEBOARD_FAB2(SCH_1):PAGE85
  J9L2   23 DQ<10> SCONN288_H44441003_PIP-SCONN,HA    I12 @BASEBOARD_FAB2_LIB.BASEBOARD_FAB2(SCH_1):PAGE86

M_L_DQ<11> @BASEBOARD_FAB2_LIB.BASEBOARD_FAB2(SCH_1):M_L_DQ(11)
  U2D1 DF81 DDR4_DQ<11> SKX_EXT_B_BGA1-IC,TBD   I172 @BASEBOARD_FAB2_LIB.BASEBOARD_FAB2(SCH_1):PAGE61
  J1A2   23 DQ<10> SCONN288_H44441004_PIP-SCONN,HA   I111 @BASEBOARD_FAB2_LIB.BASEBOARD_FAB2(SCH_1):PAGE85
  J9L2  168 DQ<11> SCONN288_H44441003_PIP-SCONN,HA    I12 @BASEBOARD_FAB2_LIB.BASEBOARD_FAB2(SCH_1):PAGE86

M_L_DQ<12> @BASEBOARD_FAB2_LIB.BASEBOARD_FAB2(SCH_1):M_L_DQ(12)
  U2D1 CY79 DDR4_DQ<12> SKX_EXT_B_BGA1-IC,TBD   I172 @BASEBOARD_FAB2_LIB.BASEBOARD_FAB2(SCH_1):PAGE61
  J1A2  159 DQ<13> SCONN288_H44441004_PIP-SCONN,HA   I111 @BASEBOARD_FAB2_LIB.BASEBOARD_FAB2(SCH_1):PAGE85
  J9L2   14 DQ<12> SCONN288_H44441003_PIP-SCONN,HA    I12 @BASEBOARD_FAB2_LIB.BASEBOARD_FAB2(SCH_1):PAGE86

M_L_DQ<13> @BASEBOARD_FAB2_LIB.BASEBOARD_FAB2(SCH_1):M_L_DQ(13)
  U2D1 CW80 DDR4_DQ<13> SKX_EXT_B_BGA1-IC,TBD   I172 @BASEBOARD_FAB2_LIB.BASEBOARD_FAB2(SCH_1):PAGE61
  J1A2   14 DQ<12> SCONN288_H44441004_PIP-SCONN,HA   I111 @BASEBOARD_FAB2_LIB.BASEBOARD_FAB2(SCH_1):PAGE85
  J9L2  159 DQ<13> SCONN288_H44441003_PIP-SCONN,HA    I12 @BASEBOARD_FAB2_LIB.BASEBOARD_FAB2(SCH_1):PAGE86

M_L_DQ<14> @BASEBOARD_FAB2_LIB.BASEBOARD_FAB2(SCH_1):M_L_DQ(14)
  U2D1 DC82 DDR4_DQ<14> SKX_EXT_B_BGA1-IC,TBD   I172 @BASEBOARD_FAB2_LIB.BASEBOARD_FAB2(SCH_1):PAGE61
  J1A2  166 DQ<15> SCONN288_H44441004_PIP-SCONN,HA   I111 @BASEBOARD_FAB2_LIB.BASEBOARD_FAB2(SCH_1):PAGE85
  J9L2   21 DQ<14> SCONN288_H44441003_PIP-SCONN,HA    I12 @BASEBOARD_FAB2_LIB.BASEBOARD_FAB2(SCH_1):PAGE86

M_L_DQ<15> @BASEBOARD_FAB2_LIB.BASEBOARD_FAB2(SCH_1):M_L_DQ(15)
  U2D1 DE82 DDR4_DQ<15> SKX_EXT_B_BGA1-IC,TBD   I172 @BASEBOARD_FAB2_LIB.BASEBOARD_FAB2(SCH_1):PAGE61
  J1A2   21 DQ<14> SCONN288_H44441004_PIP-SCONN,HA   I111 @BASEBOARD_FAB2_LIB.BASEBOARD_FAB2(SCH_1):PAGE85
  J9L2  166 DQ<15> SCONN288_H44441003_PIP-SCONN,HA    I12 @BASEBOARD_FAB2_LIB.BASEBOARD_FAB2(SCH_1):PAGE86

M_L_DQ<16> @BASEBOARD_FAB2_LIB.BASEBOARD_FAB2(SCH_1):M_L_DQ(16)
  U2D1 DW80 DDR4_DQ<16> SKX_EXT_B_BGA1-IC,TBD   I172 @BASEBOARD_FAB2_LIB.BASEBOARD_FAB2(SCH_1):PAGE61
  J1A2  172 DQ<17> SCONN288_H44441004_PIP-SCONN,HA   I111 @BASEBOARD_FAB2_LIB.BASEBOARD_FAB2(SCH_1):PAGE85
  J9L2   27 DQ<16> SCONN288_H44441003_PIP-SCONN,HA    I12 @BASEBOARD_FAB2_LIB.BASEBOARD_FAB2(SCH_1):PAGE86

M_L_DQ<17> @BASEBOARD_FAB2_LIB.BASEBOARD_FAB2(SCH_1):M_L_DQ(17)
  U2D1 EC80 DDR4_DQ<17> SKX_EXT_B_BGA1-IC,TBD   I172 @BASEBOARD_FAB2_LIB.BASEBOARD_FAB2(SCH_1):PAGE61
  J1A2   27 DQ<16> SCONN288_H44441004_PIP-SCONN,HA   I111 @BASEBOARD_FAB2_LIB.BASEBOARD_FAB2(SCH_1):PAGE85
  J9L2  172 DQ<17> SCONN288_H44441003_PIP-SCONN,HA    I12 @BASEBOARD_FAB2_LIB.BASEBOARD_FAB2(SCH_1):PAGE86

M_L_DQ<18> @BASEBOARD_FAB2_LIB.BASEBOARD_FAB2(SCH_1):M_L_DQ(18)
  U2D1 DY77 DDR4_DQ<18> SKX_EXT_B_BGA1-IC,TBD   I172 @BASEBOARD_FAB2_LIB.BASEBOARD_FAB2(SCH_1):PAGE61
  J1A2  179 DQ<19> SCONN288_H44441004_PIP-SCONN,HA   I111 @BASEBOARD_FAB2_LIB.BASEBOARD_FAB2(SCH_1):PAGE85
  J9L2   34 DQ<18> SCONN288_H44441003_PIP-SCONN,HA    I12 @BASEBOARD_FAB2_LIB.BASEBOARD_FAB2(SCH_1):PAGE86

M_L_DQ<19> @BASEBOARD_FAB2_LIB.BASEBOARD_FAB2(SCH_1):M_L_DQ(19)
  U2D1 EB77 DDR4_DQ<19> SKX_EXT_B_BGA1-IC,TBD   I172 @BASEBOARD_FAB2_LIB.BASEBOARD_FAB2(SCH_1):PAGE61
  J1A2   34 DQ<18> SCONN288_H44441004_PIP-SCONN,HA   I111 @BASEBOARD_FAB2_LIB.BASEBOARD_FAB2(SCH_1):PAGE85
  J9L2  179 DQ<19> SCONN288_H44441003_PIP-SCONN,HA    I12 @BASEBOARD_FAB2_LIB.BASEBOARD_FAB2(SCH_1):PAGE86

M_L_DQ<1> @BASEBOARD_FAB2_LIB.BASEBOARD_FAB2(SCH_1):M_L_DQ(1)
  U2D1 CK81 DDR4_DQ<1> SKX_EXT_B_BGA1-IC,TBD   I172 @BASEBOARD_FAB2_LIB.BASEBOARD_FAB2(SCH_1):PAGE61
  J1A2    5  DQ<0> SCONN288_H44441004_PIP-SCONN,HA   I111 @BASEBOARD_FAB2_LIB.BASEBOARD_FAB2(SCH_1):PAGE85
  J9L2  150  DQ<1> SCONN288_H44441003_PIP-SCONN,HA    I12 @BASEBOARD_FAB2_LIB.BASEBOARD_FAB2(SCH_1):PAGE86

M_L_DQ<20> @BASEBOARD_FAB2_LIB.BASEBOARD_FAB2(SCH_1):M_L_DQ(20)
  U2D1 DY81 DDR4_DQ<20> SKX_EXT_B_BGA1-IC,TBD   I172 @BASEBOARD_FAB2_LIB.BASEBOARD_FAB2(SCH_1):PAGE61
  J1A2  170 DQ<21> SCONN288_H44441004_PIP-SCONN,HA   I111 @BASEBOARD_FAB2_LIB.BASEBOARD_FAB2(SCH_1):PAGE85
  J9L2   25 DQ<20> SCONN288_H44441003_PIP-SCONN,HA    I12 @BASEBOARD_FAB2_LIB.BASEBOARD_FAB2(SCH_1):PAGE86

M_L_DQ<21> @BASEBOARD_FAB2_LIB.BASEBOARD_FAB2(SCH_1):M_L_DQ(21)
  U2D1 EB81 DDR4_DQ<21> SKX_EXT_B_BGA1-IC,TBD   I172 @BASEBOARD_FAB2_LIB.BASEBOARD_FAB2(SCH_1):PAGE61
  J1A2   25 DQ<20> SCONN288_H44441004_PIP-SCONN,HA   I111 @BASEBOARD_FAB2_LIB.BASEBOARD_FAB2(SCH_1):PAGE85
  J9L2  170 DQ<21> SCONN288_H44441003_PIP-SCONN,HA    I12 @BASEBOARD_FAB2_LIB.BASEBOARD_FAB2(SCH_1):PAGE86

M_L_DQ<22> @BASEBOARD_FAB2_LIB.BASEBOARD_FAB2(SCH_1):M_L_DQ(22)
  U2D1 DW78 DDR4_DQ<22> SKX_EXT_B_BGA1-IC,TBD   I172 @BASEBOARD_FAB2_LIB.BASEBOARD_FAB2(SCH_1):PAGE61
  J1A2  177 DQ<23> SCONN288_H44441004_PIP-SCONN,HA   I111 @BASEBOARD_FAB2_LIB.BASEBOARD_FAB2(SCH_1):PAGE85
  J9L2   32 DQ<22> SCONN288_H44441003_PIP-SCONN,HA    I12 @BASEBOARD_FAB2_LIB.BASEBOARD_FAB2(SCH_1):PAGE86

M_L_DQ<23> @BASEBOARD_FAB2_LIB.BASEBOARD_FAB2(SCH_1):M_L_DQ(23)
  U2D1 EC78 DDR4_DQ<23> SKX_EXT_B_BGA1-IC,TBD   I172 @BASEBOARD_FAB2_LIB.BASEBOARD_FAB2(SCH_1):PAGE61
  J1A2   32 DQ<22> SCONN288_H44441004_PIP-SCONN,HA   I111 @BASEBOARD_FAB2_LIB.BASEBOARD_FAB2(SCH_1):PAGE85
  J9L2  177 DQ<23> SCONN288_H44441003_PIP-SCONN,HA    I12 @BASEBOARD_FAB2_LIB.BASEBOARD_FAB2(SCH_1):PAGE86

M_L_DQ<24> @BASEBOARD_FAB2_LIB.BASEBOARD_FAB2(SCH_1):M_L_DQ(24)
  U2D1 ED75 DDR4_DQ<24> SKX_EXT_B_BGA1-IC,TBD   I172 @BASEBOARD_FAB2_LIB.BASEBOARD_FAB2(SCH_1):PAGE61
  J1A2  183 DQ<25> SCONN288_H44441004_PIP-SCONN,HA   I111 @BASEBOARD_FAB2_LIB.BASEBOARD_FAB2(SCH_1):PAGE85
  J9L2   38 DQ<24> SCONN288_H44441003_PIP-SCONN,HA    I12 @BASEBOARD_FAB2_LIB.BASEBOARD_FAB2(SCH_1):PAGE86

M_L_DQ<25> @BASEBOARD_FAB2_LIB.BASEBOARD_FAB2(SCH_1):M_L_DQ(25)
  U2D1 EE74 DDR4_DQ<25> SKX_EXT_B_BGA1-IC,TBD   I172 @BASEBOARD_FAB2_LIB.BASEBOARD_FAB2(SCH_1):PAGE61
  J1A2   38 DQ<24> SCONN288_H44441004_PIP-SCONN,HA   I111 @BASEBOARD_FAB2_LIB.BASEBOARD_FAB2(SCH_1):PAGE85
  J9L2  183 DQ<25> SCONN288_H44441003_PIP-SCONN,HA    I12 @BASEBOARD_FAB2_LIB.BASEBOARD_FAB2(SCH_1):PAGE86

M_L_DQ<26> @BASEBOARD_FAB2_LIB.BASEBOARD_FAB2(SCH_1):M_L_DQ(26)
  U2D1 EB71 DDR4_DQ<26> SKX_EXT_B_BGA1-IC,TBD   I172 @BASEBOARD_FAB2_LIB.BASEBOARD_FAB2(SCH_1):PAGE61
  J1A2  190 DQ<27> SCONN288_H44441004_PIP-SCONN,HA   I111 @BASEBOARD_FAB2_LIB.BASEBOARD_FAB2(SCH_1):PAGE85
  J9L2   45 DQ<26> SCONN288_H44441003_PIP-SCONN,HA    I12 @BASEBOARD_FAB2_LIB.BASEBOARD_FAB2(SCH_1):PAGE86

M_L_DQ<27> @BASEBOARD_FAB2_LIB.BASEBOARD_FAB2(SCH_1):M_L_DQ(27)
  U2D1 ED71 DDR4_DQ<27> SKX_EXT_B_BGA1-IC,TBD   I172 @BASEBOARD_FAB2_LIB.BASEBOARD_FAB2(SCH_1):PAGE61
  J1A2   45 DQ<26> SCONN288_H44441004_PIP-SCONN,HA   I111 @BASEBOARD_FAB2_LIB.BASEBOARD_FAB2(SCH_1):PAGE85
  J9L2  190 DQ<27> SCONN288_H44441003_PIP-SCONN,HA    I12 @BASEBOARD_FAB2_LIB.BASEBOARD_FAB2(SCH_1):PAGE86

M_L_DQ<28> @BASEBOARD_FAB2_LIB.BASEBOARD_FAB2(SCH_1):M_L_DQ(28)
  U2D1 EA74 DDR4_DQ<28> SKX_EXT_B_BGA1-IC,TBD   I172 @BASEBOARD_FAB2_LIB.BASEBOARD_FAB2(SCH_1):PAGE61
  J1A2  181 DQ<29> SCONN288_H44441004_PIP-SCONN,HA   I111 @BASEBOARD_FAB2_LIB.BASEBOARD_FAB2(SCH_1):PAGE85
  J9L2   36 DQ<28> SCONN288_H44441003_PIP-SCONN,HA    I12 @BASEBOARD_FAB2_LIB.BASEBOARD_FAB2(SCH_1):PAGE86

M_L_DQ<29> @BASEBOARD_FAB2_LIB.BASEBOARD_FAB2(SCH_1):M_L_DQ(29)
  U2D1 EB75 DDR4_DQ<29> SKX_EXT_B_BGA1-IC,TBD   I172 @BASEBOARD_FAB2_LIB.BASEBOARD_FAB2(SCH_1):PAGE61
  J1A2   36 DQ<28> SCONN288_H44441004_PIP-SCONN,HA   I111 @BASEBOARD_FAB2_LIB.BASEBOARD_FAB2(SCH_1):PAGE85
  J9L2  181 DQ<29> SCONN288_H44441003_PIP-SCONN,HA    I12 @BASEBOARD_FAB2_LIB.BASEBOARD_FAB2(SCH_1):PAGE86

M_L_DQ<2> @BASEBOARD_FAB2_LIB.BASEBOARD_FAB2(SCH_1):M_L_DQ(2)
  U2D1 CT81 DDR4_DQ<2> SKX_EXT_B_BGA1-IC,TBD   I172 @BASEBOARD_FAB2_LIB.BASEBOARD_FAB2(SCH_1):PAGE61
  J1A2  157  DQ<3> SCONN288_H44441004_PIP-SCONN,HA   I111 @BASEBOARD_FAB2_LIB.BASEBOARD_FAB2(SCH_1):PAGE85
  J9L2   12  DQ<2> SCONN288_H44441003_PIP-SCONN,HA    I12 @BASEBOARD_FAB2_LIB.BASEBOARD_FAB2(SCH_1):PAGE86

M_L_DQ<30> @BASEBOARD_FAB2_LIB.BASEBOARD_FAB2(SCH_1):M_L_DQ(30)
  U2D1 EA72 DDR4_DQ<30> SKX_EXT_B_BGA1-IC,TBD   I172 @BASEBOARD_FAB2_LIB.BASEBOARD_FAB2(SCH_1):PAGE61
  J1A2  188 DQ<31> SCONN288_H44441004_PIP-SCONN,HA   I111 @BASEBOARD_FAB2_LIB.BASEBOARD_FAB2(SCH_1):PAGE85
  J9L2   43 DQ<30> SCONN288_H44441003_PIP-SCONN,HA    I12 @BASEBOARD_FAB2_LIB.BASEBOARD_FAB2(SCH_1):PAGE86

M_L_DQ<31> @BASEBOARD_FAB2_LIB.BASEBOARD_FAB2(SCH_1):M_L_DQ(31)
  U2D1 EE72 DDR4_DQ<31> SKX_EXT_B_BGA1-IC,TBD   I172 @BASEBOARD_FAB2_LIB.BASEBOARD_FAB2(SCH_1):PAGE61
  J1A2   43 DQ<30> SCONN288_H44441004_PIP-SCONN,HA   I111 @BASEBOARD_FAB2_LIB.BASEBOARD_FAB2(SCH_1):PAGE85
  J9L2  188 DQ<31> SCONN288_H44441003_PIP-SCONN,HA    I12 @BASEBOARD_FAB2_LIB.BASEBOARD_FAB2(SCH_1):PAGE86

M_L_DQ<32> @BASEBOARD_FAB2_LIB.BASEBOARD_FAB2(SCH_1):M_L_DQ(32)
  U2D1 DU42 DDR4_DQ<32> SKX_EXT_B_BGA1-IC,TBD   I172 @BASEBOARD_FAB2_LIB.BASEBOARD_FAB2(SCH_1):PAGE61
  J1A2  242 DQ<33> SCONN288_H44441004_PIP-SCONN,HA   I111 @BASEBOARD_FAB2_LIB.BASEBOARD_FAB2(SCH_1):PAGE85
  J9L2   97 DQ<32> SCONN288_H44441003_PIP-SCONN,HA    I12 @BASEBOARD_FAB2_LIB.BASEBOARD_FAB2(SCH_1):PAGE86

M_L_DQ<33> @BASEBOARD_FAB2_LIB.BASEBOARD_FAB2(SCH_1):M_L_DQ(33)
  U2D1 DW42 DDR4_DQ<33> SKX_EXT_B_BGA1-IC,TBD   I172 @BASEBOARD_FAB2_LIB.BASEBOARD_FAB2(SCH_1):PAGE61
  J1A2   97 DQ<32> SCONN288_H44441004_PIP-SCONN,HA   I111 @BASEBOARD_FAB2_LIB.BASEBOARD_FAB2(SCH_1):PAGE85
  J9L2  242 DQ<33> SCONN288_H44441003_PIP-SCONN,HA    I12 @BASEBOARD_FAB2_LIB.BASEBOARD_FAB2(SCH_1):PAGE86

M_L_DQ<34> @BASEBOARD_FAB2_LIB.BASEBOARD_FAB2(SCH_1):M_L_DQ(34)
  U2D1 DP39 DDR4_DQ<34> SKX_EXT_B_BGA1-IC,TBD   I172 @BASEBOARD_FAB2_LIB.BASEBOARD_FAB2(SCH_1):PAGE61
  J1A2  249 DQ<35> SCONN288_H44441004_PIP-SCONN,HA   I111 @BASEBOARD_FAB2_LIB.BASEBOARD_FAB2(SCH_1):PAGE85
  J9L2  104 DQ<34> SCONN288_H44441003_PIP-SCONN,HA    I12 @BASEBOARD_FAB2_LIB.BASEBOARD_FAB2(SCH_1):PAGE86

M_L_DQ<35> @BASEBOARD_FAB2_LIB.BASEBOARD_FAB2(SCH_1):M_L_DQ(35)
  U2D1 DT39 DDR4_DQ<35> SKX_EXT_B_BGA1-IC,TBD   I172 @BASEBOARD_FAB2_LIB.BASEBOARD_FAB2(SCH_1):PAGE61
  J1A2  104 DQ<34> SCONN288_H44441004_PIP-SCONN,HA   I111 @BASEBOARD_FAB2_LIB.BASEBOARD_FAB2(SCH_1):PAGE85
  J9L2  249 DQ<35> SCONN288_H44441003_PIP-SCONN,HA    I12 @BASEBOARD_FAB2_LIB.BASEBOARD_FAB2(SCH_1):PAGE86

M_L_DQ<36> @BASEBOARD_FAB2_LIB.BASEBOARD_FAB2(SCH_1):M_L_DQ(36)
  U2D1 DL42 DDR4_DQ<36> SKX_EXT_B_BGA1-IC,TBD   I172 @BASEBOARD_FAB2_LIB.BASEBOARD_FAB2(SCH_1):PAGE61
  J1A2  240 DQ<37> SCONN288_H44441004_PIP-SCONN,HA   I111 @BASEBOARD_FAB2_LIB.BASEBOARD_FAB2(SCH_1):PAGE85
  J9L2   95 DQ<36> SCONN288_H44441003_PIP-SCONN,HA    I12 @BASEBOARD_FAB2_LIB.BASEBOARD_FAB2(SCH_1):PAGE86

M_L_DQ<37> @BASEBOARD_FAB2_LIB.BASEBOARD_FAB2(SCH_1):M_L_DQ(37)
  U2D1 DN42 DDR4_DQ<37> SKX_EXT_B_BGA1-IC,TBD   I172 @BASEBOARD_FAB2_LIB.BASEBOARD_FAB2(SCH_1):PAGE61
  J1A2   95 DQ<36> SCONN288_H44441004_PIP-SCONN,HA   I111 @BASEBOARD_FAB2_LIB.BASEBOARD_FAB2(SCH_1):PAGE85
  J9L2  240 DQ<37> SCONN288_H44441003_PIP-SCONN,HA    I12 @BASEBOARD_FAB2_LIB.BASEBOARD_FAB2(SCH_1):PAGE86

M_L_DQ<38> @BASEBOARD_FAB2_LIB.BASEBOARD_FAB2(SCH_1):M_L_DQ(38)
  U2D1 DN40 DDR4_DQ<38> SKX_EXT_B_BGA1-IC,TBD   I172 @BASEBOARD_FAB2_LIB.BASEBOARD_FAB2(SCH_1):PAGE61
  J1A2  247 DQ<39> SCONN288_H44441004_PIP-SCONN,HA   I111 @BASEBOARD_FAB2_LIB.BASEBOARD_FAB2(SCH_1):PAGE85
  J9L2  102 DQ<38> SCONN288_H44441003_PIP-SCONN,HA    I12 @BASEBOARD_FAB2_LIB.BASEBOARD_FAB2(SCH_1):PAGE86

M_L_DQ<39> @BASEBOARD_FAB2_LIB.BASEBOARD_FAB2(SCH_1):M_L_DQ(39)
  U2D1 DU40 DDR4_DQ<39> SKX_EXT_B_BGA1-IC,TBD   I172 @BASEBOARD_FAB2_LIB.BASEBOARD_FAB2(SCH_1):PAGE61
  J1A2  102 DQ<38> SCONN288_H44441004_PIP-SCONN,HA   I111 @BASEBOARD_FAB2_LIB.BASEBOARD_FAB2(SCH_1):PAGE85
  J9L2  247 DQ<39> SCONN288_H44441003_PIP-SCONN,HA    I12 @BASEBOARD_FAB2_LIB.BASEBOARD_FAB2(SCH_1):PAGE86

M_L_DQ<3> @BASEBOARD_FAB2_LIB.BASEBOARD_FAB2(SCH_1):M_L_DQ(3)
  U2D1 CR82 DDR4_DQ<3> SKX_EXT_B_BGA1-IC,TBD   I172 @BASEBOARD_FAB2_LIB.BASEBOARD_FAB2(SCH_1):PAGE61
  J1A2   12  DQ<2> SCONN288_H44441004_PIP-SCONN,HA   I111 @BASEBOARD_FAB2_LIB.BASEBOARD_FAB2(SCH_1):PAGE85
  J9L2  157  DQ<3> SCONN288_H44441003_PIP-SCONN,HA    I12 @BASEBOARD_FAB2_LIB.BASEBOARD_FAB2(SCH_1):PAGE86

M_L_DQ<40> @BASEBOARD_FAB2_LIB.BASEBOARD_FAB2(SCH_1):M_L_DQ(40)
  U2D1 EC34 DDR4_DQ<40> SKX_EXT_B_BGA1-IC,TBD   I172 @BASEBOARD_FAB2_LIB.BASEBOARD_FAB2(SCH_1):PAGE61
  J1A2  253 DQ<41> SCONN288_H44441004_PIP-SCONN,HA   I111 @BASEBOARD_FAB2_LIB.BASEBOARD_FAB2(SCH_1):PAGE85
  J9L2  108 DQ<40> SCONN288_H44441003_PIP-SCONN,HA    I12 @BASEBOARD_FAB2_LIB.BASEBOARD_FAB2(SCH_1):PAGE86

M_L_DQ<41> @BASEBOARD_FAB2_LIB.BASEBOARD_FAB2(SCH_1):M_L_DQ(41)
  U2D1 ED33 DDR4_DQ<41> SKX_EXT_B_BGA1-IC,TBD   I172 @BASEBOARD_FAB2_LIB.BASEBOARD_FAB2(SCH_1):PAGE61
  J1A2  108 DQ<40> SCONN288_H44441004_PIP-SCONN,HA   I111 @BASEBOARD_FAB2_LIB.BASEBOARD_FAB2(SCH_1):PAGE85
  J9L2  253 DQ<41> SCONN288_H44441003_PIP-SCONN,HA    I12 @BASEBOARD_FAB2_LIB.BASEBOARD_FAB2(SCH_1):PAGE86

M_L_DQ<42> @BASEBOARD_FAB2_LIB.BASEBOARD_FAB2(SCH_1):M_L_DQ(42)
  U2D1 EA30 DDR4_DQ<42> SKX_EXT_B_BGA1-IC,TBD   I172 @BASEBOARD_FAB2_LIB.BASEBOARD_FAB2(SCH_1):PAGE61
  J1A2  260 DQ<43> SCONN288_H44441004_PIP-SCONN,HA   I111 @BASEBOARD_FAB2_LIB.BASEBOARD_FAB2(SCH_1):PAGE85
  J9L2  115 DQ<42> SCONN288_H44441003_PIP-SCONN,HA    I12 @BASEBOARD_FAB2_LIB.BASEBOARD_FAB2(SCH_1):PAGE86

M_L_DQ<43> @BASEBOARD_FAB2_LIB.BASEBOARD_FAB2(SCH_1):M_L_DQ(43)
  U2D1 EC30 DDR4_DQ<43> SKX_EXT_B_BGA1-IC,TBD   I172 @BASEBOARD_FAB2_LIB.BASEBOARD_FAB2(SCH_1):PAGE61
  J1A2  115 DQ<42> SCONN288_H44441004_PIP-SCONN,HA   I111 @BASEBOARD_FAB2_LIB.BASEBOARD_FAB2(SCH_1):PAGE85
  J9L2  260 DQ<43> SCONN288_H44441003_PIP-SCONN,HA    I12 @BASEBOARD_FAB2_LIB.BASEBOARD_FAB2(SCH_1):PAGE86

M_L_DQ<44> @BASEBOARD_FAB2_LIB.BASEBOARD_FAB2(SCH_1):M_L_DQ(44)
  U2D1 DY33 DDR4_DQ<44> SKX_EXT_B_BGA1-IC,TBD   I172 @BASEBOARD_FAB2_LIB.BASEBOARD_FAB2(SCH_1):PAGE61
  J1A2  251 DQ<45> SCONN288_H44441004_PIP-SCONN,HA   I111 @BASEBOARD_FAB2_LIB.BASEBOARD_FAB2(SCH_1):PAGE85
  J9L2  106 DQ<44> SCONN288_H44441003_PIP-SCONN,HA    I12 @BASEBOARD_FAB2_LIB.BASEBOARD_FAB2(SCH_1):PAGE86

M_L_DQ<45> @BASEBOARD_FAB2_LIB.BASEBOARD_FAB2(SCH_1):M_L_DQ(45)
  U2D1 EA34 DDR4_DQ<45> SKX_EXT_B_BGA1-IC,TBD   I172 @BASEBOARD_FAB2_LIB.BASEBOARD_FAB2(SCH_1):PAGE61
  J1A2  106 DQ<44> SCONN288_H44441004_PIP-SCONN,HA   I111 @BASEBOARD_FAB2_LIB.BASEBOARD_FAB2(SCH_1):PAGE85
  J9L2  251 DQ<45> SCONN288_H44441003_PIP-SCONN,HA    I12 @BASEBOARD_FAB2_LIB.BASEBOARD_FAB2(SCH_1):PAGE86

M_L_DQ<46> @BASEBOARD_FAB2_LIB.BASEBOARD_FAB2(SCH_1):M_L_DQ(46)
  U2D1 DY31 DDR4_DQ<46> SKX_EXT_B_BGA1-IC,TBD   I172 @BASEBOARD_FAB2_LIB.BASEBOARD_FAB2(SCH_1):PAGE61
  J1A2  258 DQ<47> SCONN288_H44441004_PIP-SCONN,HA   I111 @BASEBOARD_FAB2_LIB.BASEBOARD_FAB2(SCH_1):PAGE85
  J9L2  113 DQ<46> SCONN288_H44441003_PIP-SCONN,HA    I12 @BASEBOARD_FAB2_LIB.BASEBOARD_FAB2(SCH_1):PAGE86

M_L_DQ<47> @BASEBOARD_FAB2_LIB.BASEBOARD_FAB2(SCH_1):M_L_DQ(47)
  U2D1 ED31 DDR4_DQ<47> SKX_EXT_B_BGA1-IC,TBD   I172 @BASEBOARD_FAB2_LIB.BASEBOARD_FAB2(SCH_1):PAGE61
  J1A2  113 DQ<46> SCONN288_H44441004_PIP-SCONN,HA   I111 @BASEBOARD_FAB2_LIB.BASEBOARD_FAB2(SCH_1):PAGE85
  J9L2  258 DQ<47> SCONN288_H44441003_PIP-SCONN,HA    I12 @BASEBOARD_FAB2_LIB.BASEBOARD_FAB2(SCH_1):PAGE86

M_L_DQ<48> @BASEBOARD_FAB2_LIB.BASEBOARD_FAB2(SCH_1):M_L_DQ(48)
  U2D1 EC28 DDR4_DQ<48> SKX_EXT_B_BGA1-IC,TBD   I172 @BASEBOARD_FAB2_LIB.BASEBOARD_FAB2(SCH_1):PAGE61
  J1A2  264 DQ<49> SCONN288_H44441004_PIP-SCONN,HA   I111 @BASEBOARD_FAB2_LIB.BASEBOARD_FAB2(SCH_1):PAGE85
  J9L2  119 DQ<48> SCONN288_H44441003_PIP-SCONN,HA    I12 @BASEBOARD_FAB2_LIB.BASEBOARD_FAB2(SCH_1):PAGE86

M_L_DQ<49> @BASEBOARD_FAB2_LIB.BASEBOARD_FAB2(SCH_1):M_L_DQ(49)
  U2D1 ED27 DDR4_DQ<49> SKX_EXT_B_BGA1-IC,TBD   I172 @BASEBOARD_FAB2_LIB.BASEBOARD_FAB2(SCH_1):PAGE61
  J1A2  119 DQ<48> SCONN288_H44441004_PIP-SCONN,HA   I111 @BASEBOARD_FAB2_LIB.BASEBOARD_FAB2(SCH_1):PAGE85
  J9L2  264 DQ<49> SCONN288_H44441003_PIP-SCONN,HA    I12 @BASEBOARD_FAB2_LIB.BASEBOARD_FAB2(SCH_1):PAGE86

M_L_DQ<4> @BASEBOARD_FAB2_LIB.BASEBOARD_FAB2(SCH_1):M_L_DQ(4)
  U2D1 CK79 DDR4_DQ<4> SKX_EXT_B_BGA1-IC,TBD   I172 @BASEBOARD_FAB2_LIB.BASEBOARD_FAB2(SCH_1):PAGE61
  J1A2  148  DQ<5> SCONN288_H44441004_PIP-SCONN,HA   I111 @BASEBOARD_FAB2_LIB.BASEBOARD_FAB2(SCH_1):PAGE85
  J9L2    3  DQ<4> SCONN288_H44441003_PIP-SCONN,HA    I12 @BASEBOARD_FAB2_LIB.BASEBOARD_FAB2(SCH_1):PAGE86

M_L_DQ<50> @BASEBOARD_FAB2_LIB.BASEBOARD_FAB2(SCH_1):M_L_DQ(50)
  U2D1 EA24 DDR4_DQ<50> SKX_EXT_B_BGA1-IC,TBD   I172 @BASEBOARD_FAB2_LIB.BASEBOARD_FAB2(SCH_1):PAGE61
  J1A2  271 DQ<51> SCONN288_H44441004_PIP-SCONN,HA   I111 @BASEBOARD_FAB2_LIB.BASEBOARD_FAB2(SCH_1):PAGE85
  J9L2  126 DQ<50> SCONN288_H44441003_PIP-SCONN,HA    I12 @BASEBOARD_FAB2_LIB.BASEBOARD_FAB2(SCH_1):PAGE86

M_L_DQ<51> @BASEBOARD_FAB2_LIB.BASEBOARD_FAB2(SCH_1):M_L_DQ(51)
  U2D1 EC24 DDR4_DQ<51> SKX_EXT_B_BGA1-IC,TBD   I172 @BASEBOARD_FAB2_LIB.BASEBOARD_FAB2(SCH_1):PAGE61
  J1A2  126 DQ<50> SCONN288_H44441004_PIP-SCONN,HA   I111 @BASEBOARD_FAB2_LIB.BASEBOARD_FAB2(SCH_1):PAGE85
  J9L2  271 DQ<51> SCONN288_H44441003_PIP-SCONN,HA    I12 @BASEBOARD_FAB2_LIB.BASEBOARD_FAB2(SCH_1):PAGE86

M_L_DQ<52> @BASEBOARD_FAB2_LIB.BASEBOARD_FAB2(SCH_1):M_L_DQ(52)
  U2D1 DY27 DDR4_DQ<52> SKX_EXT_B_BGA1-IC,TBD   I172 @BASEBOARD_FAB2_LIB.BASEBOARD_FAB2(SCH_1):PAGE61
  J1A2  262 DQ<53> SCONN288_H44441004_PIP-SCONN,HA   I111 @BASEBOARD_FAB2_LIB.BASEBOARD_FAB2(SCH_1):PAGE85
  J9L2  117 DQ<52> SCONN288_H44441003_PIP-SCONN,HA    I12 @BASEBOARD_FAB2_LIB.BASEBOARD_FAB2(SCH_1):PAGE86

M_L_DQ<53> @BASEBOARD_FAB2_LIB.BASEBOARD_FAB2(SCH_1):M_L_DQ(53)
  U2D1 EA28 DDR4_DQ<53> SKX_EXT_B_BGA1-IC,TBD   I172 @BASEBOARD_FAB2_LIB.BASEBOARD_FAB2(SCH_1):PAGE61
  J1A2  117 DQ<52> SCONN288_H44441004_PIP-SCONN,HA   I111 @BASEBOARD_FAB2_LIB.BASEBOARD_FAB2(SCH_1):PAGE85
  J9L2  262 DQ<53> SCONN288_H44441003_PIP-SCONN,HA    I12 @BASEBOARD_FAB2_LIB.BASEBOARD_FAB2(SCH_1):PAGE86

M_L_DQ<54> @BASEBOARD_FAB2_LIB.BASEBOARD_FAB2(SCH_1):M_L_DQ(54)
  U2D1 DY25 DDR4_DQ<54> SKX_EXT_B_BGA1-IC,TBD   I172 @BASEBOARD_FAB2_LIB.BASEBOARD_FAB2(SCH_1):PAGE61
  J1A2  269 DQ<55> SCONN288_H44441004_PIP-SCONN,HA   I111 @BASEBOARD_FAB2_LIB.BASEBOARD_FAB2(SCH_1):PAGE85
  J9L2  124 DQ<54> SCONN288_H44441003_PIP-SCONN,HA    I12 @BASEBOARD_FAB2_LIB.BASEBOARD_FAB2(SCH_1):PAGE86

M_L_DQ<55> @BASEBOARD_FAB2_LIB.BASEBOARD_FAB2(SCH_1):M_L_DQ(55)
  U2D1 ED25 DDR4_DQ<55> SKX_EXT_B_BGA1-IC,TBD   I172 @BASEBOARD_FAB2_LIB.BASEBOARD_FAB2(SCH_1):PAGE61
  J1A2  124 DQ<54> SCONN288_H44441004_PIP-SCONN,HA   I111 @BASEBOARD_FAB2_LIB.BASEBOARD_FAB2(SCH_1):PAGE85
  J9L2  269 DQ<55> SCONN288_H44441003_PIP-SCONN,HA    I12 @BASEBOARD_FAB2_LIB.BASEBOARD_FAB2(SCH_1):PAGE86

M_L_DQ<56> @BASEBOARD_FAB2_LIB.BASEBOARD_FAB2(SCH_1):M_L_DQ(56)
  U2D1 DF27 DDR4_DQ<56> SKX_EXT_B_BGA1-IC,TBD   I172 @BASEBOARD_FAB2_LIB.BASEBOARD_FAB2(SCH_1):PAGE61
  J1A2  275 DQ<57> SCONN288_H44441004_PIP-SCONN,HA   I111 @BASEBOARD_FAB2_LIB.BASEBOARD_FAB2(SCH_1):PAGE85
  J9L2  130 DQ<56> SCONN288_H44441003_PIP-SCONN,HA    I12 @BASEBOARD_FAB2_LIB.BASEBOARD_FAB2(SCH_1):PAGE86

M_L_DQ<57> @BASEBOARD_FAB2_LIB.BASEBOARD_FAB2(SCH_1):M_L_DQ(57)
  U2D1 DK27 DDR4_DQ<57> SKX_EXT_B_BGA1-IC,TBD   I172 @BASEBOARD_FAB2_LIB.BASEBOARD_FAB2(SCH_1):PAGE61
  J1A2  130 DQ<56> SCONN288_H44441004_PIP-SCONN,HA   I111 @BASEBOARD_FAB2_LIB.BASEBOARD_FAB2(SCH_1):PAGE85
  J9L2  275 DQ<57> SCONN288_H44441003_PIP-SCONN,HA    I12 @BASEBOARD_FAB2_LIB.BASEBOARD_FAB2(SCH_1):PAGE86

M_L_DQ<58> @BASEBOARD_FAB2_LIB.BASEBOARD_FAB2(SCH_1):M_L_DQ(58)
  U2D1 DD25 DDR4_DQ<58> SKX_EXT_B_BGA1-IC,TBD   I172 @BASEBOARD_FAB2_LIB.BASEBOARD_FAB2(SCH_1):PAGE61
  J1A2  282 DQ<59> SCONN288_H44441004_PIP-SCONN,HA   I111 @BASEBOARD_FAB2_LIB.BASEBOARD_FAB2(SCH_1):PAGE85
  J9L2  137 DQ<58> SCONN288_H44441003_PIP-SCONN,HA    I12 @BASEBOARD_FAB2_LIB.BASEBOARD_FAB2(SCH_1):PAGE86

M_L_DQ<59> @BASEBOARD_FAB2_LIB.BASEBOARD_FAB2(SCH_1):M_L_DQ(59)
  U2D1 DJ24 DDR4_DQ<59> SKX_EXT_B_BGA1-IC,TBD   I172 @BASEBOARD_FAB2_LIB.BASEBOARD_FAB2(SCH_1):PAGE61
  J1A2  137 DQ<58> SCONN288_H44441004_PIP-SCONN,HA   I111 @BASEBOARD_FAB2_LIB.BASEBOARD_FAB2(SCH_1):PAGE85
  J9L2  282 DQ<59> SCONN288_H44441003_PIP-SCONN,HA    I12 @BASEBOARD_FAB2_LIB.BASEBOARD_FAB2(SCH_1):PAGE86

M_L_DQ<5> @BASEBOARD_FAB2_LIB.BASEBOARD_FAB2(SCH_1):M_L_DQ(5)
  U2D1 CJ80 DDR4_DQ<5> SKX_EXT_B_BGA1-IC,TBD   I172 @BASEBOARD_FAB2_LIB.BASEBOARD_FAB2(SCH_1):PAGE61
  J1A2    3  DQ<4> SCONN288_H44441004_PIP-SCONN,HA   I111 @BASEBOARD_FAB2_LIB.BASEBOARD_FAB2(SCH_1):PAGE85
  J9L2  148  DQ<5> SCONN288_H44441003_PIP-SCONN,HA    I12 @BASEBOARD_FAB2_LIB.BASEBOARD_FAB2(SCH_1):PAGE86

M_L_DQ<60> @BASEBOARD_FAB2_LIB.BASEBOARD_FAB2(SCH_1):M_L_DQ(60)
  U2D1 DG28 DDR4_DQ<60> SKX_EXT_B_BGA1-IC,TBD   I172 @BASEBOARD_FAB2_LIB.BASEBOARD_FAB2(SCH_1):PAGE61
  J1A2  273 DQ<61> SCONN288_H44441004_PIP-SCONN,HA   I111 @BASEBOARD_FAB2_LIB.BASEBOARD_FAB2(SCH_1):PAGE85
  J9L2  128 DQ<60> SCONN288_H44441003_PIP-SCONN,HA    I12 @BASEBOARD_FAB2_LIB.BASEBOARD_FAB2(SCH_1):PAGE86

M_L_DQ<61> @BASEBOARD_FAB2_LIB.BASEBOARD_FAB2(SCH_1):M_L_DQ(61)
  U2D1 DJ28 DDR4_DQ<61> SKX_EXT_B_BGA1-IC,TBD   I172 @BASEBOARD_FAB2_LIB.BASEBOARD_FAB2(SCH_1):PAGE61
  J1A2  128 DQ<60> SCONN288_H44441004_PIP-SCONN,HA   I111 @BASEBOARD_FAB2_LIB.BASEBOARD_FAB2(SCH_1):PAGE85
  J9L2  273 DQ<61> SCONN288_H44441003_PIP-SCONN,HA    I12 @BASEBOARD_FAB2_LIB.BASEBOARD_FAB2(SCH_1):PAGE86

M_L_DQ<62> @BASEBOARD_FAB2_LIB.BASEBOARD_FAB2(SCH_1):M_L_DQ(62)
  U2D1 DF25 DDR4_DQ<62> SKX_EXT_B_BGA1-IC,TBD   I172 @BASEBOARD_FAB2_LIB.BASEBOARD_FAB2(SCH_1):PAGE61
  J1A2  280 DQ<63> SCONN288_H44441004_PIP-SCONN,HA   I111 @BASEBOARD_FAB2_LIB.BASEBOARD_FAB2(SCH_1):PAGE85
  J9L2  135 DQ<62> SCONN288_H44441003_PIP-SCONN,HA    I12 @BASEBOARD_FAB2_LIB.BASEBOARD_FAB2(SCH_1):PAGE86

M_L_DQ<63> @BASEBOARD_FAB2_LIB.BASEBOARD_FAB2(SCH_1):M_L_DQ(63)
  U2D1 DK25 DDR4_DQ<63> SKX_EXT_B_BGA1-IC,TBD   I172 @BASEBOARD_FAB2_LIB.BASEBOARD_FAB2(SCH_1):PAGE61
  J1A2  135 DQ<62> SCONN288_H44441004_PIP-SCONN,HA   I111 @BASEBOARD_FAB2_LIB.BASEBOARD_FAB2(SCH_1):PAGE85
  J9L2  280 DQ<63> SCONN288_H44441003_PIP-SCONN,HA    I12 @BASEBOARD_FAB2_LIB.BASEBOARD_FAB2(SCH_1):PAGE86

M_L_DQ<6> @BASEBOARD_FAB2_LIB.BASEBOARD_FAB2(SCH_1):M_L_DQ(6)
  U2D1 CR80 DDR4_DQ<6> SKX_EXT_B_BGA1-IC,TBD   I172 @BASEBOARD_FAB2_LIB.BASEBOARD_FAB2(SCH_1):PAGE61
  J1A2  155  DQ<7> SCONN288_H44441004_PIP-SCONN,HA   I111 @BASEBOARD_FAB2_LIB.BASEBOARD_FAB2(SCH_1):PAGE85
  J9L2   10  DQ<6> SCONN288_H44441003_PIP-SCONN,HA    I12 @BASEBOARD_FAB2_LIB.BASEBOARD_FAB2(SCH_1):PAGE86

M_L_DQ<7> @BASEBOARD_FAB2_LIB.BASEBOARD_FAB2(SCH_1):M_L_DQ(7)
  U2D1 CN82 DDR4_DQ<7> SKX_EXT_B_BGA1-IC,TBD   I172 @BASEBOARD_FAB2_LIB.BASEBOARD_FAB2(SCH_1):PAGE61
  J1A2   10  DQ<6> SCONN288_H44441004_PIP-SCONN,HA   I111 @BASEBOARD_FAB2_LIB.BASEBOARD_FAB2(SCH_1):PAGE85
  J9L2  155  DQ<7> SCONN288_H44441003_PIP-SCONN,HA    I12 @BASEBOARD_FAB2_LIB.BASEBOARD_FAB2(SCH_1):PAGE86

M_L_DQ<8> @BASEBOARD_FAB2_LIB.BASEBOARD_FAB2(SCH_1):M_L_DQ(8)
  U2D1 DB79 DDR4_DQ<8> SKX_EXT_B_BGA1-IC,TBD   I172 @BASEBOARD_FAB2_LIB.BASEBOARD_FAB2(SCH_1):PAGE61
  J1A2  161  DQ<9> SCONN288_H44441004_PIP-SCONN,HA   I111 @BASEBOARD_FAB2_LIB.BASEBOARD_FAB2(SCH_1):PAGE85
  J9L2   16  DQ<8> SCONN288_H44441003_PIP-SCONN,HA    I12 @BASEBOARD_FAB2_LIB.BASEBOARD_FAB2(SCH_1):PAGE86

M_L_DQ<9> @BASEBOARD_FAB2_LIB.BASEBOARD_FAB2(SCH_1):M_L_DQ(9)
  U2D1 CY81 DDR4_DQ<9> SKX_EXT_B_BGA1-IC,TBD   I172 @BASEBOARD_FAB2_LIB.BASEBOARD_FAB2(SCH_1):PAGE61
  J1A2   16  DQ<8> SCONN288_H44441004_PIP-SCONN,HA   I111 @BASEBOARD_FAB2_LIB.BASEBOARD_FAB2(SCH_1):PAGE85
  J9L2  161  DQ<9> SCONN288_H44441003_PIP-SCONN,HA    I12 @BASEBOARD_FAB2_LIB.BASEBOARD_FAB2(SCH_1):PAGE86

M_L_DQS_DN<0> @BASEBOARD_FAB2_LIB.BASEBOARD_FAB2(SCH_1):M_L_DQS_DN(0)
  U2D1 CL82 DDR4_DQS_DN<0> SKX_EXT_B_BGA1-IC,TBD   I172 @BASEBOARD_FAB2_LIB.BASEBOARD_FAB2(SCH_1):PAGE61
  J1A2  152  DQS0N SCONN288_H44441004_PIP-SCONN,HA    I66 @BASEBOARD_FAB2_LIB.BASEBOARD_FAB2(SCH_1):PAGE85
  J9L2  152  DQS0N SCONN288_H44441003_PIP-SCONN,HA   I100 @BASEBOARD_FAB2_LIB.BASEBOARD_FAB2(SCH_1):PAGE86

M_L_DQS_DN<10> @BASEBOARD_FAB2_LIB.BASEBOARD_FAB2(SCH_1):M_L_DQS_DN(10)
  U2D1 DC80 DDR4_DQS_DN<10> SKX_EXT_B_BGA1-IC,TBD   I172 @BASEBOARD_FAB2_LIB.BASEBOARD_FAB2(SCH_1):PAGE61
  J1A2   19 DQS10N SCONN288_H44441004_PIP-SCONN,HA    I66 @BASEBOARD_FAB2_LIB.BASEBOARD_FAB2(SCH_1):PAGE85
  J9L2   19 DQS10N SCONN288_H44441003_PIP-SCONN,HA   I100 @BASEBOARD_FAB2_LIB.BASEBOARD_FAB2(SCH_1):PAGE86

M_L_DQS_DN<11> @BASEBOARD_FAB2_LIB.BASEBOARD_FAB2(SCH_1):M_L_DQS_DN(11)
  U2D1 DY79 DDR4_DQS_DN<11> SKX_EXT_B_BGA1-IC,TBD   I172 @BASEBOARD_FAB2_LIB.BASEBOARD_FAB2(SCH_1):PAGE61
  J1A2   30 DQS11N SCONN288_H44441004_PIP-SCONN,HA    I66 @BASEBOARD_FAB2_LIB.BASEBOARD_FAB2(SCH_1):PAGE85
  J9L2   30 DQS11N SCONN288_H44441003_PIP-SCONN,HA   I100 @BASEBOARD_FAB2_LIB.BASEBOARD_FAB2(SCH_1):PAGE86

M_L_DQS_DN<12> @BASEBOARD_FAB2_LIB.BASEBOARD_FAB2(SCH_1):M_L_DQS_DN(12)
  U2D1 EB73 DDR4_DQS_DN<12> SKX_EXT_B_BGA1-IC,TBD   I172 @BASEBOARD_FAB2_LIB.BASEBOARD_FAB2(SCH_1):PAGE61
  J1A2   41 DQS12N SCONN288_H44441004_PIP-SCONN,HA    I66 @BASEBOARD_FAB2_LIB.BASEBOARD_FAB2(SCH_1):PAGE85
  J9L2   41 DQS12N SCONN288_H44441003_PIP-SCONN,HA   I100 @BASEBOARD_FAB2_LIB.BASEBOARD_FAB2(SCH_1):PAGE86

M_L_DQS_DN<13> @BASEBOARD_FAB2_LIB.BASEBOARD_FAB2(SCH_1):M_L_DQS_DN(13)
  U2D1 DP41 DDR4_DQS_DN<13> SKX_EXT_B_BGA1-IC,TBD   I172 @BASEBOARD_FAB2_LIB.BASEBOARD_FAB2(SCH_1):PAGE61
  J1A2  100 DQS13N SCONN288_H44441004_PIP-SCONN,HA    I66 @BASEBOARD_FAB2_LIB.BASEBOARD_FAB2(SCH_1):PAGE85
  J9L2  100 DQS13N SCONN288_H44441003_PIP-SCONN,HA   I100 @BASEBOARD_FAB2_LIB.BASEBOARD_FAB2(SCH_1):PAGE86

M_L_DQS_DN<14> @BASEBOARD_FAB2_LIB.BASEBOARD_FAB2(SCH_1):M_L_DQS_DN(14)
  U2D1 EA32 DDR4_DQS_DN<14> SKX_EXT_B_BGA1-IC,TBD   I172 @BASEBOARD_FAB2_LIB.BASEBOARD_FAB2(SCH_1):PAGE61
  J1A2  111 DQS14N SCONN288_H44441004_PIP-SCONN,HA    I66 @BASEBOARD_FAB2_LIB.BASEBOARD_FAB2(SCH_1):PAGE85
  J9L2  111 DQS14N SCONN288_H44441003_PIP-SCONN,HA   I100 @BASEBOARD_FAB2_LIB.BASEBOARD_FAB2(SCH_1):PAGE86

M_L_DQS_DN<15> @BASEBOARD_FAB2_LIB.BASEBOARD_FAB2(SCH_1):M_L_DQS_DN(15)
  U2D1 EA26 DDR4_DQS_DN<15> SKX_EXT_B_BGA1-IC,TBD   I172 @BASEBOARD_FAB2_LIB.BASEBOARD_FAB2(SCH_1):PAGE61
  J1A2  122 DQS15N SCONN288_H44441004_PIP-SCONN,HA    I66 @BASEBOARD_FAB2_LIB.BASEBOARD_FAB2(SCH_1):PAGE85
  J9L2  122 DQS15N SCONN288_H44441003_PIP-SCONN,HA   I100 @BASEBOARD_FAB2_LIB.BASEBOARD_FAB2(SCH_1):PAGE86

M_L_DQS_DN<16> @BASEBOARD_FAB2_LIB.BASEBOARD_FAB2(SCH_1):M_L_DQS_DN(16)
  U2D1 DG26 DDR4_DQS_DN<16> SKX_EXT_B_BGA1-IC,TBD   I172 @BASEBOARD_FAB2_LIB.BASEBOARD_FAB2(SCH_1):PAGE61
  J1A2  133 DQS16N SCONN288_H44441004_PIP-SCONN,HA    I66 @BASEBOARD_FAB2_LIB.BASEBOARD_FAB2(SCH_1):PAGE85
  J9L2  133 DQS16N SCONN288_H44441003_PIP-SCONN,HA   I100 @BASEBOARD_FAB2_LIB.BASEBOARD_FAB2(SCH_1):PAGE86

M_L_DQS_DN<17> @BASEBOARD_FAB2_LIB.BASEBOARD_FAB2(SCH_1):M_L_DQS_DN(17)
  U2D1 DV67 DDR4_DQS_DN<17> SKX_EXT_B_BGA1-IC,TBD   I172 @BASEBOARD_FAB2_LIB.BASEBOARD_FAB2(SCH_1):PAGE61
  J1A2   52 DQS17N SCONN288_H44441004_PIP-SCONN,HA    I66 @BASEBOARD_FAB2_LIB.BASEBOARD_FAB2(SCH_1):PAGE85
  J9L2   52 DQS17N SCONN288_H44441003_PIP-SCONN,HA   I100 @BASEBOARD_FAB2_LIB.BASEBOARD_FAB2(SCH_1):PAGE86

M_L_DQS_DN<1> @BASEBOARD_FAB2_LIB.BASEBOARD_FAB2(SCH_1):M_L_DQS_DN(1)
  U2D1 DA82 DDR4_DQS_DN<1> SKX_EXT_B_BGA1-IC,TBD   I172 @BASEBOARD_FAB2_LIB.BASEBOARD_FAB2(SCH_1):PAGE61
  J1A2  163  DQS1N SCONN288_H44441004_PIP-SCONN,HA    I66 @BASEBOARD_FAB2_LIB.BASEBOARD_FAB2(SCH_1):PAGE85
  J9L2  163  DQS1N SCONN288_H44441003_PIP-SCONN,HA   I100 @BASEBOARD_FAB2_LIB.BASEBOARD_FAB2(SCH_1):PAGE86

M_L_DQS_DN<2> @BASEBOARD_FAB2_LIB.BASEBOARD_FAB2(SCH_1):M_L_DQS_DN(2)
  U2D1 ED79 DDR4_DQS_DN<2> SKX_EXT_B_BGA1-IC,TBD   I172 @BASEBOARD_FAB2_LIB.BASEBOARD_FAB2(SCH_1):PAGE61
  J1A2  174  DQS2N SCONN288_H44441004_PIP-SCONN,HA    I66 @BASEBOARD_FAB2_LIB.BASEBOARD_FAB2(SCH_1):PAGE85
  J9L2  174  DQS2N SCONN288_H44441003_PIP-SCONN,HA   I100 @BASEBOARD_FAB2_LIB.BASEBOARD_FAB2(SCH_1):PAGE86

M_L_DQS_DN<3> @BASEBOARD_FAB2_LIB.BASEBOARD_FAB2(SCH_1):M_L_DQS_DN(3)
  U2D1 EF73 DDR4_DQS_DN<3> SKX_EXT_B_BGA1-IC,TBD   I172 @BASEBOARD_FAB2_LIB.BASEBOARD_FAB2(SCH_1):PAGE61
  J1A2  185  DQS3N SCONN288_H44441004_PIP-SCONN,HA    I66 @BASEBOARD_FAB2_LIB.BASEBOARD_FAB2(SCH_1):PAGE85
  J9L2  185  DQS3N SCONN288_H44441003_PIP-SCONN,HA   I100 @BASEBOARD_FAB2_LIB.BASEBOARD_FAB2(SCH_1):PAGE86

M_L_DQS_DN<4> @BASEBOARD_FAB2_LIB.BASEBOARD_FAB2(SCH_1):M_L_DQS_DN(4)
  U2D1 DV41 DDR4_DQS_DN<4> SKX_EXT_B_BGA1-IC,TBD   I172 @BASEBOARD_FAB2_LIB.BASEBOARD_FAB2(SCH_1):PAGE61
  J1A2  244  DQS4N SCONN288_H44441004_PIP-SCONN,HA    I66 @BASEBOARD_FAB2_LIB.BASEBOARD_FAB2(SCH_1):PAGE85
  J9L2  244  DQS4N SCONN288_H44441003_PIP-SCONN,HA   I100 @BASEBOARD_FAB2_LIB.BASEBOARD_FAB2(SCH_1):PAGE86

M_L_DQS_DN<5> @BASEBOARD_FAB2_LIB.BASEBOARD_FAB2(SCH_1):M_L_DQS_DN(5)
  U2D1 EE32 DDR4_DQS_DN<5> SKX_EXT_B_BGA1-IC,TBD   I172 @BASEBOARD_FAB2_LIB.BASEBOARD_FAB2(SCH_1):PAGE61
  J1A2  255  DQS5N SCONN288_H44441004_PIP-SCONN,HA    I66 @BASEBOARD_FAB2_LIB.BASEBOARD_FAB2(SCH_1):PAGE85
  J9L2  255  DQS5N SCONN288_H44441003_PIP-SCONN,HA   I100 @BASEBOARD_FAB2_LIB.BASEBOARD_FAB2(SCH_1):PAGE86

M_L_DQS_DN<6> @BASEBOARD_FAB2_LIB.BASEBOARD_FAB2(SCH_1):M_L_DQS_DN(6)
  U2D1 EE26 DDR4_DQS_DN<6> SKX_EXT_B_BGA1-IC,TBD   I172 @BASEBOARD_FAB2_LIB.BASEBOARD_FAB2(SCH_1):PAGE61
  J1A2  266  DQS6N SCONN288_H44441004_PIP-SCONN,HA    I66 @BASEBOARD_FAB2_LIB.BASEBOARD_FAB2(SCH_1):PAGE85
  J9L2  266  DQS6N SCONN288_H44441003_PIP-SCONN,HA   I100 @BASEBOARD_FAB2_LIB.BASEBOARD_FAB2(SCH_1):PAGE86

M_L_DQS_DN<7> @BASEBOARD_FAB2_LIB.BASEBOARD_FAB2(SCH_1):M_L_DQS_DN(7)
  U2D1 DL26 DDR4_DQS_DN<7> SKX_EXT_B_BGA1-IC,TBD   I172 @BASEBOARD_FAB2_LIB.BASEBOARD_FAB2(SCH_1):PAGE61
  J1A2  277  DQS7N SCONN288_H44441004_PIP-SCONN,HA    I66 @BASEBOARD_FAB2_LIB.BASEBOARD_FAB2(SCH_1):PAGE85
  J9L2  277  DQS7N SCONN288_H44441003_PIP-SCONN,HA   I100 @BASEBOARD_FAB2_LIB.BASEBOARD_FAB2(SCH_1):PAGE86

M_L_DQS_DN<8> @BASEBOARD_FAB2_LIB.BASEBOARD_FAB2(SCH_1):M_L_DQS_DN(8)
  U2D1 EB67 DDR4_DQS_DN<8> SKX_EXT_B_BGA1-IC,TBD   I172 @BASEBOARD_FAB2_LIB.BASEBOARD_FAB2(SCH_1):PAGE61
  J1A2  196  DQS8N SCONN288_H44441004_PIP-SCONN,HA    I66 @BASEBOARD_FAB2_LIB.BASEBOARD_FAB2(SCH_1):PAGE85
  J9L2  196  DQS8N SCONN288_H44441003_PIP-SCONN,HA   I100 @BASEBOARD_FAB2_LIB.BASEBOARD_FAB2(SCH_1):PAGE86

M_L_DQS_DN<9> @BASEBOARD_FAB2_LIB.BASEBOARD_FAB2(SCH_1):M_L_DQS_DN(9)
  U2D1 CN80 DDR4_DQS_DN<9> SKX_EXT_B_BGA1-IC,TBD   I172 @BASEBOARD_FAB2_LIB.BASEBOARD_FAB2(SCH_1):PAGE61
  J1A2    8  DQS9N SCONN288_H44441004_PIP-SCONN,HA    I66 @BASEBOARD_FAB2_LIB.BASEBOARD_FAB2(SCH_1):PAGE85
  J9L2    8  DQS9N SCONN288_H44441003_PIP-SCONN,HA   I100 @BASEBOARD_FAB2_LIB.BASEBOARD_FAB2(SCH_1):PAGE86

M_L_DQS_DP<0> @BASEBOARD_FAB2_LIB.BASEBOARD_FAB2(SCH_1):M_L_DQS_DP(0)
  U2D1 CM81 DDR4_DQS_DP<0> SKX_EXT_B_BGA1-IC,TBD   I172 @BASEBOARD_FAB2_LIB.BASEBOARD_FAB2(SCH_1):PAGE61
  J1A2  153  DQS0P SCONN288_H44441004_PIP-SCONN,HA    I66 @BASEBOARD_FAB2_LIB.BASEBOARD_FAB2(SCH_1):PAGE85
  J9L2  153  DQS0P SCONN288_H44441003_PIP-SCONN,HA   I100 @BASEBOARD_FAB2_LIB.BASEBOARD_FAB2(SCH_1):PAGE86

M_L_DQS_DP<10> @BASEBOARD_FAB2_LIB.BASEBOARD_FAB2(SCH_1):M_L_DQS_DP(10)
  U2D1 DD79 DDR4_DQS_DP<10> SKX_EXT_B_BGA1-IC,TBD   I172 @BASEBOARD_FAB2_LIB.BASEBOARD_FAB2(SCH_1):PAGE61
  J1A2   18 DQS10P SCONN288_H44441004_PIP-SCONN,HA    I66 @BASEBOARD_FAB2_LIB.BASEBOARD_FAB2(SCH_1):PAGE85
  J9L2   18 DQS10P SCONN288_H44441003_PIP-SCONN,HA   I100 @BASEBOARD_FAB2_LIB.BASEBOARD_FAB2(SCH_1):PAGE86

M_L_DQS_DP<11> @BASEBOARD_FAB2_LIB.BASEBOARD_FAB2(SCH_1):M_L_DQS_DP(11)
  U2D1 DV79 DDR4_DQS_DP<11> SKX_EXT_B_BGA1-IC,TBD   I172 @BASEBOARD_FAB2_LIB.BASEBOARD_FAB2(SCH_1):PAGE61
  J1A2   29 DQS11P SCONN288_H44441004_PIP-SCONN,HA    I66 @BASEBOARD_FAB2_LIB.BASEBOARD_FAB2(SCH_1):PAGE85
  J9L2   29 DQS11P SCONN288_H44441003_PIP-SCONN,HA   I100 @BASEBOARD_FAB2_LIB.BASEBOARD_FAB2(SCH_1):PAGE86

M_L_DQS_DP<12> @BASEBOARD_FAB2_LIB.BASEBOARD_FAB2(SCH_1):M_L_DQS_DP(12)
  U2D1 DY73 DDR4_DQS_DP<12> SKX_EXT_B_BGA1-IC,TBD   I172 @BASEBOARD_FAB2_LIB.BASEBOARD_FAB2(SCH_1):PAGE61
  J1A2   40 DQS12P SCONN288_H44441004_PIP-SCONN,HA    I66 @BASEBOARD_FAB2_LIB.BASEBOARD_FAB2(SCH_1):PAGE85
  J9L2   40 DQS12P SCONN288_H44441003_PIP-SCONN,HA   I100 @BASEBOARD_FAB2_LIB.BASEBOARD_FAB2(SCH_1):PAGE86

M_L_DQS_DP<13> @BASEBOARD_FAB2_LIB.BASEBOARD_FAB2(SCH_1):M_L_DQS_DP(13)
  U2D1 DM41 DDR4_DQS_DP<13> SKX_EXT_B_BGA1-IC,TBD   I172 @BASEBOARD_FAB2_LIB.BASEBOARD_FAB2(SCH_1):PAGE61
  J1A2   99 DQS13P SCONN288_H44441004_PIP-SCONN,HA    I66 @BASEBOARD_FAB2_LIB.BASEBOARD_FAB2(SCH_1):PAGE85
  J9L2   99 DQS13P SCONN288_H44441003_PIP-SCONN,HA   I100 @BASEBOARD_FAB2_LIB.BASEBOARD_FAB2(SCH_1):PAGE86

M_L_DQS_DP<14> @BASEBOARD_FAB2_LIB.BASEBOARD_FAB2(SCH_1):M_L_DQS_DP(14)
  U2D1 DW32 DDR4_DQS_DP<14> SKX_EXT_B_BGA1-IC,TBD   I172 @BASEBOARD_FAB2_LIB.BASEBOARD_FAB2(SCH_1):PAGE61
  J1A2  110 DQS14P SCONN288_H44441004_PIP-SCONN,HA    I66 @BASEBOARD_FAB2_LIB.BASEBOARD_FAB2(SCH_1):PAGE85
  J9L2  110 DQS14P SCONN288_H44441003_PIP-SCONN,HA   I100 @BASEBOARD_FAB2_LIB.BASEBOARD_FAB2(SCH_1):PAGE86

M_L_DQS_DP<15> @BASEBOARD_FAB2_LIB.BASEBOARD_FAB2(SCH_1):M_L_DQS_DP(15)
  U2D1 DW26 DDR4_DQS_DP<15> SKX_EXT_B_BGA1-IC,TBD   I172 @BASEBOARD_FAB2_LIB.BASEBOARD_FAB2(SCH_1):PAGE61
  J1A2  121 DQS15P SCONN288_H44441004_PIP-SCONN,HA    I66 @BASEBOARD_FAB2_LIB.BASEBOARD_FAB2(SCH_1):PAGE85
  J9L2  121 DQS15P SCONN288_H44441003_PIP-SCONN,HA   I100 @BASEBOARD_FAB2_LIB.BASEBOARD_FAB2(SCH_1):PAGE86

M_L_DQS_DP<16> @BASEBOARD_FAB2_LIB.BASEBOARD_FAB2(SCH_1):M_L_DQS_DP(16)
  U2D1 DE26 DDR4_DQS_DP<16> SKX_EXT_B_BGA1-IC,TBD   I172 @BASEBOARD_FAB2_LIB.BASEBOARD_FAB2(SCH_1):PAGE61
  J1A2  132 DQS16P SCONN288_H44441004_PIP-SCONN,HA    I66 @BASEBOARD_FAB2_LIB.BASEBOARD_FAB2(SCH_1):PAGE85
  J9L2  132 DQS16P SCONN288_H44441003_PIP-SCONN,HA   I100 @BASEBOARD_FAB2_LIB.BASEBOARD_FAB2(SCH_1):PAGE86

M_L_DQS_DP<17> @BASEBOARD_FAB2_LIB.BASEBOARD_FAB2(SCH_1):M_L_DQS_DP(17)
  U2D1 DT67 DDR4_DQS_DP<17> SKX_EXT_B_BGA1-IC,TBD   I172 @BASEBOARD_FAB2_LIB.BASEBOARD_FAB2(SCH_1):PAGE61
  J1A2   51 DQS17P SCONN288_H44441004_PIP-SCONN,HA    I66 @BASEBOARD_FAB2_LIB.BASEBOARD_FAB2(SCH_1):PAGE85
  J9L2   51 DQS17P SCONN288_H44441003_PIP-SCONN,HA   I100 @BASEBOARD_FAB2_LIB.BASEBOARD_FAB2(SCH_1):PAGE86

M_L_DQS_DP<1> @BASEBOARD_FAB2_LIB.BASEBOARD_FAB2(SCH_1):M_L_DQS_DP(1)
  U2D1 DB81 DDR4_DQS_DP<1> SKX_EXT_B_BGA1-IC,TBD   I172 @BASEBOARD_FAB2_LIB.BASEBOARD_FAB2(SCH_1):PAGE61
  J1A2  164  DQS1P SCONN288_H44441004_PIP-SCONN,HA    I66 @BASEBOARD_FAB2_LIB.BASEBOARD_FAB2(SCH_1):PAGE85
  J9L2  164  DQS1P SCONN288_H44441003_PIP-SCONN,HA   I100 @BASEBOARD_FAB2_LIB.BASEBOARD_FAB2(SCH_1):PAGE86

M_L_DQS_DP<2> @BASEBOARD_FAB2_LIB.BASEBOARD_FAB2(SCH_1):M_L_DQS_DP(2)
  U2D1 EB79 DDR4_DQS_DP<2> SKX_EXT_B_BGA1-IC,TBD   I172 @BASEBOARD_FAB2_LIB.BASEBOARD_FAB2(SCH_1):PAGE61
  J1A2  175  DQS2P SCONN288_H44441004_PIP-SCONN,HA    I66 @BASEBOARD_FAB2_LIB.BASEBOARD_FAB2(SCH_1):PAGE85
  J9L2  175  DQS2P SCONN288_H44441003_PIP-SCONN,HA   I100 @BASEBOARD_FAB2_LIB.BASEBOARD_FAB2(SCH_1):PAGE86

M_L_DQS_DP<3> @BASEBOARD_FAB2_LIB.BASEBOARD_FAB2(SCH_1):M_L_DQS_DP(3)
  U2D1 ED73 DDR4_DQS_DP<3> SKX_EXT_B_BGA1-IC,TBD   I172 @BASEBOARD_FAB2_LIB.BASEBOARD_FAB2(SCH_1):PAGE61
  J1A2  186  DQS3P SCONN288_H44441004_PIP-SCONN,HA    I66 @BASEBOARD_FAB2_LIB.BASEBOARD_FAB2(SCH_1):PAGE85
  J9L2  186  DQS3P SCONN288_H44441003_PIP-SCONN,HA   I100 @BASEBOARD_FAB2_LIB.BASEBOARD_FAB2(SCH_1):PAGE86

M_L_DQS_DP<4> @BASEBOARD_FAB2_LIB.BASEBOARD_FAB2(SCH_1):M_L_DQS_DP(4)
  U2D1 DT41 DDR4_DQS_DP<4> SKX_EXT_B_BGA1-IC,TBD   I172 @BASEBOARD_FAB2_LIB.BASEBOARD_FAB2(SCH_1):PAGE61
  J1A2  245  DQS4P SCONN288_H44441004_PIP-SCONN,HA    I66 @BASEBOARD_FAB2_LIB.BASEBOARD_FAB2(SCH_1):PAGE85
  J9L2  245  DQS4P SCONN288_H44441003_PIP-SCONN,HA   I100 @BASEBOARD_FAB2_LIB.BASEBOARD_FAB2(SCH_1):PAGE86

M_L_DQS_DP<5> @BASEBOARD_FAB2_LIB.BASEBOARD_FAB2(SCH_1):M_L_DQS_DP(5)
  U2D1 EC32 DDR4_DQS_DP<5> SKX_EXT_B_BGA1-IC,TBD   I172 @BASEBOARD_FAB2_LIB.BASEBOARD_FAB2(SCH_1):PAGE61
  J1A2  256  DQS5P SCONN288_H44441004_PIP-SCONN,HA    I66 @BASEBOARD_FAB2_LIB.BASEBOARD_FAB2(SCH_1):PAGE85
  J9L2  256  DQS5P SCONN288_H44441003_PIP-SCONN,HA   I100 @BASEBOARD_FAB2_LIB.BASEBOARD_FAB2(SCH_1):PAGE86

M_L_DQS_DP<6> @BASEBOARD_FAB2_LIB.BASEBOARD_FAB2(SCH_1):M_L_DQS_DP(6)
  U2D1 EC26 DDR4_DQS_DP<6> SKX_EXT_B_BGA1-IC,TBD   I172 @BASEBOARD_FAB2_LIB.BASEBOARD_FAB2(SCH_1):PAGE61
  J1A2  267  DQS6P SCONN288_H44441004_PIP-SCONN,HA    I66 @BASEBOARD_FAB2_LIB.BASEBOARD_FAB2(SCH_1):PAGE85
  J9L2  267  DQS6P SCONN288_H44441003_PIP-SCONN,HA   I100 @BASEBOARD_FAB2_LIB.BASEBOARD_FAB2(SCH_1):PAGE86

M_L_DQS_DP<7> @BASEBOARD_FAB2_LIB.BASEBOARD_FAB2(SCH_1):M_L_DQS_DP(7)
  U2D1 DJ26 DDR4_DQS_DP<7> SKX_EXT_B_BGA1-IC,TBD   I172 @BASEBOARD_FAB2_LIB.BASEBOARD_FAB2(SCH_1):PAGE61
  J1A2  278  DQS7P SCONN288_H44441004_PIP-SCONN,HA    I66 @BASEBOARD_FAB2_LIB.BASEBOARD_FAB2(SCH_1):PAGE85
  J9L2  278  DQS7P SCONN288_H44441003_PIP-SCONN,HA   I100 @BASEBOARD_FAB2_LIB.BASEBOARD_FAB2(SCH_1):PAGE86

M_L_DQS_DP<8> @BASEBOARD_FAB2_LIB.BASEBOARD_FAB2(SCH_1):M_L_DQS_DP(8)
  U2D1 DY67 DDR4_DQS_DP<8> SKX_EXT_B_BGA1-IC,TBD   I172 @BASEBOARD_FAB2_LIB.BASEBOARD_FAB2(SCH_1):PAGE61
  J1A2  197  DQS8P SCONN288_H44441004_PIP-SCONN,HA    I66 @BASEBOARD_FAB2_LIB.BASEBOARD_FAB2(SCH_1):PAGE85
  J9L2  197  DQS8P SCONN288_H44441003_PIP-SCONN,HA   I100 @BASEBOARD_FAB2_LIB.BASEBOARD_FAB2(SCH_1):PAGE86

M_L_DQS_DP<9> @BASEBOARD_FAB2_LIB.BASEBOARD_FAB2(SCH_1):M_L_DQS_DP(9)
  U2D1 CP79 DDR4_DQS_DP<9> SKX_EXT_B_BGA1-IC,TBD   I172 @BASEBOARD_FAB2_LIB.BASEBOARD_FAB2(SCH_1):PAGE61
  J1A2    7  DQS9P SCONN288_H44441004_PIP-SCONN,HA    I66 @BASEBOARD_FAB2_LIB.BASEBOARD_FAB2(SCH_1):PAGE85
  J9L2    7  DQS9P SCONN288_H44441003_PIP-SCONN,HA   I100 @BASEBOARD_FAB2_LIB.BASEBOARD_FAB2(SCH_1):PAGE86

M_L_ECC<0> @BASEBOARD_FAB2_LIB.BASEBOARD_FAB2(SCH_1):M_L_ECC(0)
  U2D1 DY69 DDR4_ECC<0> SKX_EXT_B_BGA1-IC,TBD   I172 @BASEBOARD_FAB2_LIB.BASEBOARD_FAB2(SCH_1):PAGE61
  J1A2  194  CB<1> SCONN288_H44441004_PIP-SCONN,HA   I111 @BASEBOARD_FAB2_LIB.BASEBOARD_FAB2(SCH_1):PAGE85
  J9L2   49  CB<0> SCONN288_H44441003_PIP-SCONN,HA    I12 @BASEBOARD_FAB2_LIB.BASEBOARD_FAB2(SCH_1):PAGE86

M_L_ECC<1> @BASEBOARD_FAB2_LIB.BASEBOARD_FAB2(SCH_1):M_L_ECC(1)
  U2D1 EA68 DDR4_ECC<1> SKX_EXT_B_BGA1-IC,TBD   I172 @BASEBOARD_FAB2_LIB.BASEBOARD_FAB2(SCH_1):PAGE61
  J1A2   49  CB<0> SCONN288_H44441004_PIP-SCONN,HA   I111 @BASEBOARD_FAB2_LIB.BASEBOARD_FAB2(SCH_1):PAGE85
  J9L2  194  CB<1> SCONN288_H44441003_PIP-SCONN,HA    I12 @BASEBOARD_FAB2_LIB.BASEBOARD_FAB2(SCH_1):PAGE86

M_L_ECC<2> @BASEBOARD_FAB2_LIB.BASEBOARD_FAB2(SCH_1):M_L_ECC(2)
  U2D1 DV65 DDR4_ECC<2> SKX_EXT_B_BGA1-IC,TBD   I172 @BASEBOARD_FAB2_LIB.BASEBOARD_FAB2(SCH_1):PAGE61
  J1A2  201  CB<3> SCONN288_H44441004_PIP-SCONN,HA   I111 @BASEBOARD_FAB2_LIB.BASEBOARD_FAB2(SCH_1):PAGE85
  J9L2   56  CB<2> SCONN288_H44441003_PIP-SCONN,HA    I12 @BASEBOARD_FAB2_LIB.BASEBOARD_FAB2(SCH_1):PAGE86

M_L_ECC<3> @BASEBOARD_FAB2_LIB.BASEBOARD_FAB2(SCH_1):M_L_ECC(3)
  U2D1 DY65 DDR4_ECC<3> SKX_EXT_B_BGA1-IC,TBD   I172 @BASEBOARD_FAB2_LIB.BASEBOARD_FAB2(SCH_1):PAGE61
  J1A2   56  CB<2> SCONN288_H44441004_PIP-SCONN,HA   I111 @BASEBOARD_FAB2_LIB.BASEBOARD_FAB2(SCH_1):PAGE85
  J9L2  201  CB<3> SCONN288_H44441003_PIP-SCONN,HA    I12 @BASEBOARD_FAB2_LIB.BASEBOARD_FAB2(SCH_1):PAGE86

M_L_ECC<4> @BASEBOARD_FAB2_LIB.BASEBOARD_FAB2(SCH_1):M_L_ECC(4)
  U2D1 DU68 DDR4_ECC<4> SKX_EXT_B_BGA1-IC,TBD   I172 @BASEBOARD_FAB2_LIB.BASEBOARD_FAB2(SCH_1):PAGE61
  J1A2  192  CB<5> SCONN288_H44441004_PIP-SCONN,HA   I111 @BASEBOARD_FAB2_LIB.BASEBOARD_FAB2(SCH_1):PAGE85
  J9L2   47  CB<4> SCONN288_H44441003_PIP-SCONN,HA    I12 @BASEBOARD_FAB2_LIB.BASEBOARD_FAB2(SCH_1):PAGE86

M_L_ECC<5> @BASEBOARD_FAB2_LIB.BASEBOARD_FAB2(SCH_1):M_L_ECC(5)
  U2D1 DV69 DDR4_ECC<5> SKX_EXT_B_BGA1-IC,TBD   I172 @BASEBOARD_FAB2_LIB.BASEBOARD_FAB2(SCH_1):PAGE61
  J1A2   47  CB<4> SCONN288_H44441004_PIP-SCONN,HA   I111 @BASEBOARD_FAB2_LIB.BASEBOARD_FAB2(SCH_1):PAGE85
  J9L2  192  CB<5> SCONN288_H44441003_PIP-SCONN,HA    I12 @BASEBOARD_FAB2_LIB.BASEBOARD_FAB2(SCH_1):PAGE86

M_L_ECC<6> @BASEBOARD_FAB2_LIB.BASEBOARD_FAB2(SCH_1):M_L_ECC(6)
  U2D1 DU66 DDR4_ECC<6> SKX_EXT_B_BGA1-IC,TBD   I172 @BASEBOARD_FAB2_LIB.BASEBOARD_FAB2(SCH_1):PAGE61
  J1A2  199  CB<7> SCONN288_H44441004_PIP-SCONN,HA   I111 @BASEBOARD_FAB2_LIB.BASEBOARD_FAB2(SCH_1):PAGE85
  J9L2   54  CB<6> SCONN288_H44441003_PIP-SCONN,HA    I12 @BASEBOARD_FAB2_LIB.BASEBOARD_FAB2(SCH_1):PAGE86

M_L_ECC<7> @BASEBOARD_FAB2_LIB.BASEBOARD_FAB2(SCH_1):M_L_ECC(7)
  U2D1 EA66 DDR4_ECC<7> SKX_EXT_B_BGA1-IC,TBD   I172 @BASEBOARD_FAB2_LIB.BASEBOARD_FAB2(SCH_1):PAGE61
  J1A2   54  CB<6> SCONN288_H44441004_PIP-SCONN,HA   I111 @BASEBOARD_FAB2_LIB.BASEBOARD_FAB2(SCH_1):PAGE85
  J9L2  199  CB<7> SCONN288_H44441003_PIP-SCONN,HA    I12 @BASEBOARD_FAB2_LIB.BASEBOARD_FAB2(SCH_1):PAGE86

M_L_MA<0> @BASEBOARD_FAB2_LIB.BASEBOARD_FAB2(SCH_1):M_L_MA(0)
  U2D1 DW52 DDR4_MA<0> SKX_EXT_B_BGA1-IC,TBD   I172 @BASEBOARD_FAB2_LIB.BASEBOARD_FAB2(SCH_1):PAGE61
  J1A2   79     A0 SCONN288_H44441004_PIP-SCONN,HA   I111 @BASEBOARD_FAB2_LIB.BASEBOARD_FAB2(SCH_1):PAGE85
  J9L2   79     A0 SCONN288_H44441003_PIP-SCONN,HA    I12 @BASEBOARD_FAB2_LIB.BASEBOARD_FAB2(SCH_1):PAGE86

M_L_MA<10> @BASEBOARD_FAB2_LIB.BASEBOARD_FAB2(SCH_1):M_L_MA(10)
  U2D1 DT55 DDR4_MA<10> SKX_EXT_B_BGA1-IC,TBD   I172 @BASEBOARD_FAB2_LIB.BASEBOARD_FAB2(SCH_1):PAGE61
  J1A2  225    A10 SCONN288_H44441004_PIP-SCONN,HA   I111 @BASEBOARD_FAB2_LIB.BASEBOARD_FAB2(SCH_1):PAGE85
  J9L2  225    A10 SCONN288_H44441003_PIP-SCONN,HA    I12 @BASEBOARD_FAB2_LIB.BASEBOARD_FAB2(SCH_1):PAGE86

M_L_MA<11> @BASEBOARD_FAB2_LIB.BASEBOARD_FAB2(SCH_1):M_L_MA(11)
  U2D1 DR60 DDR4_MA<11> SKX_EXT_B_BGA1-IC,TBD   I172 @BASEBOARD_FAB2_LIB.BASEBOARD_FAB2(SCH_1):PAGE61
  J1A2  210    A11 SCONN288_H44441004_PIP-SCONN,HA   I111 @BASEBOARD_FAB2_LIB.BASEBOARD_FAB2(SCH_1):PAGE85
  J9L2  210    A11 SCONN288_H44441003_PIP-SCONN,HA    I12 @BASEBOARD_FAB2_LIB.BASEBOARD_FAB2(SCH_1):PAGE86

M_L_MA<12> @BASEBOARD_FAB2_LIB.BASEBOARD_FAB2(SCH_1):M_L_MA(12)
  U2D1 DN60 DDR4_MA<12> SKX_EXT_B_BGA1-IC,TBD   I172 @BASEBOARD_FAB2_LIB.BASEBOARD_FAB2(SCH_1):PAGE61
  J1A2   65    A12 SCONN288_H44441004_PIP-SCONN,HA   I111 @BASEBOARD_FAB2_LIB.BASEBOARD_FAB2(SCH_1):PAGE85
  J9L2   65    A12 SCONN288_H44441003_PIP-SCONN,HA    I12 @BASEBOARD_FAB2_LIB.BASEBOARD_FAB2(SCH_1):PAGE86

M_L_MA<13> @BASEBOARD_FAB2_LIB.BASEBOARD_FAB2(SCH_1):M_L_MA(13)
  U2D1 DT51 DDR4_MA<13> SKX_EXT_B_BGA1-IC,TBD   I172 @BASEBOARD_FAB2_LIB.BASEBOARD_FAB2(SCH_1):PAGE61
  J1A2  232    A13 SCONN288_H44441004_PIP-SCONN,HA   I111 @BASEBOARD_FAB2_LIB.BASEBOARD_FAB2(SCH_1):PAGE85
  J9L2  232    A13 SCONN288_H44441003_PIP-SCONN,HA    I12 @BASEBOARD_FAB2_LIB.BASEBOARD_FAB2(SCH_1):PAGE86

M_L_MA<14> @BASEBOARD_FAB2_LIB.BASEBOARD_FAB2(SCH_1):M_L_MA(14)
  U2D1 DM51 DDR4_MA<14> SKX_EXT_B_BGA1-IC,TBD   I172 @BASEBOARD_FAB2_LIB.BASEBOARD_FAB2(SCH_1):PAGE61
  J1A2  228 A14_WE_N SCONN288_H44441004_PIP-SCONN,HA   I111 @BASEBOARD_FAB2_LIB.BASEBOARD_FAB2(SCH_1):PAGE85
  J9L2  228 A14_WE_N SCONN288_H44441003_PIP-SCONN,HA    I12 @BASEBOARD_FAB2_LIB.BASEBOARD_FAB2(SCH_1):PAGE86

M_L_MA<15> @BASEBOARD_FAB2_LIB.BASEBOARD_FAB2(SCH_1):M_L_MA(15)
  U2D1 DR52 DDR4_MA<15> SKX_EXT_B_BGA1-IC,TBD   I172 @BASEBOARD_FAB2_LIB.BASEBOARD_FAB2(SCH_1):PAGE61
  J1A2   86 A15_CAS_N SCONN288_H44441004_PIP-SCONN,HA   I111 @BASEBOARD_FAB2_LIB.BASEBOARD_FAB2(SCH_1):PAGE85
  J9L2   86 A15_CAS_N SCONN288_H44441003_PIP-SCONN,HA    I12 @BASEBOARD_FAB2_LIB.BASEBOARD_FAB2(SCH_1):PAGE86

M_L_MA<16> @BASEBOARD_FAB2_LIB.BASEBOARD_FAB2(SCH_1):M_L_MA(16)
  U2D1 DN52 DDR4_MA<16> SKX_EXT_B_BGA1-IC,TBD   I172 @BASEBOARD_FAB2_LIB.BASEBOARD_FAB2(SCH_1):PAGE61
  J1A2   82 A16_RAS_N SCONN288_H44441004_PIP-SCONN,HA   I111 @BASEBOARD_FAB2_LIB.BASEBOARD_FAB2(SCH_1):PAGE85
  J9L2   82 A16_RAS_N SCONN288_H44441003_PIP-SCONN,HA    I12 @BASEBOARD_FAB2_LIB.BASEBOARD_FAB2(SCH_1):PAGE86

M_L_MA<17> @BASEBOARD_FAB2_LIB.BASEBOARD_FAB2(SCH_1):M_L_MA(17)
  U2D1 DR48 DDR4_MA<17> SKX_EXT_B_BGA1-IC,TBD   I172 @BASEBOARD_FAB2_LIB.BASEBOARD_FAB2(SCH_1):PAGE61
  J1A2  234    A17 SCONN288_H44441004_PIP-SCONN,HA   I111 @BASEBOARD_FAB2_LIB.BASEBOARD_FAB2(SCH_1):PAGE85
  J9L2  234    A17 SCONN288_H44441003_PIP-SCONN,HA    I12 @BASEBOARD_FAB2_LIB.BASEBOARD_FAB2(SCH_1):PAGE86

M_L_MA<1> @BASEBOARD_FAB2_LIB.BASEBOARD_FAB2(SCH_1):M_L_MA(1)
  U2D1 DW58 DDR4_MA<1> SKX_EXT_B_BGA1-IC,TBD   I172 @BASEBOARD_FAB2_LIB.BASEBOARD_FAB2(SCH_1):PAGE61
  J1A2   72     A1 SCONN288_H44441004_PIP-SCONN,HA   I111 @BASEBOARD_FAB2_LIB.BASEBOARD_FAB2(SCH_1):PAGE85
  J9L2   72     A1 SCONN288_H44441003_PIP-SCONN,HA    I12 @BASEBOARD_FAB2_LIB.BASEBOARD_FAB2(SCH_1):PAGE86

M_L_MA<2> @BASEBOARD_FAB2_LIB.BASEBOARD_FAB2(SCH_1):M_L_MA(2)
  U2D1 DV57 DDR4_MA<2> SKX_EXT_B_BGA1-IC,TBD   I172 @BASEBOARD_FAB2_LIB.BASEBOARD_FAB2(SCH_1):PAGE61
  J1A2  216     A2 SCONN288_H44441004_PIP-SCONN,HA   I111 @BASEBOARD_FAB2_LIB.BASEBOARD_FAB2(SCH_1):PAGE85
  J9L2  216     A2 SCONN288_H44441003_PIP-SCONN,HA    I12 @BASEBOARD_FAB2_LIB.BASEBOARD_FAB2(SCH_1):PAGE86

M_L_MA<3> @BASEBOARD_FAB2_LIB.BASEBOARD_FAB2(SCH_1):M_L_MA(3)
  U2D1 DR58 DDR4_MA<3> SKX_EXT_B_BGA1-IC,TBD   I172 @BASEBOARD_FAB2_LIB.BASEBOARD_FAB2(SCH_1):PAGE61
  J1A2   71     A3 SCONN288_H44441004_PIP-SCONN,HA   I111 @BASEBOARD_FAB2_LIB.BASEBOARD_FAB2(SCH_1):PAGE85
  J9L2   71     A3 SCONN288_H44441003_PIP-SCONN,HA    I12 @BASEBOARD_FAB2_LIB.BASEBOARD_FAB2(SCH_1):PAGE86

M_L_MA<4> @BASEBOARD_FAB2_LIB.BASEBOARD_FAB2(SCH_1):M_L_MA(4)
  U2D1 DT59 DDR4_MA<4> SKX_EXT_B_BGA1-IC,TBD   I172 @BASEBOARD_FAB2_LIB.BASEBOARD_FAB2(SCH_1):PAGE61
  J1A2  214     A4 SCONN288_H44441004_PIP-SCONN,HA   I111 @BASEBOARD_FAB2_LIB.BASEBOARD_FAB2(SCH_1):PAGE85
  J9L2  214     A4 SCONN288_H44441003_PIP-SCONN,HA    I12 @BASEBOARD_FAB2_LIB.BASEBOARD_FAB2(SCH_1):PAGE86

M_L_MA<5> @BASEBOARD_FAB2_LIB.BASEBOARD_FAB2(SCH_1):M_L_MA(5)
  U2D1 DN58 DDR4_MA<5> SKX_EXT_B_BGA1-IC,TBD   I172 @BASEBOARD_FAB2_LIB.BASEBOARD_FAB2(SCH_1):PAGE61
  J1A2  213     A5 SCONN288_H44441004_PIP-SCONN,HA   I111 @BASEBOARD_FAB2_LIB.BASEBOARD_FAB2(SCH_1):PAGE85
  J9L2  213     A5 SCONN288_H44441003_PIP-SCONN,HA    I12 @BASEBOARD_FAB2_LIB.BASEBOARD_FAB2(SCH_1):PAGE86

M_L_MA<6> @BASEBOARD_FAB2_LIB.BASEBOARD_FAB2(SCH_1):M_L_MA(6)
  U2D1 DM59 DDR4_MA<6> SKX_EXT_B_BGA1-IC,TBD   I172 @BASEBOARD_FAB2_LIB.BASEBOARD_FAB2(SCH_1):PAGE61
  J1A2   69     A6 SCONN288_H44441004_PIP-SCONN,HA   I111 @BASEBOARD_FAB2_LIB.BASEBOARD_FAB2(SCH_1):PAGE85
  J9L2   69     A6 SCONN288_H44441003_PIP-SCONN,HA    I12 @BASEBOARD_FAB2_LIB.BASEBOARD_FAB2(SCH_1):PAGE86

M_L_MA<7> @BASEBOARD_FAB2_LIB.BASEBOARD_FAB2(SCH_1):M_L_MA(7)
  U2D1 DK61 DDR4_MA<7> SKX_EXT_B_BGA1-IC,TBD   I172 @BASEBOARD_FAB2_LIB.BASEBOARD_FAB2(SCH_1):PAGE61
  J1A2  211     A7 SCONN288_H44441004_PIP-SCONN,HA   I111 @BASEBOARD_FAB2_LIB.BASEBOARD_FAB2(SCH_1):PAGE85
  J9L2  211     A7 SCONN288_H44441003_PIP-SCONN,HA    I12 @BASEBOARD_FAB2_LIB.BASEBOARD_FAB2(SCH_1):PAGE86

M_L_MA<8> @BASEBOARD_FAB2_LIB.BASEBOARD_FAB2(SCH_1):M_L_MA(8)
  U2D1 DJ60 DDR4_MA<8> SKX_EXT_B_BGA1-IC,TBD   I172 @BASEBOARD_FAB2_LIB.BASEBOARD_FAB2(SCH_1):PAGE61
  J1A2   68     A8 SCONN288_H44441004_PIP-SCONN,HA   I111 @BASEBOARD_FAB2_LIB.BASEBOARD_FAB2(SCH_1):PAGE85
  J9L2   68     A8 SCONN288_H44441003_PIP-SCONN,HA    I12 @BASEBOARD_FAB2_LIB.BASEBOARD_FAB2(SCH_1):PAGE86

M_L_MA<9> @BASEBOARD_FAB2_LIB.BASEBOARD_FAB2(SCH_1):M_L_MA(9)
  U2D1 DV59 DDR4_MA<9> SKX_EXT_B_BGA1-IC,TBD   I172 @BASEBOARD_FAB2_LIB.BASEBOARD_FAB2(SCH_1):PAGE61
  J1A2   66     A9 SCONN288_H44441004_PIP-SCONN,HA   I111 @BASEBOARD_FAB2_LIB.BASEBOARD_FAB2(SCH_1):PAGE85
  J9L2   66     A9 SCONN288_H44441003_PIP-SCONN,HA    I12 @BASEBOARD_FAB2_LIB.BASEBOARD_FAB2(SCH_1):PAGE86

M_L_ODT<0> @BASEBOARD_FAB2_LIB.BASEBOARD_FAB2(SCH_1):M_L_ODT(0)
  U2D1 DR50 DDR4_ODT<0> SKX_EXT_B_BGA1-IC,TBD   I172 @BASEBOARD_FAB2_LIB.BASEBOARD_FAB2(SCH_1):PAGE61
  J1A2   87 ODT<0> SCONN288_H44441004_PIP-SCONN,HA   I111 @BASEBOARD_FAB2_LIB.BASEBOARD_FAB2(SCH_1):PAGE85

M_L_ODT<1> @BASEBOARD_FAB2_LIB.BASEBOARD_FAB2(SCH_1):M_L_ODT(1)
  U2D1 DN48 DDR4_ODT<1> SKX_EXT_B_BGA1-IC,TBD   I172 @BASEBOARD_FAB2_LIB.BASEBOARD_FAB2(SCH_1):PAGE61
  J1A2   91 ODT<1> SCONN288_H44441004_PIP-SCONN,HA   I111 @BASEBOARD_FAB2_LIB.BASEBOARD_FAB2(SCH_1):PAGE85

M_L_ODT<2> @BASEBOARD_FAB2_LIB.BASEBOARD_FAB2(SCH_1):M_L_ODT(2)
  U2D1 DT49 DDR4_ODT<2> SKX_EXT_B_BGA1-IC,TBD   I172 @BASEBOARD_FAB2_LIB.BASEBOARD_FAB2(SCH_1):PAGE61
  J9L2   87 ODT<0> SCONN288_H44441003_PIP-SCONN,HA    I12 @BASEBOARD_FAB2_LIB.BASEBOARD_FAB2(SCH_1):PAGE86

M_L_ODT<3> @BASEBOARD_FAB2_LIB.BASEBOARD_FAB2(SCH_1):M_L_ODT(3)
  U2D1 DM47 DDR4_ODT<3> SKX_EXT_B_BGA1-IC,TBD   I172 @BASEBOARD_FAB2_LIB.BASEBOARD_FAB2(SCH_1):PAGE61
  J9L2   91 ODT<1> SCONN288_H44441003_PIP-SCONN,HA    I12 @BASEBOARD_FAB2_LIB.BASEBOARD_FAB2(SCH_1):PAGE86

M_L_PAR @BASEBOARD_FAB2_LIB.BASEBOARD_FAB2(SCH_1):M_L_PAR
  U2D1 DV53 DDR4_PAR SKX_EXT_B_BGA1-IC,TBD   I172 @BASEBOARD_FAB2_LIB.BASEBOARD_FAB2(SCH_1):PAGE61
  J1A2  222    PAR SCONN288_H44441004_PIP-SCONN,HA   I111 @BASEBOARD_FAB2_LIB.BASEBOARD_FAB2(SCH_1):PAGE85
  J9L2  222    PAR SCONN288_H44441003_PIP-SCONN,HA    I12 @BASEBOARD_FAB2_LIB.BASEBOARD_FAB2(SCH_1):PAGE86

M_L_VREF @BASEBOARD_FAB2_LIB.BASEBOARD_FAB2(SCH_1):M_L_VREF
  J1A2  146 VREFCA SCONN288_H44441004_PIP-SCONN,HA   I111 @BASEBOARD_FAB2_LIB.BASEBOARD_FAB2(SCH_1):PAGE85
  C9L7    1      A CAP_A_0402V-0.01UF,25V,10%,X7RA   I181 @BASEBOARD_FAB2_LIB.BASEBOARD_FAB2(SCH_1):PAGE85
  J9L2  146 VREFCA SCONN288_H44441003_PIP-SCONN,HA    I12 @BASEBOARD_FAB2_LIB.BASEBOARD_FAB2(SCH_1):PAGE86
 C1A17    1      A CAP_A_0402V-0.01UF,25V,10%,X7RA   I182 @BASEBOARD_FAB2_LIB.BASEBOARD_FAB2(SCH_1):PAGE86
  R9L7    2      B RES_0402-1.00K,1%,1/16W,CHIP,GA    I22 @BASEBOARD_FAB2_LIB.BASEBOARD_FAB2(SCH_1):PAGE100
  R9L6    1      A RES_0402-1.00K,1%,1/16W,CHIP,GA    I24 @BASEBOARD_FAB2_LIB.BASEBOARD_FAB2(SCH_1):PAGE100
  R9L8    2      B RES_0402-2,1.0%,1/16W,CHIP,G21A    I29 @BASEBOARD_FAB2_LIB.BASEBOARD_FAB2(SCH_1):PAGE100

M_M_ACT_N @BASEBOARD_FAB2_LIB.BASEBOARD_FAB2(SCH_1):M_M_ACT_N
  U2D1 DC62 DDR5_ACT_N SKX_EXT_B_BGA1-IC,TBD   I172 @BASEBOARD_FAB2_LIB.BASEBOARD_FAB2(SCH_1):PAGE62
  J1A1   62  ACT_N SCONN288_H44441004_PIP-SCONN,HA   I186 @BASEBOARD_FAB2_LIB.BASEBOARD_FAB2(SCH_1):PAGE87
  J9L1   62  ACT_N SCONN288_H44441003_PIP-SCONN,HA   I111 @BASEBOARD_FAB2_LIB.BASEBOARD_FAB2(SCH_1):PAGE88

M_M_ALERT_N @BASEBOARD_FAB2_LIB.BASEBOARD_FAB2(SCH_1):M_M_ALERT_N
  U2D1 DD61 DDR5_ALERT_N SKX_EXT_B_BGA1-IC,TBD   I172 @BASEBOARD_FAB2_LIB.BASEBOARD_FAB2(SCH_1):PAGE62
  J1A1  208 ALERT_N SCONN288_H44441004_PIP-SCONN,HA   I186 @BASEBOARD_FAB2_LIB.BASEBOARD_FAB2(SCH_1):PAGE87
  J9L1  208 ALERT_N SCONN288_H44441003_PIP-SCONN,HA   I111 @BASEBOARD_FAB2_LIB.BASEBOARD_FAB2(SCH_1):PAGE88

M_M_BA<0> @BASEBOARD_FAB2_LIB.BASEBOARD_FAB2(SCH_1):M_M_BA(0)
  U2D1 DJ52 DDR5_BA<0> SKX_EXT_B_BGA1-IC,TBD   I172 @BASEBOARD_FAB2_LIB.BASEBOARD_FAB2(SCH_1):PAGE62
  J1A1   81  BA<0> SCONN288_H44441004_PIP-SCONN,HA   I186 @BASEBOARD_FAB2_LIB.BASEBOARD_FAB2(SCH_1):PAGE87
  J9L1   81  BA<0> SCONN288_H44441003_PIP-SCONN,HA   I111 @BASEBOARD_FAB2_LIB.BASEBOARD_FAB2(SCH_1):PAGE88

M_M_BA<1> @BASEBOARD_FAB2_LIB.BASEBOARD_FAB2(SCH_1):M_M_BA(1)
  U2D1 DC56 DDR5_BA<1> SKX_EXT_B_BGA1-IC,TBD   I172 @BASEBOARD_FAB2_LIB.BASEBOARD_FAB2(SCH_1):PAGE62
  J1A1  224  BA<1> SCONN288_H44441004_PIP-SCONN,HA   I186 @BASEBOARD_FAB2_LIB.BASEBOARD_FAB2(SCH_1):PAGE87
  J9L1  224  BA<1> SCONN288_H44441003_PIP-SCONN,HA   I111 @BASEBOARD_FAB2_LIB.BASEBOARD_FAB2(SCH_1):PAGE88

M_M_BG<0> @BASEBOARD_FAB2_LIB.BASEBOARD_FAB2(SCH_1):M_M_BG(0)
  U2D1 DA62 DDR5_BG<0> SKX_EXT_B_BGA1-IC,TBD   I172 @BASEBOARD_FAB2_LIB.BASEBOARD_FAB2(SCH_1):PAGE62
  J1A1   63  BG<0> SCONN288_H44441004_PIP-SCONN,HA   I186 @BASEBOARD_FAB2_LIB.BASEBOARD_FAB2(SCH_1):PAGE87
  J9L1   63  BG<0> SCONN288_H44441003_PIP-SCONN,HA   I111 @BASEBOARD_FAB2_LIB.BASEBOARD_FAB2(SCH_1):PAGE88

M_M_BG<1> @BASEBOARD_FAB2_LIB.BASEBOARD_FAB2(SCH_1):M_M_BG(1)
  U2D1 DF61 DDR5_BG<1> SKX_EXT_B_BGA1-IC,TBD   I172 @BASEBOARD_FAB2_LIB.BASEBOARD_FAB2(SCH_1):PAGE62
  J1A1  207  BG<1> SCONN288_H44441004_PIP-SCONN,HA   I186 @BASEBOARD_FAB2_LIB.BASEBOARD_FAB2(SCH_1):PAGE87
  J9L1  207  BG<1> SCONN288_H44441003_PIP-SCONN,HA   I111 @BASEBOARD_FAB2_LIB.BASEBOARD_FAB2(SCH_1):PAGE88

M_M_C<2> @BASEBOARD_FAB2_LIB.BASEBOARD_FAB2(SCH_1):M_M_C(2)
  U2D1 DF45 DDR5_CID<2> SKX_EXT_B_BGA1-IC,TBD   I172 @BASEBOARD_FAB2_LIB.BASEBOARD_FAB2(SCH_1):PAGE62
  J1A1  235   C<2> SCONN288_H44441004_PIP-SCONN,HA   I186 @BASEBOARD_FAB2_LIB.BASEBOARD_FAB2(SCH_1):PAGE87
  J9L1  235   C<2> SCONN288_H44441003_PIP-SCONN,HA   I111 @BASEBOARD_FAB2_LIB.BASEBOARD_FAB2(SCH_1):PAGE88

M_M_CKE<0> @BASEBOARD_FAB2_LIB.BASEBOARD_FAB2(SCH_1):M_M_CKE(0)
  U2D1 DG62 DDR5_CKE<0> SKX_EXT_B_BGA1-IC,TBD   I172 @BASEBOARD_FAB2_LIB.BASEBOARD_FAB2(SCH_1):PAGE62
  J1A1   60 CKE<0> SCONN288_H44441004_PIP-SCONN,HA   I186 @BASEBOARD_FAB2_LIB.BASEBOARD_FAB2(SCH_1):PAGE87

M_M_CKE<1> @BASEBOARD_FAB2_LIB.BASEBOARD_FAB2(SCH_1):M_M_CKE(1)
  U2D1 DD63 DDR5_CKE<1> SKX_EXT_B_BGA1-IC,TBD   I172 @BASEBOARD_FAB2_LIB.BASEBOARD_FAB2(SCH_1):PAGE62
  J1A1  203 CKE<1> SCONN288_H44441004_PIP-SCONN,HA   I186 @BASEBOARD_FAB2_LIB.BASEBOARD_FAB2(SCH_1):PAGE87

M_M_CKE<2> @BASEBOARD_FAB2_LIB.BASEBOARD_FAB2(SCH_1):M_M_CKE(2)
  U2D1 DK63 DDR5_CKE<2> SKX_EXT_B_BGA1-IC,TBD   I172 @BASEBOARD_FAB2_LIB.BASEBOARD_FAB2(SCH_1):PAGE62
  J9L1   60 CKE<0> SCONN288_H44441003_PIP-SCONN,HA   I111 @BASEBOARD_FAB2_LIB.BASEBOARD_FAB2(SCH_1):PAGE88

M_M_CKE<3> @BASEBOARD_FAB2_LIB.BASEBOARD_FAB2(SCH_1):M_M_CKE(3)
  U2D1 DF63 DDR5_CKE<3> SKX_EXT_B_BGA1-IC,TBD   I172 @BASEBOARD_FAB2_LIB.BASEBOARD_FAB2(SCH_1):PAGE62
  J9L1  203 CKE<1> SCONN288_H44441003_PIP-SCONN,HA   I111 @BASEBOARD_FAB2_LIB.BASEBOARD_FAB2(SCH_1):PAGE88

M_M_CLK_DN<0> @BASEBOARD_FAB2_LIB.BASEBOARD_FAB2(SCH_1):M_M_CLK_DN(0)
  U2D1 DK55 DDR5_CLK_DN<0> SKX_EXT_B_BGA1-IC,TBD   I172 @BASEBOARD_FAB2_LIB.BASEBOARD_FAB2(SCH_1):PAGE62
  J1A1   75   CK0N SCONN288_H44441004_PIP-SCONN,HA   I186 @BASEBOARD_FAB2_LIB.BASEBOARD_FAB2(SCH_1):PAGE87

M_M_CLK_DN<1> @BASEBOARD_FAB2_LIB.BASEBOARD_FAB2(SCH_1):M_M_CLK_DN(1)
  U2D1 DF55 DDR5_CLK_DN<1> SKX_EXT_B_BGA1-IC,TBD   I172 @BASEBOARD_FAB2_LIB.BASEBOARD_FAB2(SCH_1):PAGE62
  J1A1  219   CK1N SCONN288_H44441004_PIP-SCONN,HA   I186 @BASEBOARD_FAB2_LIB.BASEBOARD_FAB2(SCH_1):PAGE87

M_M_CLK_DN<2> @BASEBOARD_FAB2_LIB.BASEBOARD_FAB2(SCH_1):M_M_CLK_DN(2)
  U2D1 DK57 DDR5_CLK_DN<2> SKX_EXT_B_BGA1-IC,TBD   I172 @BASEBOARD_FAB2_LIB.BASEBOARD_FAB2(SCH_1):PAGE62
  J9L1   75   CK0N SCONN288_H44441003_PIP-SCONN,HA   I111 @BASEBOARD_FAB2_LIB.BASEBOARD_FAB2(SCH_1):PAGE88

M_M_CLK_DN<3> @BASEBOARD_FAB2_LIB.BASEBOARD_FAB2(SCH_1):M_M_CLK_DN(3)
  U2D1 DF57 DDR5_CLK_DN<3> SKX_EXT_B_BGA1-IC,TBD   I172 @BASEBOARD_FAB2_LIB.BASEBOARD_FAB2(SCH_1):PAGE62
  J9L1  219   CK1N SCONN288_H44441003_PIP-SCONN,HA   I111 @BASEBOARD_FAB2_LIB.BASEBOARD_FAB2(SCH_1):PAGE88

M_M_CLK_DP<0> @BASEBOARD_FAB2_LIB.BASEBOARD_FAB2(SCH_1):M_M_CLK_DP(0)
  U2D1 DJ54 DDR5_CLK_DP<0> SKX_EXT_B_BGA1-IC,TBD   I172 @BASEBOARD_FAB2_LIB.BASEBOARD_FAB2(SCH_1):PAGE62
  J1A1   74   CK0P SCONN288_H44441004_PIP-SCONN,HA   I186 @BASEBOARD_FAB2_LIB.BASEBOARD_FAB2(SCH_1):PAGE87

M_M_CLK_DP<1> @BASEBOARD_FAB2_LIB.BASEBOARD_FAB2(SCH_1):M_M_CLK_DP(1)
  U2D1 DG54 DDR5_CLK_DP<1> SKX_EXT_B_BGA1-IC,TBD   I172 @BASEBOARD_FAB2_LIB.BASEBOARD_FAB2(SCH_1):PAGE62
  J1A1  218   CK1P SCONN288_H44441004_PIP-SCONN,HA   I186 @BASEBOARD_FAB2_LIB.BASEBOARD_FAB2(SCH_1):PAGE87

M_M_CLK_DP<2> @BASEBOARD_FAB2_LIB.BASEBOARD_FAB2(SCH_1):M_M_CLK_DP(2)
  U2D1 DJ56 DDR5_CLK_DP<2> SKX_EXT_B_BGA1-IC,TBD   I172 @BASEBOARD_FAB2_LIB.BASEBOARD_FAB2(SCH_1):PAGE62
  J9L1   74   CK0P SCONN288_H44441003_PIP-SCONN,HA   I111 @BASEBOARD_FAB2_LIB.BASEBOARD_FAB2(SCH_1):PAGE88

M_M_CLK_DP<3> @BASEBOARD_FAB2_LIB.BASEBOARD_FAB2(SCH_1):M_M_CLK_DP(3)
  U2D1 DG56 DDR5_CLK_DP<3> SKX_EXT_B_BGA1-IC,TBD   I172 @BASEBOARD_FAB2_LIB.BASEBOARD_FAB2(SCH_1):PAGE62
  J9L1  218   CK1P SCONN288_H44441003_PIP-SCONN,HA   I111 @BASEBOARD_FAB2_LIB.BASEBOARD_FAB2(SCH_1):PAGE88

M_M_CPU_VREF @BASEBOARD_FAB2_LIB.BASEBOARD_FAB2(SCH_1):M_M_CPU_VREF
  U2D1 CV61 DDR5_CAVREF SKX_EXT_B_BGA1-IC,TBD   I172 @BASEBOARD_FAB2_LIB.BASEBOARD_FAB2(SCH_1):PAGE55
  R9L3    1      A RES_0402-2,1.0%,1/16W,CHIP,G21A    I45 @BASEBOARD_FAB2_LIB.BASEBOARD_FAB2(SCH_1):PAGE100
  C9L3    1      A CAP_A_0402V-0.01UF,25V,10%,X7RA    I46 @BASEBOARD_FAB2_LIB.BASEBOARD_FAB2(SCH_1):PAGE100

M_M_CS_N<0> @BASEBOARD_FAB2_LIB.BASEBOARD_FAB2(SCH_1):M_M_CS_N(0)
  U2D1 DK51 DDR5_CS_N<0> SKX_EXT_B_BGA1-IC,TBD   I172 @BASEBOARD_FAB2_LIB.BASEBOARD_FAB2(SCH_1):PAGE62
  J1A1   84   S0_N SCONN288_H44441004_PIP-SCONN,HA   I186 @BASEBOARD_FAB2_LIB.BASEBOARD_FAB2(SCH_1):PAGE87

M_M_CS_N<1> @BASEBOARD_FAB2_LIB.BASEBOARD_FAB2(SCH_1):M_M_CS_N(1)
  U2D1 DF49 DDR5_CS_N<1> SKX_EXT_B_BGA1-IC,TBD   I172 @BASEBOARD_FAB2_LIB.BASEBOARD_FAB2(SCH_1):PAGE62
  J1A1   89   S1_N SCONN288_H44441004_PIP-SCONN,HA   I186 @BASEBOARD_FAB2_LIB.BASEBOARD_FAB2(SCH_1):PAGE87

M_M_CS_N<2> @BASEBOARD_FAB2_LIB.BASEBOARD_FAB2(SCH_1):M_M_CS_N(2)
  U2D1 DJ46 DDR5_CS_N<2> SKX_EXT_B_BGA1-IC,TBD   I172 @BASEBOARD_FAB2_LIB.BASEBOARD_FAB2(SCH_1):PAGE62
  J1A1   93 S2_N_C<0> SCONN288_H44441004_PIP-SCONN,HA   I186 @BASEBOARD_FAB2_LIB.BASEBOARD_FAB2(SCH_1):PAGE87

M_M_CS_N<3> @BASEBOARD_FAB2_LIB.BASEBOARD_FAB2(SCH_1):M_M_CS_N(3)
  U2D1 DG46 DDR5_CS_N<3> SKX_EXT_B_BGA1-IC,TBD   I172 @BASEBOARD_FAB2_LIB.BASEBOARD_FAB2(SCH_1):PAGE62
  J1A1  237 S3_N_C<1> SCONN288_H44441004_PIP-SCONN,HA   I186 @BASEBOARD_FAB2_LIB.BASEBOARD_FAB2(SCH_1):PAGE87

M_M_CS_N<4> @BASEBOARD_FAB2_LIB.BASEBOARD_FAB2(SCH_1):M_M_CS_N(4)
  U2D1 DF51 DDR5_CS_N<4> SKX_EXT_B_BGA1-IC,TBD   I172 @BASEBOARD_FAB2_LIB.BASEBOARD_FAB2(SCH_1):PAGE62
  J9L1   84   S0_N SCONN288_H44441003_PIP-SCONN,HA   I111 @BASEBOARD_FAB2_LIB.BASEBOARD_FAB2(SCH_1):PAGE88

M_M_CS_N<5> @BASEBOARD_FAB2_LIB.BASEBOARD_FAB2(SCH_1):M_M_CS_N(5)
  U2D1 DJ48 DDR5_CS_N<5> SKX_EXT_B_BGA1-IC,TBD   I172 @BASEBOARD_FAB2_LIB.BASEBOARD_FAB2(SCH_1):PAGE62
  J9L1   89   S1_N SCONN288_H44441003_PIP-SCONN,HA   I111 @BASEBOARD_FAB2_LIB.BASEBOARD_FAB2(SCH_1):PAGE88

M_M_CS_N<6> @BASEBOARD_FAB2_LIB.BASEBOARD_FAB2(SCH_1):M_M_CS_N(6)
  U2D1 DM45 DDR5_CS_N<6> SKX_EXT_B_BGA1-IC,TBD   I172 @BASEBOARD_FAB2_LIB.BASEBOARD_FAB2(SCH_1):PAGE62
  J9L1   93 S2_N_C<0> SCONN288_H44441003_PIP-SCONN,HA   I111 @BASEBOARD_FAB2_LIB.BASEBOARD_FAB2(SCH_1):PAGE88

M_M_CS_N<7> @BASEBOARD_FAB2_LIB.BASEBOARD_FAB2(SCH_1):M_M_CS_N(7)
  U2D1 DK45 DDR5_CS_N<7> SKX_EXT_B_BGA1-IC,TBD   I172 @BASEBOARD_FAB2_LIB.BASEBOARD_FAB2(SCH_1):PAGE62
  J9L1  237 S3_N_C<1> SCONN288_H44441003_PIP-SCONN,HA   I111 @BASEBOARD_FAB2_LIB.BASEBOARD_FAB2(SCH_1):PAGE88

M_M_DQ<0> @BASEBOARD_FAB2_LIB.BASEBOARD_FAB2(SCH_1):M_M_DQ(0)
  U2D1 CR74 DDR5_DQ<0> SKX_EXT_B_BGA1-IC,TBD   I172 @BASEBOARD_FAB2_LIB.BASEBOARD_FAB2(SCH_1):PAGE62
  J1A1  150  DQ<1> SCONN288_H44441004_PIP-SCONN,HA   I186 @BASEBOARD_FAB2_LIB.BASEBOARD_FAB2(SCH_1):PAGE87
  J9L1    5  DQ<0> SCONN288_H44441003_PIP-SCONN,HA   I111 @BASEBOARD_FAB2_LIB.BASEBOARD_FAB2(SCH_1):PAGE88

M_M_DQ<10> @BASEBOARD_FAB2_LIB.BASEBOARD_FAB2(SCH_1):M_M_DQ(10)
  U2D1 DH75 DDR5_DQ<10> SKX_EXT_B_BGA1-IC,TBD   I172 @BASEBOARD_FAB2_LIB.BASEBOARD_FAB2(SCH_1):PAGE62
  J1A1  168 DQ<11> SCONN288_H44441004_PIP-SCONN,HA   I186 @BASEBOARD_FAB2_LIB.BASEBOARD_FAB2(SCH_1):PAGE87
  J9L1   23 DQ<10> SCONN288_H44441003_PIP-SCONN,HA   I111 @BASEBOARD_FAB2_LIB.BASEBOARD_FAB2(SCH_1):PAGE88

M_M_DQ<11> @BASEBOARD_FAB2_LIB.BASEBOARD_FAB2(SCH_1):M_M_DQ(11)
  U2D1 DJ76 DDR5_DQ<11> SKX_EXT_B_BGA1-IC,TBD   I172 @BASEBOARD_FAB2_LIB.BASEBOARD_FAB2(SCH_1):PAGE62
  J1A1   23 DQ<10> SCONN288_H44441004_PIP-SCONN,HA   I186 @BASEBOARD_FAB2_LIB.BASEBOARD_FAB2(SCH_1):PAGE87
  J9L1  168 DQ<11> SCONN288_H44441003_PIP-SCONN,HA   I111 @BASEBOARD_FAB2_LIB.BASEBOARD_FAB2(SCH_1):PAGE88

M_M_DQ<12> @BASEBOARD_FAB2_LIB.BASEBOARD_FAB2(SCH_1):M_M_DQ(12)
  U2D1 DC74 DDR5_DQ<12> SKX_EXT_B_BGA1-IC,TBD   I172 @BASEBOARD_FAB2_LIB.BASEBOARD_FAB2(SCH_1):PAGE62
  J1A1  159 DQ<13> SCONN288_H44441004_PIP-SCONN,HA   I186 @BASEBOARD_FAB2_LIB.BASEBOARD_FAB2(SCH_1):PAGE87
  J9L1   14 DQ<12> SCONN288_H44441003_PIP-SCONN,HA   I111 @BASEBOARD_FAB2_LIB.BASEBOARD_FAB2(SCH_1):PAGE88

M_M_DQ<13> @BASEBOARD_FAB2_LIB.BASEBOARD_FAB2(SCH_1):M_M_DQ(13)
  U2D1 DB75 DDR5_DQ<13> SKX_EXT_B_BGA1-IC,TBD   I172 @BASEBOARD_FAB2_LIB.BASEBOARD_FAB2(SCH_1):PAGE62
  J1A1   14 DQ<12> SCONN288_H44441004_PIP-SCONN,HA   I186 @BASEBOARD_FAB2_LIB.BASEBOARD_FAB2(SCH_1):PAGE87
  J9L1  159 DQ<13> SCONN288_H44441003_PIP-SCONN,HA   I111 @BASEBOARD_FAB2_LIB.BASEBOARD_FAB2(SCH_1):PAGE88

M_M_DQ<14> @BASEBOARD_FAB2_LIB.BASEBOARD_FAB2(SCH_1):M_M_DQ(14)
  U2D1 DF77 DDR5_DQ<14> SKX_EXT_B_BGA1-IC,TBD   I172 @BASEBOARD_FAB2_LIB.BASEBOARD_FAB2(SCH_1):PAGE62
  J1A1  166 DQ<15> SCONN288_H44441004_PIP-SCONN,HA   I186 @BASEBOARD_FAB2_LIB.BASEBOARD_FAB2(SCH_1):PAGE87
  J9L1   21 DQ<14> SCONN288_H44441003_PIP-SCONN,HA   I111 @BASEBOARD_FAB2_LIB.BASEBOARD_FAB2(SCH_1):PAGE88

M_M_DQ<15> @BASEBOARD_FAB2_LIB.BASEBOARD_FAB2(SCH_1):M_M_DQ(15)
  U2D1 DH77 DDR5_DQ<15> SKX_EXT_B_BGA1-IC,TBD   I172 @BASEBOARD_FAB2_LIB.BASEBOARD_FAB2(SCH_1):PAGE62
  J1A1   21 DQ<14> SCONN288_H44441004_PIP-SCONN,HA   I186 @BASEBOARD_FAB2_LIB.BASEBOARD_FAB2(SCH_1):PAGE87
  J9L1  166 DQ<15> SCONN288_H44441003_PIP-SCONN,HA   I111 @BASEBOARD_FAB2_LIB.BASEBOARD_FAB2(SCH_1):PAGE88

M_M_DQ<16> @BASEBOARD_FAB2_LIB.BASEBOARD_FAB2(SCH_1):M_M_DQ(16)
  U2D1 DG70 DDR5_DQ<16> SKX_EXT_B_BGA1-IC,TBD   I172 @BASEBOARD_FAB2_LIB.BASEBOARD_FAB2(SCH_1):PAGE62
  J1A1  172 DQ<17> SCONN288_H44441004_PIP-SCONN,HA   I186 @BASEBOARD_FAB2_LIB.BASEBOARD_FAB2(SCH_1):PAGE87
  J9L1   27 DQ<16> SCONN288_H44441003_PIP-SCONN,HA   I111 @BASEBOARD_FAB2_LIB.BASEBOARD_FAB2(SCH_1):PAGE88

M_M_DQ<17> @BASEBOARD_FAB2_LIB.BASEBOARD_FAB2(SCH_1):M_M_DQ(17)
  U2D1 DJ72 DDR5_DQ<17> SKX_EXT_B_BGA1-IC,TBD   I172 @BASEBOARD_FAB2_LIB.BASEBOARD_FAB2(SCH_1):PAGE62
  J1A1   27 DQ<16> SCONN288_H44441004_PIP-SCONN,HA   I186 @BASEBOARD_FAB2_LIB.BASEBOARD_FAB2(SCH_1):PAGE87
  J9L1  172 DQ<17> SCONN288_H44441003_PIP-SCONN,HA   I111 @BASEBOARD_FAB2_LIB.BASEBOARD_FAB2(SCH_1):PAGE88

M_M_DQ<18> @BASEBOARD_FAB2_LIB.BASEBOARD_FAB2(SCH_1):M_M_DQ(18)
  U2D1 DM69 DDR5_DQ<18> SKX_EXT_B_BGA1-IC,TBD   I172 @BASEBOARD_FAB2_LIB.BASEBOARD_FAB2(SCH_1):PAGE62
  J1A1  179 DQ<19> SCONN288_H44441004_PIP-SCONN,HA   I186 @BASEBOARD_FAB2_LIB.BASEBOARD_FAB2(SCH_1):PAGE87
  J9L1   34 DQ<18> SCONN288_H44441003_PIP-SCONN,HA   I111 @BASEBOARD_FAB2_LIB.BASEBOARD_FAB2(SCH_1):PAGE88

M_M_DQ<19> @BASEBOARD_FAB2_LIB.BASEBOARD_FAB2(SCH_1):M_M_DQ(19)
  U2D1 DN70 DDR5_DQ<19> SKX_EXT_B_BGA1-IC,TBD   I172 @BASEBOARD_FAB2_LIB.BASEBOARD_FAB2(SCH_1):PAGE62
  J1A1   34 DQ<18> SCONN288_H44441004_PIP-SCONN,HA   I186 @BASEBOARD_FAB2_LIB.BASEBOARD_FAB2(SCH_1):PAGE87
  J9L1  179 DQ<19> SCONN288_H44441003_PIP-SCONN,HA   I111 @BASEBOARD_FAB2_LIB.BASEBOARD_FAB2(SCH_1):PAGE88

M_M_DQ<1> @BASEBOARD_FAB2_LIB.BASEBOARD_FAB2(SCH_1):M_M_DQ(1)
  U2D1 CN76 DDR5_DQ<1> SKX_EXT_B_BGA1-IC,TBD   I172 @BASEBOARD_FAB2_LIB.BASEBOARD_FAB2(SCH_1):PAGE62
  J1A1    5  DQ<0> SCONN288_H44441004_PIP-SCONN,HA   I186 @BASEBOARD_FAB2_LIB.BASEBOARD_FAB2(SCH_1):PAGE87
  J9L1  150  DQ<1> SCONN288_H44441003_PIP-SCONN,HA   I111 @BASEBOARD_FAB2_LIB.BASEBOARD_FAB2(SCH_1):PAGE88

M_M_DQ<20> @BASEBOARD_FAB2_LIB.BASEBOARD_FAB2(SCH_1):M_M_DQ(20)
  U2D1 DF71 DDR5_DQ<20> SKX_EXT_B_BGA1-IC,TBD   I172 @BASEBOARD_FAB2_LIB.BASEBOARD_FAB2(SCH_1):PAGE62
  J1A1  170 DQ<21> SCONN288_H44441004_PIP-SCONN,HA   I186 @BASEBOARD_FAB2_LIB.BASEBOARD_FAB2(SCH_1):PAGE87
  J9L1   25 DQ<20> SCONN288_H44441003_PIP-SCONN,HA   I111 @BASEBOARD_FAB2_LIB.BASEBOARD_FAB2(SCH_1):PAGE88

M_M_DQ<21> @BASEBOARD_FAB2_LIB.BASEBOARD_FAB2(SCH_1):M_M_DQ(21)
  U2D1 DG72 DDR5_DQ<21> SKX_EXT_B_BGA1-IC,TBD   I172 @BASEBOARD_FAB2_LIB.BASEBOARD_FAB2(SCH_1):PAGE62
  J1A1   25 DQ<20> SCONN288_H44441004_PIP-SCONN,HA   I186 @BASEBOARD_FAB2_LIB.BASEBOARD_FAB2(SCH_1):PAGE87
  J9L1  170 DQ<21> SCONN288_H44441003_PIP-SCONN,HA   I111 @BASEBOARD_FAB2_LIB.BASEBOARD_FAB2(SCH_1):PAGE88

M_M_DQ<22> @BASEBOARD_FAB2_LIB.BASEBOARD_FAB2(SCH_1):M_M_DQ(22)
  U2D1 DK69 DDR5_DQ<22> SKX_EXT_B_BGA1-IC,TBD   I172 @BASEBOARD_FAB2_LIB.BASEBOARD_FAB2(SCH_1):PAGE62
  J1A1  177 DQ<23> SCONN288_H44441004_PIP-SCONN,HA   I186 @BASEBOARD_FAB2_LIB.BASEBOARD_FAB2(SCH_1):PAGE87
  J9L1   32 DQ<22> SCONN288_H44441003_PIP-SCONN,HA   I111 @BASEBOARD_FAB2_LIB.BASEBOARD_FAB2(SCH_1):PAGE88

M_M_DQ<23> @BASEBOARD_FAB2_LIB.BASEBOARD_FAB2(SCH_1):M_M_DQ(23)
  U2D1 DM71 DDR5_DQ<23> SKX_EXT_B_BGA1-IC,TBD   I172 @BASEBOARD_FAB2_LIB.BASEBOARD_FAB2(SCH_1):PAGE62
  J1A1   32 DQ<22> SCONN288_H44441004_PIP-SCONN,HA   I186 @BASEBOARD_FAB2_LIB.BASEBOARD_FAB2(SCH_1):PAGE87
  J9L1  177 DQ<23> SCONN288_H44441003_PIP-SCONN,HA   I111 @BASEBOARD_FAB2_LIB.BASEBOARD_FAB2(SCH_1):PAGE88

M_M_DQ<24> @BASEBOARD_FAB2_LIB.BASEBOARD_FAB2(SCH_1):M_M_DQ(24)
  U2D1 CN66 DDR5_DQ<24> SKX_EXT_B_BGA1-IC,TBD   I172 @BASEBOARD_FAB2_LIB.BASEBOARD_FAB2(SCH_1):PAGE62
  J1A1  183 DQ<25> SCONN288_H44441004_PIP-SCONN,HA   I186 @BASEBOARD_FAB2_LIB.BASEBOARD_FAB2(SCH_1):PAGE87
  J9L1   38 DQ<24> SCONN288_H44441003_PIP-SCONN,HA   I111 @BASEBOARD_FAB2_LIB.BASEBOARD_FAB2(SCH_1):PAGE88

M_M_DQ<25> @BASEBOARD_FAB2_LIB.BASEBOARD_FAB2(SCH_1):M_M_DQ(25)
  U2D1 CU66 DDR5_DQ<25> SKX_EXT_B_BGA1-IC,TBD   I172 @BASEBOARD_FAB2_LIB.BASEBOARD_FAB2(SCH_1):PAGE62
  J1A1   38 DQ<24> SCONN288_H44441004_PIP-SCONN,HA   I186 @BASEBOARD_FAB2_LIB.BASEBOARD_FAB2(SCH_1):PAGE87
  J9L1  183 DQ<25> SCONN288_H44441003_PIP-SCONN,HA   I111 @BASEBOARD_FAB2_LIB.BASEBOARD_FAB2(SCH_1):PAGE88

M_M_DQ<26> @BASEBOARD_FAB2_LIB.BASEBOARD_FAB2(SCH_1):M_M_DQ(26)
  U2D1 CP63 DDR5_DQ<26> SKX_EXT_B_BGA1-IC,TBD   I172 @BASEBOARD_FAB2_LIB.BASEBOARD_FAB2(SCH_1):PAGE62
  J1A1  190 DQ<27> SCONN288_H44441004_PIP-SCONN,HA   I186 @BASEBOARD_FAB2_LIB.BASEBOARD_FAB2(SCH_1):PAGE87
  J9L1   45 DQ<26> SCONN288_H44441003_PIP-SCONN,HA   I111 @BASEBOARD_FAB2_LIB.BASEBOARD_FAB2(SCH_1):PAGE88

M_M_DQ<27> @BASEBOARD_FAB2_LIB.BASEBOARD_FAB2(SCH_1):M_M_DQ(27)
  U2D1 CT63 DDR5_DQ<27> SKX_EXT_B_BGA1-IC,TBD   I172 @BASEBOARD_FAB2_LIB.BASEBOARD_FAB2(SCH_1):PAGE62
  J1A1   45 DQ<26> SCONN288_H44441004_PIP-SCONN,HA   I186 @BASEBOARD_FAB2_LIB.BASEBOARD_FAB2(SCH_1):PAGE87
  J9L1  190 DQ<27> SCONN288_H44441003_PIP-SCONN,HA   I111 @BASEBOARD_FAB2_LIB.BASEBOARD_FAB2(SCH_1):PAGE88

M_M_DQ<28> @BASEBOARD_FAB2_LIB.BASEBOARD_FAB2(SCH_1):M_M_DQ(28)
  U2D1 CP67 DDR5_DQ<28> SKX_EXT_B_BGA1-IC,TBD   I172 @BASEBOARD_FAB2_LIB.BASEBOARD_FAB2(SCH_1):PAGE62
  J1A1  181 DQ<29> SCONN288_H44441004_PIP-SCONN,HA   I186 @BASEBOARD_FAB2_LIB.BASEBOARD_FAB2(SCH_1):PAGE87
  J9L1   36 DQ<28> SCONN288_H44441003_PIP-SCONN,HA   I111 @BASEBOARD_FAB2_LIB.BASEBOARD_FAB2(SCH_1):PAGE88

M_M_DQ<29> @BASEBOARD_FAB2_LIB.BASEBOARD_FAB2(SCH_1):M_M_DQ(29)
  U2D1 CT67 DDR5_DQ<29> SKX_EXT_B_BGA1-IC,TBD   I172 @BASEBOARD_FAB2_LIB.BASEBOARD_FAB2(SCH_1):PAGE62
  J1A1   36 DQ<28> SCONN288_H44441004_PIP-SCONN,HA   I186 @BASEBOARD_FAB2_LIB.BASEBOARD_FAB2(SCH_1):PAGE87
  J9L1  181 DQ<29> SCONN288_H44441003_PIP-SCONN,HA   I111 @BASEBOARD_FAB2_LIB.BASEBOARD_FAB2(SCH_1):PAGE88

M_M_DQ<2> @BASEBOARD_FAB2_LIB.BASEBOARD_FAB2(SCH_1):M_M_DQ(2)
  U2D1 CW76 DDR5_DQ<2> SKX_EXT_B_BGA1-IC,TBD   I172 @BASEBOARD_FAB2_LIB.BASEBOARD_FAB2(SCH_1):PAGE62
  J1A1  157  DQ<3> SCONN288_H44441004_PIP-SCONN,HA   I186 @BASEBOARD_FAB2_LIB.BASEBOARD_FAB2(SCH_1):PAGE87
  J9L1   12  DQ<2> SCONN288_H44441003_PIP-SCONN,HA   I111 @BASEBOARD_FAB2_LIB.BASEBOARD_FAB2(SCH_1):PAGE88

M_M_DQ<30> @BASEBOARD_FAB2_LIB.BASEBOARD_FAB2(SCH_1):M_M_DQ(30)
  U2D1 CN64 DDR5_DQ<30> SKX_EXT_B_BGA1-IC,TBD   I172 @BASEBOARD_FAB2_LIB.BASEBOARD_FAB2(SCH_1):PAGE62
  J1A1  188 DQ<31> SCONN288_H44441004_PIP-SCONN,HA   I186 @BASEBOARD_FAB2_LIB.BASEBOARD_FAB2(SCH_1):PAGE87
  J9L1   43 DQ<30> SCONN288_H44441003_PIP-SCONN,HA   I111 @BASEBOARD_FAB2_LIB.BASEBOARD_FAB2(SCH_1):PAGE88

M_M_DQ<31> @BASEBOARD_FAB2_LIB.BASEBOARD_FAB2(SCH_1):M_M_DQ(31)
  U2D1 CU64 DDR5_DQ<31> SKX_EXT_B_BGA1-IC,TBD   I172 @BASEBOARD_FAB2_LIB.BASEBOARD_FAB2(SCH_1):PAGE62
  J1A1   43 DQ<30> SCONN288_H44441004_PIP-SCONN,HA   I186 @BASEBOARD_FAB2_LIB.BASEBOARD_FAB2(SCH_1):PAGE87
  J9L1  188 DQ<31> SCONN288_H44441003_PIP-SCONN,HA   I111 @BASEBOARD_FAB2_LIB.BASEBOARD_FAB2(SCH_1):PAGE88

M_M_DQ<32> @BASEBOARD_FAB2_LIB.BASEBOARD_FAB2(SCH_1):M_M_DQ(32)
  U2D1 DD41 DDR5_DQ<32> SKX_EXT_B_BGA1-IC,TBD   I172 @BASEBOARD_FAB2_LIB.BASEBOARD_FAB2(SCH_1):PAGE62
  J1A1  242 DQ<33> SCONN288_H44441004_PIP-SCONN,HA   I186 @BASEBOARD_FAB2_LIB.BASEBOARD_FAB2(SCH_1):PAGE87
  J9L1   97 DQ<32> SCONN288_H44441003_PIP-SCONN,HA   I111 @BASEBOARD_FAB2_LIB.BASEBOARD_FAB2(SCH_1):PAGE88

M_M_DQ<33> @BASEBOARD_FAB2_LIB.BASEBOARD_FAB2(SCH_1):M_M_DQ(33)
  U2D1 DG42 DDR5_DQ<33> SKX_EXT_B_BGA1-IC,TBD   I172 @BASEBOARD_FAB2_LIB.BASEBOARD_FAB2(SCH_1):PAGE62
  J1A1   97 DQ<32> SCONN288_H44441004_PIP-SCONN,HA   I186 @BASEBOARD_FAB2_LIB.BASEBOARD_FAB2(SCH_1):PAGE87
  J9L1  242 DQ<33> SCONN288_H44441003_PIP-SCONN,HA   I111 @BASEBOARD_FAB2_LIB.BASEBOARD_FAB2(SCH_1):PAGE88

M_M_DQ<34> @BASEBOARD_FAB2_LIB.BASEBOARD_FAB2(SCH_1):M_M_DQ(34)
  U2D1 DE38 DDR5_DQ<34> SKX_EXT_B_BGA1-IC,TBD   I172 @BASEBOARD_FAB2_LIB.BASEBOARD_FAB2(SCH_1):PAGE62
  J1A1  249 DQ<35> SCONN288_H44441004_PIP-SCONN,HA   I186 @BASEBOARD_FAB2_LIB.BASEBOARD_FAB2(SCH_1):PAGE87
  J9L1  104 DQ<34> SCONN288_H44441003_PIP-SCONN,HA   I111 @BASEBOARD_FAB2_LIB.BASEBOARD_FAB2(SCH_1):PAGE88

M_M_DQ<35> @BASEBOARD_FAB2_LIB.BASEBOARD_FAB2(SCH_1):M_M_DQ(35)
  U2D1 DG38 DDR5_DQ<35> SKX_EXT_B_BGA1-IC,TBD   I172 @BASEBOARD_FAB2_LIB.BASEBOARD_FAB2(SCH_1):PAGE62
  J1A1  104 DQ<34> SCONN288_H44441004_PIP-SCONN,HA   I186 @BASEBOARD_FAB2_LIB.BASEBOARD_FAB2(SCH_1):PAGE87
  J9L1  249 DQ<35> SCONN288_H44441003_PIP-SCONN,HA   I111 @BASEBOARD_FAB2_LIB.BASEBOARD_FAB2(SCH_1):PAGE88

M_M_DQ<36> @BASEBOARD_FAB2_LIB.BASEBOARD_FAB2(SCH_1):M_M_DQ(36)
  U2D1 DA42 DDR5_DQ<36> SKX_EXT_B_BGA1-IC,TBD   I172 @BASEBOARD_FAB2_LIB.BASEBOARD_FAB2(SCH_1):PAGE62
  J1A1  240 DQ<37> SCONN288_H44441004_PIP-SCONN,HA   I186 @BASEBOARD_FAB2_LIB.BASEBOARD_FAB2(SCH_1):PAGE87
  J9L1   95 DQ<36> SCONN288_H44441003_PIP-SCONN,HA   I111 @BASEBOARD_FAB2_LIB.BASEBOARD_FAB2(SCH_1):PAGE88

M_M_DQ<37> @BASEBOARD_FAB2_LIB.BASEBOARD_FAB2(SCH_1):M_M_DQ(37)
  U2D1 DE42 DDR5_DQ<37> SKX_EXT_B_BGA1-IC,TBD   I172 @BASEBOARD_FAB2_LIB.BASEBOARD_FAB2(SCH_1):PAGE62
  J1A1   95 DQ<36> SCONN288_H44441004_PIP-SCONN,HA   I186 @BASEBOARD_FAB2_LIB.BASEBOARD_FAB2(SCH_1):PAGE87
  J9L1  240 DQ<37> SCONN288_H44441003_PIP-SCONN,HA   I111 @BASEBOARD_FAB2_LIB.BASEBOARD_FAB2(SCH_1):PAGE88

M_M_DQ<38> @BASEBOARD_FAB2_LIB.BASEBOARD_FAB2(SCH_1):M_M_DQ(38)
  U2D1 DD39 DDR5_DQ<38> SKX_EXT_B_BGA1-IC,TBD   I172 @BASEBOARD_FAB2_LIB.BASEBOARD_FAB2(SCH_1):PAGE62
  J1A1  247 DQ<39> SCONN288_H44441004_PIP-SCONN,HA   I186 @BASEBOARD_FAB2_LIB.BASEBOARD_FAB2(SCH_1):PAGE87
  J9L1  102 DQ<38> SCONN288_H44441003_PIP-SCONN,HA   I111 @BASEBOARD_FAB2_LIB.BASEBOARD_FAB2(SCH_1):PAGE88

M_M_DQ<39> @BASEBOARD_FAB2_LIB.BASEBOARD_FAB2(SCH_1):M_M_DQ(39)
  U2D1 DH39 DDR5_DQ<39> SKX_EXT_B_BGA1-IC,TBD   I172 @BASEBOARD_FAB2_LIB.BASEBOARD_FAB2(SCH_1):PAGE62
  J1A1  102 DQ<38> SCONN288_H44441004_PIP-SCONN,HA   I186 @BASEBOARD_FAB2_LIB.BASEBOARD_FAB2(SCH_1):PAGE87
  J9L1  247 DQ<39> SCONN288_H44441003_PIP-SCONN,HA   I111 @BASEBOARD_FAB2_LIB.BASEBOARD_FAB2(SCH_1):PAGE88

M_M_DQ<3> @BASEBOARD_FAB2_LIB.BASEBOARD_FAB2(SCH_1):M_M_DQ(3)
  U2D1 CV77 DDR5_DQ<3> SKX_EXT_B_BGA1-IC,TBD   I172 @BASEBOARD_FAB2_LIB.BASEBOARD_FAB2(SCH_1):PAGE62
  J1A1   12  DQ<2> SCONN288_H44441004_PIP-SCONN,HA   I186 @BASEBOARD_FAB2_LIB.BASEBOARD_FAB2(SCH_1):PAGE87
  J9L1  157  DQ<3> SCONN288_H44441003_PIP-SCONN,HA   I111 @BASEBOARD_FAB2_LIB.BASEBOARD_FAB2(SCH_1):PAGE88

M_M_DQ<40> @BASEBOARD_FAB2_LIB.BASEBOARD_FAB2(SCH_1):M_M_DQ(40)
  U2D1 DF33 DDR5_DQ<40> SKX_EXT_B_BGA1-IC,TBD   I172 @BASEBOARD_FAB2_LIB.BASEBOARD_FAB2(SCH_1):PAGE62
  J1A1  253 DQ<41> SCONN288_H44441004_PIP-SCONN,HA   I186 @BASEBOARD_FAB2_LIB.BASEBOARD_FAB2(SCH_1):PAGE87
  J9L1  108 DQ<40> SCONN288_H44441003_PIP-SCONN,HA   I111 @BASEBOARD_FAB2_LIB.BASEBOARD_FAB2(SCH_1):PAGE88

M_M_DQ<41> @BASEBOARD_FAB2_LIB.BASEBOARD_FAB2(SCH_1):M_M_DQ(41)
  U2D1 DK33 DDR5_DQ<41> SKX_EXT_B_BGA1-IC,TBD   I172 @BASEBOARD_FAB2_LIB.BASEBOARD_FAB2(SCH_1):PAGE62
  J1A1  108 DQ<40> SCONN288_H44441004_PIP-SCONN,HA   I186 @BASEBOARD_FAB2_LIB.BASEBOARD_FAB2(SCH_1):PAGE87
  J9L1  253 DQ<41> SCONN288_H44441003_PIP-SCONN,HA   I111 @BASEBOARD_FAB2_LIB.BASEBOARD_FAB2(SCH_1):PAGE88

M_M_DQ<42> @BASEBOARD_FAB2_LIB.BASEBOARD_FAB2(SCH_1):M_M_DQ(42)
  U2D1 DG30 DDR5_DQ<42> SKX_EXT_B_BGA1-IC,TBD   I172 @BASEBOARD_FAB2_LIB.BASEBOARD_FAB2(SCH_1):PAGE62
  J1A1  260 DQ<43> SCONN288_H44441004_PIP-SCONN,HA   I186 @BASEBOARD_FAB2_LIB.BASEBOARD_FAB2(SCH_1):PAGE87
  J9L1  115 DQ<42> SCONN288_H44441003_PIP-SCONN,HA   I111 @BASEBOARD_FAB2_LIB.BASEBOARD_FAB2(SCH_1):PAGE88

M_M_DQ<43> @BASEBOARD_FAB2_LIB.BASEBOARD_FAB2(SCH_1):M_M_DQ(43)
  U2D1 DJ30 DDR5_DQ<43> SKX_EXT_B_BGA1-IC,TBD   I172 @BASEBOARD_FAB2_LIB.BASEBOARD_FAB2(SCH_1):PAGE62
  J1A1  115 DQ<42> SCONN288_H44441004_PIP-SCONN,HA   I186 @BASEBOARD_FAB2_LIB.BASEBOARD_FAB2(SCH_1):PAGE87
  J9L1  260 DQ<43> SCONN288_H44441003_PIP-SCONN,HA   I111 @BASEBOARD_FAB2_LIB.BASEBOARD_FAB2(SCH_1):PAGE88

M_M_DQ<44> @BASEBOARD_FAB2_LIB.BASEBOARD_FAB2(SCH_1):M_M_DQ(44)
  U2D1 DG34 DDR5_DQ<44> SKX_EXT_B_BGA1-IC,TBD   I172 @BASEBOARD_FAB2_LIB.BASEBOARD_FAB2(SCH_1):PAGE62
  J1A1  251 DQ<45> SCONN288_H44441004_PIP-SCONN,HA   I186 @BASEBOARD_FAB2_LIB.BASEBOARD_FAB2(SCH_1):PAGE87
  J9L1  106 DQ<44> SCONN288_H44441003_PIP-SCONN,HA   I111 @BASEBOARD_FAB2_LIB.BASEBOARD_FAB2(SCH_1):PAGE88

M_M_DQ<45> @BASEBOARD_FAB2_LIB.BASEBOARD_FAB2(SCH_1):M_M_DQ(45)
  U2D1 DJ34 DDR5_DQ<45> SKX_EXT_B_BGA1-IC,TBD   I172 @BASEBOARD_FAB2_LIB.BASEBOARD_FAB2(SCH_1):PAGE62
  J1A1  106 DQ<44> SCONN288_H44441004_PIP-SCONN,HA   I186 @BASEBOARD_FAB2_LIB.BASEBOARD_FAB2(SCH_1):PAGE87
  J9L1  251 DQ<45> SCONN288_H44441003_PIP-SCONN,HA   I111 @BASEBOARD_FAB2_LIB.BASEBOARD_FAB2(SCH_1):PAGE88

M_M_DQ<46> @BASEBOARD_FAB2_LIB.BASEBOARD_FAB2(SCH_1):M_M_DQ(46)
  U2D1 DF31 DDR5_DQ<46> SKX_EXT_B_BGA1-IC,TBD   I172 @BASEBOARD_FAB2_LIB.BASEBOARD_FAB2(SCH_1):PAGE62
  J1A1  258 DQ<47> SCONN288_H44441004_PIP-SCONN,HA   I186 @BASEBOARD_FAB2_LIB.BASEBOARD_FAB2(SCH_1):PAGE87
  J9L1  113 DQ<46> SCONN288_H44441003_PIP-SCONN,HA   I111 @BASEBOARD_FAB2_LIB.BASEBOARD_FAB2(SCH_1):PAGE88

M_M_DQ<47> @BASEBOARD_FAB2_LIB.BASEBOARD_FAB2(SCH_1):M_M_DQ(47)
  U2D1 DK31 DDR5_DQ<47> SKX_EXT_B_BGA1-IC,TBD   I172 @BASEBOARD_FAB2_LIB.BASEBOARD_FAB2(SCH_1):PAGE62
  J1A1  113 DQ<46> SCONN288_H44441004_PIP-SCONN,HA   I186 @BASEBOARD_FAB2_LIB.BASEBOARD_FAB2(SCH_1):PAGE87
  J9L1  258 DQ<47> SCONN288_H44441003_PIP-SCONN,HA   I111 @BASEBOARD_FAB2_LIB.BASEBOARD_FAB2(SCH_1):PAGE88

M_M_DQ<48> @BASEBOARD_FAB2_LIB.BASEBOARD_FAB2(SCH_1):M_M_DQ(48)
  U2D1 CW36 DDR5_DQ<48> SKX_EXT_B_BGA1-IC,TBD   I172 @BASEBOARD_FAB2_LIB.BASEBOARD_FAB2(SCH_1):PAGE62
  J1A1  264 DQ<49> SCONN288_H44441004_PIP-SCONN,HA   I186 @BASEBOARD_FAB2_LIB.BASEBOARD_FAB2(SCH_1):PAGE87
  J9L1  119 DQ<48> SCONN288_H44441003_PIP-SCONN,HA   I111 @BASEBOARD_FAB2_LIB.BASEBOARD_FAB2(SCH_1):PAGE88

M_M_DQ<49> @BASEBOARD_FAB2_LIB.BASEBOARD_FAB2(SCH_1):M_M_DQ(49)
  U2D1 DC36 DDR5_DQ<49> SKX_EXT_B_BGA1-IC,TBD   I172 @BASEBOARD_FAB2_LIB.BASEBOARD_FAB2(SCH_1):PAGE62
  J1A1  119 DQ<48> SCONN288_H44441004_PIP-SCONN,HA   I186 @BASEBOARD_FAB2_LIB.BASEBOARD_FAB2(SCH_1):PAGE87
  J9L1  264 DQ<49> SCONN288_H44441003_PIP-SCONN,HA   I111 @BASEBOARD_FAB2_LIB.BASEBOARD_FAB2(SCH_1):PAGE88

M_M_DQ<4> @BASEBOARD_FAB2_LIB.BASEBOARD_FAB2(SCH_1):M_M_DQ(4)
  U2D1 CN74 DDR5_DQ<4> SKX_EXT_B_BGA1-IC,TBD   I172 @BASEBOARD_FAB2_LIB.BASEBOARD_FAB2(SCH_1):PAGE62
  J1A1  148  DQ<5> SCONN288_H44441004_PIP-SCONN,HA   I186 @BASEBOARD_FAB2_LIB.BASEBOARD_FAB2(SCH_1):PAGE87
  J9L1    3  DQ<4> SCONN288_H44441003_PIP-SCONN,HA   I111 @BASEBOARD_FAB2_LIB.BASEBOARD_FAB2(SCH_1):PAGE88

M_M_DQ<50> @BASEBOARD_FAB2_LIB.BASEBOARD_FAB2(SCH_1):M_M_DQ(50)
  U2D1 CY33 DDR5_DQ<50> SKX_EXT_B_BGA1-IC,TBD   I172 @BASEBOARD_FAB2_LIB.BASEBOARD_FAB2(SCH_1):PAGE62
  J1A1  271 DQ<51> SCONN288_H44441004_PIP-SCONN,HA   I186 @BASEBOARD_FAB2_LIB.BASEBOARD_FAB2(SCH_1):PAGE87
  J9L1  126 DQ<50> SCONN288_H44441003_PIP-SCONN,HA   I111 @BASEBOARD_FAB2_LIB.BASEBOARD_FAB2(SCH_1):PAGE88

M_M_DQ<51> @BASEBOARD_FAB2_LIB.BASEBOARD_FAB2(SCH_1):M_M_DQ(51)
  U2D1 DB33 DDR5_DQ<51> SKX_EXT_B_BGA1-IC,TBD   I172 @BASEBOARD_FAB2_LIB.BASEBOARD_FAB2(SCH_1):PAGE62
  J1A1  126 DQ<50> SCONN288_H44441004_PIP-SCONN,HA   I186 @BASEBOARD_FAB2_LIB.BASEBOARD_FAB2(SCH_1):PAGE87
  J9L1  271 DQ<51> SCONN288_H44441003_PIP-SCONN,HA   I111 @BASEBOARD_FAB2_LIB.BASEBOARD_FAB2(SCH_1):PAGE88

M_M_DQ<52> @BASEBOARD_FAB2_LIB.BASEBOARD_FAB2(SCH_1):M_M_DQ(52)
  U2D1 CY37 DDR5_DQ<52> SKX_EXT_B_BGA1-IC,TBD   I172 @BASEBOARD_FAB2_LIB.BASEBOARD_FAB2(SCH_1):PAGE62
  J1A1  262 DQ<53> SCONN288_H44441004_PIP-SCONN,HA   I186 @BASEBOARD_FAB2_LIB.BASEBOARD_FAB2(SCH_1):PAGE87
  J9L1  117 DQ<52> SCONN288_H44441003_PIP-SCONN,HA   I111 @BASEBOARD_FAB2_LIB.BASEBOARD_FAB2(SCH_1):PAGE88

M_M_DQ<53> @BASEBOARD_FAB2_LIB.BASEBOARD_FAB2(SCH_1):M_M_DQ(53)
  U2D1 DB37 DDR5_DQ<53> SKX_EXT_B_BGA1-IC,TBD   I172 @BASEBOARD_FAB2_LIB.BASEBOARD_FAB2(SCH_1):PAGE62
  J1A1  117 DQ<52> SCONN288_H44441004_PIP-SCONN,HA   I186 @BASEBOARD_FAB2_LIB.BASEBOARD_FAB2(SCH_1):PAGE87
  J9L1  262 DQ<53> SCONN288_H44441003_PIP-SCONN,HA   I111 @BASEBOARD_FAB2_LIB.BASEBOARD_FAB2(SCH_1):PAGE88

M_M_DQ<54> @BASEBOARD_FAB2_LIB.BASEBOARD_FAB2(SCH_1):M_M_DQ(54)
  U2D1 CW34 DDR5_DQ<54> SKX_EXT_B_BGA1-IC,TBD   I172 @BASEBOARD_FAB2_LIB.BASEBOARD_FAB2(SCH_1):PAGE62
  J1A1  269 DQ<55> SCONN288_H44441004_PIP-SCONN,HA   I186 @BASEBOARD_FAB2_LIB.BASEBOARD_FAB2(SCH_1):PAGE87
  J9L1  124 DQ<54> SCONN288_H44441003_PIP-SCONN,HA   I111 @BASEBOARD_FAB2_LIB.BASEBOARD_FAB2(SCH_1):PAGE88

M_M_DQ<55> @BASEBOARD_FAB2_LIB.BASEBOARD_FAB2(SCH_1):M_M_DQ(55)
  U2D1 DC34 DDR5_DQ<55> SKX_EXT_B_BGA1-IC,TBD   I172 @BASEBOARD_FAB2_LIB.BASEBOARD_FAB2(SCH_1):PAGE62
  J1A1  124 DQ<54> SCONN288_H44441004_PIP-SCONN,HA   I186 @BASEBOARD_FAB2_LIB.BASEBOARD_FAB2(SCH_1):PAGE87
  J9L1  269 DQ<55> SCONN288_H44441003_PIP-SCONN,HA   I111 @BASEBOARD_FAB2_LIB.BASEBOARD_FAB2(SCH_1):PAGE88

M_M_DQ<56> @BASEBOARD_FAB2_LIB.BASEBOARD_FAB2(SCH_1):M_M_DQ(56)
  U2D1 CW30 DDR5_DQ<56> SKX_EXT_B_BGA1-IC,TBD   I172 @BASEBOARD_FAB2_LIB.BASEBOARD_FAB2(SCH_1):PAGE62
  J1A1  275 DQ<57> SCONN288_H44441004_PIP-SCONN,HA   I186 @BASEBOARD_FAB2_LIB.BASEBOARD_FAB2(SCH_1):PAGE87
  J9L1  130 DQ<56> SCONN288_H44441003_PIP-SCONN,HA   I111 @BASEBOARD_FAB2_LIB.BASEBOARD_FAB2(SCH_1):PAGE88

M_M_DQ<57> @BASEBOARD_FAB2_LIB.BASEBOARD_FAB2(SCH_1):M_M_DQ(57)
  U2D1 DC30 DDR5_DQ<57> SKX_EXT_B_BGA1-IC,TBD   I172 @BASEBOARD_FAB2_LIB.BASEBOARD_FAB2(SCH_1):PAGE62
  J1A1  130 DQ<56> SCONN288_H44441004_PIP-SCONN,HA   I186 @BASEBOARD_FAB2_LIB.BASEBOARD_FAB2(SCH_1):PAGE87
  J9L1  275 DQ<57> SCONN288_H44441003_PIP-SCONN,HA   I111 @BASEBOARD_FAB2_LIB.BASEBOARD_FAB2(SCH_1):PAGE88

M_M_DQ<58> @BASEBOARD_FAB2_LIB.BASEBOARD_FAB2(SCH_1):M_M_DQ(58)
  U2D1 CY27 DDR5_DQ<58> SKX_EXT_B_BGA1-IC,TBD   I172 @BASEBOARD_FAB2_LIB.BASEBOARD_FAB2(SCH_1):PAGE62
  J1A1  282 DQ<59> SCONN288_H44441004_PIP-SCONN,HA   I186 @BASEBOARD_FAB2_LIB.BASEBOARD_FAB2(SCH_1):PAGE87
  J9L1  137 DQ<58> SCONN288_H44441003_PIP-SCONN,HA   I111 @BASEBOARD_FAB2_LIB.BASEBOARD_FAB2(SCH_1):PAGE88

M_M_DQ<59> @BASEBOARD_FAB2_LIB.BASEBOARD_FAB2(SCH_1):M_M_DQ(59)
  U2D1 DB27 DDR5_DQ<59> SKX_EXT_B_BGA1-IC,TBD   I172 @BASEBOARD_FAB2_LIB.BASEBOARD_FAB2(SCH_1):PAGE62
  J1A1  137 DQ<58> SCONN288_H44441004_PIP-SCONN,HA   I186 @BASEBOARD_FAB2_LIB.BASEBOARD_FAB2(SCH_1):PAGE87
  J9L1  282 DQ<59> SCONN288_H44441003_PIP-SCONN,HA   I111 @BASEBOARD_FAB2_LIB.BASEBOARD_FAB2(SCH_1):PAGE88

M_M_DQ<5> @BASEBOARD_FAB2_LIB.BASEBOARD_FAB2(SCH_1):M_M_DQ(5)
  U2D1 CM75 DDR5_DQ<5> SKX_EXT_B_BGA1-IC,TBD   I172 @BASEBOARD_FAB2_LIB.BASEBOARD_FAB2(SCH_1):PAGE62
  J1A1    3  DQ<4> SCONN288_H44441004_PIP-SCONN,HA   I186 @BASEBOARD_FAB2_LIB.BASEBOARD_FAB2(SCH_1):PAGE87
  J9L1  148  DQ<5> SCONN288_H44441003_PIP-SCONN,HA   I111 @BASEBOARD_FAB2_LIB.BASEBOARD_FAB2(SCH_1):PAGE88

M_M_DQ<60> @BASEBOARD_FAB2_LIB.BASEBOARD_FAB2(SCH_1):M_M_DQ(60)
  U2D1 CY31 DDR5_DQ<60> SKX_EXT_B_BGA1-IC,TBD   I172 @BASEBOARD_FAB2_LIB.BASEBOARD_FAB2(SCH_1):PAGE62
  J1A1  273 DQ<61> SCONN288_H44441004_PIP-SCONN,HA   I186 @BASEBOARD_FAB2_LIB.BASEBOARD_FAB2(SCH_1):PAGE87
  J9L1  128 DQ<60> SCONN288_H44441003_PIP-SCONN,HA   I111 @BASEBOARD_FAB2_LIB.BASEBOARD_FAB2(SCH_1):PAGE88

M_M_DQ<61> @BASEBOARD_FAB2_LIB.BASEBOARD_FAB2(SCH_1):M_M_DQ(61)
  U2D1 DB31 DDR5_DQ<61> SKX_EXT_B_BGA1-IC,TBD   I172 @BASEBOARD_FAB2_LIB.BASEBOARD_FAB2(SCH_1):PAGE62
  J1A1  128 DQ<60> SCONN288_H44441004_PIP-SCONN,HA   I186 @BASEBOARD_FAB2_LIB.BASEBOARD_FAB2(SCH_1):PAGE87
  J9L1  273 DQ<61> SCONN288_H44441003_PIP-SCONN,HA   I111 @BASEBOARD_FAB2_LIB.BASEBOARD_FAB2(SCH_1):PAGE88

M_M_DQ<62> @BASEBOARD_FAB2_LIB.BASEBOARD_FAB2(SCH_1):M_M_DQ(62)
  U2D1 CW28 DDR5_DQ<62> SKX_EXT_B_BGA1-IC,TBD   I172 @BASEBOARD_FAB2_LIB.BASEBOARD_FAB2(SCH_1):PAGE62
  J1A1  280 DQ<63> SCONN288_H44441004_PIP-SCONN,HA   I186 @BASEBOARD_FAB2_LIB.BASEBOARD_FAB2(SCH_1):PAGE87
  J9L1  135 DQ<62> SCONN288_H44441003_PIP-SCONN,HA   I111 @BASEBOARD_FAB2_LIB.BASEBOARD_FAB2(SCH_1):PAGE88

M_M_DQ<63> @BASEBOARD_FAB2_LIB.BASEBOARD_FAB2(SCH_1):M_M_DQ(63)
  U2D1 DC28 DDR5_DQ<63> SKX_EXT_B_BGA1-IC,TBD   I172 @BASEBOARD_FAB2_LIB.BASEBOARD_FAB2(SCH_1):PAGE62
  J1A1  135 DQ<62> SCONN288_H44441004_PIP-SCONN,HA   I186 @BASEBOARD_FAB2_LIB.BASEBOARD_FAB2(SCH_1):PAGE87
  J9L1  280 DQ<63> SCONN288_H44441003_PIP-SCONN,HA   I111 @BASEBOARD_FAB2_LIB.BASEBOARD_FAB2(SCH_1):PAGE88

M_M_DQ<6> @BASEBOARD_FAB2_LIB.BASEBOARD_FAB2(SCH_1):M_M_DQ(6)
  U2D1 CV75 DDR5_DQ<6> SKX_EXT_B_BGA1-IC,TBD   I172 @BASEBOARD_FAB2_LIB.BASEBOARD_FAB2(SCH_1):PAGE62
  J1A1  155  DQ<7> SCONN288_H44441004_PIP-SCONN,HA   I186 @BASEBOARD_FAB2_LIB.BASEBOARD_FAB2(SCH_1):PAGE87
  J9L1   10  DQ<6> SCONN288_H44441003_PIP-SCONN,HA   I111 @BASEBOARD_FAB2_LIB.BASEBOARD_FAB2(SCH_1):PAGE88

M_M_DQ<7> @BASEBOARD_FAB2_LIB.BASEBOARD_FAB2(SCH_1):M_M_DQ(7)
  U2D1 CT77 DDR5_DQ<7> SKX_EXT_B_BGA1-IC,TBD   I172 @BASEBOARD_FAB2_LIB.BASEBOARD_FAB2(SCH_1):PAGE62
  J1A1   10  DQ<6> SCONN288_H44441004_PIP-SCONN,HA   I186 @BASEBOARD_FAB2_LIB.BASEBOARD_FAB2(SCH_1):PAGE87
  J9L1  155  DQ<7> SCONN288_H44441003_PIP-SCONN,HA   I111 @BASEBOARD_FAB2_LIB.BASEBOARD_FAB2(SCH_1):PAGE88

M_M_DQ<8> @BASEBOARD_FAB2_LIB.BASEBOARD_FAB2(SCH_1):M_M_DQ(8)
  U2D1 DE74 DDR5_DQ<8> SKX_EXT_B_BGA1-IC,TBD   I172 @BASEBOARD_FAB2_LIB.BASEBOARD_FAB2(SCH_1):PAGE62
  J1A1  161  DQ<9> SCONN288_H44441004_PIP-SCONN,HA   I186 @BASEBOARD_FAB2_LIB.BASEBOARD_FAB2(SCH_1):PAGE87
  J9L1   16  DQ<8> SCONN288_H44441003_PIP-SCONN,HA   I111 @BASEBOARD_FAB2_LIB.BASEBOARD_FAB2(SCH_1):PAGE88

M_M_DQ<9> @BASEBOARD_FAB2_LIB.BASEBOARD_FAB2(SCH_1):M_M_DQ(9)
  U2D1 DC76 DDR5_DQ<9> SKX_EXT_B_BGA1-IC,TBD   I172 @BASEBOARD_FAB2_LIB.BASEBOARD_FAB2(SCH_1):PAGE62
  J1A1   16  DQ<8> SCONN288_H44441004_PIP-SCONN,HA   I186 @BASEBOARD_FAB2_LIB.BASEBOARD_FAB2(SCH_1):PAGE87
  J9L1  161  DQ<9> SCONN288_H44441003_PIP-SCONN,HA   I111 @BASEBOARD_FAB2_LIB.BASEBOARD_FAB2(SCH_1):PAGE88

M_M_DQS_DN<0> @BASEBOARD_FAB2_LIB.BASEBOARD_FAB2(SCH_1):M_M_DQS_DN(0)
  U2D1 CP77 DDR5_DQS_DN<0> SKX_EXT_B_BGA1-IC,TBD   I172 @BASEBOARD_FAB2_LIB.BASEBOARD_FAB2(SCH_1):PAGE62
  J1A1  152  DQS0N SCONN288_H44441004_PIP-SCONN,HA   I187 @BASEBOARD_FAB2_LIB.BASEBOARD_FAB2(SCH_1):PAGE87
  J9L1  152  DQS0N SCONN288_H44441003_PIP-SCONN,HA    I87 @BASEBOARD_FAB2_LIB.BASEBOARD_FAB2(SCH_1):PAGE88

M_M_DQS_DN<10> @BASEBOARD_FAB2_LIB.BASEBOARD_FAB2(SCH_1):M_M_DQS_DN(10)
  U2D1 DF75 DDR5_DQS_DN<10> SKX_EXT_B_BGA1-IC,TBD   I172 @BASEBOARD_FAB2_LIB.BASEBOARD_FAB2(SCH_1):PAGE62
  J1A1   19 DQS10N SCONN288_H44441004_PIP-SCONN,HA   I187 @BASEBOARD_FAB2_LIB.BASEBOARD_FAB2(SCH_1):PAGE87
  J9L1   19 DQS10N SCONN288_H44441003_PIP-SCONN,HA    I87 @BASEBOARD_FAB2_LIB.BASEBOARD_FAB2(SCH_1):PAGE88

M_M_DQS_DN<11> @BASEBOARD_FAB2_LIB.BASEBOARD_FAB2(SCH_1):M_M_DQS_DN(11)
  U2D1 DJ70 DDR5_DQS_DN<11> SKX_EXT_B_BGA1-IC,TBD   I172 @BASEBOARD_FAB2_LIB.BASEBOARD_FAB2(SCH_1):PAGE62
  J1A1   30 DQS11N SCONN288_H44441004_PIP-SCONN,HA   I187 @BASEBOARD_FAB2_LIB.BASEBOARD_FAB2(SCH_1):PAGE87
  J9L1   30 DQS11N SCONN288_H44441003_PIP-SCONN,HA    I87 @BASEBOARD_FAB2_LIB.BASEBOARD_FAB2(SCH_1):PAGE88

M_M_DQS_DN<12> @BASEBOARD_FAB2_LIB.BASEBOARD_FAB2(SCH_1):M_M_DQS_DN(12)
  U2D1 CP65 DDR5_DQS_DN<12> SKX_EXT_B_BGA1-IC,TBD   I172 @BASEBOARD_FAB2_LIB.BASEBOARD_FAB2(SCH_1):PAGE62
  J1A1   41 DQS12N SCONN288_H44441004_PIP-SCONN,HA   I187 @BASEBOARD_FAB2_LIB.BASEBOARD_FAB2(SCH_1):PAGE87
  J9L1   41 DQS12N SCONN288_H44441003_PIP-SCONN,HA    I87 @BASEBOARD_FAB2_LIB.BASEBOARD_FAB2(SCH_1):PAGE88

M_M_DQS_DN<13> @BASEBOARD_FAB2_LIB.BASEBOARD_FAB2(SCH_1):M_M_DQS_DN(13)
  U2D1 DE40 DDR5_DQS_DN<13> SKX_EXT_B_BGA1-IC,TBD   I172 @BASEBOARD_FAB2_LIB.BASEBOARD_FAB2(SCH_1):PAGE62
  J1A1  100 DQS13N SCONN288_H44441004_PIP-SCONN,HA   I187 @BASEBOARD_FAB2_LIB.BASEBOARD_FAB2(SCH_1):PAGE87
  J9L1  100 DQS13N SCONN288_H44441003_PIP-SCONN,HA    I87 @BASEBOARD_FAB2_LIB.BASEBOARD_FAB2(SCH_1):PAGE88

M_M_DQS_DN<14> @BASEBOARD_FAB2_LIB.BASEBOARD_FAB2(SCH_1):M_M_DQS_DN(14)
  U2D1 DG32 DDR5_DQS_DN<14> SKX_EXT_B_BGA1-IC,TBD   I172 @BASEBOARD_FAB2_LIB.BASEBOARD_FAB2(SCH_1):PAGE62
  J1A1  111 DQS14N SCONN288_H44441004_PIP-SCONN,HA   I187 @BASEBOARD_FAB2_LIB.BASEBOARD_FAB2(SCH_1):PAGE87
  J9L1  111 DQS14N SCONN288_H44441003_PIP-SCONN,HA    I87 @BASEBOARD_FAB2_LIB.BASEBOARD_FAB2(SCH_1):PAGE88

M_M_DQS_DN<15> @BASEBOARD_FAB2_LIB.BASEBOARD_FAB2(SCH_1):M_M_DQS_DN(15)
  U2D1 CY35 DDR5_DQS_DN<15> SKX_EXT_B_BGA1-IC,TBD   I172 @BASEBOARD_FAB2_LIB.BASEBOARD_FAB2(SCH_1):PAGE62
  J1A1  122 DQS15N SCONN288_H44441004_PIP-SCONN,HA   I187 @BASEBOARD_FAB2_LIB.BASEBOARD_FAB2(SCH_1):PAGE87
  J9L1  122 DQS15N SCONN288_H44441003_PIP-SCONN,HA    I87 @BASEBOARD_FAB2_LIB.BASEBOARD_FAB2(SCH_1):PAGE88

M_M_DQS_DN<16> @BASEBOARD_FAB2_LIB.BASEBOARD_FAB2(SCH_1):M_M_DQS_DN(16)
  U2D1 CY29 DDR5_DQS_DN<16> SKX_EXT_B_BGA1-IC,TBD   I172 @BASEBOARD_FAB2_LIB.BASEBOARD_FAB2(SCH_1):PAGE62
  J1A1  133 DQS16N SCONN288_H44441004_PIP-SCONN,HA   I187 @BASEBOARD_FAB2_LIB.BASEBOARD_FAB2(SCH_1):PAGE87
  J9L1  133 DQS16N SCONN288_H44441003_PIP-SCONN,HA    I87 @BASEBOARD_FAB2_LIB.BASEBOARD_FAB2(SCH_1):PAGE88

M_M_DQS_DN<17> @BASEBOARD_FAB2_LIB.BASEBOARD_FAB2(SCH_1):M_M_DQS_DN(17)
  U2D1 CJ70 DDR5_DQS_DN<17> SKX_EXT_B_BGA1-IC,TBD   I172 @BASEBOARD_FAB2_LIB.BASEBOARD_FAB2(SCH_1):PAGE62
  J1A1   52 DQS17N SCONN288_H44441004_PIP-SCONN,HA   I187 @BASEBOARD_FAB2_LIB.BASEBOARD_FAB2(SCH_1):PAGE87
  J9L1   52 DQS17N SCONN288_H44441003_PIP-SCONN,HA    I87 @BASEBOARD_FAB2_LIB.BASEBOARD_FAB2(SCH_1):PAGE88

M_M_DQS_DN<1> @BASEBOARD_FAB2_LIB.BASEBOARD_FAB2(SCH_1):M_M_DQS_DN(1)
  U2D1 DD77 DDR5_DQS_DN<1> SKX_EXT_B_BGA1-IC,TBD   I172 @BASEBOARD_FAB2_LIB.BASEBOARD_FAB2(SCH_1):PAGE62
  J1A1  163  DQS1N SCONN288_H44441004_PIP-SCONN,HA   I187 @BASEBOARD_FAB2_LIB.BASEBOARD_FAB2(SCH_1):PAGE87
  J9L1  163  DQS1N SCONN288_H44441003_PIP-SCONN,HA    I87 @BASEBOARD_FAB2_LIB.BASEBOARD_FAB2(SCH_1):PAGE88

M_M_DQS_DN<2> @BASEBOARD_FAB2_LIB.BASEBOARD_FAB2(SCH_1):M_M_DQS_DN(2)
  U2D1 DL72 DDR5_DQS_DN<2> SKX_EXT_B_BGA1-IC,TBD   I172 @BASEBOARD_FAB2_LIB.BASEBOARD_FAB2(SCH_1):PAGE62
  J1A1  174  DQS2N SCONN288_H44441004_PIP-SCONN,HA   I187 @BASEBOARD_FAB2_LIB.BASEBOARD_FAB2(SCH_1):PAGE87
  J9L1  174  DQS2N SCONN288_H44441003_PIP-SCONN,HA    I87 @BASEBOARD_FAB2_LIB.BASEBOARD_FAB2(SCH_1):PAGE88

M_M_DQS_DN<3> @BASEBOARD_FAB2_LIB.BASEBOARD_FAB2(SCH_1):M_M_DQS_DN(3)
  U2D1 CV65 DDR5_DQS_DN<3> SKX_EXT_B_BGA1-IC,TBD   I172 @BASEBOARD_FAB2_LIB.BASEBOARD_FAB2(SCH_1):PAGE62
  J1A1  185  DQS3N SCONN288_H44441004_PIP-SCONN,HA   I187 @BASEBOARD_FAB2_LIB.BASEBOARD_FAB2(SCH_1):PAGE87
  J9L1  185  DQS3N SCONN288_H44441003_PIP-SCONN,HA    I87 @BASEBOARD_FAB2_LIB.BASEBOARD_FAB2(SCH_1):PAGE88

M_M_DQS_DN<4> @BASEBOARD_FAB2_LIB.BASEBOARD_FAB2(SCH_1):M_M_DQS_DN(4)
  U2D1 DG40 DDR5_DQS_DN<4> SKX_EXT_B_BGA1-IC,TBD   I172 @BASEBOARD_FAB2_LIB.BASEBOARD_FAB2(SCH_1):PAGE62
  J1A1  244  DQS4N SCONN288_H44441004_PIP-SCONN,HA   I187 @BASEBOARD_FAB2_LIB.BASEBOARD_FAB2(SCH_1):PAGE87
  J9L1  244  DQS4N SCONN288_H44441003_PIP-SCONN,HA    I87 @BASEBOARD_FAB2_LIB.BASEBOARD_FAB2(SCH_1):PAGE88

M_M_DQS_DN<5> @BASEBOARD_FAB2_LIB.BASEBOARD_FAB2(SCH_1):M_M_DQS_DN(5)
  U2D1 DL32 DDR5_DQS_DN<5> SKX_EXT_B_BGA1-IC,TBD   I172 @BASEBOARD_FAB2_LIB.BASEBOARD_FAB2(SCH_1):PAGE62
  J1A1  255  DQS5N SCONN288_H44441004_PIP-SCONN,HA   I187 @BASEBOARD_FAB2_LIB.BASEBOARD_FAB2(SCH_1):PAGE87
  J9L1  255  DQS5N SCONN288_H44441003_PIP-SCONN,HA    I87 @BASEBOARD_FAB2_LIB.BASEBOARD_FAB2(SCH_1):PAGE88

M_M_DQS_DN<6> @BASEBOARD_FAB2_LIB.BASEBOARD_FAB2(SCH_1):M_M_DQS_DN(6)
  U2D1 DD35 DDR5_DQS_DN<6> SKX_EXT_B_BGA1-IC,TBD   I172 @BASEBOARD_FAB2_LIB.BASEBOARD_FAB2(SCH_1):PAGE62
  J1A1  266  DQS6N SCONN288_H44441004_PIP-SCONN,HA   I187 @BASEBOARD_FAB2_LIB.BASEBOARD_FAB2(SCH_1):PAGE87
  J9L1  266  DQS6N SCONN288_H44441003_PIP-SCONN,HA    I87 @BASEBOARD_FAB2_LIB.BASEBOARD_FAB2(SCH_1):PAGE88

M_M_DQS_DN<7> @BASEBOARD_FAB2_LIB.BASEBOARD_FAB2(SCH_1):M_M_DQS_DN(7)
  U2D1 DD29 DDR5_DQS_DN<7> SKX_EXT_B_BGA1-IC,TBD   I172 @BASEBOARD_FAB2_LIB.BASEBOARD_FAB2(SCH_1):PAGE62
  J1A1  277  DQS7N SCONN288_H44441004_PIP-SCONN,HA   I187 @BASEBOARD_FAB2_LIB.BASEBOARD_FAB2(SCH_1):PAGE87
  J9L1  277  DQS7N SCONN288_H44441003_PIP-SCONN,HA    I87 @BASEBOARD_FAB2_LIB.BASEBOARD_FAB2(SCH_1):PAGE88

M_M_DQS_DN<8> @BASEBOARD_FAB2_LIB.BASEBOARD_FAB2(SCH_1):M_M_DQS_DN(8)
  U2D1 CN70 DDR5_DQS_DN<8> SKX_EXT_B_BGA1-IC,TBD   I172 @BASEBOARD_FAB2_LIB.BASEBOARD_FAB2(SCH_1):PAGE62
  J1A1  196  DQS8N SCONN288_H44441004_PIP-SCONN,HA   I187 @BASEBOARD_FAB2_LIB.BASEBOARD_FAB2(SCH_1):PAGE87
  J9L1  196  DQS8N SCONN288_H44441003_PIP-SCONN,HA    I87 @BASEBOARD_FAB2_LIB.BASEBOARD_FAB2(SCH_1):PAGE88

M_M_DQS_DN<9> @BASEBOARD_FAB2_LIB.BASEBOARD_FAB2(SCH_1):M_M_DQS_DN(9)
  U2D1 CT75 DDR5_DQS_DN<9> SKX_EXT_B_BGA1-IC,TBD   I172 @BASEBOARD_FAB2_LIB.BASEBOARD_FAB2(SCH_1):PAGE62
  J1A1    8  DQS9N SCONN288_H44441004_PIP-SCONN,HA   I187 @BASEBOARD_FAB2_LIB.BASEBOARD_FAB2(SCH_1):PAGE87
  J9L1    8  DQS9N SCONN288_H44441003_PIP-SCONN,HA    I87 @BASEBOARD_FAB2_LIB.BASEBOARD_FAB2(SCH_1):PAGE88

M_M_DQS_DP<0> @BASEBOARD_FAB2_LIB.BASEBOARD_FAB2(SCH_1):M_M_DQS_DP(0)
  U2D1 CR76 DDR5_DQS_DP<0> SKX_EXT_B_BGA1-IC,TBD   I172 @BASEBOARD_FAB2_LIB.BASEBOARD_FAB2(SCH_1):PAGE62
  J1A1  153  DQS0P SCONN288_H44441004_PIP-SCONN,HA   I187 @BASEBOARD_FAB2_LIB.BASEBOARD_FAB2(SCH_1):PAGE87
  J9L1  153  DQS0P SCONN288_H44441003_PIP-SCONN,HA    I87 @BASEBOARD_FAB2_LIB.BASEBOARD_FAB2(SCH_1):PAGE88

M_M_DQS_DP<10> @BASEBOARD_FAB2_LIB.BASEBOARD_FAB2(SCH_1):M_M_DQS_DP(10)
  U2D1 DG74 DDR5_DQS_DP<10> SKX_EXT_B_BGA1-IC,TBD   I172 @BASEBOARD_FAB2_LIB.BASEBOARD_FAB2(SCH_1):PAGE62
  J1A1   18 DQS10P SCONN288_H44441004_PIP-SCONN,HA   I187 @BASEBOARD_FAB2_LIB.BASEBOARD_FAB2(SCH_1):PAGE87
  J9L1   18 DQS10P SCONN288_H44441003_PIP-SCONN,HA    I87 @BASEBOARD_FAB2_LIB.BASEBOARD_FAB2(SCH_1):PAGE88

M_M_DQS_DP<11> @BASEBOARD_FAB2_LIB.BASEBOARD_FAB2(SCH_1):M_M_DQS_DP(11)
  U2D1 DH69 DDR5_DQS_DP<11> SKX_EXT_B_BGA1-IC,TBD   I172 @BASEBOARD_FAB2_LIB.BASEBOARD_FAB2(SCH_1):PAGE62
  J1A1   29 DQS11P SCONN288_H44441004_PIP-SCONN,HA   I187 @BASEBOARD_FAB2_LIB.BASEBOARD_FAB2(SCH_1):PAGE87
  J9L1   29 DQS11P SCONN288_H44441003_PIP-SCONN,HA    I87 @BASEBOARD_FAB2_LIB.BASEBOARD_FAB2(SCH_1):PAGE88

M_M_DQS_DP<12> @BASEBOARD_FAB2_LIB.BASEBOARD_FAB2(SCH_1):M_M_DQS_DP(12)
  U2D1 CM65 DDR5_DQS_DP<12> SKX_EXT_B_BGA1-IC,TBD   I172 @BASEBOARD_FAB2_LIB.BASEBOARD_FAB2(SCH_1):PAGE62
  J1A1   40 DQS12P SCONN288_H44441004_PIP-SCONN,HA   I187 @BASEBOARD_FAB2_LIB.BASEBOARD_FAB2(SCH_1):PAGE87
  J9L1   40 DQS12P SCONN288_H44441003_PIP-SCONN,HA    I87 @BASEBOARD_FAB2_LIB.BASEBOARD_FAB2(SCH_1):PAGE88

M_M_DQS_DP<13> @BASEBOARD_FAB2_LIB.BASEBOARD_FAB2(SCH_1):M_M_DQS_DP(13)
  U2D1 DC40 DDR5_DQS_DP<13> SKX_EXT_B_BGA1-IC,TBD   I172 @BASEBOARD_FAB2_LIB.BASEBOARD_FAB2(SCH_1):PAGE62
  J1A1   99 DQS13P SCONN288_H44441004_PIP-SCONN,HA   I187 @BASEBOARD_FAB2_LIB.BASEBOARD_FAB2(SCH_1):PAGE87
  J9L1   99 DQS13P SCONN288_H44441003_PIP-SCONN,HA    I87 @BASEBOARD_FAB2_LIB.BASEBOARD_FAB2(SCH_1):PAGE88

M_M_DQS_DP<14> @BASEBOARD_FAB2_LIB.BASEBOARD_FAB2(SCH_1):M_M_DQS_DP(14)
  U2D1 DE32 DDR5_DQS_DP<14> SKX_EXT_B_BGA1-IC,TBD   I172 @BASEBOARD_FAB2_LIB.BASEBOARD_FAB2(SCH_1):PAGE62
  J1A1  110 DQS14P SCONN288_H44441004_PIP-SCONN,HA   I187 @BASEBOARD_FAB2_LIB.BASEBOARD_FAB2(SCH_1):PAGE87
  J9L1  110 DQS14P SCONN288_H44441003_PIP-SCONN,HA    I87 @BASEBOARD_FAB2_LIB.BASEBOARD_FAB2(SCH_1):PAGE88

M_M_DQS_DP<15> @BASEBOARD_FAB2_LIB.BASEBOARD_FAB2(SCH_1):M_M_DQS_DP(15)
  U2D1 CV35 DDR5_DQS_DP<15> SKX_EXT_B_BGA1-IC,TBD   I172 @BASEBOARD_FAB2_LIB.BASEBOARD_FAB2(SCH_1):PAGE62
  J1A1  121 DQS15P SCONN288_H44441004_PIP-SCONN,HA   I187 @BASEBOARD_FAB2_LIB.BASEBOARD_FAB2(SCH_1):PAGE87
  J9L1  121 DQS15P SCONN288_H44441003_PIP-SCONN,HA    I87 @BASEBOARD_FAB2_LIB.BASEBOARD_FAB2(SCH_1):PAGE88

M_M_DQS_DP<16> @BASEBOARD_FAB2_LIB.BASEBOARD_FAB2(SCH_1):M_M_DQS_DP(16)
  U2D1 CV29 DDR5_DQS_DP<16> SKX_EXT_B_BGA1-IC,TBD   I172 @BASEBOARD_FAB2_LIB.BASEBOARD_FAB2(SCH_1):PAGE62
  J1A1  132 DQS16P SCONN288_H44441004_PIP-SCONN,HA   I187 @BASEBOARD_FAB2_LIB.BASEBOARD_FAB2(SCH_1):PAGE87
  J9L1  132 DQS16P SCONN288_H44441003_PIP-SCONN,HA    I87 @BASEBOARD_FAB2_LIB.BASEBOARD_FAB2(SCH_1):PAGE88

M_M_DQS_DP<17> @BASEBOARD_FAB2_LIB.BASEBOARD_FAB2(SCH_1):M_M_DQS_DP(17)
  U2D1 CG70 DDR5_DQS_DP<17> SKX_EXT_B_BGA1-IC,TBD   I172 @BASEBOARD_FAB2_LIB.BASEBOARD_FAB2(SCH_1):PAGE62
  J1A1   51 DQS17P SCONN288_H44441004_PIP-SCONN,HA   I187 @BASEBOARD_FAB2_LIB.BASEBOARD_FAB2(SCH_1):PAGE87
  J9L1   51 DQS17P SCONN288_H44441003_PIP-SCONN,HA    I87 @BASEBOARD_FAB2_LIB.BASEBOARD_FAB2(SCH_1):PAGE88

M_M_DQS_DP<1> @BASEBOARD_FAB2_LIB.BASEBOARD_FAB2(SCH_1):M_M_DQS_DP(1)
  U2D1 DE76 DDR5_DQS_DP<1> SKX_EXT_B_BGA1-IC,TBD   I172 @BASEBOARD_FAB2_LIB.BASEBOARD_FAB2(SCH_1):PAGE62
  J1A1  164  DQS1P SCONN288_H44441004_PIP-SCONN,HA   I187 @BASEBOARD_FAB2_LIB.BASEBOARD_FAB2(SCH_1):PAGE87
  J9L1  164  DQS1P SCONN288_H44441003_PIP-SCONN,HA    I87 @BASEBOARD_FAB2_LIB.BASEBOARD_FAB2(SCH_1):PAGE88

M_M_DQS_DP<2> @BASEBOARD_FAB2_LIB.BASEBOARD_FAB2(SCH_1):M_M_DQS_DP(2)
  U2D1 DK71 DDR5_DQS_DP<2> SKX_EXT_B_BGA1-IC,TBD   I172 @BASEBOARD_FAB2_LIB.BASEBOARD_FAB2(SCH_1):PAGE62
  J1A1  175  DQS2P SCONN288_H44441004_PIP-SCONN,HA   I187 @BASEBOARD_FAB2_LIB.BASEBOARD_FAB2(SCH_1):PAGE87
  J9L1  175  DQS2P SCONN288_H44441003_PIP-SCONN,HA    I87 @BASEBOARD_FAB2_LIB.BASEBOARD_FAB2(SCH_1):PAGE88

M_M_DQS_DP<3> @BASEBOARD_FAB2_LIB.BASEBOARD_FAB2(SCH_1):M_M_DQS_DP(3)
  U2D1 CT65 DDR5_DQS_DP<3> SKX_EXT_B_BGA1-IC,TBD   I172 @BASEBOARD_FAB2_LIB.BASEBOARD_FAB2(SCH_1):PAGE62
  J1A1  186  DQS3P SCONN288_H44441004_PIP-SCONN,HA   I187 @BASEBOARD_FAB2_LIB.BASEBOARD_FAB2(SCH_1):PAGE87
  J9L1  186  DQS3P SCONN288_H44441003_PIP-SCONN,HA    I87 @BASEBOARD_FAB2_LIB.BASEBOARD_FAB2(SCH_1):PAGE88

M_M_DQS_DP<4> @BASEBOARD_FAB2_LIB.BASEBOARD_FAB2(SCH_1):M_M_DQS_DP(4)
  U2D1 DJ40 DDR5_DQS_DP<4> SKX_EXT_B_BGA1-IC,TBD   I172 @BASEBOARD_FAB2_LIB.BASEBOARD_FAB2(SCH_1):PAGE62
  J1A1  245  DQS4P SCONN288_H44441004_PIP-SCONN,HA   I187 @BASEBOARD_FAB2_LIB.BASEBOARD_FAB2(SCH_1):PAGE87
  J9L1  245  DQS4P SCONN288_H44441003_PIP-SCONN,HA    I87 @BASEBOARD_FAB2_LIB.BASEBOARD_FAB2(SCH_1):PAGE88

M_M_DQS_DP<5> @BASEBOARD_FAB2_LIB.BASEBOARD_FAB2(SCH_1):M_M_DQS_DP(5)
  U2D1 DJ32 DDR5_DQS_DP<5> SKX_EXT_B_BGA1-IC,TBD   I172 @BASEBOARD_FAB2_LIB.BASEBOARD_FAB2(SCH_1):PAGE62
  J1A1  256  DQS5P SCONN288_H44441004_PIP-SCONN,HA   I187 @BASEBOARD_FAB2_LIB.BASEBOARD_FAB2(SCH_1):PAGE87
  J9L1  256  DQS5P SCONN288_H44441003_PIP-SCONN,HA    I87 @BASEBOARD_FAB2_LIB.BASEBOARD_FAB2(SCH_1):PAGE88

M_M_DQS_DP<6> @BASEBOARD_FAB2_LIB.BASEBOARD_FAB2(SCH_1):M_M_DQS_DP(6)
  U2D1 DB35 DDR5_DQS_DP<6> SKX_EXT_B_BGA1-IC,TBD   I172 @BASEBOARD_FAB2_LIB.BASEBOARD_FAB2(SCH_1):PAGE62
  J1A1  267  DQS6P SCONN288_H44441004_PIP-SCONN,HA   I187 @BASEBOARD_FAB2_LIB.BASEBOARD_FAB2(SCH_1):PAGE87
  J9L1  267  DQS6P SCONN288_H44441003_PIP-SCONN,HA    I87 @BASEBOARD_FAB2_LIB.BASEBOARD_FAB2(SCH_1):PAGE88

M_M_DQS_DP<7> @BASEBOARD_FAB2_LIB.BASEBOARD_FAB2(SCH_1):M_M_DQS_DP(7)
  U2D1 DB29 DDR5_DQS_DP<7> SKX_EXT_B_BGA1-IC,TBD   I172 @BASEBOARD_FAB2_LIB.BASEBOARD_FAB2(SCH_1):PAGE62
  J1A1  278  DQS7P SCONN288_H44441004_PIP-SCONN,HA   I187 @BASEBOARD_FAB2_LIB.BASEBOARD_FAB2(SCH_1):PAGE87
  J9L1  278  DQS7P SCONN288_H44441003_PIP-SCONN,HA    I87 @BASEBOARD_FAB2_LIB.BASEBOARD_FAB2(SCH_1):PAGE88

M_M_DQS_DP<8> @BASEBOARD_FAB2_LIB.BASEBOARD_FAB2(SCH_1):M_M_DQS_DP(8)
  U2D1 CL70 DDR5_DQS_DP<8> SKX_EXT_B_BGA1-IC,TBD   I172 @BASEBOARD_FAB2_LIB.BASEBOARD_FAB2(SCH_1):PAGE62
  J1A1  197  DQS8P SCONN288_H44441004_PIP-SCONN,HA   I187 @BASEBOARD_FAB2_LIB.BASEBOARD_FAB2(SCH_1):PAGE87
  J9L1  197  DQS8P SCONN288_H44441003_PIP-SCONN,HA    I87 @BASEBOARD_FAB2_LIB.BASEBOARD_FAB2(SCH_1):PAGE88

M_M_DQS_DP<9> @BASEBOARD_FAB2_LIB.BASEBOARD_FAB2(SCH_1):M_M_DQS_DP(9)
  U2D1 CU74 DDR5_DQS_DP<9> SKX_EXT_B_BGA1-IC,TBD   I172 @BASEBOARD_FAB2_LIB.BASEBOARD_FAB2(SCH_1):PAGE62
  J1A1    7  DQS9P SCONN288_H44441004_PIP-SCONN,HA   I187 @BASEBOARD_FAB2_LIB.BASEBOARD_FAB2(SCH_1):PAGE87
  J9L1    7  DQS9P SCONN288_H44441003_PIP-SCONN,HA    I87 @BASEBOARD_FAB2_LIB.BASEBOARD_FAB2(SCH_1):PAGE88

M_M_ECC<0> @BASEBOARD_FAB2_LIB.BASEBOARD_FAB2(SCH_1):M_M_ECC(0)
  U2D1 CH71 DDR5_ECC<0> SKX_EXT_B_BGA1-IC,TBD   I172 @BASEBOARD_FAB2_LIB.BASEBOARD_FAB2(SCH_1):PAGE62
  J1A1  194  CB<1> SCONN288_H44441004_PIP-SCONN,HA   I186 @BASEBOARD_FAB2_LIB.BASEBOARD_FAB2(SCH_1):PAGE87
  J9L1   49  CB<0> SCONN288_H44441003_PIP-SCONN,HA   I111 @BASEBOARD_FAB2_LIB.BASEBOARD_FAB2(SCH_1):PAGE88

M_M_ECC<1> @BASEBOARD_FAB2_LIB.BASEBOARD_FAB2(SCH_1):M_M_ECC(1)
  U2D1 CM71 DDR5_ECC<1> SKX_EXT_B_BGA1-IC,TBD   I172 @BASEBOARD_FAB2_LIB.BASEBOARD_FAB2(SCH_1):PAGE62
  J1A1   49  CB<0> SCONN288_H44441004_PIP-SCONN,HA   I186 @BASEBOARD_FAB2_LIB.BASEBOARD_FAB2(SCH_1):PAGE87
  J9L1  194  CB<1> SCONN288_H44441003_PIP-SCONN,HA   I111 @BASEBOARD_FAB2_LIB.BASEBOARD_FAB2(SCH_1):PAGE88

M_M_ECC<2> @BASEBOARD_FAB2_LIB.BASEBOARD_FAB2(SCH_1):M_M_ECC(2)
  U2D1 CJ68 DDR5_ECC<2> SKX_EXT_B_BGA1-IC,TBD   I172 @BASEBOARD_FAB2_LIB.BASEBOARD_FAB2(SCH_1):PAGE62
  J1A1  201  CB<3> SCONN288_H44441004_PIP-SCONN,HA   I186 @BASEBOARD_FAB2_LIB.BASEBOARD_FAB2(SCH_1):PAGE87
  J9L1   56  CB<2> SCONN288_H44441003_PIP-SCONN,HA   I111 @BASEBOARD_FAB2_LIB.BASEBOARD_FAB2(SCH_1):PAGE88

M_M_ECC<3> @BASEBOARD_FAB2_LIB.BASEBOARD_FAB2(SCH_1):M_M_ECC(3)
  U2D1 CL68 DDR5_ECC<3> SKX_EXT_B_BGA1-IC,TBD   I172 @BASEBOARD_FAB2_LIB.BASEBOARD_FAB2(SCH_1):PAGE62
  J1A1   56  CB<2> SCONN288_H44441004_PIP-SCONN,HA   I186 @BASEBOARD_FAB2_LIB.BASEBOARD_FAB2(SCH_1):PAGE87
  J9L1  201  CB<3> SCONN288_H44441003_PIP-SCONN,HA   I111 @BASEBOARD_FAB2_LIB.BASEBOARD_FAB2(SCH_1):PAGE88

M_M_ECC<4> @BASEBOARD_FAB2_LIB.BASEBOARD_FAB2(SCH_1):M_M_ECC(4)
  U2D1 CJ72 DDR5_ECC<4> SKX_EXT_B_BGA1-IC,TBD   I172 @BASEBOARD_FAB2_LIB.BASEBOARD_FAB2(SCH_1):PAGE62
  J1A1  192  CB<5> SCONN288_H44441004_PIP-SCONN,HA   I186 @BASEBOARD_FAB2_LIB.BASEBOARD_FAB2(SCH_1):PAGE87
  J9L1   47  CB<4> SCONN288_H44441003_PIP-SCONN,HA   I111 @BASEBOARD_FAB2_LIB.BASEBOARD_FAB2(SCH_1):PAGE88

M_M_ECC<5> @BASEBOARD_FAB2_LIB.BASEBOARD_FAB2(SCH_1):M_M_ECC(5)
  U2D1 CL72 DDR5_ECC<5> SKX_EXT_B_BGA1-IC,TBD   I172 @BASEBOARD_FAB2_LIB.BASEBOARD_FAB2(SCH_1):PAGE62
  J1A1   47  CB<4> SCONN288_H44441004_PIP-SCONN,HA   I186 @BASEBOARD_FAB2_LIB.BASEBOARD_FAB2(SCH_1):PAGE87
  J9L1  192  CB<5> SCONN288_H44441003_PIP-SCONN,HA   I111 @BASEBOARD_FAB2_LIB.BASEBOARD_FAB2(SCH_1):PAGE88

M_M_ECC<6> @BASEBOARD_FAB2_LIB.BASEBOARD_FAB2(SCH_1):M_M_ECC(6)
  U2D1 CH69 DDR5_ECC<6> SKX_EXT_B_BGA1-IC,TBD   I172 @BASEBOARD_FAB2_LIB.BASEBOARD_FAB2(SCH_1):PAGE62
  J1A1  199  CB<7> SCONN288_H44441004_PIP-SCONN,HA   I186 @BASEBOARD_FAB2_LIB.BASEBOARD_FAB2(SCH_1):PAGE87
  J9L1   54  CB<6> SCONN288_H44441003_PIP-SCONN,HA   I111 @BASEBOARD_FAB2_LIB.BASEBOARD_FAB2(SCH_1):PAGE88

M_M_ECC<7> @BASEBOARD_FAB2_LIB.BASEBOARD_FAB2(SCH_1):M_M_ECC(7)
  U2D1 CM69 DDR5_ECC<7> SKX_EXT_B_BGA1-IC,TBD   I172 @BASEBOARD_FAB2_LIB.BASEBOARD_FAB2(SCH_1):PAGE62
  J1A1   54  CB<6> SCONN288_H44441004_PIP-SCONN,HA   I186 @BASEBOARD_FAB2_LIB.BASEBOARD_FAB2(SCH_1):PAGE87
  J9L1  199  CB<7> SCONN288_H44441003_PIP-SCONN,HA   I111 @BASEBOARD_FAB2_LIB.BASEBOARD_FAB2(SCH_1):PAGE88

M_M_MA<0> @BASEBOARD_FAB2_LIB.BASEBOARD_FAB2(SCH_1):M_M_MA(0)
  U2D1 DF53 DDR5_MA<0> SKX_EXT_B_BGA1-IC,TBD   I172 @BASEBOARD_FAB2_LIB.BASEBOARD_FAB2(SCH_1):PAGE62
  J1A1   79     A0 SCONN288_H44441004_PIP-SCONN,HA   I186 @BASEBOARD_FAB2_LIB.BASEBOARD_FAB2(SCH_1):PAGE87
  J9L1   79     A0 SCONN288_H44441003_PIP-SCONN,HA   I111 @BASEBOARD_FAB2_LIB.BASEBOARD_FAB2(SCH_1):PAGE88

M_M_MA<10> @BASEBOARD_FAB2_LIB.BASEBOARD_FAB2(SCH_1):M_M_MA(10)
  U2D1 DD55 DDR5_MA<10> SKX_EXT_B_BGA1-IC,TBD   I172 @BASEBOARD_FAB2_LIB.BASEBOARD_FAB2(SCH_1):PAGE62
  J1A1  225    A10 SCONN288_H44441004_PIP-SCONN,HA   I186 @BASEBOARD_FAB2_LIB.BASEBOARD_FAB2(SCH_1):PAGE87
  J9L1  225    A10 SCONN288_H44441003_PIP-SCONN,HA   I111 @BASEBOARD_FAB2_LIB.BASEBOARD_FAB2(SCH_1):PAGE88

M_M_MA<11> @BASEBOARD_FAB2_LIB.BASEBOARD_FAB2(SCH_1):M_M_MA(11)
  U2D1 DA60 DDR5_MA<11> SKX_EXT_B_BGA1-IC,TBD   I172 @BASEBOARD_FAB2_LIB.BASEBOARD_FAB2(SCH_1):PAGE62
  J1A1  210    A11 SCONN288_H44441004_PIP-SCONN,HA   I186 @BASEBOARD_FAB2_LIB.BASEBOARD_FAB2(SCH_1):PAGE87
  J9L1  210    A11 SCONN288_H44441003_PIP-SCONN,HA   I111 @BASEBOARD_FAB2_LIB.BASEBOARD_FAB2(SCH_1):PAGE88

M_M_MA<12> @BASEBOARD_FAB2_LIB.BASEBOARD_FAB2(SCH_1):M_M_MA(12)
  U2D1 DG60 DDR5_MA<12> SKX_EXT_B_BGA1-IC,TBD   I172 @BASEBOARD_FAB2_LIB.BASEBOARD_FAB2(SCH_1):PAGE62
  J1A1   65    A12 SCONN288_H44441004_PIP-SCONN,HA   I186 @BASEBOARD_FAB2_LIB.BASEBOARD_FAB2(SCH_1):PAGE87
  J9L1   65    A12 SCONN288_H44441003_PIP-SCONN,HA   I111 @BASEBOARD_FAB2_LIB.BASEBOARD_FAB2(SCH_1):PAGE88

M_M_MA<13> @BASEBOARD_FAB2_LIB.BASEBOARD_FAB2(SCH_1):M_M_MA(13)
  U2D1 DD53 DDR5_MA<13> SKX_EXT_B_BGA1-IC,TBD   I172 @BASEBOARD_FAB2_LIB.BASEBOARD_FAB2(SCH_1):PAGE62
  J1A1  232    A13 SCONN288_H44441004_PIP-SCONN,HA   I186 @BASEBOARD_FAB2_LIB.BASEBOARD_FAB2(SCH_1):PAGE87
  J9L1  232    A13 SCONN288_H44441003_PIP-SCONN,HA   I111 @BASEBOARD_FAB2_LIB.BASEBOARD_FAB2(SCH_1):PAGE88

M_M_MA<14> @BASEBOARD_FAB2_LIB.BASEBOARD_FAB2(SCH_1):M_M_MA(14)
  U2D1 DJ50 DDR5_MA<14> SKX_EXT_B_BGA1-IC,TBD   I172 @BASEBOARD_FAB2_LIB.BASEBOARD_FAB2(SCH_1):PAGE62
  J1A1  228 A14_WE_N SCONN288_H44441004_PIP-SCONN,HA   I186 @BASEBOARD_FAB2_LIB.BASEBOARD_FAB2(SCH_1):PAGE87
  J9L1  228 A14_WE_N SCONN288_H44441003_PIP-SCONN,HA   I111 @BASEBOARD_FAB2_LIB.BASEBOARD_FAB2(SCH_1):PAGE88

M_M_MA<15> @BASEBOARD_FAB2_LIB.BASEBOARD_FAB2(SCH_1):M_M_MA(15)
  U2D1 DC54 DDR5_MA<15> SKX_EXT_B_BGA1-IC,TBD   I172 @BASEBOARD_FAB2_LIB.BASEBOARD_FAB2(SCH_1):PAGE62
  J1A1   86 A15_CAS_N SCONN288_H44441004_PIP-SCONN,HA   I186 @BASEBOARD_FAB2_LIB.BASEBOARD_FAB2(SCH_1):PAGE87
  J9L1   86 A15_CAS_N SCONN288_H44441003_PIP-SCONN,HA   I111 @BASEBOARD_FAB2_LIB.BASEBOARD_FAB2(SCH_1):PAGE88

M_M_MA<16> @BASEBOARD_FAB2_LIB.BASEBOARD_FAB2(SCH_1):M_M_MA(16)
  U2D1 DG52 DDR5_MA<16> SKX_EXT_B_BGA1-IC,TBD   I172 @BASEBOARD_FAB2_LIB.BASEBOARD_FAB2(SCH_1):PAGE62
  J1A1   82 A16_RAS_N SCONN288_H44441004_PIP-SCONN,HA   I186 @BASEBOARD_FAB2_LIB.BASEBOARD_FAB2(SCH_1):PAGE87
  J9L1   82 A16_RAS_N SCONN288_H44441003_PIP-SCONN,HA   I111 @BASEBOARD_FAB2_LIB.BASEBOARD_FAB2(SCH_1):PAGE88

M_M_MA<17> @BASEBOARD_FAB2_LIB.BASEBOARD_FAB2(SCH_1):M_M_MA(17)
  U2D1 DE46 DDR5_MA<17> SKX_EXT_B_BGA1-IC,TBD   I172 @BASEBOARD_FAB2_LIB.BASEBOARD_FAB2(SCH_1):PAGE62
  J1A1  234    A17 SCONN288_H44441004_PIP-SCONN,HA   I186 @BASEBOARD_FAB2_LIB.BASEBOARD_FAB2(SCH_1):PAGE87
  J9L1  234    A17 SCONN288_H44441003_PIP-SCONN,HA   I111 @BASEBOARD_FAB2_LIB.BASEBOARD_FAB2(SCH_1):PAGE88

M_M_MA<1> @BASEBOARD_FAB2_LIB.BASEBOARD_FAB2(SCH_1):M_M_MA(1)
  U2D1 DC58 DDR5_MA<1> SKX_EXT_B_BGA1-IC,TBD   I172 @BASEBOARD_FAB2_LIB.BASEBOARD_FAB2(SCH_1):PAGE62
  J1A1   72     A1 SCONN288_H44441004_PIP-SCONN,HA   I186 @BASEBOARD_FAB2_LIB.BASEBOARD_FAB2(SCH_1):PAGE87
  J9L1   72     A1 SCONN288_H44441003_PIP-SCONN,HA   I111 @BASEBOARD_FAB2_LIB.BASEBOARD_FAB2(SCH_1):PAGE88

M_M_MA<2> @BASEBOARD_FAB2_LIB.BASEBOARD_FAB2(SCH_1):M_M_MA(2)
  U2D1 DD57 DDR5_MA<2> SKX_EXT_B_BGA1-IC,TBD   I172 @BASEBOARD_FAB2_LIB.BASEBOARD_FAB2(SCH_1):PAGE62
  J1A1  216     A2 SCONN288_H44441004_PIP-SCONN,HA   I186 @BASEBOARD_FAB2_LIB.BASEBOARD_FAB2(SCH_1):PAGE87
  J9L1  216     A2 SCONN288_H44441003_PIP-SCONN,HA   I111 @BASEBOARD_FAB2_LIB.BASEBOARD_FAB2(SCH_1):PAGE88

M_M_MA<3> @BASEBOARD_FAB2_LIB.BASEBOARD_FAB2(SCH_1):M_M_MA(3)
  U2D1 DG58 DDR5_MA<3> SKX_EXT_B_BGA1-IC,TBD   I172 @BASEBOARD_FAB2_LIB.BASEBOARD_FAB2(SCH_1):PAGE62
  J1A1   71     A3 SCONN288_H44441004_PIP-SCONN,HA   I186 @BASEBOARD_FAB2_LIB.BASEBOARD_FAB2(SCH_1):PAGE87
  J9L1   71     A3 SCONN288_H44441003_PIP-SCONN,HA   I111 @BASEBOARD_FAB2_LIB.BASEBOARD_FAB2(SCH_1):PAGE88

M_M_MA<4> @BASEBOARD_FAB2_LIB.BASEBOARD_FAB2(SCH_1):M_M_MA(4)
  U2D1 DJ58 DDR5_MA<4> SKX_EXT_B_BGA1-IC,TBD   I172 @BASEBOARD_FAB2_LIB.BASEBOARD_FAB2(SCH_1):PAGE62
  J1A1  214     A4 SCONN288_H44441004_PIP-SCONN,HA   I186 @BASEBOARD_FAB2_LIB.BASEBOARD_FAB2(SCH_1):PAGE87
  J9L1  214     A4 SCONN288_H44441003_PIP-SCONN,HA   I111 @BASEBOARD_FAB2_LIB.BASEBOARD_FAB2(SCH_1):PAGE88

M_M_MA<5> @BASEBOARD_FAB2_LIB.BASEBOARD_FAB2(SCH_1):M_M_MA(5)
  U2D1 DF59 DDR5_MA<5> SKX_EXT_B_BGA1-IC,TBD   I172 @BASEBOARD_FAB2_LIB.BASEBOARD_FAB2(SCH_1):PAGE62
  J1A1  213     A5 SCONN288_H44441004_PIP-SCONN,HA   I186 @BASEBOARD_FAB2_LIB.BASEBOARD_FAB2(SCH_1):PAGE87
  J9L1  213     A5 SCONN288_H44441003_PIP-SCONN,HA   I111 @BASEBOARD_FAB2_LIB.BASEBOARD_FAB2(SCH_1):PAGE88

M_M_MA<6> @BASEBOARD_FAB2_LIB.BASEBOARD_FAB2(SCH_1):M_M_MA(6)
  U2D1 DK59 DDR5_MA<6> SKX_EXT_B_BGA1-IC,TBD   I172 @BASEBOARD_FAB2_LIB.BASEBOARD_FAB2(SCH_1):PAGE62
  J1A1   69     A6 SCONN288_H44441004_PIP-SCONN,HA   I186 @BASEBOARD_FAB2_LIB.BASEBOARD_FAB2(SCH_1):PAGE87
  J9L1   69     A6 SCONN288_H44441003_PIP-SCONN,HA   I111 @BASEBOARD_FAB2_LIB.BASEBOARD_FAB2(SCH_1):PAGE88

M_M_MA<7> @BASEBOARD_FAB2_LIB.BASEBOARD_FAB2(SCH_1):M_M_MA(7)
  U2D1 DC60 DDR5_MA<7> SKX_EXT_B_BGA1-IC,TBD   I172 @BASEBOARD_FAB2_LIB.BASEBOARD_FAB2(SCH_1):PAGE62
  J1A1  211     A7 SCONN288_H44441004_PIP-SCONN,HA   I186 @BASEBOARD_FAB2_LIB.BASEBOARD_FAB2(SCH_1):PAGE87
  J9L1  211     A7 SCONN288_H44441003_PIP-SCONN,HA   I111 @BASEBOARD_FAB2_LIB.BASEBOARD_FAB2(SCH_1):PAGE88

M_M_MA<8> @BASEBOARD_FAB2_LIB.BASEBOARD_FAB2(SCH_1):M_M_MA(8)
  U2D1 DD59 DDR5_MA<8> SKX_EXT_B_BGA1-IC,TBD   I172 @BASEBOARD_FAB2_LIB.BASEBOARD_FAB2(SCH_1):PAGE62
  J1A1   68     A8 SCONN288_H44441004_PIP-SCONN,HA   I186 @BASEBOARD_FAB2_LIB.BASEBOARD_FAB2(SCH_1):PAGE87
  J9L1   68     A8 SCONN288_H44441003_PIP-SCONN,HA   I111 @BASEBOARD_FAB2_LIB.BASEBOARD_FAB2(SCH_1):PAGE88

M_M_MA<9> @BASEBOARD_FAB2_LIB.BASEBOARD_FAB2(SCH_1):M_M_MA(9)
  U2D1 DA58 DDR5_MA<9> SKX_EXT_B_BGA1-IC,TBD   I172 @BASEBOARD_FAB2_LIB.BASEBOARD_FAB2(SCH_1):PAGE62
  J1A1   66     A9 SCONN288_H44441004_PIP-SCONN,HA   I186 @BASEBOARD_FAB2_LIB.BASEBOARD_FAB2(SCH_1):PAGE87
  J9L1   66     A9 SCONN288_H44441003_PIP-SCONN,HA   I111 @BASEBOARD_FAB2_LIB.BASEBOARD_FAB2(SCH_1):PAGE88

M_M_ODT<0> @BASEBOARD_FAB2_LIB.BASEBOARD_FAB2(SCH_1):M_M_ODT(0)
  U2D1 DG50 DDR5_ODT<0> SKX_EXT_B_BGA1-IC,TBD   I172 @BASEBOARD_FAB2_LIB.BASEBOARD_FAB2(SCH_1):PAGE62
  J1A1   87 ODT<0> SCONN288_H44441004_PIP-SCONN,HA   I186 @BASEBOARD_FAB2_LIB.BASEBOARD_FAB2(SCH_1):PAGE87

M_M_ODT<1> @BASEBOARD_FAB2_LIB.BASEBOARD_FAB2(SCH_1):M_M_ODT(1)
  U2D1 DG48 DDR5_ODT<1> SKX_EXT_B_BGA1-IC,TBD   I172 @BASEBOARD_FAB2_LIB.BASEBOARD_FAB2(SCH_1):PAGE62
  J1A1   91 ODT<1> SCONN288_H44441004_PIP-SCONN,HA   I186 @BASEBOARD_FAB2_LIB.BASEBOARD_FAB2(SCH_1):PAGE87

M_M_ODT<2> @BASEBOARD_FAB2_LIB.BASEBOARD_FAB2(SCH_1):M_M_ODT(2)
  U2D1 DK49 DDR5_ODT<2> SKX_EXT_B_BGA1-IC,TBD   I172 @BASEBOARD_FAB2_LIB.BASEBOARD_FAB2(SCH_1):PAGE62
  J9L1   87 ODT<0> SCONN288_H44441003_PIP-SCONN,HA   I111 @BASEBOARD_FAB2_LIB.BASEBOARD_FAB2(SCH_1):PAGE88

M_M_ODT<3> @BASEBOARD_FAB2_LIB.BASEBOARD_FAB2(SCH_1):M_M_ODT(3)
  U2D1 DF47 DDR5_ODT<3> SKX_EXT_B_BGA1-IC,TBD   I172 @BASEBOARD_FAB2_LIB.BASEBOARD_FAB2(SCH_1):PAGE62
  J9L1   91 ODT<1> SCONN288_H44441003_PIP-SCONN,HA   I111 @BASEBOARD_FAB2_LIB.BASEBOARD_FAB2(SCH_1):PAGE88

M_M_PAR @BASEBOARD_FAB2_LIB.BASEBOARD_FAB2(SCH_1):M_M_PAR
  U2D1 DK53 DDR5_PAR SKX_EXT_B_BGA1-IC,TBD   I172 @BASEBOARD_FAB2_LIB.BASEBOARD_FAB2(SCH_1):PAGE62
  J1A1  222    PAR SCONN288_H44441004_PIP-SCONN,HA   I186 @BASEBOARD_FAB2_LIB.BASEBOARD_FAB2(SCH_1):PAGE87
  J9L1  222    PAR SCONN288_H44441003_PIP-SCONN,HA   I111 @BASEBOARD_FAB2_LIB.BASEBOARD_FAB2(SCH_1):PAGE88

M_M_VREF @BASEBOARD_FAB2_LIB.BASEBOARD_FAB2(SCH_1):M_M_VREF
  C1A5    1      A CAP_A_0402V-0.01UF,25V,10%,X7RA   I178 @BASEBOARD_FAB2_LIB.BASEBOARD_FAB2(SCH_1):PAGE87
  J1A1  146 VREFCA SCONN288_H44441004_PIP-SCONN,HA   I186 @BASEBOARD_FAB2_LIB.BASEBOARD_FAB2(SCH_1):PAGE87
  J9L1  146 VREFCA SCONN288_H44441003_PIP-SCONN,HA   I111 @BASEBOARD_FAB2_LIB.BASEBOARD_FAB2(SCH_1):PAGE88
  C9L1    1      A CAP_A_0402V-0.01UF,25V,10%,X7RA   I177 @BASEBOARD_FAB2_LIB.BASEBOARD_FAB2(SCH_1):PAGE88
  R9L2    2      B RES_0402-1.00K,1%,1/16W,CHIP,GA    I38 @BASEBOARD_FAB2_LIB.BASEBOARD_FAB2(SCH_1):PAGE100
  R9L1    1      A RES_0402-1.00K,1%,1/16W,CHIP,GA    I40 @BASEBOARD_FAB2_LIB.BASEBOARD_FAB2(SCH_1):PAGE100
  R9L3    2      B RES_0402-2,1.0%,1/16W,CHIP,G21A    I45 @BASEBOARD_FAB2_LIB.BASEBOARD_FAB2(SCH_1):PAGE100

NC         NC
 CONX8    2      2 SMC-CONN60A-22-GP_CONN-G7-SMC-A    I48 @BASEBOARD_FAB2_LIB.BASEBOARD_FAB2(SCH_1):PAGE245
 CONX8   60     60 SMC-CONN60A-22-GP_CONN-G7-SMC-A    I48 @BASEBOARD_FAB2_LIB.BASEBOARD_FAB2(SCH_1):PAGE245
 U25W5   T7  NC#T7 H5AN4G6NAFR-TFC-GP_MEMORY-G2-HA     I1 @BASEBOARD_FAB2_LIB.BASEBOARD_FAB2(SCH_1):PAGE149
  U6W2    1   NC#1 PCA9515ADGKR-1-GP_DISCRET-G5-PA    I77 @BASEBOARD_FAB2_LIB.BASEBOARD_FAB2(SCH_1):PAGE247
 U25W4  J18 GPIOF1_NDCD4_LHAD1 AST2520A1-GP-GP_ASIC2-GB1-AST2A   I117 @BASEBOARD_FAB2_LIB.BASEBOARD_FAB2(SCH_1):PAGE145
 U25W4  E17 GPIOG4_SGPS2CK_SALT1 AST2520A1-GP-GP_ASIC2-GB1-AST2A   I117 @BASEBOARD_FAB2_LIB.BASEBOARD_FAB2(SCH_1):PAGE145
 U25W4  D16 GPIOG5_SGPS2LD_SALT2 AST2520A1-GP-GP_ASIC2-GB1-AST2A   I117 @BASEBOARD_FAB2_LIB.BASEBOARD_FAB2(SCH_1):PAGE145
 U25W4 AA22 GPIOAA3_VPOR5_NORD3_SALT10 AST2520A1-GP-GP_ASIC2-GB1-AST2A   I104 @BASEBOARD_FAB2_LIB.BASEBOARD_FAB2(SCH_1):PAGE146
 U25W4  U22 GPIOAA4_VPOR6_NORD4_SALT11 AST2520A1-GP-GP_ASIC2-GB1-AST2A   I104 @BASEBOARD_FAB2_LIB.BASEBOARD_FAB2(SCH_1):PAGE146
 U25W4  T20 GPIOAA5_VPOR7_NORD5_SALT12 AST2520A1-GP-GP_ASIC2-GB1-AST2A   I104 @BASEBOARD_FAB2_LIB.BASEBOARD_FAB2(SCH_1):PAGE146
 U25W4  N18 GPIOAA6_VPOR8_NORD6_SALT13 AST2520A1-GP-GP_ASIC2-GB1-AST2A   I104 @BASEBOARD_FAB2_LIB.BASEBOARD_FAB2(SCH_1):PAGE146
 U25W4  V18 EXTRST# AST2520A1-GP-GP_ASIC2-GB1-AST2A   I105 @BASEBOARD_FAB2_LIB.BASEBOARD_FAB2(SCH_1):PAGE146
 U25W4  N19 GPIOAB0_VPODE_NOROE# AST2520A1-GP-GP_ASIC2-GB1-AST2A   I105 @BASEBOARD_FAB2_LIB.BASEBOARD_FAB2(SCH_1):PAGE146
 U25W4  T21 GPIOAB1_VPOHS_NORWE# AST2520A1-GP-GP_ASIC2-GB1-AST2A   I105 @BASEBOARD_FAB2_LIB.BASEBOARD_FAB2(SCH_1):PAGE146
 U25W4  T22 GPIOAB2_VPOVS_WDTRST1 AST2520A1-GP-GP_ASIC2-GB1-AST2A   I105 @BASEBOARD_FAB2_LIB.BASEBOARD_FAB2(SCH_1):PAGE146
 U25W4  R20 GPIOAB3_VPOCLK_WDTRST2 AST2520A1-GP-GP_ASIC2-GB1-AST2A   I105 @BASEBOARD_FAB2_LIB.BASEBOARD_FAB2(SCH_1):PAGE146
 U25W4  Y18 HBLED# AST2520A1-GP-GP_ASIC2-GB1-AST2A   I105 @BASEBOARD_FAB2_LIB.BASEBOARD_FAB2(SCH_1):PAGE146
 U25W4   F2 ADC8_GPIX0 AST2520A1-GP-GP_ASIC2-GB1-AST2A   I106 @BASEBOARD_FAB2_LIB.BASEBOARD_FAB2(SCH_1):PAGE147
 U25W4   G3 ADC9_GPIX1 AST2520A1-GP-GP_ASIC2-GB1-AST2A   I106 @BASEBOARD_FAB2_LIB.BASEBOARD_FAB2(SCH_1):PAGE147
 U25W4   G2 ADC10_GPIX2 AST2520A1-GP-GP_ASIC2-GB1-AST2A   I106 @BASEBOARD_FAB2_LIB.BASEBOARD_FAB2(SCH_1):PAGE147
 U25W4   F1 ADC11_GPIX3 AST2520A1-GP-GP_ASIC2-GB1-AST2A   I106 @BASEBOARD_FAB2_LIB.BASEBOARD_FAB2(SCH_1):PAGE147
 U25W4   H5 ADC12_GPIX4 AST2520A1-GP-GP_ASIC2-GB1-AST2A   I106 @BASEBOARD_FAB2_LIB.BASEBOARD_FAB2(SCH_1):PAGE147
 U25W4   G1 ADC13_GPIX5 AST2520A1-GP-GP_ASIC2-GB1-AST2A   I106 @BASEBOARD_FAB2_LIB.BASEBOARD_FAB2(SCH_1):PAGE147
 U25W4   H3 ADC14_GPIX6 AST2520A1-GP-GP_ASIC2-GB1-AST2A   I106 @BASEBOARD_FAB2_LIB.BASEBOARD_FAB2(SCH_1):PAGE147
 U25W4   H4 ADC15_GPIX7 AST2520A1-GP-GP_ASIC2-GB1-AST2A   I106 @BASEBOARD_FAB2_LIB.BASEBOARD_FAB2(SCH_1):PAGE147
 U25W4   B2 RGMII2TXCK_RMII2RCLKO_GPIOT6 AST2520A1-GP-GP_ASIC2-GB1-AST2A   I106 @BASEBOARD_FAB2_LIB.BASEBOARD_FAB2(SCH_1):PAGE147
  U6W1   15    P12 PCA9555PWRG4-GP_DISCRET-G5-PCAA    I97 @BASEBOARD_FAB2_LIB.BASEBOARD_FAB2(SCH_1):PAGE247
  U6W1   16    P13 PCA9555PWRG4-GP_DISCRET-G5-PCAA    I97 @BASEBOARD_FAB2_LIB.BASEBOARD_FAB2(SCH_1):PAGE247
  U6W1   17    P14 PCA9555PWRG4-GP_DISCRET-G5-PCAA    I97 @BASEBOARD_FAB2_LIB.BASEBOARD_FAB2(SCH_1):PAGE247
  U6W1   18    P15 PCA9555PWRG4-GP_DISCRET-G5-PCAA    I97 @BASEBOARD_FAB2_LIB.BASEBOARD_FAB2(SCH_1):PAGE247
  U6W1   19    P16 PCA9555PWRG4-GP_DISCRET-G5-PCAA    I97 @BASEBOARD_FAB2_LIB.BASEBOARD_FAB2(SCH_1):PAGE247
  U6W1   20    P17 PCA9555PWRG4-GP_DISCRET-G5-PCAA    I97 @BASEBOARD_FAB2_LIB.BASEBOARD_FAB2(SCH_1):PAGE247

NC_CLK_156M_CPU0_OSC @BASEBOARD_FAB2_LIB.BASEBOARD_FAB2(SCH_1):NC_CLK_156M_CPU0_OSC
  Y6F1    2 NC_GND OSC_C_6P10-156.25MHZ,OSC,G6383A    I71 @BASEBOARD_FAB2_LIB.BASEBOARD_FAB2(SCH_1):PAGE104

NC_CLK_156M_CPU1_OSC @BASEBOARD_FAB2_LIB.BASEBOARD_FAB2(SCH_1):NC_CLK_156M_CPU1_OSC
  Y3F1    2 NC_GND OSC_C_6P10-156.25MHZ,OSC,G6383A    I72 @BASEBOARD_FAB2_LIB.BASEBOARD_FAB2(SCH_1):PAGE104

NC_CPLD1 @BASEBOARD_FAB2_LIB.BASEBOARD_FAB2(SCH_1):NC_CPLD1
  U8D7   A2  NC<0> LCMXO2_A_256BGA-IC,H63395-001    I14 @BASEBOARD_FAB2_LIB.BASEBOARD_FAB2(SCH_1):PAGE192

NC_DB1200ZL<0> @BASEBOARD_FAB2_LIB.BASEBOARD_FAB2(SCH_1):NC_DB1200ZL(0)
 EU4D2    3  NC<0> NB3W1200L_LCC-IC,H13585-001     I1 @BASEBOARD_FAB2_LIB.BASEBOARD_FAB2(SCH_1):PAGE102

NC_DB1200ZL<1> @BASEBOARD_FAB2_LIB.BASEBOARD_FAB2(SCH_1):NC_DB1200ZL(1)
 EU4D2   16  NC<1> NB3W1200L_LCC-IC,H13585-001     I1 @BASEBOARD_FAB2_LIB.BASEBOARD_FAB2(SCH_1):PAGE102

NC_DB1200ZL<2> @BASEBOARD_FAB2_LIB.BASEBOARD_FAB2(SCH_1):NC_DB1200ZL(2)
 EU4D2   15  NC<2> NB3W1200L_LCC-IC,H13585-001     I1 @BASEBOARD_FAB2_LIB.BASEBOARD_FAB2(SCH_1):PAGE102

NC_M2<0> @BASEBOARD_FAB2_LIB.BASEBOARD_FAB2(SCH_1):NC_M2(0)
  J8F1    6  NC<0> SCONN75K_H17033002_SMT1-SCONN,A    I53 @BASEBOARD_FAB2_LIB.BASEBOARD_FAB2(SCH_1):PAGE185

NC_M2<10> @BASEBOARD_FAB2_LIB.BASEBOARD_FAB2(SCH_1):NC_M2(10)
  J8F1   36 NC<10> SCONN75K_H17033002_SMT1-SCONN,A    I53 @BASEBOARD_FAB2_LIB.BASEBOARD_FAB2(SCH_1):PAGE185

NC_M2<11> @BASEBOARD_FAB2_LIB.BASEBOARD_FAB2(SCH_1):NC_M2(11)
  J8F1   40 NC<11> SCONN75K_H17033002_SMT1-SCONN,A    I53 @BASEBOARD_FAB2_LIB.BASEBOARD_FAB2(SCH_1):PAGE185

NC_M2<12> @BASEBOARD_FAB2_LIB.BASEBOARD_FAB2(SCH_1):NC_M2(12)
  J8F1   42 NC<12> SCONN75K_H17033002_SMT1-SCONN,A    I53 @BASEBOARD_FAB2_LIB.BASEBOARD_FAB2(SCH_1):PAGE185

NC_M2<13> @BASEBOARD_FAB2_LIB.BASEBOARD_FAB2(SCH_1):NC_M2(13)
  J8F1   44 NC<13> SCONN75K_H17033002_SMT1-SCONN,A    I53 @BASEBOARD_FAB2_LIB.BASEBOARD_FAB2(SCH_1):PAGE185

NC_M2<14> @BASEBOARD_FAB2_LIB.BASEBOARD_FAB2(SCH_1):NC_M2(14)
  J8F1   46 NC<14> SCONN75K_H17033002_SMT1-SCONN,A    I53 @BASEBOARD_FAB2_LIB.BASEBOARD_FAB2(SCH_1):PAGE185

NC_M2<15> @BASEBOARD_FAB2_LIB.BASEBOARD_FAB2(SCH_1):NC_M2(15)
  J8F1   48 NC<15> SCONN75K_H17033002_SMT1-SCONN,A    I53 @BASEBOARD_FAB2_LIB.BASEBOARD_FAB2(SCH_1):PAGE185

NC_M2<16> @BASEBOARD_FAB2_LIB.BASEBOARD_FAB2(SCH_1):NC_M2(16)
  J8F1   56 NC<16> SCONN75K_H17033002_SMT1-SCONN,A    I53 @BASEBOARD_FAB2_LIB.BASEBOARD_FAB2(SCH_1):PAGE185

NC_M2<17> @BASEBOARD_FAB2_LIB.BASEBOARD_FAB2(SCH_1):NC_M2(17)
  J8F1   58 NC<17> SCONN75K_H17033002_SMT1-SCONN,A    I53 @BASEBOARD_FAB2_LIB.BASEBOARD_FAB2(SCH_1):PAGE185

NC_M2<18> @BASEBOARD_FAB2_LIB.BASEBOARD_FAB2(SCH_1):NC_M2(18)
  J8F1   67 NC<18> SCONN75K_H17033002_SMT1-SCONN,A    I53 @BASEBOARD_FAB2_LIB.BASEBOARD_FAB2(SCH_1):PAGE185

NC_M2<1> @BASEBOARD_FAB2_LIB.BASEBOARD_FAB2(SCH_1):NC_M2(1)
  J8F1    8  NC<1> SCONN75K_H17033002_SMT1-SCONN,A    I53 @BASEBOARD_FAB2_LIB.BASEBOARD_FAB2(SCH_1):PAGE185

NC_M2<2> @BASEBOARD_FAB2_LIB.BASEBOARD_FAB2(SCH_1):NC_M2(2)
  J8F1   20  NC<2> SCONN75K_H17033002_SMT1-SCONN,A    I53 @BASEBOARD_FAB2_LIB.BASEBOARD_FAB2(SCH_1):PAGE185

NC_M2<3> @BASEBOARD_FAB2_LIB.BASEBOARD_FAB2(SCH_1):NC_M2(3)
  J8F1   22  NC<3> SCONN75K_H17033002_SMT1-SCONN,A    I53 @BASEBOARD_FAB2_LIB.BASEBOARD_FAB2(SCH_1):PAGE185

NC_M2<4> @BASEBOARD_FAB2_LIB.BASEBOARD_FAB2(SCH_1):NC_M2(4)
  J8F1   24  NC<4> SCONN75K_H17033002_SMT1-SCONN,A    I53 @BASEBOARD_FAB2_LIB.BASEBOARD_FAB2(SCH_1):PAGE185

NC_M2<5> @BASEBOARD_FAB2_LIB.BASEBOARD_FAB2(SCH_1):NC_M2(5)
  J8F1   26  NC<5> SCONN75K_H17033002_SMT1-SCONN,A    I53 @BASEBOARD_FAB2_LIB.BASEBOARD_FAB2(SCH_1):PAGE185

NC_M2<6> @BASEBOARD_FAB2_LIB.BASEBOARD_FAB2(SCH_1):NC_M2(6)
  J8F1   28  NC<6> SCONN75K_H17033002_SMT1-SCONN,A    I53 @BASEBOARD_FAB2_LIB.BASEBOARD_FAB2(SCH_1):PAGE185

NC_M2<7> @BASEBOARD_FAB2_LIB.BASEBOARD_FAB2(SCH_1):NC_M2(7)
  J8F1   30  NC<7> SCONN75K_H17033002_SMT1-SCONN,A    I53 @BASEBOARD_FAB2_LIB.BASEBOARD_FAB2(SCH_1):PAGE185

NC_M2<8> @BASEBOARD_FAB2_LIB.BASEBOARD_FAB2(SCH_1):NC_M2(8)
  J8F1   32  NC<8> SCONN75K_H17033002_SMT1-SCONN,A    I53 @BASEBOARD_FAB2_LIB.BASEBOARD_FAB2(SCH_1):PAGE185

NC_M2<9> @BASEBOARD_FAB2_LIB.BASEBOARD_FAB2(SCH_1):NC_M2(9)
  J8F1   34  NC<9> SCONN75K_H17033002_SMT1-SCONN,A    I53 @BASEBOARD_FAB2_LIB.BASEBOARD_FAB2(SCH_1):PAGE185

NC_P1V05_PCH_STBY_PH1_P31 @BASEBOARD_FAB2_LIB.BASEBOARD_FAB2(SCH_1):NC_P1V05_PCH_STBY_PH1_P31
 EU7A2   31     NC IR354XX_SM-IR35412,IC,H73684-0A   I117 @BASEBOARD_FAB2_LIB.BASEBOARD_FAB2(SCH_1):PAGE236

NC_PI7C9X1172_1 @BASEBOARD_FAB2_LIB.BASEBOARD_FAB2(SCH_1):NC_PI7C9X1172_1
 EU9F3    1  NC<0> PI7C9X1172_QFN-IC,H66899-001     I1 @BASEBOARD_FAB2_LIB.BASEBOARD_FAB2(SCH_1):PAGE183

NC_PI7C9X1172_8 @BASEBOARD_FAB2_LIB.BASEBOARD_FAB2(SCH_1):NC_PI7C9X1172_8
 EU9F3    8  NC<1> PI7C9X1172_QFN-IC,H66899-001     I1 @BASEBOARD_FAB2_LIB.BASEBOARD_FAB2(SCH_1):PAGE183

NC_PVCCIN_CPU0_PH1_P31 @BASEBOARD_FAB2_LIB.BASEBOARD_FAB2(SCH_1):NC_PVCCIN_CPU0_PH1_P31
 EU4E1   31     NC IR354XX_SM-IR35411,IC,H73688-0A    I63 @BASEBOARD_FAB2_LIB.BASEBOARD_FAB2(SCH_1):PAGE202

NC_PVCCIN_CPU0_PH2_P31 @BASEBOARD_FAB2_LIB.BASEBOARD_FAB2(SCH_1):NC_PVCCIN_CPU0_PH2_P31
 EU4D6   31     NC IR354XX_SM-IR35411,IC,H73688-0A    I64 @BASEBOARD_FAB2_LIB.BASEBOARD_FAB2(SCH_1):PAGE202

NC_PVCCIN_CPU0_PH3_P31 @BASEBOARD_FAB2_LIB.BASEBOARD_FAB2(SCH_1):NC_PVCCIN_CPU0_PH3_P31
 EU4D3   31     NC IR354XX_SM-IR35411,IC,H73688-0A    I70 @BASEBOARD_FAB2_LIB.BASEBOARD_FAB2(SCH_1):PAGE203

NC_PVCCIN_CPU0_PH4_P31 @BASEBOARD_FAB2_LIB.BASEBOARD_FAB2(SCH_1):NC_PVCCIN_CPU0_PH4_P31
 EU4D1   31     NC IR354XX_SM-IR35411,IC,H73688-0A    I71 @BASEBOARD_FAB2_LIB.BASEBOARD_FAB2(SCH_1):PAGE203

NC_PVCCIN_CPU0_PH5_P31 @BASEBOARD_FAB2_LIB.BASEBOARD_FAB2(SCH_1):NC_PVCCIN_CPU0_PH5_P31
 EU4C2   31     NC IR354XX_SM-IR35411,IC,H73688-0A    I71 @BASEBOARD_FAB2_LIB.BASEBOARD_FAB2(SCH_1):PAGE204

NC_PVCCIN_CPU1_PH1_P31 @BASEBOARD_FAB2_LIB.BASEBOARD_FAB2(SCH_1):NC_PVCCIN_CPU1_PH1_P31
 EU1E2   31     NC IR354XX_SM-IR35411,IC,H73688-0A    I20 @BASEBOARD_FAB2_LIB.BASEBOARD_FAB2(SCH_1):PAGE207

NC_PVCCIN_CPU1_PH2_P31 @BASEBOARD_FAB2_LIB.BASEBOARD_FAB2(SCH_1):NC_PVCCIN_CPU1_PH2_P31
 EU1D4   31     NC IR354XX_SM-IR35411,IC,H73688-0A    I24 @BASEBOARD_FAB2_LIB.BASEBOARD_FAB2(SCH_1):PAGE207

NC_PVCCIN_CPU1_PH3_P31 @BASEBOARD_FAB2_LIB.BASEBOARD_FAB2(SCH_1):NC_PVCCIN_CPU1_PH3_P31
 EU1D3   31     NC IR354XX_SM-IR35411,IC,H73688-0A    I27 @BASEBOARD_FAB2_LIB.BASEBOARD_FAB2(SCH_1):PAGE208

NC_PVCCIN_CPU1_PH4_P31 @BASEBOARD_FAB2_LIB.BASEBOARD_FAB2(SCH_1):NC_PVCCIN_CPU1_PH4_P31
 EU1D1   31     NC IR354XX_SM-IR35411,IC,H73688-0A    I71 @BASEBOARD_FAB2_LIB.BASEBOARD_FAB2(SCH_1):PAGE208

NC_PVCCIN_CPU1_PH5_P31 @BASEBOARD_FAB2_LIB.BASEBOARD_FAB2(SCH_1):NC_PVCCIN_CPU1_PH5_P31
 EU1C3   31     NC IR354XX_SM-IR35411,IC,H73688-0A    I56 @BASEBOARD_FAB2_LIB.BASEBOARD_FAB2(SCH_1):PAGE209

NC_PVCCIO_CPU0_DNC0 @BASEBOARD_FAB2_LIB.BASEBOARD_FAB2(SCH_1):NC_PVCCIO_CPU0_DNC0
 EU3P1    1 DNC<0> PXE1110B_QFN-IC,H89187-001    I93 @BASEBOARD_FAB2_LIB.BASEBOARD_FAB2(SCH_1):PAGE211

NC_PVCCIO_CPU0_DNC1 @BASEBOARD_FAB2_LIB.BASEBOARD_FAB2(SCH_1):NC_PVCCIO_CPU0_DNC1
 EU3P1    2 DNC<1> PXE1110B_QFN-IC,H89187-001    I93 @BASEBOARD_FAB2_LIB.BASEBOARD_FAB2(SCH_1):PAGE211

NC_PVCCIO_CPU0_DNC2 @BASEBOARD_FAB2_LIB.BASEBOARD_FAB2(SCH_1):NC_PVCCIO_CPU0_DNC2
 EU3P1    4 DNC<2> PXE1110B_QFN-IC,H89187-001    I93 @BASEBOARD_FAB2_LIB.BASEBOARD_FAB2(SCH_1):PAGE211

NC_PVCCIO_CPU0_DNC3 @BASEBOARD_FAB2_LIB.BASEBOARD_FAB2(SCH_1):NC_PVCCIO_CPU0_DNC3
 EU3P1   24 DNC<3> PXE1110B_QFN-IC,H89187-001    I93 @BASEBOARD_FAB2_LIB.BASEBOARD_FAB2(SCH_1):PAGE211

NC_PVCCIO_CPU0_DNC4 @BASEBOARD_FAB2_LIB.BASEBOARD_FAB2(SCH_1):NC_PVCCIO_CPU0_DNC4
 EU3P1   28 DNC<4> PXE1110B_QFN-IC,H89187-001    I93 @BASEBOARD_FAB2_LIB.BASEBOARD_FAB2(SCH_1):PAGE211

NC_PVCCIO_CPU0_PH1_P31 @BASEBOARD_FAB2_LIB.BASEBOARD_FAB2(SCH_1):NC_PVCCIO_CPU0_PH1_P31
 EU7C1   31     NC IR354XX_SM-IR35412,IC,H73684-0A   I101 @BASEBOARD_FAB2_LIB.BASEBOARD_FAB2(SCH_1):PAGE212

NC_PVCCIO_CPU1_DNC0 @BASEBOARD_FAB2_LIB.BASEBOARD_FAB2(SCH_1):NC_PVCCIO_CPU1_DNC0
 EU4D5    1 DNC<0> PXE1110B_QFN-IC,H89187-001    I96 @BASEBOARD_FAB2_LIB.BASEBOARD_FAB2(SCH_1):PAGE213

NC_PVCCIO_CPU1_DNC1 @BASEBOARD_FAB2_LIB.BASEBOARD_FAB2(SCH_1):NC_PVCCIO_CPU1_DNC1
 EU4D5    2 DNC<1> PXE1110B_QFN-IC,H89187-001    I96 @BASEBOARD_FAB2_LIB.BASEBOARD_FAB2(SCH_1):PAGE213

NC_PVCCIO_CPU1_DNC2 @BASEBOARD_FAB2_LIB.BASEBOARD_FAB2(SCH_1):NC_PVCCIO_CPU1_DNC2
 EU4D5    4 DNC<2> PXE1110B_QFN-IC,H89187-001    I96 @BASEBOARD_FAB2_LIB.BASEBOARD_FAB2(SCH_1):PAGE213

NC_PVCCIO_CPU1_DNC3 @BASEBOARD_FAB2_LIB.BASEBOARD_FAB2(SCH_1):NC_PVCCIO_CPU1_DNC3
 EU4D5   24 DNC<3> PXE1110B_QFN-IC,H89187-001    I96 @BASEBOARD_FAB2_LIB.BASEBOARD_FAB2(SCH_1):PAGE213

NC_PVCCIO_CPU1_DNC4 @BASEBOARD_FAB2_LIB.BASEBOARD_FAB2(SCH_1):NC_PVCCIO_CPU1_DNC4
 EU4D5   28 DNC<4> PXE1110B_QFN-IC,H89187-001    I96 @BASEBOARD_FAB2_LIB.BASEBOARD_FAB2(SCH_1):PAGE213

NC_PVCCIO_CPU1_PH1_P31 @BASEBOARD_FAB2_LIB.BASEBOARD_FAB2(SCH_1):NC_PVCCIO_CPU1_PH1_P31
 EU4E2   31     NC IR354XX_SM-IR35412,IC,H73684-0A   I126 @BASEBOARD_FAB2_LIB.BASEBOARD_FAB2(SCH_1):PAGE214

NC_PVDDQ_ABC_DNC0 @BASEBOARD_FAB2_LIB.BASEBOARD_FAB2(SCH_1):NC_PVDDQ_ABC_DNC0
 EU7G1    2 DNC<0> PXM1310B_QFN-IC,H89186-001   I358 @BASEBOARD_FAB2_LIB.BASEBOARD_FAB2(SCH_1):PAGE215

NC_PVDDQ_ABC_DNC1 @BASEBOARD_FAB2_LIB.BASEBOARD_FAB2(SCH_1):NC_PVDDQ_ABC_DNC1
 EU7G1   28 DNC<1> PXM1310B_QFN-IC,H89186-001   I358 @BASEBOARD_FAB2_LIB.BASEBOARD_FAB2(SCH_1):PAGE215

NC_PVDDQ_ABC_PH1_P31 @BASEBOARD_FAB2_LIB.BASEBOARD_FAB2(SCH_1):NC_PVDDQ_ABC_PH1_P31
 EU7G2   31     NC IR354XX_SM-IR35411,IC,H73688-0A   I102 @BASEBOARD_FAB2_LIB.BASEBOARD_FAB2(SCH_1):PAGE216

NC_PVDDQ_ABC_PH2_P31 @BASEBOARD_FAB2_LIB.BASEBOARD_FAB2(SCH_1):NC_PVDDQ_ABC_PH2_P31
 EU7G3   31     NC IR354XX_SM-IR35411,IC,H73688-0A   I103 @BASEBOARD_FAB2_LIB.BASEBOARD_FAB2(SCH_1):PAGE216

NC_PVDDQ_DEF_DNC0 @BASEBOARD_FAB2_LIB.BASEBOARD_FAB2(SCH_1):NC_PVDDQ_DEF_DNC0
 EU7A5    2 DNC<0> PXM1310B_QFN-IC,H89186-001    I75 @BASEBOARD_FAB2_LIB.BASEBOARD_FAB2(SCH_1):PAGE218

NC_PVDDQ_DEF_DNC1 @BASEBOARD_FAB2_LIB.BASEBOARD_FAB2(SCH_1):NC_PVDDQ_DEF_DNC1
 EU7A5   28 DNC<1> PXM1310B_QFN-IC,H89186-001    I75 @BASEBOARD_FAB2_LIB.BASEBOARD_FAB2(SCH_1):PAGE218

NC_PVDDQ_DEF_PH1_P31 @BASEBOARD_FAB2_LIB.BASEBOARD_FAB2(SCH_1):NC_PVDDQ_DEF_PH1_P31
 EU7A1   31     NC IR354XX_SM-IR35411,IC,H73688-0A   I106 @BASEBOARD_FAB2_LIB.BASEBOARD_FAB2(SCH_1):PAGE219

NC_PVDDQ_DEF_PH2_P31 @BASEBOARD_FAB2_LIB.BASEBOARD_FAB2(SCH_1):NC_PVDDQ_DEF_PH2_P31
 EU7A4   31     NC IR354XX_SM-IR35411,IC,H73688-0A   I107 @BASEBOARD_FAB2_LIB.BASEBOARD_FAB2(SCH_1):PAGE219

NC_PVDDQ_GHJ_DNC0 @BASEBOARD_FAB2_LIB.BASEBOARD_FAB2(SCH_1):NC_PVDDQ_GHJ_DNC0
 EU1G2    2 DNC<0> PXM1310B_QFN-IC,H89186-001    I90 @BASEBOARD_FAB2_LIB.BASEBOARD_FAB2(SCH_1):PAGE223

NC_PVDDQ_GHJ_DNC1 @BASEBOARD_FAB2_LIB.BASEBOARD_FAB2(SCH_1):NC_PVDDQ_GHJ_DNC1
 EU1G2   28 DNC<1> PXM1310B_QFN-IC,H89186-001    I90 @BASEBOARD_FAB2_LIB.BASEBOARD_FAB2(SCH_1):PAGE223

NC_PVDDQ_GHJ_PH1_P31 @BASEBOARD_FAB2_LIB.BASEBOARD_FAB2(SCH_1):NC_PVDDQ_GHJ_PH1_P31
 EU1G1   31     NC IR354XX_SM-IR35411,IC,H73688-0A   I110 @BASEBOARD_FAB2_LIB.BASEBOARD_FAB2(SCH_1):PAGE224

NC_PVDDQ_GHJ_PH2_P31 @BASEBOARD_FAB2_LIB.BASEBOARD_FAB2(SCH_1):NC_PVDDQ_GHJ_PH2_P31
 EU1F1   31     NC IR354XX_SM-IR35411,IC,H73688-0A   I111 @BASEBOARD_FAB2_LIB.BASEBOARD_FAB2(SCH_1):PAGE224

NC_PVDDQ_GHJ_PINALRT_N @BASEBOARD_FAB2_LIB.BASEBOARD_FAB2(SCH_1):NC_PVDDQ_GHJ_PINALRT_N
 EU1G2   12 PINALRT_N PXM1310B_QFN-IC,H89186-001    I90 @BASEBOARD_FAB2_LIB.BASEBOARD_FAB2(SCH_1):PAGE223

NC_PVDDQ_KLM_DNC0 @BASEBOARD_FAB2_LIB.BASEBOARD_FAB2(SCH_1):NC_PVDDQ_KLM_DNC0
 EU1B1    2 DNC<0> PXM1310B_QFN-IC,H89186-001    I90 @BASEBOARD_FAB2_LIB.BASEBOARD_FAB2(SCH_1):PAGE226

NC_PVDDQ_KLM_DNC1 @BASEBOARD_FAB2_LIB.BASEBOARD_FAB2(SCH_1):NC_PVDDQ_KLM_DNC1
 EU1B1   28 DNC<1> PXM1310B_QFN-IC,H89186-001    I90 @BASEBOARD_FAB2_LIB.BASEBOARD_FAB2(SCH_1):PAGE226

NC_PVDDQ_KLM_GP0 @BASEBOARD_FAB2_LIB.BASEBOARD_FAB2(SCH_1):NC_PVDDQ_KLM_GP0
 EU1B1   18    MP2 PXM1310B_QFN-IC,H89186-001    I90 @BASEBOARD_FAB2_LIB.BASEBOARD_FAB2(SCH_1):PAGE226

NC_PVDDQ_KLM_GP1 @BASEBOARD_FAB2_LIB.BASEBOARD_FAB2(SCH_1):NC_PVDDQ_KLM_GP1
 EU1B1   14    MP1 PXM1310B_QFN-IC,H89186-001    I90 @BASEBOARD_FAB2_LIB.BASEBOARD_FAB2(SCH_1):PAGE226

NC_PVDDQ_KLM_PH1_P31 @BASEBOARD_FAB2_LIB.BASEBOARD_FAB2(SCH_1):NC_PVDDQ_KLM_PH1_P31
 EU1A2   31     NC IR354XX_SM-IR35411,IC,H73688-0A   I101 @BASEBOARD_FAB2_LIB.BASEBOARD_FAB2(SCH_1):PAGE227

NC_PVDDQ_KLM_PH2_P31 @BASEBOARD_FAB2_LIB.BASEBOARD_FAB2(SCH_1):NC_PVDDQ_KLM_PH2_P31
 EU1A1   31     NC IR354XX_SM-IR35411,IC,H73688-0A   I102 @BASEBOARD_FAB2_LIB.BASEBOARD_FAB2(SCH_1):PAGE227

NC_PVDDQ_KLM_PINALRT_N @BASEBOARD_FAB2_LIB.BASEBOARD_FAB2(SCH_1):NC_PVDDQ_KLM_PINALRT_N
 EU1B1   12 PINALRT_N PXM1310B_QFN-IC,H89186-001    I90 @BASEBOARD_FAB2_LIB.BASEBOARD_FAB2(SCH_1):PAGE226

NC_PVDDQ_KLM_PWM3 @BASEBOARD_FAB2_LIB.BASEBOARD_FAB2(SCH_1):NC_PVDDQ_KLM_PWM3
 EU1B1    3  APWM3 PXM1310B_QFN-IC,H89186-001    I90 @BASEBOARD_FAB2_LIB.BASEBOARD_FAB2(SCH_1):PAGE226

NC_PVNN_PCH_DNC0 @BASEBOARD_FAB2_LIB.BASEBOARD_FAB2(SCH_1):NC_PVNN_PCH_DNC0
 EU8A1    1 DNC<0> PXE1110B_QFN-IC,H89187-001   I229 @BASEBOARD_FAB2_LIB.BASEBOARD_FAB2(SCH_1):PAGE235

NC_PVNN_PCH_DNC1 @BASEBOARD_FAB2_LIB.BASEBOARD_FAB2(SCH_1):NC_PVNN_PCH_DNC1
 EU8A1    2 DNC<1> PXE1110B_QFN-IC,H89187-001   I229 @BASEBOARD_FAB2_LIB.BASEBOARD_FAB2(SCH_1):PAGE235

NC_PVNN_PCH_DNC2 @BASEBOARD_FAB2_LIB.BASEBOARD_FAB2(SCH_1):NC_PVNN_PCH_DNC2
 EU8A1    4 DNC<2> PXE1110B_QFN-IC,H89187-001   I229 @BASEBOARD_FAB2_LIB.BASEBOARD_FAB2(SCH_1):PAGE235

NC_PVNN_PCH_DNC3 @BASEBOARD_FAB2_LIB.BASEBOARD_FAB2(SCH_1):NC_PVNN_PCH_DNC3
 EU8A1   24 DNC<3> PXE1110B_QFN-IC,H89187-001   I229 @BASEBOARD_FAB2_LIB.BASEBOARD_FAB2(SCH_1):PAGE235

NC_PVNN_PCH_DNC4 @BASEBOARD_FAB2_LIB.BASEBOARD_FAB2(SCH_1):NC_PVNN_PCH_DNC4
 EU8A1   28 DNC<4> PXE1110B_QFN-IC,H89187-001   I229 @BASEBOARD_FAB2_LIB.BASEBOARD_FAB2(SCH_1):PAGE235

NC_PVNN_PCH_PH1_P31 @BASEBOARD_FAB2_LIB.BASEBOARD_FAB2(SCH_1):NC_PVNN_PCH_PH1_P31
 EU7A3   31     NC IR354XX_SM-IR35412,IC,H73684-0A   I116 @BASEBOARD_FAB2_LIB.BASEBOARD_FAB2(SCH_1):PAGE236

NC_PVSA_CPU0_P31 @BASEBOARD_FAB2_LIB.BASEBOARD_FAB2(SCH_1):NC_PVSA_CPU0_P31
 EU4C1   31     NC IR354XX_SM-IR35412,IC,H73684-0A    I46 @BASEBOARD_FAB2_LIB.BASEBOARD_FAB2(SCH_1):PAGE205

NC_PVSA_CPU1_P31 @BASEBOARD_FAB2_LIB.BASEBOARD_FAB2(SCH_1):NC_PVSA_CPU1_P31
 EU1C1   31     NC IR354XX_SM-IR35412,IC,H73684-0A    I51 @BASEBOARD_FAB2_LIB.BASEBOARD_FAB2(SCH_1):PAGE210

NC_SPRNGVLLE_22 @BASEBOARD_FAB2_LIB.BASEBOARD_FAB2(SCH_1):NC_SPRNGVLLE_22
 EU9E1   22     NC SPRINGVILLE_SM1-IC,G47144-004    I72 @BASEBOARD_FAB2_LIB.BASEBOARD_FAB2(SCH_1):PAGE139

NIC_LED_ACT_ANODE_R @BASEBOARD_FAB2_LIB.BASEBOARD_FAB2(SCH_1):NIC_LED_ACT_ANODE_R
  R9G4    1      A RES_0402-0.0,5%,1/16W,CHIP,G21A    I56 @BASEBOARD_FAB2_LIB.BASEBOARD_FAB2(SCH_1):PAGE141
 JA9G1   L4     L4 CONN17_H71061002_PIP1-CONN,H71A   I109 @BASEBOARD_FAB2_LIB.BASEBOARD_FAB2(SCH_1):PAGE141

NIC_MDI_MNG_RX_DN @BASEBOARD_FAB2_LIB.BASEBOARD_FAB2(SCH_1):NIC_MDI_MNG_RX_DN
 C9G12    2      B CAP_0402LF-4700PF,50V,10%,EMPTA   I100 @BASEBOARD_FAB2_LIB.BASEBOARD_FAB2(SCH_1):PAGE141
  J1F1   E5   IOE5 CONN76_H22707001_THMT1-CONN,H2A   I111 @BASEBOARD_FAB2_LIB.BASEBOARD_FAB2(SCH_1):PAGE181

NIC_MDI_MNG_RX_DP @BASEBOARD_FAB2_LIB.BASEBOARD_FAB2(SCH_1):NIC_MDI_MNG_RX_DP
  C9G9    2      B CAP_0402LF-4700PF,50V,10%,EMPTA    I99 @BASEBOARD_FAB2_LIB.BASEBOARD_FAB2(SCH_1):PAGE141
  J1F1   D5   IOD5 CONN76_H22707001_THMT1-CONN,H2A   I111 @BASEBOARD_FAB2_LIB.BASEBOARD_FAB2(SCH_1):PAGE181

NIC_MDI_MNG_TX_DN @BASEBOARD_FAB2_LIB.BASEBOARD_FAB2(SCH_1):NIC_MDI_MNG_TX_DN
 C9G13    2      B CAP_0402LF-4700PF,50V,10%,EMPTA   I102 @BASEBOARD_FAB2_LIB.BASEBOARD_FAB2(SCH_1):PAGE141
  J1F1   B5   IOB5 CONN76_H22707001_THMT1-CONN,H2A   I111 @BASEBOARD_FAB2_LIB.BASEBOARD_FAB2(SCH_1):PAGE181

NIC_MDI_MNG_TX_DP @BASEBOARD_FAB2_LIB.BASEBOARD_FAB2(SCH_1):NIC_MDI_MNG_TX_DP
 C9G16    2      B CAP_0402LF-4700PF,50V,10%,EMPTA   I101 @BASEBOARD_FAB2_LIB.BASEBOARD_FAB2(SCH_1):PAGE141
  J1F1   A5   IOA5 CONN76_H22707001_THMT1-CONN,H2A   I111 @BASEBOARD_FAB2_LIB.BASEBOARD_FAB2(SCH_1):PAGE181

NIC_MDI_SPRV_RJ45_0_DN @BASEBOARD_FAB2_LIB.BASEBOARD_FAB2(SCH_1):NIC_MDI_SPRV_RJ45_0_DN
 EU9E1   57 MDI_MINUS0_SFP_I2C_DATA SPRINGVILLE_SM1-IC,G47144-004    I72 @BASEBOARD_FAB2_LIB.BASEBOARD_FAB2(SCH_1):PAGE139
 R9G22    1      A RES_0402-0.0,5%,1/16W,CHIP,G21A    I82 @BASEBOARD_FAB2_LIB.BASEBOARD_FAB2(SCH_1):PAGE141

NIC_MDI_SPRV_RJ45_0_DP @BASEBOARD_FAB2_LIB.BASEBOARD_FAB2(SCH_1):NIC_MDI_SPRV_RJ45_0_DP
 EU9E1   58 MDI_PLUS0_NC SPRINGVILLE_SM1-IC,G47144-004    I72 @BASEBOARD_FAB2_LIB.BASEBOARD_FAB2(SCH_1):PAGE139
 R9G24    1      A RES_0402-0.0,5%,1/16W,CHIP,G21A    I81 @BASEBOARD_FAB2_LIB.BASEBOARD_FAB2(SCH_1):PAGE141

NIC_MDI_SPRV_RJ45_0_R_DN @BASEBOARD_FAB2_LIB.BASEBOARD_FAB2(SCH_1):NIC_MDI_SPRV_RJ45_0_R_DN
 R9G22    2      B RES_0402-0.0,5%,1/16W,CHIP,G21A    I82 @BASEBOARD_FAB2_LIB.BASEBOARD_FAB2(SCH_1):PAGE141
 JA9G1  R10  TRD1N CONN17_H71061002_PIP1-CONN,H71A   I109 @BASEBOARD_FAB2_LIB.BASEBOARD_FAB2(SCH_1):PAGE141

NIC_MDI_SPRV_RJ45_0_R_DP @BASEBOARD_FAB2_LIB.BASEBOARD_FAB2(SCH_1):NIC_MDI_SPRV_RJ45_0_R_DP
 R9G24    2      B RES_0402-0.0,5%,1/16W,CHIP,G21A    I81 @BASEBOARD_FAB2_LIB.BASEBOARD_FAB2(SCH_1):PAGE141
 JA9G1  R11  TRD1P CONN17_H71061002_PIP1-CONN,H71A   I109 @BASEBOARD_FAB2_LIB.BASEBOARD_FAB2(SCH_1):PAGE141

NIC_MDI_SPRV_RJ45_1_DN @BASEBOARD_FAB2_LIB.BASEBOARD_FAB2(SCH_1):NIC_MDI_SPRV_RJ45_1_DN
 EU9E1   54 MDI_MINUS1_SRDS_SIG_DET SPRINGVILLE_SM1-IC,G47144-004    I72 @BASEBOARD_FAB2_LIB.BASEBOARD_FAB2(SCH_1):PAGE139
 R9G20    1      A RES_0402-0.0,5%,1/16W,CHIP,G21A    I80 @BASEBOARD_FAB2_LIB.BASEBOARD_FAB2(SCH_1):PAGE141

NIC_MDI_SPRV_RJ45_1_DP @BASEBOARD_FAB2_LIB.BASEBOARD_FAB2(SCH_1):NIC_MDI_SPRV_RJ45_1_DP
 EU9E1   55 MDI_PLUS1_SFP_I2C_CLK SPRINGVILLE_SM1-IC,G47144-004    I72 @BASEBOARD_FAB2_LIB.BASEBOARD_FAB2(SCH_1):PAGE139
 R9G19    1      A RES_0402-0.0,5%,1/16W,CHIP,G21A    I79 @BASEBOARD_FAB2_LIB.BASEBOARD_FAB2(SCH_1):PAGE141

NIC_MDI_SPRV_RJ45_1_R_DN @BASEBOARD_FAB2_LIB.BASEBOARD_FAB2(SCH_1):NIC_MDI_SPRV_RJ45_1_R_DN
 R9G20    2      B RES_0402-0.0,5%,1/16W,CHIP,G21A    I80 @BASEBOARD_FAB2_LIB.BASEBOARD_FAB2(SCH_1):PAGE141
 JA9G1   R5  TRD2N CONN17_H71061002_PIP1-CONN,H71A   I109 @BASEBOARD_FAB2_LIB.BASEBOARD_FAB2(SCH_1):PAGE141

NIC_MDI_SPRV_RJ45_1_R_DP @BASEBOARD_FAB2_LIB.BASEBOARD_FAB2(SCH_1):NIC_MDI_SPRV_RJ45_1_R_DP
 R9G19    2      B RES_0402-0.0,5%,1/16W,CHIP,G21A    I79 @BASEBOARD_FAB2_LIB.BASEBOARD_FAB2(SCH_1):PAGE141
 JA9G1   R4  TRD2P CONN17_H71061002_PIP1-CONN,H71A   I109 @BASEBOARD_FAB2_LIB.BASEBOARD_FAB2(SCH_1):PAGE141

NIC_MDI_SPRV_RJ45_2_R_DN @BASEBOARD_FAB2_LIB.BASEBOARD_FAB2(SCH_1):NIC_MDI_SPRV_RJ45_2_R_DN
 R9G17    2      B RES_0402-0.0,5%,1/16W,CHIP,G21A    I78 @BASEBOARD_FAB2_LIB.BASEBOARD_FAB2(SCH_1):PAGE141
 JA9G1   R2  TRD3N CONN17_H71061002_PIP1-CONN,H71A   I109 @BASEBOARD_FAB2_LIB.BASEBOARD_FAB2(SCH_1):PAGE141

NIC_MDI_SPRV_RJ45_2_R_DP @BASEBOARD_FAB2_LIB.BASEBOARD_FAB2(SCH_1):NIC_MDI_SPRV_RJ45_2_R_DP
 R9G18    2      B RES_0402-0.0,5%,1/16W,CHIP,G21A    I77 @BASEBOARD_FAB2_LIB.BASEBOARD_FAB2(SCH_1):PAGE141
 JA9G1   R3  TRD3P CONN17_H71061002_PIP1-CONN,H71A   I109 @BASEBOARD_FAB2_LIB.BASEBOARD_FAB2(SCH_1):PAGE141

NIC_MDI_SPRV_RJ45_3_R_DN @BASEBOARD_FAB2_LIB.BASEBOARD_FAB2(SCH_1):NIC_MDI_SPRV_RJ45_3_R_DN
 R9G11    2      B RES_0402-0.0,5%,1/16W,CHIP,G21A    I76 @BASEBOARD_FAB2_LIB.BASEBOARD_FAB2(SCH_1):PAGE141
 JA9G1   R9  TRD4N CONN17_H71061002_PIP1-CONN,H71A   I109 @BASEBOARD_FAB2_LIB.BASEBOARD_FAB2(SCH_1):PAGE141

NIC_MDI_SPRV_RJ45_3_R_DP @BASEBOARD_FAB2_LIB.BASEBOARD_FAB2(SCH_1):NIC_MDI_SPRV_RJ45_3_R_DP
  R9G9    2      B RES_0402-0.0,5%,1/16W,CHIP,G21A    I75 @BASEBOARD_FAB2_LIB.BASEBOARD_FAB2(SCH_1):PAGE141
 JA9G1   R8  TRD4P CONN17_H71061002_PIP1-CONN,H71A   I109 @BASEBOARD_FAB2_LIB.BASEBOARD_FAB2(SCH_1):PAGE141

NIC_SER_N_MDI_3_DN @BASEBOARD_FAB2_LIB.BASEBOARD_FAB2(SCH_1):NIC_SER_N_MDI_3_DN
 EU9E1   49 MDI_MINUS3_SERN SPRINGVILLE_SM1-IC,G47144-004    I72 @BASEBOARD_FAB2_LIB.BASEBOARD_FAB2(SCH_1):PAGE139
 R9G11    1      A RES_0402-0.0,5%,1/16W,CHIP,G21A    I76 @BASEBOARD_FAB2_LIB.BASEBOARD_FAB2(SCH_1):PAGE141
 C9G12    1      A CAP_0402LF-4700PF,50V,10%,EMPTA   I100 @BASEBOARD_FAB2_LIB.BASEBOARD_FAB2(SCH_1):PAGE141

NIC_SER_P_MDI_3_DP @BASEBOARD_FAB2_LIB.BASEBOARD_FAB2(SCH_1):NIC_SER_P_MDI_3_DP
 EU9E1   50 MDI_PLUS3_SERP SPRINGVILLE_SM1-IC,G47144-004    I72 @BASEBOARD_FAB2_LIB.BASEBOARD_FAB2(SCH_1):PAGE139
  R9G9    1      A RES_0402-0.0,5%,1/16W,CHIP,G21A    I75 @BASEBOARD_FAB2_LIB.BASEBOARD_FAB2(SCH_1):PAGE141
  C9G9    1      A CAP_0402LF-4700PF,50V,10%,EMPTA    I99 @BASEBOARD_FAB2_LIB.BASEBOARD_FAB2(SCH_1):PAGE141

NIC_SET_N_MDI_2_DN @BASEBOARD_FAB2_LIB.BASEBOARD_FAB2(SCH_1):NIC_SET_N_MDI_2_DN
 EU9E1   52 MDI_MINUS2_SETN SPRINGVILLE_SM1-IC,G47144-004    I72 @BASEBOARD_FAB2_LIB.BASEBOARD_FAB2(SCH_1):PAGE139
 R9G17    1      A RES_0402-0.0,5%,1/16W,CHIP,G21A    I78 @BASEBOARD_FAB2_LIB.BASEBOARD_FAB2(SCH_1):PAGE141
 C9G13    1      A CAP_0402LF-4700PF,50V,10%,EMPTA   I102 @BASEBOARD_FAB2_LIB.BASEBOARD_FAB2(SCH_1):PAGE141

NIC_SET_P_MDI_2_DP @BASEBOARD_FAB2_LIB.BASEBOARD_FAB2(SCH_1):NIC_SET_P_MDI_2_DP
 EU9E1   53 MDI_PLUS2_SETP SPRINGVILLE_SM1-IC,G47144-004    I72 @BASEBOARD_FAB2_LIB.BASEBOARD_FAB2(SCH_1):PAGE139
 R9G18    1      A RES_0402-0.0,5%,1/16W,CHIP,G21A    I77 @BASEBOARD_FAB2_LIB.BASEBOARD_FAB2(SCH_1):PAGE141
 C9G16    1      A CAP_0402LF-4700PF,50V,10%,EMPTA   I101 @BASEBOARD_FAB2_LIB.BASEBOARD_FAB2(SCH_1):PAGE141

P0V7_GTL2014_2 @BASEBOARD_FAB2_LIB.BASEBOARD_FAB2(SCH_1):P0V7_GTL2014_2
  U9G1    4   VREF GTL2014_SM-IC,D66151-001     I1 @BASEBOARD_FAB2_LIB.BASEBOARD_FAB2(SCH_1):PAGE152
 R1U43    2      B RES_0402-49.9,1%,1/16W,CHIP,G2A    I25 @BASEBOARD_FAB2_LIB.BASEBOARD_FAB2(SCH_1):PAGE152
 R1U37    1      A RES_0402-100.0,1%,1/16W,CHIP,GA    I26 @BASEBOARD_FAB2_LIB.BASEBOARD_FAB2(SCH_1):PAGE152
 C1U22    1      A CAP_A_0402V-0.1UF,16V,10%,X7R,A    I27 @BASEBOARD_FAB2_LIB.BASEBOARD_FAB2(SCH_1):PAGE152

P0V7_GTL2104_5_VREF @BASEBOARD_FAB2_LIB.BASEBOARD_FAB2(SCH_1):P0V7_GTL2104_5_VREF
  U2T4    4   VREF GTL2014_SM-IC,D66151-001    I30 @BASEBOARD_FAB2_LIB.BASEBOARD_FAB2(SCH_1):PAGE93
 C2T32    1      A CAP_A_0402V-0.1UF,16V,10%,X7R,A    I95 @BASEBOARD_FAB2_LIB.BASEBOARD_FAB2(SCH_1):PAGE93
 R2T36    2      B RES_0402-49.9,1%,1/16W,CHIP,G2A    I97 @BASEBOARD_FAB2_LIB.BASEBOARD_FAB2(SCH_1):PAGE93
 R2T39    1      A RES_0402-100.0,1%,1/16W,CHIP,GA    I98 @BASEBOARD_FAB2_LIB.BASEBOARD_FAB2(SCH_1):PAGE93

P0V7_GTL2104_VREF_0 @BASEBOARD_FAB2_LIB.BASEBOARD_FAB2(SCH_1):P0V7_GTL2104_VREF_0
  U7D2    4   VREF GTL2014_SM-IC,D66151-001    I32 @BASEBOARD_FAB2_LIB.BASEBOARD_FAB2(SCH_1):PAGE92
 R7D32    1      A RES_0402-100.0,1%,1/16W,CHIP,GA    I48 @BASEBOARD_FAB2_LIB.BASEBOARD_FAB2(SCH_1):PAGE92
 R7D33    2      B RES_0402-49.9,1%,1/16W,CHIP,G2A    I51 @BASEBOARD_FAB2_LIB.BASEBOARD_FAB2(SCH_1):PAGE92
  C7D5    1      A CAP_A_0402V-0.1UF,16V,10%,X7R,A    I52 @BASEBOARD_FAB2_LIB.BASEBOARD_FAB2(SCH_1):PAGE92

P0V7_GTL2104_VREF_1 @BASEBOARD_FAB2_LIB.BASEBOARD_FAB2(SCH_1):P0V7_GTL2104_VREF_1
  U3P2    4   VREF GTL2014_SM-IC,D66151-001     I1 @BASEBOARD_FAB2_LIB.BASEBOARD_FAB2(SCH_1):PAGE92
 C3P49    1      A CAP_A_0402V-0.1UF,16V,10%,X7R,A    I37 @BASEBOARD_FAB2_LIB.BASEBOARD_FAB2(SCH_1):PAGE92
 R3P49    1      A RES_0402-100.0,1%,1/16W,CHIP,GA    I38 @BASEBOARD_FAB2_LIB.BASEBOARD_FAB2(SCH_1):PAGE92
 R3P45    2      B RES_0402-49.9,1%,1/16W,CHIP,G2A    I39 @BASEBOARD_FAB2_LIB.BASEBOARD_FAB2(SCH_1):PAGE92

P0V9_LAN @BASEBOARD_FAB2_LIB.BASEBOARD_FAB2(SCH_1):P0V9_LAN
 EU9E1   59 VDD0P9<0> SPRINGVILLE_SM1-IC,G47144-004    I72 @BASEBOARD_FAB2_LIB.BASEBOARD_FAB2(SCH_1):PAGE139
 EU9E1   32 VDD0P9<1> SPRINGVILLE_SM1-IC,G47144-004    I72 @BASEBOARD_FAB2_LIB.BASEBOARD_FAB2(SCH_1):PAGE139
 EU9E1   11 VDD0P9<2> SPRINGVILLE_SM1-IC,G47144-004    I72 @BASEBOARD_FAB2_LIB.BASEBOARD_FAB2(SCH_1):PAGE139
 EU9E1   42 VDD0P9<3> SPRINGVILLE_SM1-IC,G47144-004    I72 @BASEBOARD_FAB2_LIB.BASEBOARD_FAB2(SCH_1):PAGE139
  C1T4    1      A CAP_0603-10UF,6.3V,20%,X6S,E15A   I134 @BASEBOARD_FAB2_LIB.BASEBOARD_FAB2(SCH_1):PAGE139
 C1R18    1      A CAP_A_0402V-0.1UF,16V,10%,X7R,A   I157 @BASEBOARD_FAB2_LIB.BASEBOARD_FAB2(SCH_1):PAGE139
  C1T5    1      A CAP_A_0402V-0.1UF,16V,10%,X7R,A   I158 @BASEBOARD_FAB2_LIB.BASEBOARD_FAB2(SCH_1):PAGE139
 C1R24    1      A CAP_A_0402V-0.1UF,16V,10%,X7R,A   I159 @BASEBOARD_FAB2_LIB.BASEBOARD_FAB2(SCH_1):PAGE139
 C1R15    1      A CAP_A_0402V-0.1UF,16V,10%,X7R,A   I160 @BASEBOARD_FAB2_LIB.BASEBOARD_FAB2(SCH_1):PAGE139
 C1R16    1      A CAP_0603-10UF,6.3V,20%,X6S,E15A   I161 @BASEBOARD_FAB2_LIB.BASEBOARD_FAB2(SCH_1):PAGE139
  C9E1    1      A CAP_A_0603V-22.0UF,4V,20%,EMPTA   I163 @BASEBOARD_FAB2_LIB.BASEBOARD_FAB2(SCH_1):PAGE139
 R1R15    1      A RES_0603-0,5.0%,1/10W,CHIP,G22A   I237 @BASEBOARD_FAB2_LIB.BASEBOARD_FAB2(SCH_1):PAGE139
 C9E12    1      A CAP_A_0603V-22.0UF,4V,20%,EMPTA   I241 @BASEBOARD_FAB2_LIB.BASEBOARD_FAB2(SCH_1):PAGE139

P0V9_LAN_I210 @BASEBOARD_FAB2_LIB.BASEBOARD_FAB2(SCH_1):P0V9_LAN_I210
 EU9E1   38 VDD0P9_OUT SPRINGVILLE_SM1-IC,G47144-004    I72 @BASEBOARD_FAB2_LIB.BASEBOARD_FAB2(SCH_1):PAGE139
 R1R15    2      B RES_0603-0,5.0%,1/10W,CHIP,G22A   I237 @BASEBOARD_FAB2_LIB.BASEBOARD_FAB2(SCH_1):PAGE139

P12V @BASEBOARD_FAB2_LIB.BASEBOARD_FAB2(SCH_1):P12V
 C2U20    1      A CAP_A_0402V-0.1UF,16V,10%,X7R,A     I1 @BASEBOARD_FAB2_LIB.BASEBOARD_FAB2(SCH_1):PAGE108
 C2U24    1      A CAP_A_0402V-0.1UF,16V,10%,X7R,A     I2 @BASEBOARD_FAB2_LIB.BASEBOARD_FAB2(SCH_1):PAGE108
  J8G1    1    IO1 SCONN200_H68296001_SM-CONN,H68A   I258 @BASEBOARD_FAB2_LIB.BASEBOARD_FAB2(SCH_1):PAGE108
  J8G1    2    IO2 SCONN200_H68296001_SM-CONN,H68A   I258 @BASEBOARD_FAB2_LIB.BASEBOARD_FAB2(SCH_1):PAGE108
  J8G1    3    IO3 SCONN200_H68296001_SM-CONN,H68A   I258 @BASEBOARD_FAB2_LIB.BASEBOARD_FAB2(SCH_1):PAGE108
  J8G1    4    IO4 SCONN200_H68296001_SM-CONN,H68A   I258 @BASEBOARD_FAB2_LIB.BASEBOARD_FAB2(SCH_1):PAGE108
  J8G1    5    IO5 SCONN200_H68296001_SM-CONN,H68A   I258 @BASEBOARD_FAB2_LIB.BASEBOARD_FAB2(SCH_1):PAGE108
  J8G1    6    IO6 SCONN200_H68296001_SM-CONN,H68A   I258 @BASEBOARD_FAB2_LIB.BASEBOARD_FAB2(SCH_1):PAGE108
  J8G1    7    IO7 SCONN200_H68296001_SM-CONN,H68A   I258 @BASEBOARD_FAB2_LIB.BASEBOARD_FAB2(SCH_1):PAGE108
  J8G1    8    IO8 SCONN200_H68296001_SM-CONN,H68A   I258 @BASEBOARD_FAB2_LIB.BASEBOARD_FAB2(SCH_1):PAGE108
  J8G1    9    IO9 SCONN200_H68296001_SM-CONN,H68A   I258 @BASEBOARD_FAB2_LIB.BASEBOARD_FAB2(SCH_1):PAGE108
  J8G1   10   IO10 SCONN200_H68296001_SM-CONN,H68A   I258 @BASEBOARD_FAB2_LIB.BASEBOARD_FAB2(SCH_1):PAGE108
  J8G1   11   IO11 SCONN200_H68296001_SM-CONN,H68A   I258 @BASEBOARD_FAB2_LIB.BASEBOARD_FAB2(SCH_1):PAGE108
  J8G1   12   IO12 SCONN200_H68296001_SM-CONN,H68A   I258 @BASEBOARD_FAB2_LIB.BASEBOARD_FAB2(SCH_1):PAGE108
  F9B1    1   A<0> FUSE_SM-IC,C94311-016    I38 @BASEBOARD_FAB2_LIB.BASEBOARD_FAB2(SCH_1):PAGE172
 R8D38    1      A RES_0402-100.0K,1%,1/16W,CHIP,A   I112 @BASEBOARD_FAB2_LIB.BASEBOARD_FAB2(SCH_1):PAGE196
 EU7E1    6      S SLG55021_SM-IC,G56246-001    I19 @BASEBOARD_FAB2_LIB.BASEBOARD_FAB2(SCH_1):PAGE198
  C7E9    1      A CAP_A_0402V-0.1UF,16V,10%,X7R,A    I49 @BASEBOARD_FAB2_LIB.BASEBOARD_FAB2(SCH_1):PAGE198
  C7E8    1      A CAP_0805-10UF,16V,10%,X6S,C953A    I50 @BASEBOARD_FAB2_LIB.BASEBOARD_FAB2(SCH_1):PAGE198
  Q7E7    1    SRC MOSFET_N_LCC3-BSZ019N03LS,NFETA    I88 @BASEBOARD_FAB2_LIB.BASEBOARD_FAB2(SCH_1):PAGE198

P12V_FAN @BASEBOARD_FAB2_LIB.BASEBOARD_FAB2(SCH_1):P12V_FAN
  J1F2    2    IO2 CONN6_C74770005_PIP-HDR,C74770A     I1 @BASEBOARD_FAB2_LIB.BASEBOARD_FAB2(SCH_1):PAGE161
 C1E21    1      A CAP_0805-10UF,16V,10%,X6S,C953A     I3 @BASEBOARD_FAB2_LIB.BASEBOARD_FAB2(SCH_1):PAGE161
 C1E20    1      A CAP_A_0402V-0.1UF,16V,10%,X7R,A     I4 @BASEBOARD_FAB2_LIB.BASEBOARD_FAB2(SCH_1):PAGE161
  C9M5    1      A CAP_A_0402V-0.1UF,16V,10%,X7R,A    I26 @BASEBOARD_FAB2_LIB.BASEBOARD_FAB2(SCH_1):PAGE161
  C9M4    1      A CAP_0805-10UF,16V,10%,X6S,C953A    I27 @BASEBOARD_FAB2_LIB.BASEBOARD_FAB2(SCH_1):PAGE161
  J1B2    2    IO2 CONN6_C74770005_PIP-HDR,C74770A    I32 @BASEBOARD_FAB2_LIB.BASEBOARD_FAB2(SCH_1):PAGE161
 C1B18    1      A CAP_0805-10UF,16V,10%,X6S,C953A    I61 @BASEBOARD_FAB2_LIB.BASEBOARD_FAB2(SCH_1):PAGE198
 C1B19    1      A CAP_A_0402V-0.1UF,16V,10%,X7R,A    I64 @BASEBOARD_FAB2_LIB.BASEBOARD_FAB2(SCH_1):PAGE198
 EU9M1    6      S SLG55021_SM-IC,G56246-001    I69 @BASEBOARD_FAB2_LIB.BASEBOARD_FAB2(SCH_1):PAGE198
  Q1B1    1    SRC MOSFET_N_LCC3-BSZ019N03LS,NFETA    I86 @BASEBOARD_FAB2_LIB.BASEBOARD_FAB2(SCH_1):PAGE198

P12V_FAN_SWITCH_G @BASEBOARD_FAB2_LIB.BASEBOARD_FAB2(SCH_1):P12V_FAN_SWITCH_G
 EU9M1    7      G SLG55021_SM-IC,G56246-001    I69 @BASEBOARD_FAB2_LIB.BASEBOARD_FAB2(SCH_1):PAGE198
  Q1B1    4   GATE MOSFET_N_LCC3-BSZ019N03LS,NFETA    I86 @BASEBOARD_FAB2_LIB.BASEBOARD_FAB2(SCH_1):PAGE198

P12V_HDD_SATA @BASEBOARD_FAB2_LIB.BASEBOARD_FAB2(SCH_1):P12V_HDD_SATA
  J8A4    4    IO4 CONN4_H73295001_PIP-EMPTY,H732A    I25 @BASEBOARD_FAB2_LIB.BASEBOARD_FAB2(SCH_1):PAGE172
  C9B2    1      A CAP_0805-10UF,16V,10%,X6S,C953A    I36 @BASEBOARD_FAB2_LIB.BASEBOARD_FAB2(SCH_1):PAGE172
  F9B1    2   B<0> FUSE_SM-IC,C94311-016    I38 @BASEBOARD_FAB2_LIB.BASEBOARD_FAB2(SCH_1):PAGE172
  J2L1    4    IO4 CONN4_H73295001_PIP-CONN,H7329A    I53 @BASEBOARD_FAB2_LIB.BASEBOARD_FAB2(SCH_1):PAGE172

P12V_HSC_SENN0 @BASEBOARD_FAB2_LIB.BASEBOARD_FAB2(SCH_1):P12V_HSC_SENN0
 R1D49    4      4 RES_PWR_6PAD-0.001,1%,3W,CHIP,A    I50 @BASEBOARD_FAB2_LIB.BASEBOARD_FAB2(SCH_1):PAGE200
 R1D47    1      A RES_0402-10.0,1%,1/16W,CHIP,G2A    I52 @BASEBOARD_FAB2_LIB.BASEBOARD_FAB2(SCH_1):PAGE200

P12V_HSC_SENN1 @BASEBOARD_FAB2_LIB.BASEBOARD_FAB2(SCH_1):P12V_HSC_SENN1
  R9R1    4      4 RES_PWR_6PAD-0.001,1%,3W,CHIP,A    I49 @BASEBOARD_FAB2_LIB.BASEBOARD_FAB2(SCH_1):PAGE200
 R9P26    1      A RES_0402-10.0,1%,1/16W,CHIP,G2A    I51 @BASEBOARD_FAB2_LIB.BASEBOARD_FAB2(SCH_1):PAGE200

P12V_HSC_SENP0 @BASEBOARD_FAB2_LIB.BASEBOARD_FAB2(SCH_1):P12V_HSC_SENP0
 R1D46    1      A RES_0402-10.0,1%,1/16W,CHIP,G2A    I48 @BASEBOARD_FAB2_LIB.BASEBOARD_FAB2(SCH_1):PAGE200
 R1D49    3      3 RES_PWR_6PAD-0.001,1%,3W,CHIP,A    I50 @BASEBOARD_FAB2_LIB.BASEBOARD_FAB2(SCH_1):PAGE200

P12V_HSC_SENP1 @BASEBOARD_FAB2_LIB.BASEBOARD_FAB2(SCH_1):P12V_HSC_SENP1
 R9P27    1      A RES_0402-10.0,1%,1/16W,CHIP,G2A    I47 @BASEBOARD_FAB2_LIB.BASEBOARD_FAB2(SCH_1):PAGE200
  R9R1    3      3 RES_PWR_6PAD-0.001,1%,3W,CHIP,A    I49 @BASEBOARD_FAB2_LIB.BASEBOARD_FAB2(SCH_1):PAGE200

P12V_HSC_VCC @BASEBOARD_FAB2_LIB.BASEBOARD_FAB2(SCH_1):P12V_HSC_VCC
 R9P30    2      B RES_0603-10.0,1%,1/10W,CHIP,G2A     I2 @BASEBOARD_FAB2_LIB.BASEBOARD_FAB2(SCH_1):PAGE199
 C1D25    1      A CAP_0402-1.0UF,16V,10%,X6S,D97A     I3 @BASEBOARD_FAB2_LIB.BASEBOARD_FAB2(SCH_1):PAGE199
 EU1D2   30    VCC ADM1278_SM-IC,G99251-001    I10 @BASEBOARD_FAB2_LIB.BASEBOARD_FAB2(SCH_1):PAGE199

P12V_MB0_SW @BASEBOARD_FAB2_LIB.BASEBOARD_FAB2(SCH_1):P12V_MB0_SW
  R9R1    2      2 RES_PWR_6PAD-0.001,1%,3W,CHIP,A    I49 @BASEBOARD_FAB2_LIB.BASEBOARD_FAB2(SCH_1):PAGE200
  R9R1    6      6 RES_PWR_6PAD-0.001,1%,3W,CHIP,A    I49 @BASEBOARD_FAB2_LIB.BASEBOARD_FAB2(SCH_1):PAGE200
 R1D49    2      2 RES_PWR_6PAD-0.001,1%,3W,CHIP,A    I50 @BASEBOARD_FAB2_LIB.BASEBOARD_FAB2(SCH_1):PAGE200
 R1D49    6      6 RES_PWR_6PAD-0.001,1%,3W,CHIP,A    I50 @BASEBOARD_FAB2_LIB.BASEBOARD_FAB2(SCH_1):PAGE200
 EU1E3    5      D MOSFETN_1D3S_SOT5-IC,G68777-001    I54 @BASEBOARD_FAB2_LIB.BASEBOARD_FAB2(SCH_1):PAGE200
 EU9R1    5      D MOSFETN_1D3S_SOT5-IC,G68777-001    I57 @BASEBOARD_FAB2_LIB.BASEBOARD_FAB2(SCH_1):PAGE200
 EU1E1    5      D MOSFETN_1D3S_SOT5-IC,G68777-001    I59 @BASEBOARD_FAB2_LIB.BASEBOARD_FAB2(SCH_1):PAGE200

P12V_NVDIMM_ABC @BASEBOARD_FAB2_LIB.BASEBOARD_FAB2(SCH_1):P12V_NVDIMM_ABC
  J4G1  145 12V<0> SCONN288_H44441004_PIP-SCONN,HA   I260 @BASEBOARD_FAB2_LIB.BASEBOARD_FAB2(SCH_1):PAGE43
  J4G1    1 12V<1> SCONN288_H44441004_PIP-SCONN,HA   I260 @BASEBOARD_FAB2_LIB.BASEBOARD_FAB2(SCH_1):PAGE43
  J6T1  145 12V<0> SCONN288_H44441003_PIP-SCONN,HA    I75 @BASEBOARD_FAB2_LIB.BASEBOARD_FAB2(SCH_1):PAGE44
  J6T1    1 12V<1> SCONN288_H44441003_PIP-SCONN,HA    I75 @BASEBOARD_FAB2_LIB.BASEBOARD_FAB2(SCH_1):PAGE44
  J4G2  145 12V<0> SCONN288_H44441004_PIP-SCONN,HA   I169 @BASEBOARD_FAB2_LIB.BASEBOARD_FAB2(SCH_1):PAGE45
  J4G2    1 12V<1> SCONN288_H44441004_PIP-SCONN,HA   I169 @BASEBOARD_FAB2_LIB.BASEBOARD_FAB2(SCH_1):PAGE45
  J6U1  145 12V<0> SCONN288_H44441003_PIP-SCONN,HA    I67 @BASEBOARD_FAB2_LIB.BASEBOARD_FAB2(SCH_1):PAGE46
  J6U1    1 12V<1> SCONN288_H44441003_PIP-SCONN,HA    I67 @BASEBOARD_FAB2_LIB.BASEBOARD_FAB2(SCH_1):PAGE46
  J4G3  145 12V<0> SCONN288_H44441004_PIP-SCONN,HA   I179 @BASEBOARD_FAB2_LIB.BASEBOARD_FAB2(SCH_1):PAGE47
  J4G3    1 12V<1> SCONN288_H44441004_PIP-SCONN,HA   I179 @BASEBOARD_FAB2_LIB.BASEBOARD_FAB2(SCH_1):PAGE47
  J6U2  145 12V<0> SCONN288_H44441003_PIP-SCONN,HA   I171 @BASEBOARD_FAB2_LIB.BASEBOARD_FAB2(SCH_1):PAGE48
  J6U2    1 12V<1> SCONN288_H44441003_PIP-SCONN,HA   I171 @BASEBOARD_FAB2_LIB.BASEBOARD_FAB2(SCH_1):PAGE48
 C6U18    1      A CAP_0805-10UF,16V,10%,X7R,G106A    I52 @BASEBOARD_FAB2_LIB.BASEBOARD_FAB2(SCH_1):PAGE197
  C6T2    1      A CAP_0805-10UF,16V,10%,X7R,G106A    I54 @BASEBOARD_FAB2_LIB.BASEBOARD_FAB2(SCH_1):PAGE197
 C6U10    1      A CAP_0805-10UF,16V,10%,X7R,G106A    I65 @BASEBOARD_FAB2_LIB.BASEBOARD_FAB2(SCH_1):PAGE197
  U4F1    4    RSN MAX9634_SOT-IC,H35789-001    I97 @BASEBOARD_FAB2_LIB.BASEBOARD_FAB2(SCH_1):PAGE197
  R4F2    1      A RES_1206-0.002,1%,1W,CHIP,G521A    I99 @BASEBOARD_FAB2_LIB.BASEBOARD_FAB2(SCH_1):PAGE197

P12V_NVDIMM_DEF @BASEBOARD_FAB2_LIB.BASEBOARD_FAB2(SCH_1):P12V_NVDIMM_DEF
  J4B1  145 12V<0> SCONN288_H44441004_PIP-SCONN,HA   I169 @BASEBOARD_FAB2_LIB.BASEBOARD_FAB2(SCH_1):PAGE49
  J4B1    1 12V<1> SCONN288_H44441004_PIP-SCONN,HA   I169 @BASEBOARD_FAB2_LIB.BASEBOARD_FAB2(SCH_1):PAGE49
  J6M1  145 12V<0> SCONN288_H44441003_PIP-SCONN,HA    I50 @BASEBOARD_FAB2_LIB.BASEBOARD_FAB2(SCH_1):PAGE50
  J6M1    1 12V<1> SCONN288_H44441003_PIP-SCONN,HA    I50 @BASEBOARD_FAB2_LIB.BASEBOARD_FAB2(SCH_1):PAGE50
  J4A2  145 12V<0> SCONN288_H44441004_PIP-SCONN,HA   I167 @BASEBOARD_FAB2_LIB.BASEBOARD_FAB2(SCH_1):PAGE51
  J4A2    1 12V<1> SCONN288_H44441004_PIP-SCONN,HA   I167 @BASEBOARD_FAB2_LIB.BASEBOARD_FAB2(SCH_1):PAGE51
  J6L2  145 12V<0> SCONN288_H44441003_PIP-SCONN,HA    I55 @BASEBOARD_FAB2_LIB.BASEBOARD_FAB2(SCH_1):PAGE52
  J6L2    1 12V<1> SCONN288_H44441003_PIP-SCONN,HA    I55 @BASEBOARD_FAB2_LIB.BASEBOARD_FAB2(SCH_1):PAGE52
  J4A1  145 12V<0> SCONN288_H44441004_PIP-SCONN,HA   I171 @BASEBOARD_FAB2_LIB.BASEBOARD_FAB2(SCH_1):PAGE53
  J4A1    1 12V<1> SCONN288_H44441004_PIP-SCONN,HA   I171 @BASEBOARD_FAB2_LIB.BASEBOARD_FAB2(SCH_1):PAGE53
  J6L1  145 12V<0> SCONN288_H44441003_PIP-SCONN,HA   I170 @BASEBOARD_FAB2_LIB.BASEBOARD_FAB2(SCH_1):PAGE54
  J6L1    1 12V<1> SCONN288_H44441003_PIP-SCONN,HA   I170 @BASEBOARD_FAB2_LIB.BASEBOARD_FAB2(SCH_1):PAGE54
 C4B11    1      A CAP_0805-10UF,16V,10%,X7R,G106A    I59 @BASEBOARD_FAB2_LIB.BASEBOARD_FAB2(SCH_1):PAGE197
  C4A4    1      A CAP_0805-10UF,16V,10%,X7R,G106A    I62 @BASEBOARD_FAB2_LIB.BASEBOARD_FAB2(SCH_1):PAGE197
 C4A17    1      A CAP_0805-10UF,16V,10%,X7R,G106A    I67 @BASEBOARD_FAB2_LIB.BASEBOARD_FAB2(SCH_1):PAGE197
  U4B1    4    RSN MAX9634_SOT-IC,H35789-001   I120 @BASEBOARD_FAB2_LIB.BASEBOARD_FAB2(SCH_1):PAGE197
 R4B12    1      A RES_1206-0.002,1%,1W,CHIP,G521A   I121 @BASEBOARD_FAB2_LIB.BASEBOARD_FAB2(SCH_1):PAGE197

P12V_NVDIMM_GHJ @BASEBOARD_FAB2_LIB.BASEBOARD_FAB2(SCH_1):P12V_NVDIMM_GHJ
  J1G1  145 12V<0> SCONN288_H44441004_PIP-SCONN,HA   I171 @BASEBOARD_FAB2_LIB.BASEBOARD_FAB2(SCH_1):PAGE77
  J1G1    1 12V<1> SCONN288_H44441004_PIP-SCONN,HA   I171 @BASEBOARD_FAB2_LIB.BASEBOARD_FAB2(SCH_1):PAGE77
  J9T1  145 12V<0> SCONN288_H44441003_PIP-SCONN,HA    I75 @BASEBOARD_FAB2_LIB.BASEBOARD_FAB2(SCH_1):PAGE78
  J9T1    1 12V<1> SCONN288_H44441003_PIP-SCONN,HA    I75 @BASEBOARD_FAB2_LIB.BASEBOARD_FAB2(SCH_1):PAGE78
  J1G2  145 12V<0> SCONN288_H44441004_PIP-SCONN,HA   I169 @BASEBOARD_FAB2_LIB.BASEBOARD_FAB2(SCH_1):PAGE79
  J1G2    1 12V<1> SCONN288_H44441004_PIP-SCONN,HA   I169 @BASEBOARD_FAB2_LIB.BASEBOARD_FAB2(SCH_1):PAGE79
  J9U1  145 12V<0> SCONN288_H44441003_PIP-SCONN,HA    I56 @BASEBOARD_FAB2_LIB.BASEBOARD_FAB2(SCH_1):PAGE80
  J9U1    1 12V<1> SCONN288_H44441003_PIP-SCONN,HA    I56 @BASEBOARD_FAB2_LIB.BASEBOARD_FAB2(SCH_1):PAGE80
  J1G3  145 12V<0> SCONN288_H44441004_PIP-SCONN,HA   I169 @BASEBOARD_FAB2_LIB.BASEBOARD_FAB2(SCH_1):PAGE81
  J1G3    1 12V<1> SCONN288_H44441004_PIP-SCONN,HA   I169 @BASEBOARD_FAB2_LIB.BASEBOARD_FAB2(SCH_1):PAGE81
  J9U2  145 12V<0> SCONN288_H44441003_PIP-SCONN,HA   I171 @BASEBOARD_FAB2_LIB.BASEBOARD_FAB2(SCH_1):PAGE82
  J9U2    1 12V<1> SCONN288_H44441003_PIP-SCONN,HA   I171 @BASEBOARD_FAB2_LIB.BASEBOARD_FAB2(SCH_1):PAGE82
  C9T8    1      A CAP_0805-10UF,16V,10%,X7R,G106A    I70 @BASEBOARD_FAB2_LIB.BASEBOARD_FAB2(SCH_1):PAGE197
 C9U11    1      A CAP_0805-10UF,16V,10%,X7R,G106A    I73 @BASEBOARD_FAB2_LIB.BASEBOARD_FAB2(SCH_1):PAGE197
  C9U8    1      A CAP_0805-10UF,16V,10%,X7R,G106A    I76 @BASEBOARD_FAB2_LIB.BASEBOARD_FAB2(SCH_1):PAGE197
  R1F3    1      A RES_1206-0.002,1%,1W,CHIP,G521A   I131 @BASEBOARD_FAB2_LIB.BASEBOARD_FAB2(SCH_1):PAGE197
  U1F1    4    RSN MAX9634_SOT-IC,H35789-001   I133 @BASEBOARD_FAB2_LIB.BASEBOARD_FAB2(SCH_1):PAGE197

P12V_NVDIMM_KLM @BASEBOARD_FAB2_LIB.BASEBOARD_FAB2(SCH_1):P12V_NVDIMM_KLM
  J1B1  145 12V<0> SCONN288_H44441004_PIP-SCONN,HA   I167 @BASEBOARD_FAB2_LIB.BASEBOARD_FAB2(SCH_1):PAGE83
  J1B1    1 12V<1> SCONN288_H44441004_PIP-SCONN,HA   I167 @BASEBOARD_FAB2_LIB.BASEBOARD_FAB2(SCH_1):PAGE83
  J9M1  145 12V<0> SCONN288_H44441003_PIP-SCONN,HA    I57 @BASEBOARD_FAB2_LIB.BASEBOARD_FAB2(SCH_1):PAGE84
  J9M1    1 12V<1> SCONN288_H44441003_PIP-SCONN,HA    I57 @BASEBOARD_FAB2_LIB.BASEBOARD_FAB2(SCH_1):PAGE84
  J1A2  145 12V<0> SCONN288_H44441004_PIP-SCONN,HA   I172 @BASEBOARD_FAB2_LIB.BASEBOARD_FAB2(SCH_1):PAGE85
  J1A2    1 12V<1> SCONN288_H44441004_PIP-SCONN,HA   I172 @BASEBOARD_FAB2_LIB.BASEBOARD_FAB2(SCH_1):PAGE85
  J9L2  145 12V<0> SCONN288_H44441003_PIP-SCONN,HA    I55 @BASEBOARD_FAB2_LIB.BASEBOARD_FAB2(SCH_1):PAGE86
  J9L2    1 12V<1> SCONN288_H44441003_PIP-SCONN,HA    I55 @BASEBOARD_FAB2_LIB.BASEBOARD_FAB2(SCH_1):PAGE86
  J1A1  145 12V<0> SCONN288_H44441004_PIP-SCONN,HA   I169 @BASEBOARD_FAB2_LIB.BASEBOARD_FAB2(SCH_1):PAGE87
  J1A1    1 12V<1> SCONN288_H44441004_PIP-SCONN,HA   I169 @BASEBOARD_FAB2_LIB.BASEBOARD_FAB2(SCH_1):PAGE87
  J9L1  145 12V<0> SCONN288_H44441003_PIP-SCONN,HA   I168 @BASEBOARD_FAB2_LIB.BASEBOARD_FAB2(SCH_1):PAGE88
  J9L1    1 12V<1> SCONN288_H44441003_PIP-SCONN,HA   I168 @BASEBOARD_FAB2_LIB.BASEBOARD_FAB2(SCH_1):PAGE88
  C1A4    1      A CAP_0805-10UF,16V,10%,X7R,G106A    I79 @BASEBOARD_FAB2_LIB.BASEBOARD_FAB2(SCH_1):PAGE197
  C1B7    1      A CAP_0805-10UF,16V,10%,X7R,G106A    I82 @BASEBOARD_FAB2_LIB.BASEBOARD_FAB2(SCH_1):PAGE197
 C1A16    1      A CAP_0805-10UF,16V,10%,X7R,G106A    I85 @BASEBOARD_FAB2_LIB.BASEBOARD_FAB2(SCH_1):PAGE197
  R9M4    1      A RES_1206-0.002,1%,1W,CHIP,G521A   I142 @BASEBOARD_FAB2_LIB.BASEBOARD_FAB2(SCH_1):PAGE197
  U1B1    4    RSN MAX9634_SOT-IC,H35789-001   I144 @BASEBOARD_FAB2_LIB.BASEBOARD_FAB2(SCH_1):PAGE197

P12V_PSU @BASEBOARD_FAB2_LIB.BASEBOARD_FAB2(SCH_1):P12V_PSU
  R9T9    1      A RES_0402-4.75K,1%,1/16W,CHIP,GA   I177 @BASEBOARD_FAB2_LIB.BASEBOARD_FAB2(SCH_1):PAGE181
  R9T6    1      A RES_0402-15.0K,1%,1/16W,CHIP,GA   I183 @BASEBOARD_FAB2_LIB.BASEBOARD_FAB2(SCH_1):PAGE181
  J1E1   A1     A1 CONN12_G98257001_THMT-CONN,G98A    I29 @BASEBOARD_FAB2_LIB.BASEBOARD_FAB2(SCH_1):PAGE195
  J1E1   A2     A2 CONN12_G98257001_THMT-CONN,G98A    I29 @BASEBOARD_FAB2_LIB.BASEBOARD_FAB2(SCH_1):PAGE195
  J1E1   A3     A3 CONN12_G98257001_THMT-CONN,G98A    I29 @BASEBOARD_FAB2_LIB.BASEBOARD_FAB2(SCH_1):PAGE195
  J1E1   B1     B1 CONN12_G98257001_THMT-CONN,G98A    I29 @BASEBOARD_FAB2_LIB.BASEBOARD_FAB2(SCH_1):PAGE195
  J1E1   B2     B2 CONN12_G98257001_THMT-CONN,G98A    I29 @BASEBOARD_FAB2_LIB.BASEBOARD_FAB2(SCH_1):PAGE195
  J1E1   B3     B3 CONN12_G98257001_THMT-CONN,G98A    I29 @BASEBOARD_FAB2_LIB.BASEBOARD_FAB2(SCH_1):PAGE195
  C9R5    1      A CAP_0805-10UF,16V,10%,X6S,C953A    I31 @BASEBOARD_FAB2_LIB.BASEBOARD_FAB2(SCH_1):PAGE195
 C1E12    1      A CAP_0805-10UF,16V,10%,X6S,C953A    I32 @BASEBOARD_FAB2_LIB.BASEBOARD_FAB2(SCH_1):PAGE195
 C1E15    1      A CAP_0805-10UF,16V,10%,X6S,C953A    I35 @BASEBOARD_FAB2_LIB.BASEBOARD_FAB2(SCH_1):PAGE195
 C9R12    1      A CAP_A_0402V-0.1UF,16V,10%,X7R,A    I36 @BASEBOARD_FAB2_LIB.BASEBOARD_FAB2(SCH_1):PAGE195
  C9R6    1      A CAP_A_0402V-0.1UF,16V,10%,X7R,A    I37 @BASEBOARD_FAB2_LIB.BASEBOARD_FAB2(SCH_1):PAGE195
 C1E17    1      A CAP_A_0402V-0.1UF,16V,10%,X7R,A    I38 @BASEBOARD_FAB2_LIB.BASEBOARD_FAB2(SCH_1):PAGE195
 C1E16    1      A CAP_A_0402V-0.1UF,16V,10%,X7R,A    I39 @BASEBOARD_FAB2_LIB.BASEBOARD_FAB2(SCH_1):PAGE195
  J1D1   A1     A1 CONN12_G98257001_THMT-CONN,G98A    I78 @BASEBOARD_FAB2_LIB.BASEBOARD_FAB2(SCH_1):PAGE195
  J1D1   A2     A2 CONN12_G98257001_THMT-CONN,G98A    I78 @BASEBOARD_FAB2_LIB.BASEBOARD_FAB2(SCH_1):PAGE195
  J1D1   A3     A3 CONN12_G98257001_THMT-CONN,G98A    I78 @BASEBOARD_FAB2_LIB.BASEBOARD_FAB2(SCH_1):PAGE195
  J1D1   B1     B1 CONN12_G98257001_THMT-CONN,G98A    I78 @BASEBOARD_FAB2_LIB.BASEBOARD_FAB2(SCH_1):PAGE195
  J1D1   B2     B2 CONN12_G98257001_THMT-CONN,G98A    I78 @BASEBOARD_FAB2_LIB.BASEBOARD_FAB2(SCH_1):PAGE195
  J1D1   B3     B3 CONN12_G98257001_THMT-CONN,G98A    I78 @BASEBOARD_FAB2_LIB.BASEBOARD_FAB2(SCH_1):PAGE195
 R9P30    1      A RES_0603-10.0,1%,1/10W,CHIP,G2A     I2 @BASEBOARD_FAB2_LIB.BASEBOARD_FAB2(SCH_1):PAGE199
 R9P28    1      A RES_0402-100.0K,1%,1/16W,CHIP,A     I6 @BASEBOARD_FAB2_LIB.BASEBOARD_FAB2(SCH_1):PAGE199
 R9P29    1      A RES_0402-100.0K,1%,1/16W,CHIP,A    I12 @BASEBOARD_FAB2_LIB.BASEBOARD_FAB2(SCH_1):PAGE199
 R1D15    1      A RES_0402-100.0K,1%,1/16W,CHIP,A    I92 @BASEBOARD_FAB2_LIB.BASEBOARD_FAB2(SCH_1):PAGE199
 VR1D1    1      C ZENER_SM-13V,IC,H69095-001    I99 @BASEBOARD_FAB2_LIB.BASEBOARD_FAB2(SCH_1):PAGE199
  R9R1    1      1 RES_PWR_6PAD-0.001,1%,3W,CHIP,A    I49 @BASEBOARD_FAB2_LIB.BASEBOARD_FAB2(SCH_1):PAGE200
  R9R1    5      5 RES_PWR_6PAD-0.001,1%,3W,CHIP,A    I49 @BASEBOARD_FAB2_LIB.BASEBOARD_FAB2(SCH_1):PAGE200
 R1D49    1      1 RES_PWR_6PAD-0.001,1%,3W,CHIP,A    I50 @BASEBOARD_FAB2_LIB.BASEBOARD_FAB2(SCH_1):PAGE200
 R1D49    5      5 RES_PWR_6PAD-0.001,1%,3W,CHIP,A    I50 @BASEBOARD_FAB2_LIB.BASEBOARD_FAB2(SCH_1):PAGE200

P12V_STBY @BASEBOARD_FAB2_LIB.BASEBOARD_FAB2(SCH_1):P12V_STBY
  R1L9    1      A RES_0402-100.0K,1%,1/16W,CHIP,A   I130 @BASEBOARD_FAB2_LIB.BASEBOARD_FAB2(SCH_1):PAGE155
 R1U32    1      A RES_0402-5.11K,1%,1/16W,CHIP,GA    I82 @BASEBOARD_FAB2_LIB.BASEBOARD_FAB2(SCH_1):PAGE169
 C1M27    1      A CAP_0805-10UF,16V,10%,X6S,C953A     I3 @BASEBOARD_FAB2_LIB.BASEBOARD_FAB2(SCH_1):PAGE186
 C1M26    1      A CAP_0805-10UF,16V,10%,X6S,C953A     I6 @BASEBOARD_FAB2_LIB.BASEBOARD_FAB2(SCH_1):PAGE186
 C1M23    1      A CAP_A_0402V-0.1UF,16V,10%,X7R,A     I7 @BASEBOARD_FAB2_LIB.BASEBOARD_FAB2(SCH_1):PAGE186
 C1M22    1      A CAP_A_0402V-0.1UF,16V,10%,X7R,A     I8 @BASEBOARD_FAB2_LIB.BASEBOARD_FAB2(SCH_1):PAGE186
  J9B3    2    IO2 SCONN120_A28699018_SM-SCONN,A2A   I336 @BASEBOARD_FAB2_LIB.BASEBOARD_FAB2(SCH_1):PAGE186
  J9B3    4    IO4 SCONN120_A28699018_SM-SCONN,A2A   I336 @BASEBOARD_FAB2_LIB.BASEBOARD_FAB2(SCH_1):PAGE186
  J9B3    6    IO6 SCONN120_A28699018_SM-SCONN,A2A   I336 @BASEBOARD_FAB2_LIB.BASEBOARD_FAB2(SCH_1):PAGE186
  J8E3    2    IO2 SCONN80_E67482007_SM-CONN,E674A   I119 @BASEBOARD_FAB2_LIB.BASEBOARD_FAB2(SCH_1):PAGE187
  J8E3    4    IO4 SCONN80_E67482007_SM-CONN,E674A   I119 @BASEBOARD_FAB2_LIB.BASEBOARD_FAB2(SCH_1):PAGE187
 C2R15    1      A CAP_A_0402V-0.1UF,16V,10%,X7R,A     I2 @BASEBOARD_FAB2_LIB.BASEBOARD_FAB2(SCH_1):PAGE188
 C2R18    1      A CAP_A_0402V-0.1UF,16V,10%,X7R,A     I3 @BASEBOARD_FAB2_LIB.BASEBOARD_FAB2(SCH_1):PAGE188
 C2P11    1      A CAP_A_0402V-0.1UF,16V,10%,X7R,A    I21 @BASEBOARD_FAB2_LIB.BASEBOARD_FAB2(SCH_1):PAGE188
 C2P12    1      A CAP_A_0402V-0.1UF,16V,10%,X7R,A    I23 @BASEBOARD_FAB2_LIB.BASEBOARD_FAB2(SCH_1):PAGE188
 C2R17    1      A CAP_A_0402V-0.1UF,16V,10%,X7R,A    I25 @BASEBOARD_FAB2_LIB.BASEBOARD_FAB2(SCH_1):PAGE188
  J8E4   33   IO33 SCONN64_H87568002_A_SMT-CONN,HA    I27 @BASEBOARD_FAB2_LIB.BASEBOARD_FAB2(SCH_1):PAGE188
  J8E4   34   IO34 SCONN64_H87568002_A_SMT-CONN,HA    I27 @BASEBOARD_FAB2_LIB.BASEBOARD_FAB2(SCH_1):PAGE188
  J8E4   35   IO35 SCONN64_H87568002_A_SMT-CONN,HA    I27 @BASEBOARD_FAB2_LIB.BASEBOARD_FAB2(SCH_1):PAGE188
 C2R16    1      A CAP_A_0402V-0.1UF,16V,10%,X7R,A    I40 @BASEBOARD_FAB2_LIB.BASEBOARD_FAB2(SCH_1):PAGE188
 C2P10    1      A CAP_1206LF-22UF,16V,10%,X6S,D3A    I41 @BASEBOARD_FAB2_LIB.BASEBOARD_FAB2(SCH_1):PAGE188
 C2P16    1      A CAP_A_0402V-0.1UF,16V,10%,X7R,A    I53 @BASEBOARD_FAB2_LIB.BASEBOARD_FAB2(SCH_1):PAGE188
 C2P15    1      A CAP_A_0402V-0.1UF,16V,10%,X7R,A    I55 @BASEBOARD_FAB2_LIB.BASEBOARD_FAB2(SCH_1):PAGE188
 C2P14    1      A CAP_A_0402V-0.1UF,16V,10%,X7R,A    I56 @BASEBOARD_FAB2_LIB.BASEBOARD_FAB2(SCH_1):PAGE188
 C2P13    1      A CAP_A_0402V-0.1UF,16V,10%,X7R,A    I57 @BASEBOARD_FAB2_LIB.BASEBOARD_FAB2(SCH_1):PAGE188
  J4B2   A1   IOA1 SCONN120_H61426002_SM-CONN,H61A    I46 @BASEBOARD_FAB2_LIB.BASEBOARD_FAB2(SCH_1):PAGE193
  J4B2   A2   IOA2 SCONN120_H61426002_SM-CONN,H61A    I46 @BASEBOARD_FAB2_LIB.BASEBOARD_FAB2(SCH_1):PAGE193
  J4B2   A3   IOA3 SCONN120_H61426002_SM-CONN,H61A    I46 @BASEBOARD_FAB2_LIB.BASEBOARD_FAB2(SCH_1):PAGE193
  J4B2   A4   IOA4 SCONN120_H61426002_SM-CONN,H61A    I46 @BASEBOARD_FAB2_LIB.BASEBOARD_FAB2(SCH_1):PAGE193
  J4B2   A5   IOA5 SCONN120_H61426002_SM-CONN,H61A    I46 @BASEBOARD_FAB2_LIB.BASEBOARD_FAB2(SCH_1):PAGE193
  J4B2   A6   IOA6 SCONN120_H61426002_SM-CONN,H61A    I46 @BASEBOARD_FAB2_LIB.BASEBOARD_FAB2(SCH_1):PAGE193
  J4B2   A7   IOA7 SCONN120_H61426002_SM-CONN,H61A    I46 @BASEBOARD_FAB2_LIB.BASEBOARD_FAB2(SCH_1):PAGE193
  J4B2   A8   IOA8 SCONN120_H61426002_SM-CONN,H61A    I46 @BASEBOARD_FAB2_LIB.BASEBOARD_FAB2(SCH_1):PAGE193
  J4B2   B1   IOB1 SCONN120_H61426002_SM-CONN,H61A    I46 @BASEBOARD_FAB2_LIB.BASEBOARD_FAB2(SCH_1):PAGE193
  J4B2   B2   IOB2 SCONN120_H61426002_SM-CONN,H61A    I46 @BASEBOARD_FAB2_LIB.BASEBOARD_FAB2(SCH_1):PAGE193
  J4B2   B3   IOB3 SCONN120_H61426002_SM-CONN,H61A    I46 @BASEBOARD_FAB2_LIB.BASEBOARD_FAB2(SCH_1):PAGE193
  J4B2   B4   IOB4 SCONN120_H61426002_SM-CONN,H61A    I46 @BASEBOARD_FAB2_LIB.BASEBOARD_FAB2(SCH_1):PAGE193
  J4B2   B5   IOB5 SCONN120_H61426002_SM-CONN,H61A    I46 @BASEBOARD_FAB2_LIB.BASEBOARD_FAB2(SCH_1):PAGE193
  J4B2   B6   IOB6 SCONN120_H61426002_SM-CONN,H61A    I46 @BASEBOARD_FAB2_LIB.BASEBOARD_FAB2(SCH_1):PAGE193
  J4B2   B7   IOB7 SCONN120_H61426002_SM-CONN,H61A    I46 @BASEBOARD_FAB2_LIB.BASEBOARD_FAB2(SCH_1):PAGE193
  J4B2   B8   IOB8 SCONN120_H61426002_SM-CONN,H61A    I46 @BASEBOARD_FAB2_LIB.BASEBOARD_FAB2(SCH_1):PAGE193
  J6B1   A1   IOA1 SCONN120_H61426002_SM-CONN,H61A    I56 @BASEBOARD_FAB2_LIB.BASEBOARD_FAB2(SCH_1):PAGE194
  J6B1   A2   IOA2 SCONN120_H61426002_SM-CONN,H61A    I56 @BASEBOARD_FAB2_LIB.BASEBOARD_FAB2(SCH_1):PAGE194
  J6B1   A3   IOA3 SCONN120_H61426002_SM-CONN,H61A    I56 @BASEBOARD_FAB2_LIB.BASEBOARD_FAB2(SCH_1):PAGE194
  J6B1   A4   IOA4 SCONN120_H61426002_SM-CONN,H61A    I56 @BASEBOARD_FAB2_LIB.BASEBOARD_FAB2(SCH_1):PAGE194
  J6B1   A5   IOA5 SCONN120_H61426002_SM-CONN,H61A    I56 @BASEBOARD_FAB2_LIB.BASEBOARD_FAB2(SCH_1):PAGE194
  J6B1   A6   IOA6 SCONN120_H61426002_SM-CONN,H61A    I56 @BASEBOARD_FAB2_LIB.BASEBOARD_FAB2(SCH_1):PAGE194
  J6B1   A7   IOA7 SCONN120_H61426002_SM-CONN,H61A    I56 @BASEBOARD_FAB2_LIB.BASEBOARD_FAB2(SCH_1):PAGE194
  J6B1   A8   IOA8 SCONN120_H61426002_SM-CONN,H61A    I56 @BASEBOARD_FAB2_LIB.BASEBOARD_FAB2(SCH_1):PAGE194
  J6B1   B1   IOB1 SCONN120_H61426002_SM-CONN,H61A    I56 @BASEBOARD_FAB2_LIB.BASEBOARD_FAB2(SCH_1):PAGE194
  J6B1   B2   IOB2 SCONN120_H61426002_SM-CONN,H61A    I56 @BASEBOARD_FAB2_LIB.BASEBOARD_FAB2(SCH_1):PAGE194
  J6B1   B3   IOB3 SCONN120_H61426002_SM-CONN,H61A    I56 @BASEBOARD_FAB2_LIB.BASEBOARD_FAB2(SCH_1):PAGE194
  J6B1   B4   IOB4 SCONN120_H61426002_SM-CONN,H61A    I56 @BASEBOARD_FAB2_LIB.BASEBOARD_FAB2(SCH_1):PAGE194
  J6B1   B5   IOB5 SCONN120_H61426002_SM-CONN,H61A    I56 @BASEBOARD_FAB2_LIB.BASEBOARD_FAB2(SCH_1):PAGE194
  J6B1   B6   IOB6 SCONN120_H61426002_SM-CONN,H61A    I56 @BASEBOARD_FAB2_LIB.BASEBOARD_FAB2(SCH_1):PAGE194
  J6B1   B7   IOB7 SCONN120_H61426002_SM-CONN,H61A    I56 @BASEBOARD_FAB2_LIB.BASEBOARD_FAB2(SCH_1):PAGE194
  J6B1   B8   IOB8 SCONN120_H61426002_SM-CONN,H61A    I56 @BASEBOARD_FAB2_LIB.BASEBOARD_FAB2(SCH_1):PAGE194
  C4F6    1      A CAPP_4040LF-470UF,16V,20%,ALUMA    I82 @BASEBOARD_FAB2_LIB.BASEBOARD_FAB2(SCH_1):PAGE195
 C4B13    1      A CAPP_4040LF-470UF,16V,20%,ALUMA    I83 @BASEBOARD_FAB2_LIB.BASEBOARD_FAB2(SCH_1):PAGE195
 C1B14    1      A CAPP_4040LF-470UF,16V,20%,ALUMA    I84 @BASEBOARD_FAB2_LIB.BASEBOARD_FAB2(SCH_1):PAGE195
  C1F7    1      A CAPP_4040LF-470UF,16V,20%,ALUMA    I85 @BASEBOARD_FAB2_LIB.BASEBOARD_FAB2(SCH_1):PAGE195
  C4F5    1      A CAPP_3018-68UF,16V,20%,TANT,72A    I96 @BASEBOARD_FAB2_LIB.BASEBOARD_FAB2(SCH_1):PAGE195
 C4B14    1      A CAPP_3018-68UF,16V,20%,TANT,72A    I97 @BASEBOARD_FAB2_LIB.BASEBOARD_FAB2(SCH_1):PAGE195
  C3T6    1      A CAPP_3018-68UF,16V,20%,TANT,72A    I98 @BASEBOARD_FAB2_LIB.BASEBOARD_FAB2(SCH_1):PAGE195
  C9M3    1      A CAPP_3018-68UF,16V,20%,TANT,72A    I99 @BASEBOARD_FAB2_LIB.BASEBOARD_FAB2(SCH_1):PAGE195
  C3B6    1      A CAPP_3018-68UF,16V,20%,TANT,72A   I100 @BASEBOARD_FAB2_LIB.BASEBOARD_FAB2(SCH_1):PAGE195
 C1R23    1      A CAPP_3018-68UF,16V,20%,TANT,72A   I101 @BASEBOARD_FAB2_LIB.BASEBOARD_FAB2(SCH_1):PAGE195
  C4M6    1      A CAPP_3018-68UF,16V,20%,TANT,72A   I102 @BASEBOARD_FAB2_LIB.BASEBOARD_FAB2(SCH_1):PAGE195
  C1M5    1      A CAPP_3018-68UF,16V,20%,TANT,72A   I103 @BASEBOARD_FAB2_LIB.BASEBOARD_FAB2(SCH_1):PAGE195
 C3T13    1      A CAPP_3018-68UF,16V,20%,TANT,72A   I104 @BASEBOARD_FAB2_LIB.BASEBOARD_FAB2(SCH_1):PAGE195
  C4M7    1      A CAPP_3018-68UF,16V,20%,TANT,72A   I105 @BASEBOARD_FAB2_LIB.BASEBOARD_FAB2(SCH_1):PAGE195
 C3T15    1      A CAPP_3018-68UF,16V,20%,TANT,72A   I106 @BASEBOARD_FAB2_LIB.BASEBOARD_FAB2(SCH_1):PAGE195
  C7M6    1      A CAPP_3018-68UF,16V,20%,TANT,72A   I108 @BASEBOARD_FAB2_LIB.BASEBOARD_FAB2(SCH_1):PAGE195
  C6N5    1      A CAPP_3018-68UF,16V,20%,TANT,72A   I109 @BASEBOARD_FAB2_LIB.BASEBOARD_FAB2(SCH_1):PAGE195
  C9T3    1      A CAPP_3018-68UF,16V,20%,TANT,72A   I111 @BASEBOARD_FAB2_LIB.BASEBOARD_FAB2(SCH_1):PAGE195
  C4F4    1      A CAPP_3018-68UF,16V,20%,TANT,72A   I112 @BASEBOARD_FAB2_LIB.BASEBOARD_FAB2(SCH_1):PAGE195
  C3T3    1      A CAPP_3018-68UF,16V,20%,TANT,72A   I113 @BASEBOARD_FAB2_LIB.BASEBOARD_FAB2(SCH_1):PAGE195
 R3P48    1      A RES_0402-90.9K,1%,1/16W,CHIP,GA    I74 @BASEBOARD_FAB2_LIB.BASEBOARD_FAB2(SCH_1):PAGE196
  U4F1    5    RSP MAX9634_SOT-IC,H35789-001    I97 @BASEBOARD_FAB2_LIB.BASEBOARD_FAB2(SCH_1):PAGE197
  R4F2    2      B RES_1206-0.002,1%,1W,CHIP,G521A    I99 @BASEBOARD_FAB2_LIB.BASEBOARD_FAB2(SCH_1):PAGE197
  U4B1    5    RSP MAX9634_SOT-IC,H35789-001   I120 @BASEBOARD_FAB2_LIB.BASEBOARD_FAB2(SCH_1):PAGE197
 R4B12    2      B RES_1206-0.002,1%,1W,CHIP,G521A   I121 @BASEBOARD_FAB2_LIB.BASEBOARD_FAB2(SCH_1):PAGE197
  R1F3    2      B RES_1206-0.002,1%,1W,CHIP,G521A   I131 @BASEBOARD_FAB2_LIB.BASEBOARD_FAB2(SCH_1):PAGE197
  U1F1    5    RSP MAX9634_SOT-IC,H35789-001   I133 @BASEBOARD_FAB2_LIB.BASEBOARD_FAB2(SCH_1):PAGE197
  R9M4    2      B RES_1206-0.002,1%,1W,CHIP,G521A   I142 @BASEBOARD_FAB2_LIB.BASEBOARD_FAB2(SCH_1):PAGE197
  U1B1    5    RSP MAX9634_SOT-IC,H35789-001   I144 @BASEBOARD_FAB2_LIB.BASEBOARD_FAB2(SCH_1):PAGE197
 EU7E1    5      D SLG55021_SM-IC,G56246-001    I19 @BASEBOARD_FAB2_LIB.BASEBOARD_FAB2(SCH_1):PAGE198
  C7E5    1      A CAP_A_0402V-0.1UF,16V,10%,X7R,A    I52 @BASEBOARD_FAB2_LIB.BASEBOARD_FAB2(SCH_1):PAGE198
  C7E6    1      A CAP_0805-10UF,16V,10%,X6S,C953A    I53 @BASEBOARD_FAB2_LIB.BASEBOARD_FAB2(SCH_1):PAGE198
 EU9M1    5      D SLG55021_SM-IC,G56246-001    I69 @BASEBOARD_FAB2_LIB.BASEBOARD_FAB2(SCH_1):PAGE198
 C9M10    1      A CAP_0805-10UF,16V,10%,X6S,C953A    I74 @BASEBOARD_FAB2_LIB.BASEBOARD_FAB2(SCH_1):PAGE198
  C9M9    1      A CAP_A_0402V-0.1UF,16V,10%,X7R,A    I76 @BASEBOARD_FAB2_LIB.BASEBOARD_FAB2(SCH_1):PAGE198
  Q1B1    5    DRN MOSFET_N_LCC3-BSZ019N03LS,NFETA    I86 @BASEBOARD_FAB2_LIB.BASEBOARD_FAB2(SCH_1):PAGE198
  Q7E7    5    DRN MOSFET_N_LCC3-BSZ019N03LS,NFETA    I88 @BASEBOARD_FAB2_LIB.BASEBOARD_FAB2(SCH_1):PAGE198
 R9P18    1      A RES_0402-15.0K,1%,1/16W,CHIP,GA    I41 @BASEBOARD_FAB2_LIB.BASEBOARD_FAB2(SCH_1):PAGE199
 R9P23    1      A RES_0402-100.0K,1%,1/16W,CHIP,A    I54 @BASEBOARD_FAB2_LIB.BASEBOARD_FAB2(SCH_1):PAGE199
 R1D36    1      A RES_0402-1.00K,1%,1/16W,CHIP,GA    I65 @BASEBOARD_FAB2_LIB.BASEBOARD_FAB2(SCH_1):PAGE199
 EU1E3    1     S1 MOSFETN_1D3S_SOT5-IC,G68777-001    I54 @BASEBOARD_FAB2_LIB.BASEBOARD_FAB2(SCH_1):PAGE200
 EU1E3    2     S2 MOSFETN_1D3S_SOT5-IC,G68777-001    I54 @BASEBOARD_FAB2_LIB.BASEBOARD_FAB2(SCH_1):PAGE200
 EU1E3    3     S3 MOSFETN_1D3S_SOT5-IC,G68777-001    I54 @BASEBOARD_FAB2_LIB.BASEBOARD_FAB2(SCH_1):PAGE200
 EU9R1    1     S1 MOSFETN_1D3S_SOT5-IC,G68777-001    I57 @BASEBOARD_FAB2_LIB.BASEBOARD_FAB2(SCH_1):PAGE200
 EU9R1    2     S2 MOSFETN_1D3S_SOT5-IC,G68777-001    I57 @BASEBOARD_FAB2_LIB.BASEBOARD_FAB2(SCH_1):PAGE200
 EU9R1    3     S3 MOSFETN_1D3S_SOT5-IC,G68777-001    I57 @BASEBOARD_FAB2_LIB.BASEBOARD_FAB2(SCH_1):PAGE200
 EU1E1    1     S1 MOSFETN_1D3S_SOT5-IC,G68777-001    I59 @BASEBOARD_FAB2_LIB.BASEBOARD_FAB2(SCH_1):PAGE200
 EU1E1    2     S2 MOSFETN_1D3S_SOT5-IC,G68777-001    I59 @BASEBOARD_FAB2_LIB.BASEBOARD_FAB2(SCH_1):PAGE200
 EU1E1    3     S3 MOSFETN_1D3S_SOT5-IC,G68777-001    I59 @BASEBOARD_FAB2_LIB.BASEBOARD_FAB2(SCH_1):PAGE200
 R9P13    1      A RES_0402-274K,1.0%,1/16W,CHIP,A   I107 @BASEBOARD_FAB2_LIB.BASEBOARD_FAB2(SCH_1):PAGE200
  R9P7    1      A RES_0402-249K,1.0%,1/16W,CHIP,A   I145 @BASEBOARD_FAB2_LIB.BASEBOARD_FAB2(SCH_1):PAGE200
  U9P1    2    VDD TPS3700_SM-IC,H69492-001   I163 @BASEBOARD_FAB2_LIB.BASEBOARD_FAB2(SCH_1):PAGE200
  U1D2    2    VDD TPS3700_SM-IC,H69492-001   I170 @BASEBOARD_FAB2_LIB.BASEBOARD_FAB2(SCH_1):PAGE200
  C9P6    1      A CAP_A_0402V-0.1UF,16V,10%,X7R,A   I185 @BASEBOARD_FAB2_LIB.BASEBOARD_FAB2(SCH_1):PAGE200
  C1D9    1      A CAP_A_0402V-0.1UF,16V,10%,X7R,A   I187 @BASEBOARD_FAB2_LIB.BASEBOARD_FAB2(SCH_1):PAGE200
 CR1F5    1      C DIODE_SM-MBRS340T3G,EMPTY,C819A   I220 @BASEBOARD_FAB2_LIB.BASEBOARD_FAB2(SCH_1):PAGE200
 R9P33    1      A RES_0402-100.0K,1%,1/16W,CHIP,A   I222 @BASEBOARD_FAB2_LIB.BASEBOARD_FAB2(SCH_1):PAGE200
  L4C1    1    INA INDUCTOR_SM-100NH,IND,D92183-0A    I46 @BASEBOARD_FAB2_LIB.BASEBOARD_FAB2(SCH_1):PAGE204
  L1B2    1    INA INDUCTOR_SM-100NH,IND,D92183-0A    I32 @BASEBOARD_FAB2_LIB.BASEBOARD_FAB2(SCH_1):PAGE209
  L7C1    1    INA INDUCTOR_SM-100NH,IND,D92183-0B    I56 @BASEBOARD_FAB2_LIB.BASEBOARD_FAB2(SCH_1):PAGE212
  L7F2    1    INA INDUCTOR_SM-100NH,IND,D92183-0B   I124 @BASEBOARD_FAB2_LIB.BASEBOARD_FAB2(SCH_1):PAGE217
  L7A5    1    INA INDUCTOR_SM-100NH,IND,D92183-0B   I124 @BASEBOARD_FAB2_LIB.BASEBOARD_FAB2(SCH_1):PAGE220
  L1F1    1    INA INDUCTOR_SM-100NH,IND,D92183-0B   I124 @BASEBOARD_FAB2_LIB.BASEBOARD_FAB2(SCH_1):PAGE225
  L1B1    1    INA INDUCTOR_SM-100NH,IND,D92183-0B   I124 @BASEBOARD_FAB2_LIB.BASEBOARD_FAB2(SCH_1):PAGE228
 FB7F1    1      A FERRITE_SM-22,FB,656554-051   I162 @BASEBOARD_FAB2_LIB.BASEBOARD_FAB2(SCH_1):PAGE231
 FB7B1    1      A FERRITE_SM-22,FB,656554-051   I200 @BASEBOARD_FAB2_LIB.BASEBOARD_FAB2(SCH_1):PAGE232
 FB4G1    1      A FERRITE_SM-22,FB,656554-051   I198 @BASEBOARD_FAB2_LIB.BASEBOARD_FAB2(SCH_1):PAGE233
 FB4A1    1      A FERRITE_SM-22,FB,656554-051   I154 @BASEBOARD_FAB2_LIB.BASEBOARD_FAB2(SCH_1):PAGE234
 FB9E1    1      A FERRITE_SM-22,FB,656554-051   I132 @BASEBOARD_FAB2_LIB.BASEBOARD_FAB2(SCH_1):PAGE240
 FB7E1    1      A FERRITE_SM-22,FB,656554-051    I82 @BASEBOARD_FAB2_LIB.BASEBOARD_FAB2(SCH_1):PAGE241

P12V_SWITCH_G @BASEBOARD_FAB2_LIB.BASEBOARD_FAB2(SCH_1):P12V_SWITCH_G
 EU7E1    7      G SLG55021_SM-IC,G56246-001    I19 @BASEBOARD_FAB2_LIB.BASEBOARD_FAB2(SCH_1):PAGE198
  Q7E7    4   GATE MOSFET_N_LCC3-BSZ019N03LS,NFETA    I88 @BASEBOARD_FAB2_LIB.BASEBOARD_FAB2(SCH_1):PAGE198

P1V05_PCH_STBY @BASEBOARD_FAB2_LIB.BASEBOARD_FAB2(SCH_1):P1V05_PCH_STBY
  C9A6    1      A CAP_A_0402V-1.0UF,6.3V,10%,X6SA    I25 @BASEBOARD_FAB2_LIB.BASEBOARD_FAB2(SCH_1):PAGE111
  J9A3   43   IO43 SCONN60_C21100002_SMLF-CONN,C2A    I26 @BASEBOARD_FAB2_LIB.BASEBOARD_FAB2(SCH_1):PAGE111
  J9A3   44   IO44 SCONN60_C21100002_SMLF-CONN,C2A    I26 @BASEBOARD_FAB2_LIB.BASEBOARD_FAB2(SCH_1):PAGE111
  C1L5    1      A CAP_A_0402V-1.0UF,6.3V,10%,X6SA    I30 @BASEBOARD_FAB2_LIB.BASEBOARD_FAB2(SCH_1):PAGE111
 R9A17    2      B RES_0402-1.00K,1%,1/16W,CHIP,GA    I57 @BASEBOARD_FAB2_LIB.BASEBOARD_FAB2(SCH_1):PAGE111
 R1L39    1      A RES_0402-100.0,1%,1/16W,CHIP,GA    I76 @BASEBOARD_FAB2_LIB.BASEBOARD_FAB2(SCH_1):PAGE112
 R1L41    1      A RES_0402-100.0,1%,1/16W,CHIP,GA    I77 @BASEBOARD_FAB2_LIB.BASEBOARD_FAB2(SCH_1):PAGE112
 R9A11    1      A RES_0402-150.0,1%,1/16W,CHIP,GA    I78 @BASEBOARD_FAB2_LIB.BASEBOARD_FAB2(SCH_1):PAGE112
 R8A13    1      A RES_0402-150.0,1%,1/16W,CHIP,GA    I79 @BASEBOARD_FAB2_LIB.BASEBOARD_FAB2(SCH_1):PAGE112
 R8A14    1      A RES_0402-150.0,1%,1/16W,CHIP,GA    I80 @BASEBOARD_FAB2_LIB.BASEBOARD_FAB2(SCH_1):PAGE112
  U7C1 AH50 VCCA_CLKUNF_1P05<0> LBG_CORE_QAT_EXT_D_BGA1-IC,H91A    I63 @BASEBOARD_FAB2_LIB.BASEBOARD_FAB2(SCH_1):PAGE122
  U7C1  U50 VCCA_CLKUNF_1P05<1> LBG_CORE_QAT_EXT_D_BGA1-IC,H91A    I63 @BASEBOARD_FAB2_LIB.BASEBOARD_FAB2(SCH_1):PAGE122
  U7C1 AW45 VCCMPHY_1P05<0> LBG_CORE_QAT_EXT_D_BGA1-IC,H91A    I63 @BASEBOARD_FAB2_LIB.BASEBOARD_FAB2(SCH_1):PAGE122
  U7C1 AW43 VCCMPHY_1P05<1> LBG_CORE_QAT_EXT_D_BGA1-IC,H91A    I63 @BASEBOARD_FAB2_LIB.BASEBOARD_FAB2(SCH_1):PAGE122
  U7C1 AJ43 VCCMPHY_1P05<2> LBG_CORE_QAT_EXT_D_BGA1-IC,H91A    I63 @BASEBOARD_FAB2_LIB.BASEBOARD_FAB2(SCH_1):PAGE122
  U7C1 AU45 VCCMPHY_1P05<3> LBG_CORE_QAT_EXT_D_BGA1-IC,H91A    I63 @BASEBOARD_FAB2_LIB.BASEBOARD_FAB2(SCH_1):PAGE122
  U7C1 AU43 VCCMPHY_1P05<4> LBG_CORE_QAT_EXT_D_BGA1-IC,H91A    I63 @BASEBOARD_FAB2_LIB.BASEBOARD_FAB2(SCH_1):PAGE122
  U7C1 AT45 VCCMPHY_1P05<5> LBG_CORE_QAT_EXT_D_BGA1-IC,H91A    I63 @BASEBOARD_FAB2_LIB.BASEBOARD_FAB2(SCH_1):PAGE122
  U7C1 AT43 VCCMPHY_1P05<6> LBG_CORE_QAT_EXT_D_BGA1-IC,H91A    I63 @BASEBOARD_FAB2_LIB.BASEBOARD_FAB2(SCH_1):PAGE122
  U7C1 AP45 VCCMPHY_1P05<7> LBG_CORE_QAT_EXT_D_BGA1-IC,H91A    I63 @BASEBOARD_FAB2_LIB.BASEBOARD_FAB2(SCH_1):PAGE122
  U7C1 AP43 VCCMPHY_1P05<8> LBG_CORE_QAT_EXT_D_BGA1-IC,H91A    I63 @BASEBOARD_FAB2_LIB.BASEBOARD_FAB2(SCH_1):PAGE122
  U7C1 AM45 VCCMPHY_1P05<9> LBG_CORE_QAT_EXT_D_BGA1-IC,H91A    I63 @BASEBOARD_FAB2_LIB.BASEBOARD_FAB2(SCH_1):PAGE122
  U7C1 AM43 VCCMPHY_1P05<10> LBG_CORE_QAT_EXT_D_BGA1-IC,H91A    I63 @BASEBOARD_FAB2_LIB.BASEBOARD_FAB2(SCH_1):PAGE122
  U7C1 AK45 VCCMPHY_1P05<11> LBG_CORE_QAT_EXT_D_BGA1-IC,H91A    I63 @BASEBOARD_FAB2_LIB.BASEBOARD_FAB2(SCH_1):PAGE122
  U7C1 AK43 VCCMPHY_1P05<12> LBG_CORE_QAT_EXT_D_BGA1-IC,H91A    I63 @BASEBOARD_FAB2_LIB.BASEBOARD_FAB2(SCH_1):PAGE122
  U7C1 BB37 VCCP10GBE_LV_1P05<0> LBG_CORE_QAT_EXT_D_BGA1-IC,H91A    I63 @BASEBOARD_FAB2_LIB.BASEBOARD_FAB2(SCH_1):PAGE122
  U7C1 BB33 VCCP10GBE_LV_1P05<1> LBG_CORE_QAT_EXT_D_BGA1-IC,H91A    I63 @BASEBOARD_FAB2_LIB.BASEBOARD_FAB2(SCH_1):PAGE122
  U7C1 BA37 VCCP10GBE_LV_1P05<2> LBG_CORE_QAT_EXT_D_BGA1-IC,H91A    I63 @BASEBOARD_FAB2_LIB.BASEBOARD_FAB2(SCH_1):PAGE122
  U7C1 BA36 VCCP10GBE_LV_1P05<3> LBG_CORE_QAT_EXT_D_BGA1-IC,H91A    I63 @BASEBOARD_FAB2_LIB.BASEBOARD_FAB2(SCH_1):PAGE122
  U7C1 BA34 VCCP10GBE_LV_1P05<4> LBG_CORE_QAT_EXT_D_BGA1-IC,H91A    I63 @BASEBOARD_FAB2_LIB.BASEBOARD_FAB2(SCH_1):PAGE122
  U7C1 BA32 VCCP10GBE_LV_1P05<5> LBG_CORE_QAT_EXT_D_BGA1-IC,H91A    I63 @BASEBOARD_FAB2_LIB.BASEBOARD_FAB2(SCH_1):PAGE122
  U7C1 BA30 VCCP10GBE_LV_1P05<6> LBG_CORE_QAT_EXT_D_BGA1-IC,H91A    I63 @BASEBOARD_FAB2_LIB.BASEBOARD_FAB2(SCH_1):PAGE122
  U7C1 AT48 VCCP_HSIOPLLUNF_1P05 LBG_CORE_QAT_EXT_D_BGA1-IC,H91A    I63 @BASEBOARD_FAB2_LIB.BASEBOARD_FAB2(SCH_1):PAGE122
  U7C1 AM48 VCCP_UPPLLUNF_1P05 LBG_CORE_QAT_EXT_D_BGA1-IC,H91A    I63 @BASEBOARD_FAB2_LIB.BASEBOARD_FAB2(SCH_1):PAGE122
  U7C1 BF46 VCCPRIM_1P05<0> LBG_CORE_QAT_EXT_D_BGA1-IC,H91A    I63 @BASEBOARD_FAB2_LIB.BASEBOARD_FAB2(SCH_1):PAGE122
  U7C1 BE48 VCCPRIM_1P05<1> LBG_CORE_QAT_EXT_D_BGA1-IC,H91A    I63 @BASEBOARD_FAB2_LIB.BASEBOARD_FAB2(SCH_1):PAGE122
  U7C1 AU39 VCCPRIM_1P05<2> LBG_CORE_QAT_EXT_D_BGA1-IC,H91A    I63 @BASEBOARD_FAB2_LIB.BASEBOARD_FAB2(SCH_1):PAGE122
  U7C1 AU37 VCCPRIM_1P05<3> LBG_CORE_QAT_EXT_D_BGA1-IC,H91A    I63 @BASEBOARD_FAB2_LIB.BASEBOARD_FAB2(SCH_1):PAGE122
  U7C1 AT39 VCCPRIM_1P05<4> LBG_CORE_QAT_EXT_D_BGA1-IC,H91A    I63 @BASEBOARD_FAB2_LIB.BASEBOARD_FAB2(SCH_1):PAGE122
  U7C1 AM27 VCCPRIM_1P05<5> LBG_CORE_QAT_EXT_D_BGA1-IC,H91A    I63 @BASEBOARD_FAB2_LIB.BASEBOARD_FAB2(SCH_1):PAGE122
  U7C1 AJ29 VCCPRIM_1P05<6> LBG_CORE_QAT_EXT_D_BGA1-IC,H91A    I63 @BASEBOARD_FAB2_LIB.BASEBOARD_FAB2(SCH_1):PAGE122
  U7C1 AC26 VCCPRIM_1P05<7> LBG_CORE_QAT_EXT_D_BGA1-IC,H91A    I63 @BASEBOARD_FAB2_LIB.BASEBOARD_FAB2(SCH_1):PAGE122
  U7C1 AA46 VCCPRIM_1P05<8> LBG_CORE_QAT_EXT_D_BGA1-IC,H91A    I63 @BASEBOARD_FAB2_LIB.BASEBOARD_FAB2(SCH_1):PAGE122
  U7C1 AA45 VCCPRIM_1P05<9> LBG_CORE_QAT_EXT_D_BGA1-IC,H91A    I63 @BASEBOARD_FAB2_LIB.BASEBOARD_FAB2(SCH_1):PAGE122
  U7C1  Y46 VCCPRIM_1P05<10> LBG_CORE_QAT_EXT_D_BGA1-IC,H91A    I63 @BASEBOARD_FAB2_LIB.BASEBOARD_FAB2(SCH_1):PAGE122
  U7C1  Y45 VCCPRIM_1P05<11> LBG_CORE_QAT_EXT_D_BGA1-IC,H91A    I63 @BASEBOARD_FAB2_LIB.BASEBOARD_FAB2(SCH_1):PAGE122
  U7C1  V44 VCCPRIM_1P05<12> LBG_CORE_QAT_EXT_D_BGA1-IC,H91A    I63 @BASEBOARD_FAB2_LIB.BASEBOARD_FAB2(SCH_1):PAGE122
  U7C1  U46 VCCPRIM_1P05<13> LBG_CORE_QAT_EXT_D_BGA1-IC,H91A    I63 @BASEBOARD_FAB2_LIB.BASEBOARD_FAB2(SCH_1):PAGE122
  U7C1  T44 VCCPRIM_1P05<14> LBG_CORE_QAT_EXT_D_BGA1-IC,H91A    I63 @BASEBOARD_FAB2_LIB.BASEBOARD_FAB2(SCH_1):PAGE122
  U7C1  R46 VCCPRIM_1P05<15> LBG_CORE_QAT_EXT_D_BGA1-IC,H91A    I63 @BASEBOARD_FAB2_LIB.BASEBOARD_FAB2(SCH_1):PAGE122
  U7C1  R42 VCCPRIM_1P05<16> LBG_CORE_QAT_EXT_D_BGA1-IC,H91A    I63 @BASEBOARD_FAB2_LIB.BASEBOARD_FAB2(SCH_1):PAGE122
  U7C1 AK27 VCCPRIM_1P05<17> LBG_CORE_QAT_EXT_D_BGA1-IC,H91A    I63 @BASEBOARD_FAB2_LIB.BASEBOARD_FAB2(SCH_1):PAGE122
  U7C1 AA24 VCCPRIM_1P05<18> LBG_CORE_QAT_EXT_D_BGA1-IC,H91A    I63 @BASEBOARD_FAB2_LIB.BASEBOARD_FAB2(SCH_1):PAGE122
  U7C1  Y26 VCCPRIM_1P05<19> LBG_CORE_QAT_EXT_D_BGA1-IC,H91A    I63 @BASEBOARD_FAB2_LIB.BASEBOARD_FAB2(SCH_1):PAGE122
  U7C1 AE27 VCCMPHY_1P05<13> LBG_CORE_QAT_EXT_D_BGA1-IC,H91A    I21 @BASEBOARD_FAB2_LIB.BASEBOARD_FAB2(SCH_1):PAGE123
 FB3M1    1      A FERRITE_SM-120,FB,693286-027     I8 @BASEBOARD_FAB2_LIB.BASEBOARD_FAB2(SCH_1):PAGE127
 C3M21    1      A CAP_A_0402V-1.0UF,6.3V,10%,X6SA     I9 @BASEBOARD_FAB2_LIB.BASEBOARD_FAB2(SCH_1):PAGE127
 FB3M2    1      A FERRITE_SM-120,FB,693286-027    I17 @BASEBOARD_FAB2_LIB.BASEBOARD_FAB2(SCH_1):PAGE127
 C3M22    1      A CAP_A_0402V-1.0UF,6.3V,10%,X6SA    I18 @BASEBOARD_FAB2_LIB.BASEBOARD_FAB2(SCH_1):PAGE127
 FB3M3    1      A FERRITE_SM-120,FB,693286-027    I26 @BASEBOARD_FAB2_LIB.BASEBOARD_FAB2(SCH_1):PAGE127
 C3M30    1      A CAP_A_0402V-1.0UF,6.3V,10%,X6SA    I27 @BASEBOARD_FAB2_LIB.BASEBOARD_FAB2(SCH_1):PAGE127
 FB2M1    1      A FERRITE_SM-120,FB,693286-027    I46 @BASEBOARD_FAB2_LIB.BASEBOARD_FAB2(SCH_1):PAGE127
 FB3M4    1      A FERRITE_SM-120,FB,693286-027    I56 @BASEBOARD_FAB2_LIB.BASEBOARD_FAB2(SCH_1):PAGE127
 C3M31    1      A CAP_A_0402V-1.0UF,6.3V,10%,X6SA    I57 @BASEBOARD_FAB2_LIB.BASEBOARD_FAB2(SCH_1):PAGE127
 FB2M2    1      A FERRITE_SM-120,FB,693286-027    I69 @BASEBOARD_FAB2_LIB.BASEBOARD_FAB2(SCH_1):PAGE127
  L2M1    1    INA INDUCTOR_SMT-0.022UH,IND,72189A    I71 @BASEBOARD_FAB2_LIB.BASEBOARD_FAB2(SCH_1):PAGE127
  C2M8    1      A CAP_A_0402V-1.0UF,6.3V,10%,X6SA    I74 @BASEBOARD_FAB2_LIB.BASEBOARD_FAB2(SCH_1):PAGE127
  C2M6    1      A CAP_A_0402V-1.0UF,6.3V,10%,X6SA    I76 @BASEBOARD_FAB2_LIB.BASEBOARD_FAB2(SCH_1):PAGE127
 C2M25    1      A CAP_A_0402V-1.0UF,6.3V,10%,X6SA    I78 @BASEBOARD_FAB2_LIB.BASEBOARD_FAB2(SCH_1):PAGE127
 C7B15    1      A CAP_A_0603V-22.0UF,4V,20%,X6S,A     I1 @BASEBOARD_FAB2_LIB.BASEBOARD_FAB2(SCH_1):PAGE131
 C7B19    1      A CAP_A_0603V-22.0UF,4V,20%,X6S,A     I2 @BASEBOARD_FAB2_LIB.BASEBOARD_FAB2(SCH_1):PAGE131
 C7B16    1      A CAP_A_0603V-22.0UF,4V,20%,X6S,A     I3 @BASEBOARD_FAB2_LIB.BASEBOARD_FAB2(SCH_1):PAGE131
 C7B21    1      A CAP_A_0603V-22.0UF,4V,20%,X6S,A     I4 @BASEBOARD_FAB2_LIB.BASEBOARD_FAB2(SCH_1):PAGE131
 C7B20    1      A CAP_A_0603V-22.0UF,4V,20%,X6S,A     I6 @BASEBOARD_FAB2_LIB.BASEBOARD_FAB2(SCH_1):PAGE131
 C7B23    1      A CAP_A_0603V-22.0UF,4V,20%,X6S,A     I7 @BASEBOARD_FAB2_LIB.BASEBOARD_FAB2(SCH_1):PAGE131
 C8B10    1      A CAP_A_0603V-22.0UF,4V,20%,X6S,A     I8 @BASEBOARD_FAB2_LIB.BASEBOARD_FAB2(SCH_1):PAGE131
 C7B22    1      A CAP_A_0603V-22.0UF,4V,20%,X6S,A    I10 @BASEBOARD_FAB2_LIB.BASEBOARD_FAB2(SCH_1):PAGE131
 C7B24    1      A CAP_A_0603V-22.0UF,4V,20%,X6S,A    I11 @BASEBOARD_FAB2_LIB.BASEBOARD_FAB2(SCH_1):PAGE131
 C7B18    1      A CAP_A_0603V-22.0UF,4V,20%,X6S,A    I12 @BASEBOARD_FAB2_LIB.BASEBOARD_FAB2(SCH_1):PAGE131
  C8B9    1      A CAP_A_0603V-22.0UF,4V,20%,X6S,A    I14 @BASEBOARD_FAB2_LIB.BASEBOARD_FAB2(SCH_1):PAGE131
 C8B11    1      A CAP_A_0603V-22.0UF,4V,20%,X6S,A    I15 @BASEBOARD_FAB2_LIB.BASEBOARD_FAB2(SCH_1):PAGE131
 C8B14    1      A CAP_A_0603V-22.0UF,4V,20%,X6S,A    I16 @BASEBOARD_FAB2_LIB.BASEBOARD_FAB2(SCH_1):PAGE131
 C7B17    1      A CAP_A_0603V-22.0UF,4V,20%,X6S,A    I18 @BASEBOARD_FAB2_LIB.BASEBOARD_FAB2(SCH_1):PAGE131
 C8B13    1      A CAP_A_0603V-22.0UF,4V,20%,X6S,A    I20 @BASEBOARD_FAB2_LIB.BASEBOARD_FAB2(SCH_1):PAGE131
 C8B16    1      A CAP_0805-47UF,4V,20%,X6S,C9533A    I22 @BASEBOARD_FAB2_LIB.BASEBOARD_FAB2(SCH_1):PAGE131
 C8B15    1      A CAP_0805-47UF,4V,20%,X6S,C9533A    I24 @BASEBOARD_FAB2_LIB.BASEBOARD_FAB2(SCH_1):PAGE131
 C2M22    1      A CAP_A_0402V-1.0UF,6.3V,10%,X6SA    I27 @BASEBOARD_FAB2_LIB.BASEBOARD_FAB2(SCH_1):PAGE131
 C2M21    1      A CAP_A_0402V-1.0UF,6.3V,10%,X6SA    I28 @BASEBOARD_FAB2_LIB.BASEBOARD_FAB2(SCH_1):PAGE131
 C2M18    1      A CAP_A_0402V-1.0UF,6.3V,10%,X6SA    I29 @BASEBOARD_FAB2_LIB.BASEBOARD_FAB2(SCH_1):PAGE131
 C2M19    1      A CAP_A_0402V-1.0UF,6.3V,10%,X6SA    I31 @BASEBOARD_FAB2_LIB.BASEBOARD_FAB2(SCH_1):PAGE131
 C3M38    1      A CAP_A_0402V-1.0UF,6.3V,10%,X6SA    I32 @BASEBOARD_FAB2_LIB.BASEBOARD_FAB2(SCH_1):PAGE131
 C2M17    1      A CAP_0805-47UF,4V,20%,X6S,C9533A    I34 @BASEBOARD_FAB2_LIB.BASEBOARD_FAB2(SCH_1):PAGE131
 C2M11    1      A CAP_0805-47UF,4V,20%,X6S,C9533A    I35 @BASEBOARD_FAB2_LIB.BASEBOARD_FAB2(SCH_1):PAGE131
 C8A13    1      A CAP_0805-47UF,4V,20%,X6S,C9533A    I37 @BASEBOARD_FAB2_LIB.BASEBOARD_FAB2(SCH_1):PAGE131
 C2M20    1      A CAP_A_0402V-1.0UF,6.3V,10%,X6SA    I39 @BASEBOARD_FAB2_LIB.BASEBOARD_FAB2(SCH_1):PAGE131
 C2N13    1      A CAP_A_0402V-1.0UF,6.3V,10%,X6SA    I40 @BASEBOARD_FAB2_LIB.BASEBOARD_FAB2(SCH_1):PAGE131
  C2N2    1      A CAP_A_0402V-1.0UF,6.3V,10%,X6SA    I41 @BASEBOARD_FAB2_LIB.BASEBOARD_FAB2(SCH_1):PAGE131
 C3M43    1      A CAP_A_0402V-1.0UF,6.3V,10%,X6SA    I42 @BASEBOARD_FAB2_LIB.BASEBOARD_FAB2(SCH_1):PAGE131
  C2N7    1      A CAP_A_0402V-1.0UF,6.3V,10%,X6SA    I43 @BASEBOARD_FAB2_LIB.BASEBOARD_FAB2(SCH_1):PAGE131
 C3M39    1      A CAP_A_0402V-1.0UF,6.3V,10%,X6SA    I44 @BASEBOARD_FAB2_LIB.BASEBOARD_FAB2(SCH_1):PAGE131
 C3M42    1      A CAP_A_0402V-1.0UF,6.3V,10%,X6SA    I45 @BASEBOARD_FAB2_LIB.BASEBOARD_FAB2(SCH_1):PAGE131
  C2N8    1      A CAP_A_0402V-1.0UF,6.3V,10%,X6SA    I47 @BASEBOARD_FAB2_LIB.BASEBOARD_FAB2(SCH_1):PAGE131
 C2M13    1      A CAP_A_0603V-22.0UF,4V,20%,X6S,A    I48 @BASEBOARD_FAB2_LIB.BASEBOARD_FAB2(SCH_1):PAGE131
 C2N10    1      A CAP_A_0603V-22.0UF,4V,20%,X6S,A    I50 @BASEBOARD_FAB2_LIB.BASEBOARD_FAB2(SCH_1):PAGE131
 C2M12    1      A CAP_A_0603V-22.0UF,4V,20%,X6S,A    I52 @BASEBOARD_FAB2_LIB.BASEBOARD_FAB2(SCH_1):PAGE131
  R3P7    1      A RES_0402-1.00K,1%,1/16W,CHIP,GA   I315 @BASEBOARD_FAB2_LIB.BASEBOARD_FAB2(SCH_1):PAGE133
  R3P5    1      A RES_0402-1.00K,1%,1/16W,CHIP,GA   I316 @BASEBOARD_FAB2_LIB.BASEBOARD_FAB2(SCH_1):PAGE133
  R3P6    1      A RES_0402-1.00K,1%,1/16W,CHIP,GA   I317 @BASEBOARD_FAB2_LIB.BASEBOARD_FAB2(SCH_1):PAGE133
 R3N15    1      A RES_0402-1.00K,1%,1/16W,CHIP,GA   I318 @BASEBOARD_FAB2_LIB.BASEBOARD_FAB2(SCH_1):PAGE133
 R3N16    1      A RES_0402-1.00K,1%,1/16W,CHIP,GA   I321 @BASEBOARD_FAB2_LIB.BASEBOARD_FAB2(SCH_1):PAGE133
  R3P8    1      A RES_0402-1.00K,1%,1/16W,CHIP,GA   I322 @BASEBOARD_FAB2_LIB.BASEBOARD_FAB2(SCH_1):PAGE133
 R7D44    1      A RES_0402-4.75K,1%,1/16W,CHIP,GA   I356 @BASEBOARD_FAB2_LIB.BASEBOARD_FAB2(SCH_1):PAGE133
 R3P53    1      A RES_0402-4.75K,1%,1/16W,CHIP,GA   I357 @BASEBOARD_FAB2_LIB.BASEBOARD_FAB2(SCH_1):PAGE133
 R7C21    1      A RES_0402-10.0K,1%,1/16W,CHIP,GA     I9 @BASEBOARD_FAB2_LIB.BASEBOARD_FAB2(SCH_1):PAGE134
 FB1U3    2      B FERRITE_SMLF-30,FB,693286-021    I57 @BASEBOARD_FAB2_LIB.BASEBOARD_FAB2(SCH_1):PAGE169
  L7A4    2    INB INDUCTOR_SM-0.3UH,IND,D92183-0A    I45 @BASEBOARD_FAB2_LIB.BASEBOARD_FAB2(SCH_1):PAGE236
 C7A42    1      A CAP_0805LF-22UF,4V,20%,X6S,C95A    I46 @BASEBOARD_FAB2_LIB.BASEBOARD_FAB2(SCH_1):PAGE236
 R8B14    2      B RES_0402-0.0,5%,1/16W,CHIP,G21A    I56 @BASEBOARD_FAB2_LIB.BASEBOARD_FAB2(SCH_1):PAGE236
 C3L19    1      A CAPP_SM-470UF,2V,20%,ALUM,6990A    I76 @BASEBOARD_FAB2_LIB.BASEBOARD_FAB2(SCH_1):PAGE236
 C2L46    1      A CAPP_SM-470UF,2V,20%,ALUM,6990A    I77 @BASEBOARD_FAB2_LIB.BASEBOARD_FAB2(SCH_1):PAGE236
 C8A15    1      A CAPP_SM-470UF,2V,20%,ALUM,6990A    I78 @BASEBOARD_FAB2_LIB.BASEBOARD_FAB2(SCH_1):PAGE236
 C2L25    1      A CAPP_SM-470UF,2V,20%,ALUM,6990A    I79 @BASEBOARD_FAB2_LIB.BASEBOARD_FAB2(SCH_1):PAGE236
 EU7A2    1    VOS IR354XX_SM-IR35412,IC,H73684-0A   I117 @BASEBOARD_FAB2_LIB.BASEBOARD_FAB2(SCH_1):PAGE236

P1V05_PCH_STBY_ISCLK_PLL @BASEBOARD_FAB2_LIB.BASEBOARD_FAB2(SCH_1):P1V05_PCH_STBY_ISCLK_PLL
  U7C1  W50 VCCA_CLKFILT_1P05<0> LBG_CORE_QAT_EXT_D_BGA1-IC,H91A    I63 @BASEBOARD_FAB2_LIB.BASEBOARD_FAB2(SCH_1):PAGE122
  U7C1 AG45 VCCA_CLKFILT_1P05<1> LBG_CORE_QAT_EXT_D_BGA1-IC,H91A    I63 @BASEBOARD_FAB2_LIB.BASEBOARD_FAB2(SCH_1):PAGE122
  U7C1 AJ46 VCCA_CLKFILT_1P05<2> LBG_CORE_QAT_EXT_D_BGA1-IC,H91A    I63 @BASEBOARD_FAB2_LIB.BASEBOARD_FAB2(SCH_1):PAGE122
  U7C1 AJ48 VCCA_CLKFILT_1P05<3> LBG_CORE_QAT_EXT_D_BGA1-IC,H91A    I63 @BASEBOARD_FAB2_LIB.BASEBOARD_FAB2(SCH_1):PAGE122
  U7C1 AE46 VCCA_CLKFILT_1P05<4> LBG_CORE_QAT_EXT_D_BGA1-IC,H91A    I63 @BASEBOARD_FAB2_LIB.BASEBOARD_FAB2(SCH_1):PAGE122
 FB3M4    2      B FERRITE_SM-120,FB,693286-027    I56 @BASEBOARD_FAB2_LIB.BASEBOARD_FAB2(SCH_1):PAGE127
 C3M29    1      A CAP_A_0402V-1.0UF,6.3V,10%,X6SA    I80 @BASEBOARD_FAB2_LIB.BASEBOARD_FAB2(SCH_1):PAGE127
 C3M24    1      A CAP_0603LF-10UF,4V,20%,X6S,E15A    I81 @BASEBOARD_FAB2_LIB.BASEBOARD_FAB2(SCH_1):PAGE127

P1V05_PCH_STBY_KR_PLL @BASEBOARD_FAB2_LIB.BASEBOARD_FAB2(SCH_1):P1V05_PCH_STBY_KR_PLL
  R2N4    1      A RES_0402-1.0K,0.1%,1/16W,CHIP,A    I96 @BASEBOARD_FAB2_LIB.BASEBOARD_FAB2(SCH_1):PAGE118
  R2M6    2      B RES_0402-1.0K,0.1%,1/16W,CHIP,A    I99 @BASEBOARD_FAB2_LIB.BASEBOARD_FAB2(SCH_1):PAGE118
  U7C1 BD38 VCCP10GBEPLL_1P05<0> LBG_CORE_QAT_EXT_D_BGA1-IC,H91A    I63 @BASEBOARD_FAB2_LIB.BASEBOARD_FAB2(SCH_1):PAGE122
  U7C1 BB40 VCCP10GBEPLL_1P05<1> LBG_CORE_QAT_EXT_D_BGA1-IC,H91A    I63 @BASEBOARD_FAB2_LIB.BASEBOARD_FAB2(SCH_1):PAGE122
  U7C1 BA41 VCCP10GBEPLL_1P05<2> LBG_CORE_QAT_EXT_D_BGA1-IC,H91A    I63 @BASEBOARD_FAB2_LIB.BASEBOARD_FAB2(SCH_1):PAGE122
  U7C1 BA39 VCCP10GBEPLL_1P05<3> LBG_CORE_QAT_EXT_D_BGA1-IC,H91A    I63 @BASEBOARD_FAB2_LIB.BASEBOARD_FAB2(SCH_1):PAGE122
  C2N6    1      A CAP_0603LF-10UF,4V,20%,X6S,E15A    I64 @BASEBOARD_FAB2_LIB.BASEBOARD_FAB2(SCH_1):PAGE127
  C2N5    1      A CAP_A_0402V-1.0UF,6.3V,10%,X6SA    I65 @BASEBOARD_FAB2_LIB.BASEBOARD_FAB2(SCH_1):PAGE127
  L2M1    2    INB INDUCTOR_SMT-0.022UH,IND,72189A    I71 @BASEBOARD_FAB2_LIB.BASEBOARD_FAB2(SCH_1):PAGE127

P1V05_PCH_STBY_VCCA_PLL0 @BASEBOARD_FAB2_LIB.BASEBOARD_FAB2(SCH_1):P1V05_PCH_STBY_VCCA_PLL0
  U7C1 AG48 VCCA_PLL0_1P05 LBG_CORE_QAT_EXT_D_BGA1-IC,H91A    I63 @BASEBOARD_FAB2_LIB.BASEBOARD_FAB2(SCH_1):PAGE122
 FB3M2    2      B FERRITE_SM-120,FB,693286-027    I17 @BASEBOARD_FAB2_LIB.BASEBOARD_FAB2(SCH_1):PAGE127
 C3M20    1      A CAP_A_0402V-1.0UF,6.3V,10%,X6SA    I84 @BASEBOARD_FAB2_LIB.BASEBOARD_FAB2(SCH_1):PAGE127
 C3M18    1      A CAP_0603LF-10UF,4V,20%,X6S,E15A    I85 @BASEBOARD_FAB2_LIB.BASEBOARD_FAB2(SCH_1):PAGE127

P1V05_PCH_STBY_VCCA_PLL1 @BASEBOARD_FAB2_LIB.BASEBOARD_FAB2(SCH_1):P1V05_PCH_STBY_VCCA_PLL1
  U7C1 AE45 VCCA_PLL1_1P05 LBG_CORE_QAT_EXT_D_BGA1-IC,H91A    I63 @BASEBOARD_FAB2_LIB.BASEBOARD_FAB2(SCH_1):PAGE122
 FB3M1    2      B FERRITE_SM-120,FB,693286-027     I8 @BASEBOARD_FAB2_LIB.BASEBOARD_FAB2(SCH_1):PAGE127
 C3M17    1      A CAP_0603LF-10UF,4V,20%,X6S,E15A    I86 @BASEBOARD_FAB2_LIB.BASEBOARD_FAB2(SCH_1):PAGE127
 C3M19    1      A CAP_A_0402V-1.0UF,6.3V,10%,X6SA    I87 @BASEBOARD_FAB2_LIB.BASEBOARD_FAB2(SCH_1):PAGE127

P1V05_PCH_STBY_VCCA_XTAL @BASEBOARD_FAB2_LIB.BASEBOARD_FAB2(SCH_1):P1V05_PCH_STBY_VCCA_XTAL
  U7C1 AD50 VCCA_CLKXTAL_1P05 LBG_CORE_QAT_EXT_D_BGA1-IC,H91A    I63 @BASEBOARD_FAB2_LIB.BASEBOARD_FAB2(SCH_1):PAGE122
 FB3M3    2      B FERRITE_SM-120,FB,693286-027    I26 @BASEBOARD_FAB2_LIB.BASEBOARD_FAB2(SCH_1):PAGE127
 C3M23    1      A CAP_0603LF-10UF,4V,20%,X6S,E15A    I82 @BASEBOARD_FAB2_LIB.BASEBOARD_FAB2(SCH_1):PAGE127
 C3M27    1      A CAP_A_0402V-1.0UF,6.3V,10%,X6SA    I83 @BASEBOARD_FAB2_LIB.BASEBOARD_FAB2(SCH_1):PAGE127

P1V05_PCH_STBY_WM20_PLL @BASEBOARD_FAB2_LIB.BASEBOARD_FAB2(SCH_1):P1V05_PCH_STBY_WM20_PLL
  U7C1 AN50 VCCP_UPPLL_1P05<0> LBG_CORE_QAT_EXT_D_BGA1-IC,H91A    I63 @BASEBOARD_FAB2_LIB.BASEBOARD_FAB2(SCH_1):PAGE122
  U7C1 AK50 VCCP_UPPLL_1P05<2> LBG_CORE_QAT_EXT_D_BGA1-IC,H91A    I63 @BASEBOARD_FAB2_LIB.BASEBOARD_FAB2(SCH_1):PAGE122
  C2M5    1      A CAP_0603LF-10UF,4V,20%,X6S,E15A    I43 @BASEBOARD_FAB2_LIB.BASEBOARD_FAB2(SCH_1):PAGE127
  C2M7    1      A CAP_A_0402V-1.0UF,6.3V,10%,X6SA    I44 @BASEBOARD_FAB2_LIB.BASEBOARD_FAB2(SCH_1):PAGE127
 FB2M1    2      B FERRITE_SM-120,FB,693286-027    I46 @BASEBOARD_FAB2_LIB.BASEBOARD_FAB2(SCH_1):PAGE127

P1V05_PCH_STBY_WM26_PLL @BASEBOARD_FAB2_LIB.BASEBOARD_FAB2(SCH_1):P1V05_PCH_STBY_WM26_PLL
  U7C1 AW48 VCCP_HSIOPLL_1P05<0> LBG_CORE_QAT_EXT_D_BGA1-IC,H91A    I63 @BASEBOARD_FAB2_LIB.BASEBOARD_FAB2(SCH_1):PAGE122
  U7C1 AU48 VCCP_HSIOPLL_1P05<2> LBG_CORE_QAT_EXT_D_BGA1-IC,H91A    I63 @BASEBOARD_FAB2_LIB.BASEBOARD_FAB2(SCH_1):PAGE122
  U7C1 AP48 VCCP_HSIOPLL_1P05<3> LBG_CORE_QAT_EXT_D_BGA1-IC,H91A    I63 @BASEBOARD_FAB2_LIB.BASEBOARD_FAB2(SCH_1):PAGE122
 C2M10    1      A CAP_0603LF-10UF,4V,20%,X6S,E15A    I49 @BASEBOARD_FAB2_LIB.BASEBOARD_FAB2(SCH_1):PAGE127
  C2M9    1      A CAP_A_0402V-1.0UF,6.3V,10%,X6SA    I50 @BASEBOARD_FAB2_LIB.BASEBOARD_FAB2(SCH_1):PAGE127
 FB2M2    2      B FERRITE_SM-120,FB,693286-027    I69 @BASEBOARD_FAB2_LIB.BASEBOARD_FAB2(SCH_1):PAGE127

P1V15_AUX_BMC @BASEBOARD_FAB2_LIB.BASEBOARD_FAB2(SCH_1):P1V15_AUX_BMC
 C9E10    1      A CAP_0603-10UF,6.3V,20%,X6S,E15A    I23 @BASEBOARD_FAB2_LIB.BASEBOARD_FAB2(SCH_1):PAGE238
  C9F4    1      A CAP_0805LF-22UF,4V,20%,X6S,C95A    I30 @BASEBOARD_FAB2_LIB.BASEBOARD_FAB2(SCH_1):PAGE238
 EU9F1    1 VOUT<0> RT9059_DFN-IC,H65765-001    I40 @BASEBOARD_FAB2_LIB.BASEBOARD_FAB2(SCH_1):PAGE238
 EU9F1    2 VOUT<1> RT9059_DFN-IC,H65765-001    I40 @BASEBOARD_FAB2_LIB.BASEBOARD_FAB2(SCH_1):PAGE238
 EU9F1    3 VOUT<2> RT9059_DFN-IC,H65765-001    I40 @BASEBOARD_FAB2_LIB.BASEBOARD_FAB2(SCH_1):PAGE238
  R9F6    1      1 4K42R2F-GP_SMD-RG-4K42R2F-GP,6A    I45 @BASEBOARD_FAB2_LIB.BASEBOARD_FAB2(SCH_1):PAGE238
 FB2T7    1      1 HCB1608KF-800T30-GP_DISCRET-G9A    I39 @BASEBOARD_FAB2_LIB.BASEBOARD_FAB2(SCH_1):PAGE150
C25W30    1      1 SC4D7U10V3KX-GP_SMD-BCG-SC4D7UA    I43 @BASEBOARD_FAB2_LIB.BASEBOARD_FAB2(SCH_1):PAGE150
C25W29    1      A CAP_0805-10UF,16V,10%,X6S,C953A    I45 @BASEBOARD_FAB2_LIB.BASEBOARD_FAB2(SCH_1):PAGE150
C25W28    1      A CAP_0402-1.0UF,6.3V,10%,X6S,D9A    I46 @BASEBOARD_FAB2_LIB.BASEBOARD_FAB2(SCH_1):PAGE150
C25W27    1      A CAP_0402-1.0UF,6.3V,10%,X6S,D9A    I48 @BASEBOARD_FAB2_LIB.BASEBOARD_FAB2(SCH_1):PAGE150
C25W26    1      A CAP_0402-1.0UF,6.3V,10%,X6S,D9A    I71 @BASEBOARD_FAB2_LIB.BASEBOARD_FAB2(SCH_1):PAGE150
C25W25    1      A CAP_0402-1.0UF,6.3V,10%,X6S,D9A    I72 @BASEBOARD_FAB2_LIB.BASEBOARD_FAB2(SCH_1):PAGE150
C25W24    1      A CAP_0402-1.0UF,6.3V,10%,X6S,D9A    I73 @BASEBOARD_FAB2_LIB.BASEBOARD_FAB2(SCH_1):PAGE150
C25W23    1      A CAP_0402-1.0UF,6.3V,10%,X6S,D9A    I75 @BASEBOARD_FAB2_LIB.BASEBOARD_FAB2(SCH_1):PAGE150
 U25W4   F6 IV11D0 AST2520A1-GP-GP_ASIC2-GB1-AST2A    I28 @BASEBOARD_FAB2_LIB.BASEBOARD_FAB2(SCH_1):PAGE148
 U25W4  G10 IV11D1 AST2520A1-GP-GP_ASIC2-GB1-AST2A    I28 @BASEBOARD_FAB2_LIB.BASEBOARD_FAB2(SCH_1):PAGE148
 U25W4  G11 IV11D2 AST2520A1-GP-GP_ASIC2-GB1-AST2A    I28 @BASEBOARD_FAB2_LIB.BASEBOARD_FAB2(SCH_1):PAGE148
 U25W4  G12 IV11D3 AST2520A1-GP-GP_ASIC2-GB1-AST2A    I28 @BASEBOARD_FAB2_LIB.BASEBOARD_FAB2(SCH_1):PAGE148
 U25W4  G13 IV11D4 AST2520A1-GP-GP_ASIC2-GB1-AST2A    I28 @BASEBOARD_FAB2_LIB.BASEBOARD_FAB2(SCH_1):PAGE148
 U25W4  G14 IV11D5 AST2520A1-GP-GP_ASIC2-GB1-AST2A    I28 @BASEBOARD_FAB2_LIB.BASEBOARD_FAB2(SCH_1):PAGE148
 U25W4  G15 IV11D6 AST2520A1-GP-GP_ASIC2-GB1-AST2A    I28 @BASEBOARD_FAB2_LIB.BASEBOARD_FAB2(SCH_1):PAGE148
 U25W4   G7 IV11D7 AST2520A1-GP-GP_ASIC2-GB1-AST2A    I28 @BASEBOARD_FAB2_LIB.BASEBOARD_FAB2(SCH_1):PAGE148
 U25W4   G8 IV11D8 AST2520A1-GP-GP_ASIC2-GB1-AST2A    I28 @BASEBOARD_FAB2_LIB.BASEBOARD_FAB2(SCH_1):PAGE148
 U25W4   G9 IV11D9 AST2520A1-GP-GP_ASIC2-GB1-AST2A    I28 @BASEBOARD_FAB2_LIB.BASEBOARD_FAB2(SCH_1):PAGE148
 U25W4  H16 IV11D10 AST2520A1-GP-GP_ASIC2-GB1-AST2A    I28 @BASEBOARD_FAB2_LIB.BASEBOARD_FAB2(SCH_1):PAGE148
 U25W4  J16 IV11D11 AST2520A1-GP-GP_ASIC2-GB1-AST2A    I28 @BASEBOARD_FAB2_LIB.BASEBOARD_FAB2(SCH_1):PAGE148
 U25W4   L7 IV11D12 AST2520A1-GP-GP_ASIC2-GB1-AST2A    I28 @BASEBOARD_FAB2_LIB.BASEBOARD_FAB2(SCH_1):PAGE148
 U25W4  N16 IV11D13 AST2520A1-GP-GP_ASIC2-GB1-AST2A    I28 @BASEBOARD_FAB2_LIB.BASEBOARD_FAB2(SCH_1):PAGE148
 U25W4   N7 IV11D14 AST2520A1-GP-GP_ASIC2-GB1-AST2A    I28 @BASEBOARD_FAB2_LIB.BASEBOARD_FAB2(SCH_1):PAGE148
 U25W4  P10 IV11D15 AST2520A1-GP-GP_ASIC2-GB1-AST2A    I28 @BASEBOARD_FAB2_LIB.BASEBOARD_FAB2(SCH_1):PAGE148
 U25W4  P11 IV11D16 AST2520A1-GP-GP_ASIC2-GB1-AST2A    I28 @BASEBOARD_FAB2_LIB.BASEBOARD_FAB2(SCH_1):PAGE148
 U25W4  P12 IV11D17 AST2520A1-GP-GP_ASIC2-GB1-AST2A    I28 @BASEBOARD_FAB2_LIB.BASEBOARD_FAB2(SCH_1):PAGE148
 U25W4  P13 IV11D18 AST2520A1-GP-GP_ASIC2-GB1-AST2A    I28 @BASEBOARD_FAB2_LIB.BASEBOARD_FAB2(SCH_1):PAGE148
 U25W4  P14 IV11D19 AST2520A1-GP-GP_ASIC2-GB1-AST2A    I28 @BASEBOARD_FAB2_LIB.BASEBOARD_FAB2(SCH_1):PAGE148
 U25W4  P16 IV11D20 AST2520A1-GP-GP_ASIC2-GB1-AST2A    I28 @BASEBOARD_FAB2_LIB.BASEBOARD_FAB2(SCH_1):PAGE148
 U25W4   P7 IV11D21 AST2520A1-GP-GP_ASIC2-GB1-AST2A    I28 @BASEBOARD_FAB2_LIB.BASEBOARD_FAB2(SCH_1):PAGE148
 U25W4   P9 IV11D22 AST2520A1-GP-GP_ASIC2-GB1-AST2A    I28 @BASEBOARD_FAB2_LIB.BASEBOARD_FAB2(SCH_1):PAGE148
 U25W4  R16 IV11D23 AST2520A1-GP-GP_ASIC2-GB1-AST2A    I28 @BASEBOARD_FAB2_LIB.BASEBOARD_FAB2(SCH_1):PAGE148
 U25W4   R7 IV11D24 AST2520A1-GP-GP_ASIC2-GB1-AST2A    I28 @BASEBOARD_FAB2_LIB.BASEBOARD_FAB2(SCH_1):PAGE148
 U25W4  L17 PEAV11 AST2520A1-GP-GP_ASIC2-GB1-AST2A    I28 @BASEBOARD_FAB2_LIB.BASEBOARD_FAB2(SCH_1):PAGE148
 U25W4  V17 PLLDV11 AST2520A1-GP-GP_ASIC2-GB1-AST2A    I28 @BASEBOARD_FAB2_LIB.BASEBOARD_FAB2(SCH_1):PAGE148

P1V2_AUX_BMC @BASEBOARD_FAB2_LIB.BASEBOARD_FAB2(SCH_1):P1V2_AUX_BMC
 C9F13    1      A CAP_0805LF-22UF,4V,20%,X6S,C95A     I7 @BASEBOARD_FAB2_LIB.BASEBOARD_FAB2(SCH_1):PAGE239
 C1T15    1      A CAP_0603-10UF,6.3V,20%,X6S,E15A    I12 @BASEBOARD_FAB2_LIB.BASEBOARD_FAB2(SCH_1):PAGE239
 EU9F2    1 VOUT<0> RT9059_DFN-IC,H65765-001    I70 @BASEBOARD_FAB2_LIB.BASEBOARD_FAB2(SCH_1):PAGE239
 EU9F2    2 VOUT<1> RT9059_DFN-IC,H65765-001    I70 @BASEBOARD_FAB2_LIB.BASEBOARD_FAB2(SCH_1):PAGE239
 EU9F2    3 VOUT<2> RT9059_DFN-IC,H65765-001    I70 @BASEBOARD_FAB2_LIB.BASEBOARD_FAB2(SCH_1):PAGE239
 R9F31    1      1 5K1R2F-2-GP_SMD-RG-5K1R2F-2-GPA    I98 @BASEBOARD_FAB2_LIB.BASEBOARD_FAB2(SCH_1):PAGE239
C25W55    1      1 SCD1U16V2KX-3GP_SMD-BCG-SCD1U1A    I10 @BASEBOARD_FAB2_LIB.BASEBOARD_FAB2(SCH_1):PAGE150
C25W54    1      A CAP_0402-1.0UF,6.3V,10%,X6S,D9A    I12 @BASEBOARD_FAB2_LIB.BASEBOARD_FAB2(SCH_1):PAGE150
C25W53    1      A CAP_0402-1.0UF,6.3V,10%,X6S,D9A    I13 @BASEBOARD_FAB2_LIB.BASEBOARD_FAB2(SCH_1):PAGE150
C25W52    1      A CAP_0402-1.0UF,6.3V,10%,X6S,D9A    I14 @BASEBOARD_FAB2_LIB.BASEBOARD_FAB2(SCH_1):PAGE150
C25W51    1      A CAP_0402-1.0UF,6.3V,10%,X6S,D9A    I19 @BASEBOARD_FAB2_LIB.BASEBOARD_FAB2(SCH_1):PAGE150
 U25W5   B3 VDD<0> H5AN4G6NAFR-TFC-GP_MEMORY-G2-HA     I1 @BASEBOARD_FAB2_LIB.BASEBOARD_FAB2(SCH_1):PAGE149
 U25W5   B9 VDD<1> H5AN4G6NAFR-TFC-GP_MEMORY-G2-HA     I1 @BASEBOARD_FAB2_LIB.BASEBOARD_FAB2(SCH_1):PAGE149
 U25W5   D1 VDD<2> H5AN4G6NAFR-TFC-GP_MEMORY-G2-HA     I1 @BASEBOARD_FAB2_LIB.BASEBOARD_FAB2(SCH_1):PAGE149
 U25W5   G7 VDD<3> H5AN4G6NAFR-TFC-GP_MEMORY-G2-HA     I1 @BASEBOARD_FAB2_LIB.BASEBOARD_FAB2(SCH_1):PAGE149
 U25W5   J1 VDD<4> H5AN4G6NAFR-TFC-GP_MEMORY-G2-HA     I1 @BASEBOARD_FAB2_LIB.BASEBOARD_FAB2(SCH_1):PAGE149
 U25W5   J9 VDD<5> H5AN4G6NAFR-TFC-GP_MEMORY-G2-HA     I1 @BASEBOARD_FAB2_LIB.BASEBOARD_FAB2(SCH_1):PAGE149
 U25W5   L1 VDD<6> H5AN4G6NAFR-TFC-GP_MEMORY-G2-HA     I1 @BASEBOARD_FAB2_LIB.BASEBOARD_FAB2(SCH_1):PAGE149
 U25W5   L9 VDD<7> H5AN4G6NAFR-TFC-GP_MEMORY-G2-HA     I1 @BASEBOARD_FAB2_LIB.BASEBOARD_FAB2(SCH_1):PAGE149
 U25W5   R1 VDD<8> H5AN4G6NAFR-TFC-GP_MEMORY-G2-HA     I1 @BASEBOARD_FAB2_LIB.BASEBOARD_FAB2(SCH_1):PAGE149
 U25W5   T9 VDD<9> H5AN4G6NAFR-TFC-GP_MEMORY-G2-HA     I1 @BASEBOARD_FAB2_LIB.BASEBOARD_FAB2(SCH_1):PAGE149
 U25W5   A1 VDDQ<0> H5AN4G6NAFR-TFC-GP_MEMORY-G2-HA     I1 @BASEBOARD_FAB2_LIB.BASEBOARD_FAB2(SCH_1):PAGE149
 U25W5   A9 VDDQ<1> H5AN4G6NAFR-TFC-GP_MEMORY-G2-HA     I1 @BASEBOARD_FAB2_LIB.BASEBOARD_FAB2(SCH_1):PAGE149
 U25W5   C1 VDDQ<2> H5AN4G6NAFR-TFC-GP_MEMORY-G2-HA     I1 @BASEBOARD_FAB2_LIB.BASEBOARD_FAB2(SCH_1):PAGE149
 U25W5   D9 VDDQ<3> H5AN4G6NAFR-TFC-GP_MEMORY-G2-HA     I1 @BASEBOARD_FAB2_LIB.BASEBOARD_FAB2(SCH_1):PAGE149
 U25W5   F2 VDDQ<4> H5AN4G6NAFR-TFC-GP_MEMORY-G2-HA     I1 @BASEBOARD_FAB2_LIB.BASEBOARD_FAB2(SCH_1):PAGE149
 U25W5   F8 VDDQ<5> H5AN4G6NAFR-TFC-GP_MEMORY-G2-HA     I1 @BASEBOARD_FAB2_LIB.BASEBOARD_FAB2(SCH_1):PAGE149
 U25W5   G1 VDDQ<6> H5AN4G6NAFR-TFC-GP_MEMORY-G2-HA     I1 @BASEBOARD_FAB2_LIB.BASEBOARD_FAB2(SCH_1):PAGE149
 U25W5   G9 VDDQ<7> H5AN4G6NAFR-TFC-GP_MEMORY-G2-HA     I1 @BASEBOARD_FAB2_LIB.BASEBOARD_FAB2(SCH_1):PAGE149
 U25W5   J2 VDDQ<8> H5AN4G6NAFR-TFC-GP_MEMORY-G2-HA     I1 @BASEBOARD_FAB2_LIB.BASEBOARD_FAB2(SCH_1):PAGE149
 U25W5   J8 VDDQ<9> H5AN4G6NAFR-TFC-GP_MEMORY-G2-HA     I1 @BASEBOARD_FAB2_LIB.BASEBOARD_FAB2(SCH_1):PAGE149
 R9F29    1      A RES_0402-4.75K,1%,1/16W,CHIP,GA    I16 @BASEBOARD_FAB2_LIB.BASEBOARD_FAB2(SCH_1):PAGE149
C25W16    1      A CAP_0402LF-100.0PF,50V,5%,COG,A    I37 @BASEBOARD_FAB2_LIB.BASEBOARD_FAB2(SCH_1):PAGE149
C25W17    1      1 SC1U16V3KX-2GP_SMD-BCG-SC1U16VA    I38 @BASEBOARD_FAB2_LIB.BASEBOARD_FAB2(SCH_1):PAGE149
C25W18    1      1 SC1U16V3KX-2GP_SMD-BCG-SC1U16VA    I68 @BASEBOARD_FAB2_LIB.BASEBOARD_FAB2(SCH_1):PAGE149
C25W19    1      1 SC4D7U10V3KX-GP_SMD-BCG-SC4D7UA    I69 @BASEBOARD_FAB2_LIB.BASEBOARD_FAB2(SCH_1):PAGE149
 C25W1    1      A CAP_0402-1.0UF,16V,10%,X6S,D97A    I71 @BASEBOARD_FAB2_LIB.BASEBOARD_FAB2(SCH_1):PAGE149
 C25W2    1      A CAP_0402-1.0UF,16V,10%,X6S,D97A    I72 @BASEBOARD_FAB2_LIB.BASEBOARD_FAB2(SCH_1):PAGE149
 C25W3    1      A CAP_0402-1.0UF,16V,10%,X6S,D97A    I73 @BASEBOARD_FAB2_LIB.BASEBOARD_FAB2(SCH_1):PAGE149
 C25W4    1      A CAP_0402-1.0UF,16V,10%,X6S,D97A    I74 @BASEBOARD_FAB2_LIB.BASEBOARD_FAB2(SCH_1):PAGE149
 C25W5    1      A CAP_0402-1.0UF,16V,10%,X6S,D97A    I96 @BASEBOARD_FAB2_LIB.BASEBOARD_FAB2(SCH_1):PAGE149
 C25W6    1      A CAP_0402-1.0UF,16V,10%,X6S,D97A    I97 @BASEBOARD_FAB2_LIB.BASEBOARD_FAB2(SCH_1):PAGE149
R25W119    1      A RES_0402-4.75K,1%,1/16W,CHIP,GA   I120 @BASEBOARD_FAB2_LIB.BASEBOARD_FAB2(SCH_1):PAGE149
 R1T30    1      A RES_0402-1.00K,1%,1/16W,CHIP,GA   I124 @BASEBOARD_FAB2_LIB.BASEBOARD_FAB2(SCH_1):PAGE149
C25W10    1      A CAP_0402LF-0.01UF,25V,10%,X7R,A   I158 @BASEBOARD_FAB2_LIB.BASEBOARD_FAB2(SCH_1):PAGE149
R25W27    2      2 120R2F-GP_RCL_GP-120R2F-GP,64.A   I186 @BASEBOARD_FAB2_LIB.BASEBOARD_FAB2(SCH_1):PAGE149
R25W28    2      2 120R2F-GP_RCL_GP-120R2F-GP,64.A   I187 @BASEBOARD_FAB2_LIB.BASEBOARD_FAB2(SCH_1):PAGE149
R25W30    2      2 120R2F-GP_RCL_GP-120R2F-GP,64.A   I188 @BASEBOARD_FAB2_LIB.BASEBOARD_FAB2(SCH_1):PAGE149
R25W29    2      2 120R2F-GP_RCL_GP-120R2F-GP,64.A   I189 @BASEBOARD_FAB2_LIB.BASEBOARD_FAB2(SCH_1):PAGE149
R25W31    2      2 120R2F-GP_RCL_GP-120R2F-GP,64.A   I190 @BASEBOARD_FAB2_LIB.BASEBOARD_FAB2(SCH_1):PAGE149
R25W32    2      2 120R2F-GP_RCL_GP-120R2F-GP,64.A   I191 @BASEBOARD_FAB2_LIB.BASEBOARD_FAB2(SCH_1):PAGE149
R25W33    2      2 120R2F-GP_RCL_GP-120R2F-GP,64.A   I192 @BASEBOARD_FAB2_LIB.BASEBOARD_FAB2(SCH_1):PAGE149
R25W34    2      2 120R2F-GP_RCL_GP-120R2F-GP,64.A   I193 @BASEBOARD_FAB2_LIB.BASEBOARD_FAB2(SCH_1):PAGE149
R25W35    2      2 120R2F-GP_RCL_GP-120R2F-GP,64.A   I194 @BASEBOARD_FAB2_LIB.BASEBOARD_FAB2(SCH_1):PAGE149
R25W36    2      2 120R2F-GP_RCL_GP-120R2F-GP,64.A   I195 @BASEBOARD_FAB2_LIB.BASEBOARD_FAB2(SCH_1):PAGE149
R25W37    2      2 120R2F-GP_RCL_GP-120R2F-GP,64.A   I196 @BASEBOARD_FAB2_LIB.BASEBOARD_FAB2(SCH_1):PAGE149
R25W38    2      2 120R2F-GP_RCL_GP-120R2F-GP,64.A   I197 @BASEBOARD_FAB2_LIB.BASEBOARD_FAB2(SCH_1):PAGE149
R25W39    2      2 120R2F-GP_RCL_GP-120R2F-GP,64.A   I198 @BASEBOARD_FAB2_LIB.BASEBOARD_FAB2(SCH_1):PAGE149
R25W41    2      2 120R2F-GP_RCL_GP-120R2F-GP,64.A   I199 @BASEBOARD_FAB2_LIB.BASEBOARD_FAB2(SCH_1):PAGE149
R25W40    2      2 120R2F-GP_RCL_GP-120R2F-GP,64.A   I200 @BASEBOARD_FAB2_LIB.BASEBOARD_FAB2(SCH_1):PAGE149
R25W42    2      2 120R2F-GP_RCL_GP-120R2F-GP,64.A   I201 @BASEBOARD_FAB2_LIB.BASEBOARD_FAB2(SCH_1):PAGE149
R25W43    2      2 120R2F-GP_RCL_GP-120R2F-GP,64.A   I202 @BASEBOARD_FAB2_LIB.BASEBOARD_FAB2(SCH_1):PAGE149
R25W44    2      2 120R2F-GP_RCL_GP-120R2F-GP,64.A   I203 @BASEBOARD_FAB2_LIB.BASEBOARD_FAB2(SCH_1):PAGE149
R25W45    2      2 120R2F-GP_RCL_GP-120R2F-GP,64.A   I204 @BASEBOARD_FAB2_LIB.BASEBOARD_FAB2(SCH_1):PAGE149
R25W46    2      2 120R2F-GP_RCL_GP-120R2F-GP,64.A   I205 @BASEBOARD_FAB2_LIB.BASEBOARD_FAB2(SCH_1):PAGE149
R25W47    2      2 120R2F-GP_RCL_GP-120R2F-GP,64.A   I206 @BASEBOARD_FAB2_LIB.BASEBOARD_FAB2(SCH_1):PAGE149
R25W48    2      2 120R2F-GP_RCL_GP-120R2F-GP,64.A   I207 @BASEBOARD_FAB2_LIB.BASEBOARD_FAB2(SCH_1):PAGE149
R25W49    2      2 120R2F-GP_RCL_GP-120R2F-GP,64.A   I208 @BASEBOARD_FAB2_LIB.BASEBOARD_FAB2(SCH_1):PAGE149
R25W50    2      2 120R2F-GP_RCL_GP-120R2F-GP,64.A   I209 @BASEBOARD_FAB2_LIB.BASEBOARD_FAB2(SCH_1):PAGE149
R25W51    2      2 120R2F-GP_RCL_GP-120R2F-GP,64.A   I210 @BASEBOARD_FAB2_LIB.BASEBOARD_FAB2(SCH_1):PAGE149
R25W52    2      2 120R2F-GP_RCL_GP-120R2F-GP,64.A   I211 @BASEBOARD_FAB2_LIB.BASEBOARD_FAB2(SCH_1):PAGE149
 U25W4  T10  MVDD0 AST2520A1-GP-GP_ASIC2-GB1-AST2A    I28 @BASEBOARD_FAB2_LIB.BASEBOARD_FAB2(SCH_1):PAGE148
 U25W4  T12  MVDD1 AST2520A1-GP-GP_ASIC2-GB1-AST2A    I28 @BASEBOARD_FAB2_LIB.BASEBOARD_FAB2(SCH_1):PAGE148
 U25W4  T13  MVDD2 AST2520A1-GP-GP_ASIC2-GB1-AST2A    I28 @BASEBOARD_FAB2_LIB.BASEBOARD_FAB2(SCH_1):PAGE148
 U25W4  T14  MVDD3 AST2520A1-GP-GP_ASIC2-GB1-AST2A    I28 @BASEBOARD_FAB2_LIB.BASEBOARD_FAB2(SCH_1):PAGE148
 U25W4   T8  MVDD4 AST2520A1-GP-GP_ASIC2-GB1-AST2A    I28 @BASEBOARD_FAB2_LIB.BASEBOARD_FAB2(SCH_1):PAGE148

P1V5_LAN @BASEBOARD_FAB2_LIB.BASEBOARD_FAB2(SCH_1):P1V5_LAN
 EU9E1   47 VDD1P5<1> SPRINGVILLE_SM1-IC,G47144-004    I72 @BASEBOARD_FAB2_LIB.BASEBOARD_FAB2(SCH_1):PAGE139
 EU9E1   39 VDD1P5_OUT SPRINGVILLE_SM1-IC,G47144-004    I72 @BASEBOARD_FAB2_LIB.BASEBOARD_FAB2(SCH_1):PAGE139
 C1R30    1      A CAP_0603-10UF,6.3V,20%,X6S,E15A   I135 @BASEBOARD_FAB2_LIB.BASEBOARD_FAB2(SCH_1):PAGE139
 C1R26    1      A CAP_A_0402V-0.1UF,16V,10%,X7R,A   I149 @BASEBOARD_FAB2_LIB.BASEBOARD_FAB2(SCH_1):PAGE139
 C1R29    1      A CAP_A_0402V-0.1UF,16V,10%,X7R,A   I150 @BASEBOARD_FAB2_LIB.BASEBOARD_FAB2(SCH_1):PAGE139
 C1R19    1      A CAP_A_0402V-0.1UF,16V,10%,X7R,A   I151 @BASEBOARD_FAB2_LIB.BASEBOARD_FAB2(SCH_1):PAGE139
 C1R31    1      A CAP_A_0402V-0.1UF,16V,10%,X7R,A   I152 @BASEBOARD_FAB2_LIB.BASEBOARD_FAB2(SCH_1):PAGE139
 C1R17    1      A CAP_0603-10UF,6.3V,20%,X6S,E15A   I153 @BASEBOARD_FAB2_LIB.BASEBOARD_FAB2(SCH_1):PAGE139
  C9E6    1      A CAP_1210-47UF,16V,20%,EMPTY,D3A   I155 @BASEBOARD_FAB2_LIB.BASEBOARD_FAB2(SCH_1):PAGE139
 R1T32    1      A RES_0603-0,5.0%,1/10W,CHIP,G22A   I238 @BASEBOARD_FAB2_LIB.BASEBOARD_FAB2(SCH_1):PAGE139
 R1T33    1      A RES_0603-0,5.0%,1/10W,EMPTY,G2A   I240 @BASEBOARD_FAB2_LIB.BASEBOARD_FAB2(SCH_1):PAGE139

P1V5_LAN_I210 @BASEBOARD_FAB2_LIB.BASEBOARD_FAB2(SCH_1):P1V5_LAN_I210
 EU9E1   56 VDD1P5<0> SPRINGVILLE_SM1-IC,G47144-004    I72 @BASEBOARD_FAB2_LIB.BASEBOARD_FAB2(SCH_1):PAGE139
 R1T32    2      B RES_0603-0,5.0%,1/10W,CHIP,G22A   I238 @BASEBOARD_FAB2_LIB.BASEBOARD_FAB2(SCH_1):PAGE139

P1V8_MCP_CPU0 @BASEBOARD_FAB2_LIB.BASEBOARD_FAB2(SCH_1):P1V8_MCP_CPU0
  U5D1  B17 RSVD<294> SKX_EXT_B_BGA1-IC,TBD   I204 @BASEBOARD_FAB2_LIB.BASEBOARD_FAB2(SCH_1):PAGE22
  U5D1  B15 RSVD<295> SKX_EXT_B_BGA1-IC,TBD   I204 @BASEBOARD_FAB2_LIB.BASEBOARD_FAB2(SCH_1):PAGE22
  U5D1  B13 RSVD<296> SKX_EXT_B_BGA1-IC,TBD   I204 @BASEBOARD_FAB2_LIB.BASEBOARD_FAB2(SCH_1):PAGE22
  U5D1  A16 RSVD<301> SKX_EXT_B_BGA1-IC,TBD   I204 @BASEBOARD_FAB2_LIB.BASEBOARD_FAB2(SCH_1):PAGE22
  U5D1  A14 RSVD<302> SKX_EXT_B_BGA1-IC,TBD   I204 @BASEBOARD_FAB2_LIB.BASEBOARD_FAB2(SCH_1):PAGE22
  C6D1    1      A CAP_0603LF-10UF,4V,20%,X6S,E15A    I19 @BASEBOARD_FAB2_LIB.BASEBOARD_FAB2(SCH_1):PAGE38
  U5D1 BT27 CD_VCCIN<0> SKX_EXT_B_BGA1-IC,TBD    I34 @BASEBOARD_FAB2_LIB.BASEBOARD_FAB2(SCH_1):PAGE38
  U5D1 BU26 CD_VCCIN<1> SKX_EXT_B_BGA1-IC,TBD    I34 @BASEBOARD_FAB2_LIB.BASEBOARD_FAB2(SCH_1):PAGE38
  U5D1 BV27 CD_VCCIN<2> SKX_EXT_B_BGA1-IC,TBD    I34 @BASEBOARD_FAB2_LIB.BASEBOARD_FAB2(SCH_1):PAGE38
  U5D1 BY27 CD_VCCIN<3> SKX_EXT_B_BGA1-IC,TBD    I34 @BASEBOARD_FAB2_LIB.BASEBOARD_FAB2(SCH_1):PAGE38
 C1M29    1      A CAP_A_0402V-0.1UF,16V,10%,X7R,A   I147 @BASEBOARD_FAB2_LIB.BASEBOARD_FAB2(SCH_1):PAGE113
  J9B4    4    IO4 SCONN10_C12536004_SMLF-CONN,C1A   I175 @BASEBOARD_FAB2_LIB.BASEBOARD_FAB2(SCH_1):PAGE113
  U1M5    2      A 74CBTLV1G125_SMLF-IC,C88177-00A   I196 @BASEBOARD_FAB2_LIB.BASEBOARD_FAB2(SCH_1):PAGE113
 R1M19    1      A RES_0402-1.00K,1%,1/16W,CHIP,GA   I202 @BASEBOARD_FAB2_LIB.BASEBOARD_FAB2(SCH_1):PAGE113
 R9B12    1      A RES_0402-1.00K,1%,1/16W,CHIP,GA   I203 @BASEBOARD_FAB2_LIB.BASEBOARD_FAB2(SCH_1):PAGE113
 R1M20    1      A RES_0402-1.00K,1%,1/16W,CHIP,GA   I204 @BASEBOARD_FAB2_LIB.BASEBOARD_FAB2(SCH_1):PAGE113
 R1M21    1      A RES_0402-1.00K,1%,1/16W,CHIP,GA   I205 @BASEBOARD_FAB2_LIB.BASEBOARD_FAB2(SCH_1):PAGE113
  U4R1    2      A 74CBTLV1G125_SMLF-IC,C88177-00A   I206 @BASEBOARD_FAB2_LIB.BASEBOARD_FAB2(SCH_1):PAGE113
  C4T2    1      A CAP_A_0402V-1.0UF,6.3V,10%,X6SA     I9 @BASEBOARD_FAB2_LIB.BASEBOARD_FAB2(SCH_1):PAGE194
  C4T1    1      A CAP_A_0402V-1.0UF,6.3V,10%,X6SA    I16 @BASEBOARD_FAB2_LIB.BASEBOARD_FAB2(SCH_1):PAGE194
  J6E1   E1   IOE1 SCONN120_H61426002_SM-CONN,H61A    I55 @BASEBOARD_FAB2_LIB.BASEBOARD_FAB2(SCH_1):PAGE194
  J6E1   E2   IOE2 SCONN120_H61426002_SM-CONN,H61A    I55 @BASEBOARD_FAB2_LIB.BASEBOARD_FAB2(SCH_1):PAGE194
  J6E1   F1   IOF1 SCONN120_H61426002_SM-CONN,H61A    I55 @BASEBOARD_FAB2_LIB.BASEBOARD_FAB2(SCH_1):PAGE194
  J6E1   F2   IOF2 SCONN120_H61426002_SM-CONN,H61A    I55 @BASEBOARD_FAB2_LIB.BASEBOARD_FAB2(SCH_1):PAGE194
  C3T1    1      A CAP_A_0603V-47UF,4V,20%,X5R,60A   I149 @BASEBOARD_FAB2_LIB.BASEBOARD_FAB2(SCH_1):PAGE194
  C3T2    1      A CAP_A_0603V-47UF,4V,20%,X5R,60A   I150 @BASEBOARD_FAB2_LIB.BASEBOARD_FAB2(SCH_1):PAGE194

P1V8_MCP_CPU1 @BASEBOARD_FAB2_LIB.BASEBOARD_FAB2(SCH_1):P1V8_MCP_CPU1
  U2D1  B17 RSVD<294> SKX_EXT_B_BGA1-IC,TBD   I169 @BASEBOARD_FAB2_LIB.BASEBOARD_FAB2(SCH_1):PAGE56
  U2D1  B15 RSVD<295> SKX_EXT_B_BGA1-IC,TBD   I169 @BASEBOARD_FAB2_LIB.BASEBOARD_FAB2(SCH_1):PAGE56
  U2D1  B13 RSVD<296> SKX_EXT_B_BGA1-IC,TBD   I169 @BASEBOARD_FAB2_LIB.BASEBOARD_FAB2(SCH_1):PAGE56
  U2D1  A16 RSVD<301> SKX_EXT_B_BGA1-IC,TBD   I169 @BASEBOARD_FAB2_LIB.BASEBOARD_FAB2(SCH_1):PAGE56
  U2D1  A14 RSVD<302> SKX_EXT_B_BGA1-IC,TBD   I169 @BASEBOARD_FAB2_LIB.BASEBOARD_FAB2(SCH_1):PAGE56
  C3D3    1      A CAP_0603LF-10UF,4V,20%,X6S,E15A    I25 @BASEBOARD_FAB2_LIB.BASEBOARD_FAB2(SCH_1):PAGE72
  U2D1 BT27 CD_VCCIN<0> SKX_EXT_B_BGA1-IC,TBD    I33 @BASEBOARD_FAB2_LIB.BASEBOARD_FAB2(SCH_1):PAGE72
  U2D1 BU26 CD_VCCIN<1> SKX_EXT_B_BGA1-IC,TBD    I33 @BASEBOARD_FAB2_LIB.BASEBOARD_FAB2(SCH_1):PAGE72
  U2D1 BV27 CD_VCCIN<2> SKX_EXT_B_BGA1-IC,TBD    I33 @BASEBOARD_FAB2_LIB.BASEBOARD_FAB2(SCH_1):PAGE72
  U2D1 BY27 CD_VCCIN<3> SKX_EXT_B_BGA1-IC,TBD    I33 @BASEBOARD_FAB2_LIB.BASEBOARD_FAB2(SCH_1):PAGE72
  U6M1    2      A 74CBTLV1G125_SMLF-IC,C88177-00A   I190 @BASEBOARD_FAB2_LIB.BASEBOARD_FAB2(SCH_1):PAGE113
  J4E1   E1   IOE1 SCONN120_H61426002_SM-CONN,H61A    I45 @BASEBOARD_FAB2_LIB.BASEBOARD_FAB2(SCH_1):PAGE193
  J4E1   E2   IOE2 SCONN120_H61426002_SM-CONN,H61A    I45 @BASEBOARD_FAB2_LIB.BASEBOARD_FAB2(SCH_1):PAGE193
  J4E1   F1   IOF1 SCONN120_H61426002_SM-CONN,H61A    I45 @BASEBOARD_FAB2_LIB.BASEBOARD_FAB2(SCH_1):PAGE193
  J4E1   F2   IOF2 SCONN120_H61426002_SM-CONN,H61A    I45 @BASEBOARD_FAB2_LIB.BASEBOARD_FAB2(SCH_1):PAGE193
  C4F1    1      A CAP_A_0402V-1.0UF,6.3V,10%,X6SA    I68 @BASEBOARD_FAB2_LIB.BASEBOARD_FAB2(SCH_1):PAGE193
  C4F3    1      A CAP_A_0402V-1.0UF,6.3V,10%,X6SA    I70 @BASEBOARD_FAB2_LIB.BASEBOARD_FAB2(SCH_1):PAGE193
  C3F1    1      A CAP_A_0603V-47UF,4V,20%,X5R,60A   I140 @BASEBOARD_FAB2_LIB.BASEBOARD_FAB2(SCH_1):PAGE193
  C4F2    1      A CAP_A_0603V-47UF,4V,20%,X5R,60A   I141 @BASEBOARD_FAB2_LIB.BASEBOARD_FAB2(SCH_1):PAGE193

P1V8_PCH_STBY @BASEBOARD_FAB2_LIB.BASEBOARD_FAB2(SCH_1):P1V8_PCH_STBY
  U7C1 BA29 VCCP10GBE_HV_1P8<0> LBG_CORE_QAT_EXT_D_BGA1-IC,H91A    I63 @BASEBOARD_FAB2_LIB.BASEBOARD_FAB2(SCH_1):PAGE122
  U7C1 BA27 VCCP10GBE_HV_1P8<1> LBG_CORE_QAT_EXT_D_BGA1-IC,H91A    I63 @BASEBOARD_FAB2_LIB.BASEBOARD_FAB2(SCH_1):PAGE122
  U7C1 BD46 VCCP_1P8<0> LBG_CORE_QAT_EXT_D_BGA1-IC,H91A    I63 @BASEBOARD_FAB2_LIB.BASEBOARD_FAB2(SCH_1):PAGE122
  U7C1 AE26 VCCP_1P8<1> LBG_CORE_QAT_EXT_D_BGA1-IC,H91A    I63 @BASEBOARD_FAB2_LIB.BASEBOARD_FAB2(SCH_1):PAGE122
  U7C1 AU29 VCCPGPP_1P8<0> LBG_CORE_QAT_EXT_D_BGA1-IC,H91A    I63 @BASEBOARD_FAB2_LIB.BASEBOARD_FAB2(SCH_1):PAGE122
  U7C1 AW29 VCCPGPP_1P8<1> LBG_CORE_QAT_EXT_D_BGA1-IC,H91A    I63 @BASEBOARD_FAB2_LIB.BASEBOARD_FAB2(SCH_1):PAGE122
  U7C1 AT29 VCCPGPP_1P8<2> LBG_CORE_QAT_EXT_D_BGA1-IC,H91A    I63 @BASEBOARD_FAB2_LIB.BASEBOARD_FAB2(SCH_1):PAGE122
  U7C1 AM29 VCCPGPP_1P8<3> LBG_CORE_QAT_EXT_D_BGA1-IC,H91A    I63 @BASEBOARD_FAB2_LIB.BASEBOARD_FAB2(SCH_1):PAGE122
  U7C1 AP29 VCCPGPP_1P8<4> LBG_CORE_QAT_EXT_D_BGA1-IC,H91A    I63 @BASEBOARD_FAB2_LIB.BASEBOARD_FAB2(SCH_1):PAGE122
  U7C1 AW27 VCCPGPP_1P8<5> LBG_CORE_QAT_EXT_D_BGA1-IC,H91A    I63 @BASEBOARD_FAB2_LIB.BASEBOARD_FAB2(SCH_1):PAGE122
  U7C1 AK24 VCCPGPP_1P8<6> LBG_CORE_QAT_EXT_D_BGA1-IC,H91A    I63 @BASEBOARD_FAB2_LIB.BASEBOARD_FAB2(SCH_1):PAGE122
  U7C1 AG27 VCCPHDA_1P8 LBG_CORE_QAT_EXT_D_BGA1-IC,H91A    I63 @BASEBOARD_FAB2_LIB.BASEBOARD_FAB2(SCH_1):PAGE122
  U7C1 AK29 VCCPSPI_1P8 LBG_CORE_QAT_EXT_D_BGA1-IC,H91A    I63 @BASEBOARD_FAB2_LIB.BASEBOARD_FAB2(SCH_1):PAGE122
  C8B2    1      A CAP_A_0603V-22.0UF,4V,20%,X6S,A    I30 @BASEBOARD_FAB2_LIB.BASEBOARD_FAB2(SCH_1):PAGE130
  C8B3    1      A CAP_A_0603V-22.0UF,4V,20%,X6S,A    I32 @BASEBOARD_FAB2_LIB.BASEBOARD_FAB2(SCH_1):PAGE130
  C7D3    1      A CAP_A_0603V-22.0UF,4V,20%,X6S,A    I38 @BASEBOARD_FAB2_LIB.BASEBOARD_FAB2(SCH_1):PAGE130
  C8B4    1      A CAP_A_0603V-22.0UF,4V,20%,X6S,A    I39 @BASEBOARD_FAB2_LIB.BASEBOARD_FAB2(SCH_1):PAGE130
  C8B1    1      A CAP_A_0603V-22.0UF,4V,20%,X6S,A    I41 @BASEBOARD_FAB2_LIB.BASEBOARD_FAB2(SCH_1):PAGE130
  C2M1    1      A CAP_A_0603V-22.0UF,4V,20%,X6S,A    I43 @BASEBOARD_FAB2_LIB.BASEBOARD_FAB2(SCH_1):PAGE130
  C2M2    1      A CAP_A_0603V-22.0UF,4V,20%,X6S,A    I45 @BASEBOARD_FAB2_LIB.BASEBOARD_FAB2(SCH_1):PAGE130
 C2N15    1      A CAP_A_0402V-1.0UF,6.3V,10%,X6SA    I47 @BASEBOARD_FAB2_LIB.BASEBOARD_FAB2(SCH_1):PAGE130
 C3N21    1      A CAP_A_0402V-1.0UF,6.3V,10%,X6SA    I49 @BASEBOARD_FAB2_LIB.BASEBOARD_FAB2(SCH_1):PAGE130
 C3N25    1      A CAP_A_0402V-1.0UF,6.3V,10%,X6SA    I50 @BASEBOARD_FAB2_LIB.BASEBOARD_FAB2(SCH_1):PAGE130
 C2N16    1      A CAP_A_0402V-1.0UF,6.3V,10%,X6SA    I52 @BASEBOARD_FAB2_LIB.BASEBOARD_FAB2(SCH_1):PAGE130
 C3N22    1      A CAP_A_0402V-1.0UF,6.3V,10%,X6SA    I53 @BASEBOARD_FAB2_LIB.BASEBOARD_FAB2(SCH_1):PAGE130
 C2L45    1      A CAP_0805-22UF,6.3V,20%,X6S,C95A    I12 @BASEBOARD_FAB2_LIB.BASEBOARD_FAB2(SCH_1):PAGE237
 C8A14    1      A CAP_0805-22UF,6.3V,20%,X6S,C95A    I13 @BASEBOARD_FAB2_LIB.BASEBOARD_FAB2(SCH_1):PAGE237
 R8A12    1      A RES_0603-475.0,1%,1/10W,CHIP,GA    I15 @BASEBOARD_FAB2_LIB.BASEBOARD_FAB2(SCH_1):PAGE237
 C8A12    1      A CAP_0805-47UF,4V,20%,X6S,C9533A    I77 @BASEBOARD_FAB2_LIB.BASEBOARD_FAB2(SCH_1):PAGE237
 C2L32    1      A CAP_0805-47UF,4V,20%,X6S,C9533A    I79 @BASEBOARD_FAB2_LIB.BASEBOARD_FAB2(SCH_1):PAGE237
 R2L20    1      A RES_0402-63.4K,1.0%,1/16W,CHIPA    I81 @BASEBOARD_FAB2_LIB.BASEBOARD_FAB2(SCH_1):PAGE237
 EU8A2    1 VOUT<0> RT9059_DFN-IC,H65765-001    I86 @BASEBOARD_FAB2_LIB.BASEBOARD_FAB2(SCH_1):PAGE237
 EU8A2    2 VOUT<1> RT9059_DFN-IC,H65765-001    I86 @BASEBOARD_FAB2_LIB.BASEBOARD_FAB2(SCH_1):PAGE237
 EU8A2    3 VOUT<2> RT9059_DFN-IC,H65765-001    I86 @BASEBOARD_FAB2_LIB.BASEBOARD_FAB2(SCH_1):PAGE237

P2E_SSB_BMC_RX_C_DN @BASEBOARD_FAB2_LIB.BASEBOARD_FAB2(SCH_1):P2E_SSB_BMC_RX_C_DN
  U7C1 AN70 PCIE4_GBE_RXN LBG_CORE_QAT_EXT_D_BGA1-IC,H91A   I220 @BASEBOARD_FAB2_LIB.BASEBOARD_FAB2(SCH_1):PAGE116
  R3M9    1      A RES_0402-100.0K,1%,1/16W,CHIP,A   I234 @BASEBOARD_FAB2_LIB.BASEBOARD_FAB2(SCH_1):PAGE116
C25W21    2      B CAP_A_0402V-0.1UF,16V,10%,EMPTA    I44 @BASEBOARD_FAB2_LIB.BASEBOARD_FAB2(SCH_1):PAGE145

P2E_SSB_BMC_RX_C_DP @BASEBOARD_FAB2_LIB.BASEBOARD_FAB2(SCH_1):P2E_SSB_BMC_RX_C_DP
  U7C1 AN72 PCIE4_GBE_RXP LBG_CORE_QAT_EXT_D_BGA1-IC,H91A   I220 @BASEBOARD_FAB2_LIB.BASEBOARD_FAB2(SCH_1):PAGE116
  R3M8    1      A RES_0402-100.0K,1%,1/16W,CHIP,A   I235 @BASEBOARD_FAB2_LIB.BASEBOARD_FAB2(SCH_1):PAGE116
C25W20    2      B CAP_A_0402V-0.1UF,16V,10%,EMPTA    I45 @BASEBOARD_FAB2_LIB.BASEBOARD_FAB2(SCH_1):PAGE145

P2E_SSB_BMC_RX_DN @BASEBOARD_FAB2_LIB.BASEBOARD_FAB2(SCH_1):P2E_SSB_BMC_RX_DN
C25W21    1      A CAP_A_0402V-0.1UF,16V,10%,EMPTA    I44 @BASEBOARD_FAB2_LIB.BASEBOARD_FAB2(SCH_1):PAGE145
 U25W4  L22  PETXN AST2520A1-GP-GP_ASIC2-GB1-AST2A   I117 @BASEBOARD_FAB2_LIB.BASEBOARD_FAB2(SCH_1):PAGE145

P2E_SSB_BMC_RX_DP @BASEBOARD_FAB2_LIB.BASEBOARD_FAB2(SCH_1):P2E_SSB_BMC_RX_DP
C25W20    1      A CAP_A_0402V-0.1UF,16V,10%,EMPTA    I45 @BASEBOARD_FAB2_LIB.BASEBOARD_FAB2(SCH_1):PAGE145
 U25W4  L21  PETXP AST2520A1-GP-GP_ASIC2-GB1-AST2A   I117 @BASEBOARD_FAB2_LIB.BASEBOARD_FAB2(SCH_1):PAGE145

P2E_SSB_BMC_TX_C_DN @BASEBOARD_FAB2_LIB.BASEBOARD_FAB2(SCH_1):P2E_SSB_BMC_TX_C_DN
  C2M3    2      B CAP_A_0402V-0.1UF,16V,10%,EMPTA   I183 @BASEBOARD_FAB2_LIB.BASEBOARD_FAB2(SCH_1):PAGE116
R25W65    1      A RES_0402-100.0K,1%,1/16W,CHIP,A    I38 @BASEBOARD_FAB2_LIB.BASEBOARD_FAB2(SCH_1):PAGE145
 U25W4  M22  PERXN AST2520A1-GP-GP_ASIC2-GB1-AST2A   I117 @BASEBOARD_FAB2_LIB.BASEBOARD_FAB2(SCH_1):PAGE145

P2E_SSB_BMC_TX_C_DP @BASEBOARD_FAB2_LIB.BASEBOARD_FAB2(SCH_1):P2E_SSB_BMC_TX_C_DP
  C2M4    2      B CAP_A_0402V-0.1UF,16V,10%,EMPTA   I182 @BASEBOARD_FAB2_LIB.BASEBOARD_FAB2(SCH_1):PAGE116
R25W64    1      A RES_0402-100.0K,1%,1/16W,CHIP,A    I36 @BASEBOARD_FAB2_LIB.BASEBOARD_FAB2(SCH_1):PAGE145
 U25W4  M21  PERXP AST2520A1-GP-GP_ASIC2-GB1-AST2A   I117 @BASEBOARD_FAB2_LIB.BASEBOARD_FAB2(SCH_1):PAGE145

P2E_SSB_BMC_TX_DN @BASEBOARD_FAB2_LIB.BASEBOARD_FAB2(SCH_1):P2E_SSB_BMC_TX_DN
  C2M3    1      A CAP_A_0402V-0.1UF,16V,10%,EMPTA   I183 @BASEBOARD_FAB2_LIB.BASEBOARD_FAB2(SCH_1):PAGE116
  U7C1 BG66 PCIE4_GBE_TXN LBG_CORE_QAT_EXT_D_BGA1-IC,H91A   I220 @BASEBOARD_FAB2_LIB.BASEBOARD_FAB2(SCH_1):PAGE116

P2E_SSB_BMC_TX_DP @BASEBOARD_FAB2_LIB.BASEBOARD_FAB2(SCH_1):P2E_SSB_BMC_TX_DP
  C2M4    1      A CAP_A_0402V-0.1UF,16V,10%,EMPTA   I182 @BASEBOARD_FAB2_LIB.BASEBOARD_FAB2(SCH_1):PAGE116
  U7C1 BJ66 PCIE4_GBE_TXP LBG_CORE_QAT_EXT_D_BGA1-IC,H91A   I220 @BASEBOARD_FAB2_LIB.BASEBOARD_FAB2(SCH_1):PAGE116

P2V5_AUX_BMC @BASEBOARD_FAB2_LIB.BASEBOARD_FAB2(SCH_1):P2V5_AUX_BMC
EU25F2    1 VOUT<0> RT9059_DFN-IC,H65765-001    I73 @BASEBOARD_FAB2_LIB.BASEBOARD_FAB2(SCH_1):PAGE239
EU25F2    2 VOUT<1> RT9059_DFN-IC,H65765-001    I73 @BASEBOARD_FAB2_LIB.BASEBOARD_FAB2(SCH_1):PAGE239
EU25F2    3 VOUT<2> RT9059_DFN-IC,H65765-001    I73 @BASEBOARD_FAB2_LIB.BASEBOARD_FAB2(SCH_1):PAGE239
 C9W13    1      A CAP_0805LF-22UF,4V,20%,X6S,C95A    I81 @BASEBOARD_FAB2_LIB.BASEBOARD_FAB2(SCH_1):PAGE239
 C1W15    1      A CAP_0603-10UF,6.3V,20%,X6S,E15A    I83 @BASEBOARD_FAB2_LIB.BASEBOARD_FAB2(SCH_1):PAGE239
 U25W5   B1 VPP<0> H5AN4G6NAFR-TFC-GP_MEMORY-G2-HA     I1 @BASEBOARD_FAB2_LIB.BASEBOARD_FAB2(SCH_1):PAGE149
C25W15    1      1 SCD1U16V2KX-3GP_SMD-BCG-SCD1U1A    I39 @BASEBOARD_FAB2_LIB.BASEBOARD_FAB2(SCH_1):PAGE149
C25W14    1      1 SCD1U16V2KX-3GP_SMD-BCG-SCD1U1A    I44 @BASEBOARD_FAB2_LIB.BASEBOARD_FAB2(SCH_1):PAGE149
 R9W31    1      1 21K5R2F-GP_RCL_GP-21K5R2F-GP,6A    I99 @BASEBOARD_FAB2_LIB.BASEBOARD_FAB2(SCH_1):PAGE239

P3E_CPU0_PE1_PCH_CON_RXN<10> @BASEBOARD_FAB2_LIB.BASEBOARD_FAB2(SCH_1):P3E_CPU0_PE1_PCH_CON_RXN(10)
  J8G1   88   IO88 SCONN200_H68296001_SM-CONN,H68A   I258 @BASEBOARD_FAB2_LIB.BASEBOARD_FAB2(SCH_1):PAGE108
  R780    2      B RES_0402-0.0,5%,1/16W,CHIP,G21A    I97 @BASEBOARD_FAB2_LIB.BASEBOARD_FAB2(SCH_1):PAGE244

P3E_CPU0_PE1_PCH_CON_RXN<11> @BASEBOARD_FAB2_LIB.BASEBOARD_FAB2(SCH_1):P3E_CPU0_PE1_PCH_CON_RXN(11)
  J8G1   82   IO82 SCONN200_H68296001_SM-CONN,H68A   I258 @BASEBOARD_FAB2_LIB.BASEBOARD_FAB2(SCH_1):PAGE108
  R778    2      B RES_0402-0.0,5%,1/16W,CHIP,G21A    I94 @BASEBOARD_FAB2_LIB.BASEBOARD_FAB2(SCH_1):PAGE244

P3E_CPU0_PE1_PCH_CON_RXN<12> @BASEBOARD_FAB2_LIB.BASEBOARD_FAB2(SCH_1):P3E_CPU0_PE1_PCH_CON_RXN(12)
  J8G1   76   IO76 SCONN200_H68296001_SM-CONN,H68A   I258 @BASEBOARD_FAB2_LIB.BASEBOARD_FAB2(SCH_1):PAGE108
  R775    2      B RES_0402-0.0,5%,1/16W,CHIP,G21A    I93 @BASEBOARD_FAB2_LIB.BASEBOARD_FAB2(SCH_1):PAGE244

P3E_CPU0_PE1_PCH_CON_RXN<13> @BASEBOARD_FAB2_LIB.BASEBOARD_FAB2(SCH_1):P3E_CPU0_PE1_PCH_CON_RXN(13)
  J8G1   70   IO70 SCONN200_H68296001_SM-CONN,H68A   I258 @BASEBOARD_FAB2_LIB.BASEBOARD_FAB2(SCH_1):PAGE108
  R771    2      B RES_0402-0.0,5%,1/16W,CHIP,G21A    I65 @BASEBOARD_FAB2_LIB.BASEBOARD_FAB2(SCH_1):PAGE244

P3E_CPU0_PE1_PCH_CON_RXN<14> @BASEBOARD_FAB2_LIB.BASEBOARD_FAB2(SCH_1):P3E_CPU0_PE1_PCH_CON_RXN(14)
  J8G1   60   IO60 SCONN200_H68296001_SM-CONN,H68A   I258 @BASEBOARD_FAB2_LIB.BASEBOARD_FAB2(SCH_1):PAGE108
  R768    2      B RES_0402-0.0,5%,1/16W,CHIP,G21A    I66 @BASEBOARD_FAB2_LIB.BASEBOARD_FAB2(SCH_1):PAGE244

P3E_CPU0_PE1_PCH_CON_RXN<15> @BASEBOARD_FAB2_LIB.BASEBOARD_FAB2(SCH_1):P3E_CPU0_PE1_PCH_CON_RXN(15)
  J8G1   54   IO54 SCONN200_H68296001_SM-CONN,H68A   I258 @BASEBOARD_FAB2_LIB.BASEBOARD_FAB2(SCH_1):PAGE108
  R760    2      B RES_0402-0.0,5%,1/16W,CHIP,G21A    I64 @BASEBOARD_FAB2_LIB.BASEBOARD_FAB2(SCH_1):PAGE244

P3E_CPU0_PE1_PCH_CON_RXN<8> @BASEBOARD_FAB2_LIB.BASEBOARD_FAB2(SCH_1):P3E_CPU0_PE1_PCH_CON_RXN(8)
  J8G1  100  IO100 SCONN200_H68296001_SM-CONN,H68A   I258 @BASEBOARD_FAB2_LIB.BASEBOARD_FAB2(SCH_1):PAGE108
  R784    2      B RES_0402-0.0,5%,1/16W,CHIP,G21A    I99 @BASEBOARD_FAB2_LIB.BASEBOARD_FAB2(SCH_1):PAGE244

P3E_CPU0_PE1_PCH_CON_RXN<9> @BASEBOARD_FAB2_LIB.BASEBOARD_FAB2(SCH_1):P3E_CPU0_PE1_PCH_CON_RXN(9)
  J8G1   96   IO96 SCONN200_H68296001_SM-CONN,H68A   I258 @BASEBOARD_FAB2_LIB.BASEBOARD_FAB2(SCH_1):PAGE108
  R782    2      B RES_0402-0.0,5%,1/16W,CHIP,G21A    I98 @BASEBOARD_FAB2_LIB.BASEBOARD_FAB2(SCH_1):PAGE244

P3E_CPU0_PE1_PCH_CON_RXP<10> @BASEBOARD_FAB2_LIB.BASEBOARD_FAB2(SCH_1):P3E_CPU0_PE1_PCH_CON_RXP(10)
  J8G1   90   IO90 SCONN200_H68296001_SM-CONN,H68A   I258 @BASEBOARD_FAB2_LIB.BASEBOARD_FAB2(SCH_1):PAGE108
  R781    2      B RES_0402-0.0,5%,1/16W,CHIP,G21A    I86 @BASEBOARD_FAB2_LIB.BASEBOARD_FAB2(SCH_1):PAGE244

P3E_CPU0_PE1_PCH_CON_RXP<11> @BASEBOARD_FAB2_LIB.BASEBOARD_FAB2(SCH_1):P3E_CPU0_PE1_PCH_CON_RXP(11)
  J8G1   84   IO84 SCONN200_H68296001_SM-CONN,H68A   I258 @BASEBOARD_FAB2_LIB.BASEBOARD_FAB2(SCH_1):PAGE108
  R779    2      B RES_0402-0.0,5%,1/16W,CHIP,G21A    I74 @BASEBOARD_FAB2_LIB.BASEBOARD_FAB2(SCH_1):PAGE244

P3E_CPU0_PE1_PCH_CON_RXP<12> @BASEBOARD_FAB2_LIB.BASEBOARD_FAB2(SCH_1):P3E_CPU0_PE1_PCH_CON_RXP(12)
  J8G1   78   IO78 SCONN200_H68296001_SM-CONN,H68A   I258 @BASEBOARD_FAB2_LIB.BASEBOARD_FAB2(SCH_1):PAGE108
  R777    2      B RES_0402-0.0,5%,1/16W,CHIP,G21A    I80 @BASEBOARD_FAB2_LIB.BASEBOARD_FAB2(SCH_1):PAGE244

P3E_CPU0_PE1_PCH_CON_RXP<13> @BASEBOARD_FAB2_LIB.BASEBOARD_FAB2(SCH_1):P3E_CPU0_PE1_PCH_CON_RXP(13)
  J8G1   72   IO72 SCONN200_H68296001_SM-CONN,H68A   I258 @BASEBOARD_FAB2_LIB.BASEBOARD_FAB2(SCH_1):PAGE108
  R774    2      B RES_0402-0.0,5%,1/16W,CHIP,G21A    I72 @BASEBOARD_FAB2_LIB.BASEBOARD_FAB2(SCH_1):PAGE244

P3E_CPU0_PE1_PCH_CON_RXP<14> @BASEBOARD_FAB2_LIB.BASEBOARD_FAB2(SCH_1):P3E_CPU0_PE1_PCH_CON_RXP(14)
  J8G1   62   IO62 SCONN200_H68296001_SM-CONN,H68A   I258 @BASEBOARD_FAB2_LIB.BASEBOARD_FAB2(SCH_1):PAGE108
  R769    2      B RES_0402-0.0,5%,1/16W,CHIP,G21A    I58 @BASEBOARD_FAB2_LIB.BASEBOARD_FAB2(SCH_1):PAGE244

P3E_CPU0_PE1_PCH_CON_RXP<15> @BASEBOARD_FAB2_LIB.BASEBOARD_FAB2(SCH_1):P3E_CPU0_PE1_PCH_CON_RXP(15)
  J8G1   56   IO56 SCONN200_H68296001_SM-CONN,H68A   I258 @BASEBOARD_FAB2_LIB.BASEBOARD_FAB2(SCH_1):PAGE108
  R767    2      B RES_0402-0.0,5%,1/16W,CHIP,G21A    I39 @BASEBOARD_FAB2_LIB.BASEBOARD_FAB2(SCH_1):PAGE244

P3E_CPU0_PE1_PCH_CON_RXP<8> @BASEBOARD_FAB2_LIB.BASEBOARD_FAB2(SCH_1):P3E_CPU0_PE1_PCH_CON_RXP(8)
  R785    2      B RES_0402-0.0,5%,1/16W,CHIP,G21A   I103 @BASEBOARD_FAB2_LIB.BASEBOARD_FAB2(SCH_1):PAGE244
  J8G1  102  IO102 SCONN200_H68296001_SM-CONN,H68A    I78 @BASEBOARD_FAB2_LIB.BASEBOARD_FAB2(SCH_1):PAGE109

P3E_CPU0_PE1_PCH_CON_RXP<9> @BASEBOARD_FAB2_LIB.BASEBOARD_FAB2(SCH_1):P3E_CPU0_PE1_PCH_CON_RXP(9)
  J8G1   94   IO94 SCONN200_H68296001_SM-CONN,H68A   I258 @BASEBOARD_FAB2_LIB.BASEBOARD_FAB2(SCH_1):PAGE108
  R783    2      B RES_0402-0.0,5%,1/16W,CHIP,G21A    I77 @BASEBOARD_FAB2_LIB.BASEBOARD_FAB2(SCH_1):PAGE244

P3E_CPU0_PE1_PCH_CON_TXN<10> @BASEBOARD_FAB2_LIB.BASEBOARD_FAB2(SCH_1):P3E_CPU0_PE1_PCH_CON_TXN(10)
  J8G1   85   IO85 SCONN200_H68296001_SM-CONN,H68A   I258 @BASEBOARD_FAB2_LIB.BASEBOARD_FAB2(SCH_1):PAGE108
  C834    2      B CAP_0402-0.22UF,16V,10%,X7R,A3A    I50 @BASEBOARD_FAB2_LIB.BASEBOARD_FAB2(SCH_1):PAGE244

P3E_CPU0_PE1_PCH_CON_TXN<11> @BASEBOARD_FAB2_LIB.BASEBOARD_FAB2(SCH_1):P3E_CPU0_PE1_PCH_CON_TXN(11)
  J8G1   79   IO79 SCONN200_H68296001_SM-CONN,H68A   I258 @BASEBOARD_FAB2_LIB.BASEBOARD_FAB2(SCH_1):PAGE108
  C832    2      B CAP_0402-0.22UF,16V,10%,X7R,A3A    I30 @BASEBOARD_FAB2_LIB.BASEBOARD_FAB2(SCH_1):PAGE244

P3E_CPU0_PE1_PCH_CON_TXN<12> @BASEBOARD_FAB2_LIB.BASEBOARD_FAB2(SCH_1):P3E_CPU0_PE1_PCH_CON_TXN(12)
  J8G1   73   IO73 SCONN200_H68296001_SM-CONN,H68A   I258 @BASEBOARD_FAB2_LIB.BASEBOARD_FAB2(SCH_1):PAGE108
  C840    2      B CAP_0402-0.22UF,16V,10%,X7R,A3A    I29 @BASEBOARD_FAB2_LIB.BASEBOARD_FAB2(SCH_1):PAGE244

P3E_CPU0_PE1_PCH_CON_TXN<13> @BASEBOARD_FAB2_LIB.BASEBOARD_FAB2(SCH_1):P3E_CPU0_PE1_PCH_CON_TXN(13)
  J8G1   67   IO67 SCONN200_H68296001_SM-CONN,H68A   I258 @BASEBOARD_FAB2_LIB.BASEBOARD_FAB2(SCH_1):PAGE108
  C828    2      B CAP_0402-0.22UF,16V,10%,X7R,A3A    I28 @BASEBOARD_FAB2_LIB.BASEBOARD_FAB2(SCH_1):PAGE244

P3E_CPU0_PE1_PCH_CON_TXN<14> @BASEBOARD_FAB2_LIB.BASEBOARD_FAB2(SCH_1):P3E_CPU0_PE1_PCH_CON_TXN(14)
  J8G1   59   IO59 SCONN200_H68296001_SM-CONN,H68A   I258 @BASEBOARD_FAB2_LIB.BASEBOARD_FAB2(SCH_1):PAGE108
  C826    2      B CAP_0402-0.22UF,16V,10%,X7R,A3A    I24 @BASEBOARD_FAB2_LIB.BASEBOARD_FAB2(SCH_1):PAGE244

P3E_CPU0_PE1_PCH_CON_TXN<15> @BASEBOARD_FAB2_LIB.BASEBOARD_FAB2(SCH_1):P3E_CPU0_PE1_PCH_CON_TXN(15)
  J8G1   51   IO51 SCONN200_H68296001_SM-CONN,H68A   I258 @BASEBOARD_FAB2_LIB.BASEBOARD_FAB2(SCH_1):PAGE108
  C830    2      B CAP_0402-0.22UF,16V,10%,X7R,A3A    I23 @BASEBOARD_FAB2_LIB.BASEBOARD_FAB2(SCH_1):PAGE244

P3E_CPU0_PE1_PCH_CON_TXN<8> @BASEBOARD_FAB2_LIB.BASEBOARD_FAB2(SCH_1):P3E_CPU0_PE1_PCH_CON_TXN(8)
  J8G1   97   IO97 SCONN200_H68296001_SM-CONN,H68A   I258 @BASEBOARD_FAB2_LIB.BASEBOARD_FAB2(SCH_1):PAGE108
  C842    2      B CAP_0402-0.22UF,16V,10%,X7R,A3A    I52 @BASEBOARD_FAB2_LIB.BASEBOARD_FAB2(SCH_1):PAGE244

P3E_CPU0_PE1_PCH_CON_TXN<9> @BASEBOARD_FAB2_LIB.BASEBOARD_FAB2(SCH_1):P3E_CPU0_PE1_PCH_CON_TXN(9)
  J8G1   91   IO91 SCONN200_H68296001_SM-CONN,H68A   I258 @BASEBOARD_FAB2_LIB.BASEBOARD_FAB2(SCH_1):PAGE108
  C844    2      B CAP_0402-0.22UF,16V,10%,X7R,A3A    I51 @BASEBOARD_FAB2_LIB.BASEBOARD_FAB2(SCH_1):PAGE244

P3E_CPU0_PE1_PCH_CON_TXP<10> @BASEBOARD_FAB2_LIB.BASEBOARD_FAB2(SCH_1):P3E_CPU0_PE1_PCH_CON_TXP(10)
  J8G1   87   IO87 SCONN200_H68296001_SM-CONN,H68A   I258 @BASEBOARD_FAB2_LIB.BASEBOARD_FAB2(SCH_1):PAGE108
  C835    2      B CAP_0402-0.22UF,16V,10%,X7R,A3A    I41 @BASEBOARD_FAB2_LIB.BASEBOARD_FAB2(SCH_1):PAGE244

P3E_CPU0_PE1_PCH_CON_TXP<11> @BASEBOARD_FAB2_LIB.BASEBOARD_FAB2(SCH_1):P3E_CPU0_PE1_PCH_CON_TXP(11)
  J8G1   81   IO81 SCONN200_H68296001_SM-CONN,H68A   I258 @BASEBOARD_FAB2_LIB.BASEBOARD_FAB2(SCH_1):PAGE108
  C833    2      B CAP_0402-0.22UF,16V,10%,X7R,A3A     I8 @BASEBOARD_FAB2_LIB.BASEBOARD_FAB2(SCH_1):PAGE244

P3E_CPU0_PE1_PCH_CON_TXP<12> @BASEBOARD_FAB2_LIB.BASEBOARD_FAB2(SCH_1):P3E_CPU0_PE1_PCH_CON_TXP(12)
  J8G1   75   IO75 SCONN200_H68296001_SM-CONN,H68A   I258 @BASEBOARD_FAB2_LIB.BASEBOARD_FAB2(SCH_1):PAGE108
  C841    2      B CAP_0402-0.22UF,16V,10%,X7R,A3A    I17 @BASEBOARD_FAB2_LIB.BASEBOARD_FAB2(SCH_1):PAGE244

P3E_CPU0_PE1_PCH_CON_TXP<13> @BASEBOARD_FAB2_LIB.BASEBOARD_FAB2(SCH_1):P3E_CPU0_PE1_PCH_CON_TXP(13)
  J8G1   69   IO69 SCONN200_H68296001_SM-CONN,H68A   I258 @BASEBOARD_FAB2_LIB.BASEBOARD_FAB2(SCH_1):PAGE108
  C829    2      B CAP_0402-0.22UF,16V,10%,X7R,A3A     I5 @BASEBOARD_FAB2_LIB.BASEBOARD_FAB2(SCH_1):PAGE244

P3E_CPU0_PE1_PCH_CON_TXP<14> @BASEBOARD_FAB2_LIB.BASEBOARD_FAB2(SCH_1):P3E_CPU0_PE1_PCH_CON_TXP(14)
  J8G1   57   IO57 SCONN200_H68296001_SM-CONN,H68A   I258 @BASEBOARD_FAB2_LIB.BASEBOARD_FAB2(SCH_1):PAGE108
  C827    2      B CAP_0402-0.22UF,16V,10%,X7R,A3A    I12 @BASEBOARD_FAB2_LIB.BASEBOARD_FAB2(SCH_1):PAGE244

P3E_CPU0_PE1_PCH_CON_TXP<15> @BASEBOARD_FAB2_LIB.BASEBOARD_FAB2(SCH_1):P3E_CPU0_PE1_PCH_CON_TXP(15)
  J8G1   53   IO53 SCONN200_H68296001_SM-CONN,H68A   I258 @BASEBOARD_FAB2_LIB.BASEBOARD_FAB2(SCH_1):PAGE108
  C831    2      B CAP_0402-0.22UF,16V,10%,X7R,A3A     I2 @BASEBOARD_FAB2_LIB.BASEBOARD_FAB2(SCH_1):PAGE244

P3E_CPU0_PE1_PCH_CON_TXP<8> @BASEBOARD_FAB2_LIB.BASEBOARD_FAB2(SCH_1):P3E_CPU0_PE1_PCH_CON_TXP(8)
  J8G1   99   IO99 SCONN200_H68296001_SM-CONN,H68A   I258 @BASEBOARD_FAB2_LIB.BASEBOARD_FAB2(SCH_1):PAGE108
  C843    2      B CAP_0402-0.22UF,16V,10%,X7R,A3A    I47 @BASEBOARD_FAB2_LIB.BASEBOARD_FAB2(SCH_1):PAGE244

P3E_CPU0_PE1_PCH_CON_TXP<9> @BASEBOARD_FAB2_LIB.BASEBOARD_FAB2(SCH_1):P3E_CPU0_PE1_PCH_CON_TXP(9)
  J8G1   93   IO93 SCONN200_H68296001_SM-CONN,H68A   I258 @BASEBOARD_FAB2_LIB.BASEBOARD_FAB2(SCH_1):PAGE108
  C845    2      B CAP_0402-0.22UF,16V,10%,X7R,A3A    I35 @BASEBOARD_FAB2_LIB.BASEBOARD_FAB2(SCH_1):PAGE244

P3E_CPU0_PE1_PCH_C_TXN<10> @BASEBOARD_FAB2_LIB.BASEBOARD_FAB2(SCH_1):P3E_CPU0_PE1_PCH_C_TXN(10)
 C6B15    2      B CAP_0402-0.22UF,16V,10%,X7R,A3A   I163 @BASEBOARD_FAB2_LIB.BASEBOARD_FAB2(SCH_1):PAGE105
  U7C1  A59 PCIEUP_10_RXP LBG_CORE_QAT_EXT_D_BGA1-IC,H91A     I9 @BASEBOARD_FAB2_LIB.BASEBOARD_FAB2(SCH_1):PAGE117

P3E_CPU0_PE1_PCH_C_TXN<11> @BASEBOARD_FAB2_LIB.BASEBOARD_FAB2(SCH_1):P3E_CPU0_PE1_PCH_C_TXN(11)
 C6B14    2      B CAP_0402-0.22UF,16V,10%,X7R,A3A   I181 @BASEBOARD_FAB2_LIB.BASEBOARD_FAB2(SCH_1):PAGE105
  U7C1  D60 PCIEUP_11_RXN LBG_CORE_QAT_EXT_D_BGA1-IC,H91A     I9 @BASEBOARD_FAB2_LIB.BASEBOARD_FAB2(SCH_1):PAGE117

P3E_CPU0_PE1_PCH_C_TXN<12> @BASEBOARD_FAB2_LIB.BASEBOARD_FAB2(SCH_1):P3E_CPU0_PE1_PCH_C_TXN(12)
 C6B11    2      B CAP_0402-0.22UF,16V,10%,X7R,A3A   I166 @BASEBOARD_FAB2_LIB.BASEBOARD_FAB2(SCH_1):PAGE105
  U7C1  A61 PCIEUP_12_RXP LBG_CORE_QAT_EXT_D_BGA1-IC,H91A     I9 @BASEBOARD_FAB2_LIB.BASEBOARD_FAB2(SCH_1):PAGE117

P3E_CPU0_PE1_PCH_C_TXN<13> @BASEBOARD_FAB2_LIB.BASEBOARD_FAB2(SCH_1):P3E_CPU0_PE1_PCH_C_TXN(13)
  C6B9    2      B CAP_0402-0.22UF,16V,10%,X7R,A3A   I185 @BASEBOARD_FAB2_LIB.BASEBOARD_FAB2(SCH_1):PAGE105
  U7C1  B62 PCIEUP_13_RXP LBG_CORE_QAT_EXT_D_BGA1-IC,H91A     I9 @BASEBOARD_FAB2_LIB.BASEBOARD_FAB2(SCH_1):PAGE117

P3E_CPU0_PE1_PCH_C_TXN<14> @BASEBOARD_FAB2_LIB.BASEBOARD_FAB2(SCH_1):P3E_CPU0_PE1_PCH_C_TXN(14)
  C6B6    2      B CAP_0402-0.22UF,16V,10%,X7R,A3A   I169 @BASEBOARD_FAB2_LIB.BASEBOARD_FAB2(SCH_1):PAGE105
  U7C1  A63 PCIEUP_14_RXP LBG_CORE_QAT_EXT_D_BGA1-IC,H91A     I9 @BASEBOARD_FAB2_LIB.BASEBOARD_FAB2(SCH_1):PAGE117

P3E_CPU0_PE1_PCH_C_TXN<15> @BASEBOARD_FAB2_LIB.BASEBOARD_FAB2(SCH_1):P3E_CPU0_PE1_PCH_C_TXN(15)
  C6B4    2      B CAP_0402-0.22UF,16V,10%,X7R,A3A   I196 @BASEBOARD_FAB2_LIB.BASEBOARD_FAB2(SCH_1):PAGE105
  U7C1  B64 PCIEUP_15_RXP LBG_CORE_QAT_EXT_D_BGA1-IC,H91A     I9 @BASEBOARD_FAB2_LIB.BASEBOARD_FAB2(SCH_1):PAGE117

P3E_CPU0_PE1_PCH_C_TXN<8> @BASEBOARD_FAB2_LIB.BASEBOARD_FAB2(SCH_1):P3E_CPU0_PE1_PCH_C_TXN(8)
 C6B19    2      B CAP_0402-0.22UF,16V,10%,X7R,A3A   I160 @BASEBOARD_FAB2_LIB.BASEBOARD_FAB2(SCH_1):PAGE105
  U7C1  A57 PCIEUP_8_RXP LBG_CORE_QAT_EXT_D_BGA1-IC,H91A     I9 @BASEBOARD_FAB2_LIB.BASEBOARD_FAB2(SCH_1):PAGE117

P3E_CPU0_PE1_PCH_C_TXN<9> @BASEBOARD_FAB2_LIB.BASEBOARD_FAB2(SCH_1):P3E_CPU0_PE1_PCH_C_TXN(9)
 C6B17    2      B CAP_0402-0.22UF,16V,10%,X7R,A3A   I175 @BASEBOARD_FAB2_LIB.BASEBOARD_FAB2(SCH_1):PAGE105
  U7C1  B58 PCIEUP_9_RXP LBG_CORE_QAT_EXT_D_BGA1-IC,H91A     I9 @BASEBOARD_FAB2_LIB.BASEBOARD_FAB2(SCH_1):PAGE117

P3E_CPU0_PE1_PCH_C_TXP<10> @BASEBOARD_FAB2_LIB.BASEBOARD_FAB2(SCH_1):P3E_CPU0_PE1_PCH_C_TXP(10)
 C6B16    2      B CAP_0402-0.22UF,16V,10%,X7R,A3A   I180 @BASEBOARD_FAB2_LIB.BASEBOARD_FAB2(SCH_1):PAGE105
  U7C1  C59 PCIEUP_10_RXN LBG_CORE_QAT_EXT_D_BGA1-IC,H91A     I9 @BASEBOARD_FAB2_LIB.BASEBOARD_FAB2(SCH_1):PAGE117

P3E_CPU0_PE1_PCH_C_TXP<11> @BASEBOARD_FAB2_LIB.BASEBOARD_FAB2(SCH_1):P3E_CPU0_PE1_PCH_C_TXP(11)
 C6B13    2      B CAP_0402-0.22UF,16V,10%,X7R,A3A   I189 @BASEBOARD_FAB2_LIB.BASEBOARD_FAB2(SCH_1):PAGE105
  U7C1  B60 PCIEUP_11_RXP LBG_CORE_QAT_EXT_D_BGA1-IC,H91A     I9 @BASEBOARD_FAB2_LIB.BASEBOARD_FAB2(SCH_1):PAGE117

P3E_CPU0_PE1_PCH_C_TXP<12> @BASEBOARD_FAB2_LIB.BASEBOARD_FAB2(SCH_1):P3E_CPU0_PE1_PCH_C_TXP(12)
 C6B12    2      B CAP_0402-0.22UF,16V,10%,X7R,A3A   I187 @BASEBOARD_FAB2_LIB.BASEBOARD_FAB2(SCH_1):PAGE105
  U7C1  C61 PCIEUP_12_RXN LBG_CORE_QAT_EXT_D_BGA1-IC,H91A     I9 @BASEBOARD_FAB2_LIB.BASEBOARD_FAB2(SCH_1):PAGE117

P3E_CPU0_PE1_PCH_C_TXP<13> @BASEBOARD_FAB2_LIB.BASEBOARD_FAB2(SCH_1):P3E_CPU0_PE1_PCH_C_TXP(13)
 C6B10    2      B CAP_0402-0.22UF,16V,10%,X7R,A3A   I193 @BASEBOARD_FAB2_LIB.BASEBOARD_FAB2(SCH_1):PAGE105
  U7C1  D62 PCIEUP_13_RXN LBG_CORE_QAT_EXT_D_BGA1-IC,H91A     I9 @BASEBOARD_FAB2_LIB.BASEBOARD_FAB2(SCH_1):PAGE117

P3E_CPU0_PE1_PCH_C_TXP<14> @BASEBOARD_FAB2_LIB.BASEBOARD_FAB2(SCH_1):P3E_CPU0_PE1_PCH_C_TXP(14)
  C6B8    2      B CAP_0402-0.22UF,16V,10%,X7R,A3A   I198 @BASEBOARD_FAB2_LIB.BASEBOARD_FAB2(SCH_1):PAGE105
  U7C1  C63 PCIEUP_14_RXN LBG_CORE_QAT_EXT_D_BGA1-IC,H91A     I9 @BASEBOARD_FAB2_LIB.BASEBOARD_FAB2(SCH_1):PAGE117

P3E_CPU0_PE1_PCH_C_TXP<15> @BASEBOARD_FAB2_LIB.BASEBOARD_FAB2(SCH_1):P3E_CPU0_PE1_PCH_C_TXP(15)
  C6B5    2      B CAP_0402-0.22UF,16V,10%,X7R,A3A   I201 @BASEBOARD_FAB2_LIB.BASEBOARD_FAB2(SCH_1):PAGE105
  U7C1  D64 PCIEUP_15_RXN LBG_CORE_QAT_EXT_D_BGA1-IC,H91A     I9 @BASEBOARD_FAB2_LIB.BASEBOARD_FAB2(SCH_1):PAGE117

P3E_CPU0_PE1_PCH_C_TXP<8> @BASEBOARD_FAB2_LIB.BASEBOARD_FAB2(SCH_1):P3E_CPU0_PE1_PCH_C_TXP(8)
 C6B20    2      B CAP_0402-0.22UF,16V,10%,X7R,A3A   I173 @BASEBOARD_FAB2_LIB.BASEBOARD_FAB2(SCH_1):PAGE105
  U7C1  C57 PCIEUP_8_RXN LBG_CORE_QAT_EXT_D_BGA1-IC,H91A     I9 @BASEBOARD_FAB2_LIB.BASEBOARD_FAB2(SCH_1):PAGE117

P3E_CPU0_PE1_PCH_C_TXP<9> @BASEBOARD_FAB2_LIB.BASEBOARD_FAB2(SCH_1):P3E_CPU0_PE1_PCH_C_TXP(9)
 C6B18    2      B CAP_0402-0.22UF,16V,10%,X7R,A3A   I153 @BASEBOARD_FAB2_LIB.BASEBOARD_FAB2(SCH_1):PAGE105
  U7C1  D58 PCIEUP_9_RXN LBG_CORE_QAT_EXT_D_BGA1-IC,H91A     I9 @BASEBOARD_FAB2_LIB.BASEBOARD_FAB2(SCH_1):PAGE117

P3E_CPU0_PE1_PCH_RXN<0> @BASEBOARD_FAB2_LIB.BASEBOARD_FAB2(SCH_1):P3E_CPU0_PE1_PCH_RXN(0)
  C2U4    1      A CAP_0402-0.22UF,16V,10%,X7R,A3A   I257 @BASEBOARD_FAB2_LIB.BASEBOARD_FAB2(SCH_1):PAGE107
  U7C1  J52 PCIEUP_0_TXN LBG_CORE_QAT_EXT_D_BGA1-IC,H91A     I9 @BASEBOARD_FAB2_LIB.BASEBOARD_FAB2(SCH_1):PAGE117

P3E_CPU0_PE1_PCH_RXN<10> @BASEBOARD_FAB2_LIB.BASEBOARD_FAB2(SCH_1):P3E_CPU0_PE1_PCH_RXN(10)
  U5D1 DT11 PE1_RX_DN<10> SKX_EXT_B_BGA1-IC,TBD    I84 @BASEBOARD_FAB2_LIB.BASEBOARD_FAB2(SCH_1):PAGE30
 C3M32    2      B CAP_0402-0.22UF,16V,10%,X7R,A3A   I223 @BASEBOARD_FAB2_LIB.BASEBOARD_FAB2(SCH_1):PAGE105
  R780    1      A RES_0402-0.0,5%,1/16W,CHIP,G21A    I97 @BASEBOARD_FAB2_LIB.BASEBOARD_FAB2(SCH_1):PAGE244

P3E_CPU0_PE1_PCH_RXN<11> @BASEBOARD_FAB2_LIB.BASEBOARD_FAB2(SCH_1):P3E_CPU0_PE1_PCH_RXN(11)
  U5D1 DT13 PE1_RX_DN<11> SKX_EXT_B_BGA1-IC,TBD    I84 @BASEBOARD_FAB2_LIB.BASEBOARD_FAB2(SCH_1):PAGE30
 C3M26    2      B CAP_0402-0.22UF,16V,10%,X7R,A3A   I229 @BASEBOARD_FAB2_LIB.BASEBOARD_FAB2(SCH_1):PAGE105
  R778    1      A RES_0402-0.0,5%,1/16W,CHIP,G21A    I94 @BASEBOARD_FAB2_LIB.BASEBOARD_FAB2(SCH_1):PAGE244

P3E_CPU0_PE1_PCH_RXN<12> @BASEBOARD_FAB2_LIB.BASEBOARD_FAB2(SCH_1):P3E_CPU0_PE1_PCH_RXN(12)
  U5D1 DV13 PE1_RX_DN<12> SKX_EXT_B_BGA1-IC,TBD    I84 @BASEBOARD_FAB2_LIB.BASEBOARD_FAB2(SCH_1):PAGE30
  C3M4    2      B CAP_0402-0.22UF,16V,10%,X7R,A3A   I244 @BASEBOARD_FAB2_LIB.BASEBOARD_FAB2(SCH_1):PAGE105
  R775    1      A RES_0402-0.0,5%,1/16W,CHIP,G21A    I93 @BASEBOARD_FAB2_LIB.BASEBOARD_FAB2(SCH_1):PAGE244

P3E_CPU0_PE1_PCH_RXN<13> @BASEBOARD_FAB2_LIB.BASEBOARD_FAB2(SCH_1):P3E_CPU0_PE1_PCH_RXN(13)
  U5D1 DW14 PE1_RX_DN<13> SKX_EXT_B_BGA1-IC,TBD    I84 @BASEBOARD_FAB2_LIB.BASEBOARD_FAB2(SCH_1):PAGE30
 C3M14    2      B CAP_0402-0.22UF,16V,10%,X7R,A3A   I253 @BASEBOARD_FAB2_LIB.BASEBOARD_FAB2(SCH_1):PAGE105
  R771    1      A RES_0402-0.0,5%,1/16W,CHIP,G21A    I65 @BASEBOARD_FAB2_LIB.BASEBOARD_FAB2(SCH_1):PAGE244

P3E_CPU0_PE1_PCH_RXN<14> @BASEBOARD_FAB2_LIB.BASEBOARD_FAB2(SCH_1):P3E_CPU0_PE1_PCH_RXN(14)
  U5D1 DY15 PE1_RX_DN<14> SKX_EXT_B_BGA1-IC,TBD    I84 @BASEBOARD_FAB2_LIB.BASEBOARD_FAB2(SCH_1):PAGE30
 C3M12    2      B CAP_0402-0.22UF,16V,10%,X7R,A3A   I246 @BASEBOARD_FAB2_LIB.BASEBOARD_FAB2(SCH_1):PAGE105
  R768    1      A RES_0402-0.0,5%,1/16W,CHIP,G21A    I66 @BASEBOARD_FAB2_LIB.BASEBOARD_FAB2(SCH_1):PAGE244

P3E_CPU0_PE1_PCH_RXN<15> @BASEBOARD_FAB2_LIB.BASEBOARD_FAB2(SCH_1):P3E_CPU0_PE1_PCH_RXN(15)
  U5D1 DU16 PE1_RX_DN<15> SKX_EXT_B_BGA1-IC,TBD    I84 @BASEBOARD_FAB2_LIB.BASEBOARD_FAB2(SCH_1):PAGE30
  C3M1    2      B CAP_0402-0.22UF,16V,10%,X7R,A3A   I255 @BASEBOARD_FAB2_LIB.BASEBOARD_FAB2(SCH_1):PAGE105
  R760    1      A RES_0402-0.0,5%,1/16W,CHIP,G21A    I64 @BASEBOARD_FAB2_LIB.BASEBOARD_FAB2(SCH_1):PAGE244

P3E_CPU0_PE1_PCH_RXN<1> @BASEBOARD_FAB2_LIB.BASEBOARD_FAB2(SCH_1):P3E_CPU0_PE1_PCH_RXN(1)
  C2U6    1      A CAP_0402-0.22UF,16V,10%,X7R,A3A   I260 @BASEBOARD_FAB2_LIB.BASEBOARD_FAB2(SCH_1):PAGE107
  U7C1  P56 PCIEUP_1_TXN LBG_CORE_QAT_EXT_D_BGA1-IC,H91A     I9 @BASEBOARD_FAB2_LIB.BASEBOARD_FAB2(SCH_1):PAGE117

P3E_CPU0_PE1_PCH_RXN<2> @BASEBOARD_FAB2_LIB.BASEBOARD_FAB2(SCH_1):P3E_CPU0_PE1_PCH_RXN(2)
  C2U8    1      A CAP_0402-0.22UF,16V,10%,X7R,A3A   I264 @BASEBOARD_FAB2_LIB.BASEBOARD_FAB2(SCH_1):PAGE107
  U7C1  H54 PCIEUP_2_TXN LBG_CORE_QAT_EXT_D_BGA1-IC,H91A     I9 @BASEBOARD_FAB2_LIB.BASEBOARD_FAB2(SCH_1):PAGE117

P3E_CPU0_PE1_PCH_RXN<3> @BASEBOARD_FAB2_LIB.BASEBOARD_FAB2(SCH_1):P3E_CPU0_PE1_PCH_RXN(3)
 C2U10    1      A CAP_0402-0.22UF,16V,10%,X7R,A3A   I267 @BASEBOARD_FAB2_LIB.BASEBOARD_FAB2(SCH_1):PAGE107
  U7C1  J56 PCIEUP_3_TXN LBG_CORE_QAT_EXT_D_BGA1-IC,H91A     I9 @BASEBOARD_FAB2_LIB.BASEBOARD_FAB2(SCH_1):PAGE117

P3E_CPU0_PE1_PCH_RXN<4> @BASEBOARD_FAB2_LIB.BASEBOARD_FAB2(SCH_1):P3E_CPU0_PE1_PCH_RXN(4)
 C2U12    1      A CAP_0402-0.22UF,16V,10%,X7R,A3A   I265 @BASEBOARD_FAB2_LIB.BASEBOARD_FAB2(SCH_1):PAGE107
  U7C1  N58 PCIEUP_4_TXN LBG_CORE_QAT_EXT_D_BGA1-IC,H91A     I9 @BASEBOARD_FAB2_LIB.BASEBOARD_FAB2(SCH_1):PAGE117

P3E_CPU0_PE1_PCH_RXN<5> @BASEBOARD_FAB2_LIB.BASEBOARD_FAB2(SCH_1):P3E_CPU0_PE1_PCH_RXN(5)
 C2U14    1      A CAP_0402-0.22UF,16V,10%,X7R,A3A   I287 @BASEBOARD_FAB2_LIB.BASEBOARD_FAB2(SCH_1):PAGE107
  U7C1  N61 PCIEUP_5_TXN LBG_CORE_QAT_EXT_D_BGA1-IC,H91A     I9 @BASEBOARD_FAB2_LIB.BASEBOARD_FAB2(SCH_1):PAGE117

P3E_CPU0_PE1_PCH_RXN<6> @BASEBOARD_FAB2_LIB.BASEBOARD_FAB2(SCH_1):P3E_CPU0_PE1_PCH_RXN(6)
 C2U16    1      A CAP_0402-0.22UF,16V,10%,X7R,A3A   I286 @BASEBOARD_FAB2_LIB.BASEBOARD_FAB2(SCH_1):PAGE107
  U7C1  H61 PCIEUP_6_TXN LBG_CORE_QAT_EXT_D_BGA1-IC,H91A     I9 @BASEBOARD_FAB2_LIB.BASEBOARD_FAB2(SCH_1):PAGE117

P3E_CPU0_PE1_PCH_RXN<7> @BASEBOARD_FAB2_LIB.BASEBOARD_FAB2(SCH_1):P3E_CPU0_PE1_PCH_RXN(7)
 C2U18    1      A CAP_0402-0.22UF,16V,10%,X7R,A3A   I294 @BASEBOARD_FAB2_LIB.BASEBOARD_FAB2(SCH_1):PAGE107
  U7C1  P59 PCIEUP_7_TXN LBG_CORE_QAT_EXT_D_BGA1-IC,H91A     I9 @BASEBOARD_FAB2_LIB.BASEBOARD_FAB2(SCH_1):PAGE117

P3E_CPU0_PE1_PCH_RXN<8> @BASEBOARD_FAB2_LIB.BASEBOARD_FAB2(SCH_1):P3E_CPU0_PE1_PCH_RXN(8)
  U5D1 DM11 PE1_RX_DN<8> SKX_EXT_B_BGA1-IC,TBD    I84 @BASEBOARD_FAB2_LIB.BASEBOARD_FAB2(SCH_1):PAGE30
 C3M33    2      B CAP_0402-0.22UF,16V,10%,X7R,A3A   I217 @BASEBOARD_FAB2_LIB.BASEBOARD_FAB2(SCH_1):PAGE105
  R784    1      A RES_0402-0.0,5%,1/16W,CHIP,G21A    I99 @BASEBOARD_FAB2_LIB.BASEBOARD_FAB2(SCH_1):PAGE244

P3E_CPU0_PE1_PCH_RXN<9> @BASEBOARD_FAB2_LIB.BASEBOARD_FAB2(SCH_1):P3E_CPU0_PE1_PCH_RXN(9)
  U5D1 DP11 PE1_RX_DN<9> SKX_EXT_B_BGA1-IC,TBD    I84 @BASEBOARD_FAB2_LIB.BASEBOARD_FAB2(SCH_1):PAGE30
 C3M35    2      B CAP_0402-0.22UF,16V,10%,X7R,A3A   I225 @BASEBOARD_FAB2_LIB.BASEBOARD_FAB2(SCH_1):PAGE105
  R782    1      A RES_0402-0.0,5%,1/16W,CHIP,G21A    I98 @BASEBOARD_FAB2_LIB.BASEBOARD_FAB2(SCH_1):PAGE244

P3E_CPU0_PE1_PCH_RXP<0> @BASEBOARD_FAB2_LIB.BASEBOARD_FAB2(SCH_1):P3E_CPU0_PE1_PCH_RXP(0)
  C2U3    1      A CAP_0402-0.22UF,16V,10%,X7R,A3A   I272 @BASEBOARD_FAB2_LIB.BASEBOARD_FAB2(SCH_1):PAGE107
  U7C1  G52 PCIEUP_0_TXP LBG_CORE_QAT_EXT_D_BGA1-IC,H91A     I9 @BASEBOARD_FAB2_LIB.BASEBOARD_FAB2(SCH_1):PAGE117

P3E_CPU0_PE1_PCH_RXP<10> @BASEBOARD_FAB2_LIB.BASEBOARD_FAB2(SCH_1):P3E_CPU0_PE1_PCH_RXP(10)
  U5D1 DR12 PE1_RX_DP<10> SKX_EXT_B_BGA1-IC,TBD    I84 @BASEBOARD_FAB2_LIB.BASEBOARD_FAB2(SCH_1):PAGE30
 C3M28    2      B CAP_0402-0.22UF,16V,10%,X7R,A3A   I212 @BASEBOARD_FAB2_LIB.BASEBOARD_FAB2(SCH_1):PAGE105
  R781    1      A RES_0402-0.0,5%,1/16W,CHIP,G21A    I86 @BASEBOARD_FAB2_LIB.BASEBOARD_FAB2(SCH_1):PAGE244

P3E_CPU0_PE1_PCH_RXP<11> @BASEBOARD_FAB2_LIB.BASEBOARD_FAB2(SCH_1):P3E_CPU0_PE1_PCH_RXP(11)
  U5D1 DP13 PE1_RX_DP<11> SKX_EXT_B_BGA1-IC,TBD    I84 @BASEBOARD_FAB2_LIB.BASEBOARD_FAB2(SCH_1):PAGE30
 C3M25    2      B CAP_0402-0.22UF,16V,10%,X7R,A3A   I205 @BASEBOARD_FAB2_LIB.BASEBOARD_FAB2(SCH_1):PAGE105
  R779    1      A RES_0402-0.0,5%,1/16W,CHIP,G21A    I74 @BASEBOARD_FAB2_LIB.BASEBOARD_FAB2(SCH_1):PAGE244

P3E_CPU0_PE1_PCH_RXP<12> @BASEBOARD_FAB2_LIB.BASEBOARD_FAB2(SCH_1):P3E_CPU0_PE1_PCH_RXP(12)
  U5D1 DU12 PE1_RX_DP<12> SKX_EXT_B_BGA1-IC,TBD    I84 @BASEBOARD_FAB2_LIB.BASEBOARD_FAB2(SCH_1):PAGE30
  C3M3    2      B CAP_0402-0.22UF,16V,10%,X7R,A3A   I232 @BASEBOARD_FAB2_LIB.BASEBOARD_FAB2(SCH_1):PAGE105
  R777    1      A RES_0402-0.0,5%,1/16W,CHIP,G21A    I80 @BASEBOARD_FAB2_LIB.BASEBOARD_FAB2(SCH_1):PAGE244

P3E_CPU0_PE1_PCH_RXP<13> @BASEBOARD_FAB2_LIB.BASEBOARD_FAB2(SCH_1):P3E_CPU0_PE1_PCH_RXP(13)
  U5D1 DY13 PE1_RX_DP<13> SKX_EXT_B_BGA1-IC,TBD    I84 @BASEBOARD_FAB2_LIB.BASEBOARD_FAB2(SCH_1):PAGE30
 C3M13    2      B CAP_0402-0.22UF,16V,10%,X7R,A3A   I239 @BASEBOARD_FAB2_LIB.BASEBOARD_FAB2(SCH_1):PAGE105
  R774    1      A RES_0402-0.0,5%,1/16W,CHIP,G21A    I72 @BASEBOARD_FAB2_LIB.BASEBOARD_FAB2(SCH_1):PAGE244

P3E_CPU0_PE1_PCH_RXP<14> @BASEBOARD_FAB2_LIB.BASEBOARD_FAB2(SCH_1):P3E_CPU0_PE1_PCH_RXP(14)
  U5D1 DV15 PE1_RX_DP<14> SKX_EXT_B_BGA1-IC,TBD    I84 @BASEBOARD_FAB2_LIB.BASEBOARD_FAB2(SCH_1):PAGE30
 C3M11    2      B CAP_0402-0.22UF,16V,10%,X7R,A3A   I234 @BASEBOARD_FAB2_LIB.BASEBOARD_FAB2(SCH_1):PAGE105
  R769    1      A RES_0402-0.0,5%,1/16W,CHIP,G21A    I58 @BASEBOARD_FAB2_LIB.BASEBOARD_FAB2(SCH_1):PAGE244

P3E_CPU0_PE1_PCH_RXP<15> @BASEBOARD_FAB2_LIB.BASEBOARD_FAB2(SCH_1):P3E_CPU0_PE1_PCH_RXP(15)
  U5D1 DT15 PE1_RX_DP<15> SKX_EXT_B_BGA1-IC,TBD    I84 @BASEBOARD_FAB2_LIB.BASEBOARD_FAB2(SCH_1):PAGE30
  C3M2    2      B CAP_0402-0.22UF,16V,10%,X7R,A3A   I247 @BASEBOARD_FAB2_LIB.BASEBOARD_FAB2(SCH_1):PAGE105
  R767    1      A RES_0402-0.0,5%,1/16W,CHIP,G21A    I39 @BASEBOARD_FAB2_LIB.BASEBOARD_FAB2(SCH_1):PAGE244

P3E_CPU0_PE1_PCH_RXP<1> @BASEBOARD_FAB2_LIB.BASEBOARD_FAB2(SCH_1):P3E_CPU0_PE1_PCH_RXP(1)
  C2U5    1      A CAP_0402-0.22UF,16V,10%,X7R,A3A   I274 @BASEBOARD_FAB2_LIB.BASEBOARD_FAB2(SCH_1):PAGE107
  U7C1  M56 PCIEUP_1_TXP LBG_CORE_QAT_EXT_D_BGA1-IC,H91A     I9 @BASEBOARD_FAB2_LIB.BASEBOARD_FAB2(SCH_1):PAGE117

P3E_CPU0_PE1_PCH_RXP<2> @BASEBOARD_FAB2_LIB.BASEBOARD_FAB2(SCH_1):P3E_CPU0_PE1_PCH_RXP(2)
  C2U7    1      A CAP_0402-0.22UF,16V,10%,X7R,A3A   I277 @BASEBOARD_FAB2_LIB.BASEBOARD_FAB2(SCH_1):PAGE107
  U7C1  G56 PCIEUP_2_TXP LBG_CORE_QAT_EXT_D_BGA1-IC,H91A     I9 @BASEBOARD_FAB2_LIB.BASEBOARD_FAB2(SCH_1):PAGE117

P3E_CPU0_PE1_PCH_RXP<3> @BASEBOARD_FAB2_LIB.BASEBOARD_FAB2(SCH_1):P3E_CPU0_PE1_PCH_RXP(3)
  C2U9    1      A CAP_0402-0.22UF,16V,10%,X7R,A3A   I279 @BASEBOARD_FAB2_LIB.BASEBOARD_FAB2(SCH_1):PAGE107
  U7C1  K58 PCIEUP_3_TXP LBG_CORE_QAT_EXT_D_BGA1-IC,H91A     I9 @BASEBOARD_FAB2_LIB.BASEBOARD_FAB2(SCH_1):PAGE117

P3E_CPU0_PE1_PCH_RXP<4> @BASEBOARD_FAB2_LIB.BASEBOARD_FAB2(SCH_1):P3E_CPU0_PE1_PCH_RXP(4)
 C2U11    1      A CAP_0402-0.22UF,16V,10%,X7R,A3A   I278 @BASEBOARD_FAB2_LIB.BASEBOARD_FAB2(SCH_1):PAGE107
  U7C1  M59 PCIEUP_4_TXP LBG_CORE_QAT_EXT_D_BGA1-IC,H91A     I9 @BASEBOARD_FAB2_LIB.BASEBOARD_FAB2(SCH_1):PAGE117

P3E_CPU0_PE1_PCH_RXP<5> @BASEBOARD_FAB2_LIB.BASEBOARD_FAB2(SCH_1):P3E_CPU0_PE1_PCH_RXP(5)
 C2U13    1      A CAP_0402-0.22UF,16V,10%,X7R,A3A   I297 @BASEBOARD_FAB2_LIB.BASEBOARD_FAB2(SCH_1):PAGE107
  U7C1  K61 PCIEUP_5_TXP LBG_CORE_QAT_EXT_D_BGA1-IC,H91A     I9 @BASEBOARD_FAB2_LIB.BASEBOARD_FAB2(SCH_1):PAGE117

P3E_CPU0_PE1_PCH_RXP<6> @BASEBOARD_FAB2_LIB.BASEBOARD_FAB2(SCH_1):P3E_CPU0_PE1_PCH_RXP(6)
 C2U15    1      A CAP_0402-0.22UF,16V,10%,X7R,A3A   I296 @BASEBOARD_FAB2_LIB.BASEBOARD_FAB2(SCH_1):PAGE107
  U7C1  J63 PCIEUP_6_TXP LBG_CORE_QAT_EXT_D_BGA1-IC,H91A     I9 @BASEBOARD_FAB2_LIB.BASEBOARD_FAB2(SCH_1):PAGE117

P3E_CPU0_PE1_PCH_RXP<7> @BASEBOARD_FAB2_LIB.BASEBOARD_FAB2(SCH_1):P3E_CPU0_PE1_PCH_RXP(7)
 C2U17    1      A CAP_0402-0.22UF,16V,10%,X7R,A3A   I300 @BASEBOARD_FAB2_LIB.BASEBOARD_FAB2(SCH_1):PAGE107
  U7C1  R61 PCIEUP_7_TXP LBG_CORE_QAT_EXT_D_BGA1-IC,H91A     I9 @BASEBOARD_FAB2_LIB.BASEBOARD_FAB2(SCH_1):PAGE117

P3E_CPU0_PE1_PCH_RXP<8> @BASEBOARD_FAB2_LIB.BASEBOARD_FAB2(SCH_1):P3E_CPU0_PE1_PCH_RXP(8)
  U5D1 DK11 PE1_RX_DP<8> SKX_EXT_B_BGA1-IC,TBD    I84 @BASEBOARD_FAB2_LIB.BASEBOARD_FAB2(SCH_1):PAGE30
 C3M34    2      B CAP_0402-0.22UF,16V,10%,X7R,A3A   I206 @BASEBOARD_FAB2_LIB.BASEBOARD_FAB2(SCH_1):PAGE105
  R785    1      A RES_0402-0.0,5%,1/16W,CHIP,G21A   I103 @BASEBOARD_FAB2_LIB.BASEBOARD_FAB2(SCH_1):PAGE244

P3E_CPU0_PE1_PCH_RXP<9> @BASEBOARD_FAB2_LIB.BASEBOARD_FAB2(SCH_1):P3E_CPU0_PE1_PCH_RXP(9)
  U5D1 DN10 PE1_RX_DP<9> SKX_EXT_B_BGA1-IC,TBD    I84 @BASEBOARD_FAB2_LIB.BASEBOARD_FAB2(SCH_1):PAGE30
 C3M36    2      B CAP_0402-0.22UF,16V,10%,X7R,A3A   I218 @BASEBOARD_FAB2_LIB.BASEBOARD_FAB2(SCH_1):PAGE105
  R783    1      A RES_0402-0.0,5%,1/16W,CHIP,G21A    I77 @BASEBOARD_FAB2_LIB.BASEBOARD_FAB2(SCH_1):PAGE244

P3E_CPU0_PE1_PCH_R_RXN<10> @BASEBOARD_FAB2_LIB.BASEBOARD_FAB2(SCH_1):P3E_CPU0_PE1_PCH_R_RXN(10)
 C3M32    1      A CAP_0402-0.22UF,16V,10%,X7R,A3A   I223 @BASEBOARD_FAB2_LIB.BASEBOARD_FAB2(SCH_1):PAGE105
  U7C1  N65 PCIEUP_10_TXN LBG_CORE_QAT_EXT_D_BGA1-IC,H91A     I9 @BASEBOARD_FAB2_LIB.BASEBOARD_FAB2(SCH_1):PAGE117

P3E_CPU0_PE1_PCH_R_RXN<11> @BASEBOARD_FAB2_LIB.BASEBOARD_FAB2(SCH_1):P3E_CPU0_PE1_PCH_R_RXN(11)
 C3M26    1      A CAP_0402-0.22UF,16V,10%,X7R,A3A   I229 @BASEBOARD_FAB2_LIB.BASEBOARD_FAB2(SCH_1):PAGE105
  U7C1  T59 PCIEUP_11_TXN LBG_CORE_QAT_EXT_D_BGA1-IC,H91A     I9 @BASEBOARD_FAB2_LIB.BASEBOARD_FAB2(SCH_1):PAGE117

P3E_CPU0_PE1_PCH_R_RXN<12> @BASEBOARD_FAB2_LIB.BASEBOARD_FAB2(SCH_1):P3E_CPU0_PE1_PCH_R_RXN(12)
  C3M4    1      A CAP_0402-0.22UF,16V,10%,X7R,A3A   I244 @BASEBOARD_FAB2_LIB.BASEBOARD_FAB2(SCH_1):PAGE105
  U7C1  R65 PCIEUP_12_TXN LBG_CORE_QAT_EXT_D_BGA1-IC,H91A     I9 @BASEBOARD_FAB2_LIB.BASEBOARD_FAB2(SCH_1):PAGE117

P3E_CPU0_PE1_PCH_R_RXN<13> @BASEBOARD_FAB2_LIB.BASEBOARD_FAB2(SCH_1):P3E_CPU0_PE1_PCH_R_RXN(13)
 C3M14    1      A CAP_0402-0.22UF,16V,10%,X7R,A3A   I253 @BASEBOARD_FAB2_LIB.BASEBOARD_FAB2(SCH_1):PAGE105
  U7C1  T63 PCIEUP_13_TXN LBG_CORE_QAT_EXT_D_BGA1-IC,H91A     I9 @BASEBOARD_FAB2_LIB.BASEBOARD_FAB2(SCH_1):PAGE117

P3E_CPU0_PE1_PCH_R_RXN<14> @BASEBOARD_FAB2_LIB.BASEBOARD_FAB2(SCH_1):P3E_CPU0_PE1_PCH_R_RXN(14)
 C3M12    1      A CAP_0402-0.22UF,16V,10%,X7R,A3A   I246 @BASEBOARD_FAB2_LIB.BASEBOARD_FAB2(SCH_1):PAGE105
  U7C1  W65 PCIEUP_14_TXN LBG_CORE_QAT_EXT_D_BGA1-IC,H91A     I9 @BASEBOARD_FAB2_LIB.BASEBOARD_FAB2(SCH_1):PAGE117

P3E_CPU0_PE1_PCH_R_RXN<15> @BASEBOARD_FAB2_LIB.BASEBOARD_FAB2(SCH_1):P3E_CPU0_PE1_PCH_R_RXN(15)
  C3M1    1      A CAP_0402-0.22UF,16V,10%,X7R,A3A   I255 @BASEBOARD_FAB2_LIB.BASEBOARD_FAB2(SCH_1):PAGE105
  U7C1  Y66 PCIEUP_15_TXN LBG_CORE_QAT_EXT_D_BGA1-IC,H91A     I9 @BASEBOARD_FAB2_LIB.BASEBOARD_FAB2(SCH_1):PAGE117

P3E_CPU0_PE1_PCH_R_RXN<8> @BASEBOARD_FAB2_LIB.BASEBOARD_FAB2(SCH_1):P3E_CPU0_PE1_PCH_R_RXN(8)
 C3M33    1      A CAP_0402-0.22UF,16V,10%,X7R,A3A   I217 @BASEBOARD_FAB2_LIB.BASEBOARD_FAB2(SCH_1):PAGE105
  U7C1  K65 PCIEUP_8_TXN LBG_CORE_QAT_EXT_D_BGA1-IC,H91A     I9 @BASEBOARD_FAB2_LIB.BASEBOARD_FAB2(SCH_1):PAGE117

P3E_CPU0_PE1_PCH_R_RXN<9> @BASEBOARD_FAB2_LIB.BASEBOARD_FAB2(SCH_1):P3E_CPU0_PE1_PCH_R_RXN(9)
 C3M35    1      A CAP_0402-0.22UF,16V,10%,X7R,A3A   I225 @BASEBOARD_FAB2_LIB.BASEBOARD_FAB2(SCH_1):PAGE105
  U7C1  J66 PCIEUP_9_TXN LBG_CORE_QAT_EXT_D_BGA1-IC,H91A     I9 @BASEBOARD_FAB2_LIB.BASEBOARD_FAB2(SCH_1):PAGE117

P3E_CPU0_PE1_PCH_R_RXP<10> @BASEBOARD_FAB2_LIB.BASEBOARD_FAB2(SCH_1):P3E_CPU0_PE1_PCH_R_RXP(10)
 C3M28    1      A CAP_0402-0.22UF,16V,10%,X7R,A3A   I212 @BASEBOARD_FAB2_LIB.BASEBOARD_FAB2(SCH_1):PAGE105
  U7C1  P66 PCIEUP_10_TXP LBG_CORE_QAT_EXT_D_BGA1-IC,H91A     I9 @BASEBOARD_FAB2_LIB.BASEBOARD_FAB2(SCH_1):PAGE117

P3E_CPU0_PE1_PCH_R_RXP<11> @BASEBOARD_FAB2_LIB.BASEBOARD_FAB2(SCH_1):P3E_CPU0_PE1_PCH_R_RXP(11)
 C3M25    1      A CAP_0402-0.22UF,16V,10%,X7R,A3A   I205 @BASEBOARD_FAB2_LIB.BASEBOARD_FAB2(SCH_1):PAGE105
  U7C1  V59 PCIEUP_11_TXP LBG_CORE_QAT_EXT_D_BGA1-IC,H91A     I9 @BASEBOARD_FAB2_LIB.BASEBOARD_FAB2(SCH_1):PAGE117

P3E_CPU0_PE1_PCH_R_RXP<12> @BASEBOARD_FAB2_LIB.BASEBOARD_FAB2(SCH_1):P3E_CPU0_PE1_PCH_R_RXP(12)
  C3M3    1      A CAP_0402-0.22UF,16V,10%,X7R,A3A   I232 @BASEBOARD_FAB2_LIB.BASEBOARD_FAB2(SCH_1):PAGE105
  U7C1  U65 PCIEUP_12_TXP LBG_CORE_QAT_EXT_D_BGA1-IC,H91A     I9 @BASEBOARD_FAB2_LIB.BASEBOARD_FAB2(SCH_1):PAGE117

P3E_CPU0_PE1_PCH_R_RXP<13> @BASEBOARD_FAB2_LIB.BASEBOARD_FAB2(SCH_1):P3E_CPU0_PE1_PCH_R_RXP(13)
 C3M13    1      A CAP_0402-0.22UF,16V,10%,X7R,A3A   I239 @BASEBOARD_FAB2_LIB.BASEBOARD_FAB2(SCH_1):PAGE105
  U7C1  U61 PCIEUP_13_TXP LBG_CORE_QAT_EXT_D_BGA1-IC,H91A     I9 @BASEBOARD_FAB2_LIB.BASEBOARD_FAB2(SCH_1):PAGE117

P3E_CPU0_PE1_PCH_R_RXP<14> @BASEBOARD_FAB2_LIB.BASEBOARD_FAB2(SCH_1):P3E_CPU0_PE1_PCH_R_RXP(14)
 C3M11    1      A CAP_0402-0.22UF,16V,10%,X7R,A3A   I234 @BASEBOARD_FAB2_LIB.BASEBOARD_FAB2(SCH_1):PAGE105
  U7C1  V63 PCIEUP_14_TXP LBG_CORE_QAT_EXT_D_BGA1-IC,H91A     I9 @BASEBOARD_FAB2_LIB.BASEBOARD_FAB2(SCH_1):PAGE117

P3E_CPU0_PE1_PCH_R_RXP<15> @BASEBOARD_FAB2_LIB.BASEBOARD_FAB2(SCH_1):P3E_CPU0_PE1_PCH_R_RXP(15)
  C3M2    1      A CAP_0402-0.22UF,16V,10%,X7R,A3A   I247 @BASEBOARD_FAB2_LIB.BASEBOARD_FAB2(SCH_1):PAGE105
  U7C1 AA65 PCIEUP_15_TXP LBG_CORE_QAT_EXT_D_BGA1-IC,H91A     I9 @BASEBOARD_FAB2_LIB.BASEBOARD_FAB2(SCH_1):PAGE117

P3E_CPU0_PE1_PCH_R_RXP<8> @BASEBOARD_FAB2_LIB.BASEBOARD_FAB2(SCH_1):P3E_CPU0_PE1_PCH_R_RXP(8)
 C3M34    1      A CAP_0402-0.22UF,16V,10%,X7R,A3A   I206 @BASEBOARD_FAB2_LIB.BASEBOARD_FAB2(SCH_1):PAGE105
  U7C1  M63 PCIEUP_8_TXP LBG_CORE_QAT_EXT_D_BGA1-IC,H91A     I9 @BASEBOARD_FAB2_LIB.BASEBOARD_FAB2(SCH_1):PAGE117

P3E_CPU0_PE1_PCH_R_RXP<9> @BASEBOARD_FAB2_LIB.BASEBOARD_FAB2(SCH_1):P3E_CPU0_PE1_PCH_R_RXP(9)
 C3M36    1      A CAP_0402-0.22UF,16V,10%,X7R,A3A   I218 @BASEBOARD_FAB2_LIB.BASEBOARD_FAB2(SCH_1):PAGE105
  U7C1  M66 PCIEUP_9_TXP LBG_CORE_QAT_EXT_D_BGA1-IC,H91A     I9 @BASEBOARD_FAB2_LIB.BASEBOARD_FAB2(SCH_1):PAGE117

P3E_CPU0_PE1_PCH_TXN<0> @BASEBOARD_FAB2_LIB.BASEBOARD_FAB2(SCH_1):P3E_CPU0_PE1_PCH_TXN(0)
 C3P13    2      B CAP_0402-0.22UF,16V,10%,X7R,A3A   I207 @BASEBOARD_FAB2_LIB.BASEBOARD_FAB2(SCH_1):PAGE107
  U7C1  C48 PCIEUP_0_RXN LBG_CORE_QAT_EXT_D_BGA1-IC,H91A     I9 @BASEBOARD_FAB2_LIB.BASEBOARD_FAB2(SCH_1):PAGE117

P3E_CPU0_PE1_PCH_TXN<10> @BASEBOARD_FAB2_LIB.BASEBOARD_FAB2(SCH_1):P3E_CPU0_PE1_PCH_TXN(10)
  U5D1  DW4 PE1_TX_DN<10> SKX_EXT_B_BGA1-IC,TBD    I84 @BASEBOARD_FAB2_LIB.BASEBOARD_FAB2(SCH_1):PAGE30
 C6B15    1      A CAP_0402-0.22UF,16V,10%,X7R,A3A   I163 @BASEBOARD_FAB2_LIB.BASEBOARD_FAB2(SCH_1):PAGE105
  C834    1      A CAP_0402-0.22UF,16V,10%,X7R,A3A    I50 @BASEBOARD_FAB2_LIB.BASEBOARD_FAB2(SCH_1):PAGE244

P3E_CPU0_PE1_PCH_TXN<11> @BASEBOARD_FAB2_LIB.BASEBOARD_FAB2(SCH_1):P3E_CPU0_PE1_PCH_TXN(11)
  U5D1  DU6 PE1_TX_DN<11> SKX_EXT_B_BGA1-IC,TBD    I84 @BASEBOARD_FAB2_LIB.BASEBOARD_FAB2(SCH_1):PAGE30
 C6B14    1      A CAP_0402-0.22UF,16V,10%,X7R,A3A   I181 @BASEBOARD_FAB2_LIB.BASEBOARD_FAB2(SCH_1):PAGE105
  C832    1      A CAP_0402-0.22UF,16V,10%,X7R,A3A    I30 @BASEBOARD_FAB2_LIB.BASEBOARD_FAB2(SCH_1):PAGE244

P3E_CPU0_PE1_PCH_TXN<12> @BASEBOARD_FAB2_LIB.BASEBOARD_FAB2(SCH_1):P3E_CPU0_PE1_PCH_TXN(12)
  U5D1  DV7 PE1_TX_DN<12> SKX_EXT_B_BGA1-IC,TBD    I84 @BASEBOARD_FAB2_LIB.BASEBOARD_FAB2(SCH_1):PAGE30
 C6B11    1      A CAP_0402-0.22UF,16V,10%,X7R,A3A   I166 @BASEBOARD_FAB2_LIB.BASEBOARD_FAB2(SCH_1):PAGE105
  C840    1      A CAP_0402-0.22UF,16V,10%,X7R,A3A    I29 @BASEBOARD_FAB2_LIB.BASEBOARD_FAB2(SCH_1):PAGE244

P3E_CPU0_PE1_PCH_TXN<13> @BASEBOARD_FAB2_LIB.BASEBOARD_FAB2(SCH_1):P3E_CPU0_PE1_PCH_TXN(13)
  U5D1  DY7 PE1_TX_DN<13> SKX_EXT_B_BGA1-IC,TBD    I84 @BASEBOARD_FAB2_LIB.BASEBOARD_FAB2(SCH_1):PAGE30
  C6B9    1      A CAP_0402-0.22UF,16V,10%,X7R,A3A   I185 @BASEBOARD_FAB2_LIB.BASEBOARD_FAB2(SCH_1):PAGE105
  C828    1      A CAP_0402-0.22UF,16V,10%,X7R,A3A    I28 @BASEBOARD_FAB2_LIB.BASEBOARD_FAB2(SCH_1):PAGE244

P3E_CPU0_PE1_PCH_TXN<14> @BASEBOARD_FAB2_LIB.BASEBOARD_FAB2(SCH_1):P3E_CPU0_PE1_PCH_TXN(14)
  U5D1  EA8 PE1_TX_DN<14> SKX_EXT_B_BGA1-IC,TBD    I84 @BASEBOARD_FAB2_LIB.BASEBOARD_FAB2(SCH_1):PAGE30
  C6B6    1      A CAP_0402-0.22UF,16V,10%,X7R,A3A   I169 @BASEBOARD_FAB2_LIB.BASEBOARD_FAB2(SCH_1):PAGE105
  C826    1      A CAP_0402-0.22UF,16V,10%,X7R,A3A    I24 @BASEBOARD_FAB2_LIB.BASEBOARD_FAB2(SCH_1):PAGE244

P3E_CPU0_PE1_PCH_TXN<15> @BASEBOARD_FAB2_LIB.BASEBOARD_FAB2(SCH_1):P3E_CPU0_PE1_PCH_TXN(15)
  U5D1  ED9 PE1_TX_DN<15> SKX_EXT_B_BGA1-IC,TBD    I84 @BASEBOARD_FAB2_LIB.BASEBOARD_FAB2(SCH_1):PAGE30
  C6B4    1      A CAP_0402-0.22UF,16V,10%,X7R,A3A   I196 @BASEBOARD_FAB2_LIB.BASEBOARD_FAB2(SCH_1):PAGE105
  C830    1      A CAP_0402-0.22UF,16V,10%,X7R,A3A    I23 @BASEBOARD_FAB2_LIB.BASEBOARD_FAB2(SCH_1):PAGE244

P3E_CPU0_PE1_PCH_TXN<1> @BASEBOARD_FAB2_LIB.BASEBOARD_FAB2(SCH_1):P3E_CPU0_PE1_PCH_TXN(1)
 C3P17    2      B CAP_0402-0.22UF,16V,10%,X7R,A3A   I208 @BASEBOARD_FAB2_LIB.BASEBOARD_FAB2(SCH_1):PAGE107
  U7C1  D49 PCIEUP_1_RXN LBG_CORE_QAT_EXT_D_BGA1-IC,H91A     I9 @BASEBOARD_FAB2_LIB.BASEBOARD_FAB2(SCH_1):PAGE117

P3E_CPU0_PE1_PCH_TXN<2> @BASEBOARD_FAB2_LIB.BASEBOARD_FAB2(SCH_1):P3E_CPU0_PE1_PCH_TXN(2)
 C3P20    2      B CAP_0402-0.22UF,16V,10%,X7R,A3A   I215 @BASEBOARD_FAB2_LIB.BASEBOARD_FAB2(SCH_1):PAGE107
  U7C1  C50 PCIEUP_2_RXN LBG_CORE_QAT_EXT_D_BGA1-IC,H91A     I9 @BASEBOARD_FAB2_LIB.BASEBOARD_FAB2(SCH_1):PAGE117

P3E_CPU0_PE1_PCH_TXN<3> @BASEBOARD_FAB2_LIB.BASEBOARD_FAB2(SCH_1):P3E_CPU0_PE1_PCH_TXN(3)
 C3P25    2      B CAP_0402-0.22UF,16V,10%,X7R,A3A   I216 @BASEBOARD_FAB2_LIB.BASEBOARD_FAB2(SCH_1):PAGE107
  U7C1  D51 PCIEUP_3_RXN LBG_CORE_QAT_EXT_D_BGA1-IC,H91A     I9 @BASEBOARD_FAB2_LIB.BASEBOARD_FAB2(SCH_1):PAGE117

P3E_CPU0_PE1_PCH_TXN<4> @BASEBOARD_FAB2_LIB.BASEBOARD_FAB2(SCH_1):P3E_CPU0_PE1_PCH_TXN(4)
 C3P28    2      B CAP_0402-0.22UF,16V,10%,X7R,A3A   I232 @BASEBOARD_FAB2_LIB.BASEBOARD_FAB2(SCH_1):PAGE107
  U7C1  C52 PCIEUP_4_RXN LBG_CORE_QAT_EXT_D_BGA1-IC,H91A     I9 @BASEBOARD_FAB2_LIB.BASEBOARD_FAB2(SCH_1):PAGE117

P3E_CPU0_PE1_PCH_TXN<5> @BASEBOARD_FAB2_LIB.BASEBOARD_FAB2(SCH_1):P3E_CPU0_PE1_PCH_TXN(5)
 C3P32    2      B CAP_0402-0.22UF,16V,10%,X7R,A3A   I234 @BASEBOARD_FAB2_LIB.BASEBOARD_FAB2(SCH_1):PAGE107
  U7C1  D53 PCIEUP_5_RXN LBG_CORE_QAT_EXT_D_BGA1-IC,H91A     I9 @BASEBOARD_FAB2_LIB.BASEBOARD_FAB2(SCH_1):PAGE117

P3E_CPU0_PE1_PCH_TXN<6> @BASEBOARD_FAB2_LIB.BASEBOARD_FAB2(SCH_1):P3E_CPU0_PE1_PCH_TXN(6)
 C3P37    2      B CAP_0402-0.22UF,16V,10%,X7R,A3A   I235 @BASEBOARD_FAB2_LIB.BASEBOARD_FAB2(SCH_1):PAGE107
  U7C1  C54 PCIEUP_6_RXN LBG_CORE_QAT_EXT_D_BGA1-IC,H91A     I9 @BASEBOARD_FAB2_LIB.BASEBOARD_FAB2(SCH_1):PAGE117

P3E_CPU0_PE1_PCH_TXN<7> @BASEBOARD_FAB2_LIB.BASEBOARD_FAB2(SCH_1):P3E_CPU0_PE1_PCH_TXN(7)
 C3P40    2      B CAP_0402-0.22UF,16V,10%,X7R,A3A   I241 @BASEBOARD_FAB2_LIB.BASEBOARD_FAB2(SCH_1):PAGE107
  U7C1  D55 PCIEUP_7_RXN LBG_CORE_QAT_EXT_D_BGA1-IC,H91A     I9 @BASEBOARD_FAB2_LIB.BASEBOARD_FAB2(SCH_1):PAGE117

P3E_CPU0_PE1_PCH_TXN<8> @BASEBOARD_FAB2_LIB.BASEBOARD_FAB2(SCH_1):P3E_CPU0_PE1_PCH_TXN(8)
  U5D1  DT5 PE1_TX_DN<8> SKX_EXT_B_BGA1-IC,TBD    I84 @BASEBOARD_FAB2_LIB.BASEBOARD_FAB2(SCH_1):PAGE30
 C6B19    1      A CAP_0402-0.22UF,16V,10%,X7R,A3A   I160 @BASEBOARD_FAB2_LIB.BASEBOARD_FAB2(SCH_1):PAGE105
  C842    1      A CAP_0402-0.22UF,16V,10%,X7R,A3A    I52 @BASEBOARD_FAB2_LIB.BASEBOARD_FAB2(SCH_1):PAGE244

P3E_CPU0_PE1_PCH_TXN<9> @BASEBOARD_FAB2_LIB.BASEBOARD_FAB2(SCH_1):P3E_CPU0_PE1_PCH_TXN(9)
  U5D1  DV3 PE1_TX_DN<9> SKX_EXT_B_BGA1-IC,TBD    I84 @BASEBOARD_FAB2_LIB.BASEBOARD_FAB2(SCH_1):PAGE30
 C6B17    1      A CAP_0402-0.22UF,16V,10%,X7R,A3A   I175 @BASEBOARD_FAB2_LIB.BASEBOARD_FAB2(SCH_1):PAGE105
  C844    1      A CAP_0402-0.22UF,16V,10%,X7R,A3A    I51 @BASEBOARD_FAB2_LIB.BASEBOARD_FAB2(SCH_1):PAGE244

P3E_CPU0_PE1_PCH_TXP<0> @BASEBOARD_FAB2_LIB.BASEBOARD_FAB2(SCH_1):P3E_CPU0_PE1_PCH_TXP(0)
 C3P11    2      B CAP_0402-0.22UF,16V,10%,X7R,A3A   I212 @BASEBOARD_FAB2_LIB.BASEBOARD_FAB2(SCH_1):PAGE107
  U7C1  A48 PCIEUP_0_RXP LBG_CORE_QAT_EXT_D_BGA1-IC,H91A     I9 @BASEBOARD_FAB2_LIB.BASEBOARD_FAB2(SCH_1):PAGE117

P3E_CPU0_PE1_PCH_TXP<10> @BASEBOARD_FAB2_LIB.BASEBOARD_FAB2(SCH_1):P3E_CPU0_PE1_PCH_TXP(10)
  U5D1  DU4 PE1_TX_DP<10> SKX_EXT_B_BGA1-IC,TBD    I84 @BASEBOARD_FAB2_LIB.BASEBOARD_FAB2(SCH_1):PAGE30
 C6B16    1      A CAP_0402-0.22UF,16V,10%,X7R,A3A   I180 @BASEBOARD_FAB2_LIB.BASEBOARD_FAB2(SCH_1):PAGE105
  C835    1      A CAP_0402-0.22UF,16V,10%,X7R,A3A    I41 @BASEBOARD_FAB2_LIB.BASEBOARD_FAB2(SCH_1):PAGE244

P3E_CPU0_PE1_PCH_TXP<11> @BASEBOARD_FAB2_LIB.BASEBOARD_FAB2(SCH_1):P3E_CPU0_PE1_PCH_TXP(11)
  U5D1  DV5 PE1_TX_DP<11> SKX_EXT_B_BGA1-IC,TBD    I84 @BASEBOARD_FAB2_LIB.BASEBOARD_FAB2(SCH_1):PAGE30
 C6B13    1      A CAP_0402-0.22UF,16V,10%,X7R,A3A   I189 @BASEBOARD_FAB2_LIB.BASEBOARD_FAB2(SCH_1):PAGE105
  C833    1      A CAP_0402-0.22UF,16V,10%,X7R,A3A     I8 @BASEBOARD_FAB2_LIB.BASEBOARD_FAB2(SCH_1):PAGE244

P3E_CPU0_PE1_PCH_TXP<12> @BASEBOARD_FAB2_LIB.BASEBOARD_FAB2(SCH_1):P3E_CPU0_PE1_PCH_TXP(12)
  U5D1  DT7 PE1_TX_DP<12> SKX_EXT_B_BGA1-IC,TBD    I84 @BASEBOARD_FAB2_LIB.BASEBOARD_FAB2(SCH_1):PAGE30
 C6B12    1      A CAP_0402-0.22UF,16V,10%,X7R,A3A   I187 @BASEBOARD_FAB2_LIB.BASEBOARD_FAB2(SCH_1):PAGE105
  C841    1      A CAP_0402-0.22UF,16V,10%,X7R,A3A    I17 @BASEBOARD_FAB2_LIB.BASEBOARD_FAB2(SCH_1):PAGE244

P3E_CPU0_PE1_PCH_TXP<13> @BASEBOARD_FAB2_LIB.BASEBOARD_FAB2(SCH_1):P3E_CPU0_PE1_PCH_TXP(13)
  U5D1  DW6 PE1_TX_DP<13> SKX_EXT_B_BGA1-IC,TBD    I84 @BASEBOARD_FAB2_LIB.BASEBOARD_FAB2(SCH_1):PAGE30
 C6B10    1      A CAP_0402-0.22UF,16V,10%,X7R,A3A   I193 @BASEBOARD_FAB2_LIB.BASEBOARD_FAB2(SCH_1):PAGE105
  C829    1      A CAP_0402-0.22UF,16V,10%,X7R,A3A     I5 @BASEBOARD_FAB2_LIB.BASEBOARD_FAB2(SCH_1):PAGE244

P3E_CPU0_PE1_PCH_TXP<14> @BASEBOARD_FAB2_LIB.BASEBOARD_FAB2(SCH_1):P3E_CPU0_PE1_PCH_TXP(14)
  U5D1  EB7 PE1_TX_DP<14> SKX_EXT_B_BGA1-IC,TBD    I84 @BASEBOARD_FAB2_LIB.BASEBOARD_FAB2(SCH_1):PAGE30
  C6B8    1      A CAP_0402-0.22UF,16V,10%,X7R,A3A   I198 @BASEBOARD_FAB2_LIB.BASEBOARD_FAB2(SCH_1):PAGE105
  C827    1      A CAP_0402-0.22UF,16V,10%,X7R,A3A    I12 @BASEBOARD_FAB2_LIB.BASEBOARD_FAB2(SCH_1):PAGE244

P3E_CPU0_PE1_PCH_TXP<15> @BASEBOARD_FAB2_LIB.BASEBOARD_FAB2(SCH_1):P3E_CPU0_PE1_PCH_TXP(15)
  U5D1  EC8 PE1_TX_DP<15> SKX_EXT_B_BGA1-IC,TBD    I84 @BASEBOARD_FAB2_LIB.BASEBOARD_FAB2(SCH_1):PAGE30
  C6B5    1      A CAP_0402-0.22UF,16V,10%,X7R,A3A   I201 @BASEBOARD_FAB2_LIB.BASEBOARD_FAB2(SCH_1):PAGE105
  C831    1      A CAP_0402-0.22UF,16V,10%,X7R,A3A     I2 @BASEBOARD_FAB2_LIB.BASEBOARD_FAB2(SCH_1):PAGE244

P3E_CPU0_PE1_PCH_TXP<1> @BASEBOARD_FAB2_LIB.BASEBOARD_FAB2(SCH_1):P3E_CPU0_PE1_PCH_TXP(1)
 C3P15    2      B CAP_0402-0.22UF,16V,10%,X7R,A3A   I226 @BASEBOARD_FAB2_LIB.BASEBOARD_FAB2(SCH_1):PAGE107
  U7C1  B49 PCIEUP_1_RXP LBG_CORE_QAT_EXT_D_BGA1-IC,H91A     I9 @BASEBOARD_FAB2_LIB.BASEBOARD_FAB2(SCH_1):PAGE117

P3E_CPU0_PE1_PCH_TXP<2> @BASEBOARD_FAB2_LIB.BASEBOARD_FAB2(SCH_1):P3E_CPU0_PE1_PCH_TXP(2)
 C3P18    2      B CAP_0402-0.22UF,16V,10%,X7R,A3A   I219 @BASEBOARD_FAB2_LIB.BASEBOARD_FAB2(SCH_1):PAGE107
  U7C1  A50 PCIEUP_2_RXP LBG_CORE_QAT_EXT_D_BGA1-IC,H91A     I9 @BASEBOARD_FAB2_LIB.BASEBOARD_FAB2(SCH_1):PAGE117

P3E_CPU0_PE1_PCH_TXP<3> @BASEBOARD_FAB2_LIB.BASEBOARD_FAB2(SCH_1):P3E_CPU0_PE1_PCH_TXP(3)
 C3P23    2      B CAP_0402-0.22UF,16V,10%,X7R,A3A   I229 @BASEBOARD_FAB2_LIB.BASEBOARD_FAB2(SCH_1):PAGE107
  U7C1  B51 PCIEUP_3_RXP LBG_CORE_QAT_EXT_D_BGA1-IC,H91A     I9 @BASEBOARD_FAB2_LIB.BASEBOARD_FAB2(SCH_1):PAGE117

P3E_CPU0_PE1_PCH_TXP<4> @BASEBOARD_FAB2_LIB.BASEBOARD_FAB2(SCH_1):P3E_CPU0_PE1_PCH_TXP(4)
 C3P27    2      B CAP_0402-0.22UF,16V,10%,X7R,A3A   I223 @BASEBOARD_FAB2_LIB.BASEBOARD_FAB2(SCH_1):PAGE107
  U7C1  A52 PCIEUP_4_RXP LBG_CORE_QAT_EXT_D_BGA1-IC,H91A     I9 @BASEBOARD_FAB2_LIB.BASEBOARD_FAB2(SCH_1):PAGE117

P3E_CPU0_PE1_PCH_TXP<5> @BASEBOARD_FAB2_LIB.BASEBOARD_FAB2(SCH_1):P3E_CPU0_PE1_PCH_TXP(5)
 C3P30    2      B CAP_0402-0.22UF,16V,10%,X7R,A3A   I245 @BASEBOARD_FAB2_LIB.BASEBOARD_FAB2(SCH_1):PAGE107
  U7C1  B53 PCIEUP_5_RXP LBG_CORE_QAT_EXT_D_BGA1-IC,H91A     I9 @BASEBOARD_FAB2_LIB.BASEBOARD_FAB2(SCH_1):PAGE117

P3E_CPU0_PE1_PCH_TXP<6> @BASEBOARD_FAB2_LIB.BASEBOARD_FAB2(SCH_1):P3E_CPU0_PE1_PCH_TXP(6)
 C3P35    2      B CAP_0402-0.22UF,16V,10%,X7R,A3A   I240 @BASEBOARD_FAB2_LIB.BASEBOARD_FAB2(SCH_1):PAGE107
  U7C1  A54 PCIEUP_6_RXP LBG_CORE_QAT_EXT_D_BGA1-IC,H91A     I9 @BASEBOARD_FAB2_LIB.BASEBOARD_FAB2(SCH_1):PAGE117

P3E_CPU0_PE1_PCH_TXP<7> @BASEBOARD_FAB2_LIB.BASEBOARD_FAB2(SCH_1):P3E_CPU0_PE1_PCH_TXP(7)
 C3P39    2      B CAP_0402-0.22UF,16V,10%,X7R,A3A   I248 @BASEBOARD_FAB2_LIB.BASEBOARD_FAB2(SCH_1):PAGE107
  U7C1  B55 PCIEUP_7_RXP LBG_CORE_QAT_EXT_D_BGA1-IC,H91A     I9 @BASEBOARD_FAB2_LIB.BASEBOARD_FAB2(SCH_1):PAGE117

P3E_CPU0_PE1_PCH_TXP<8> @BASEBOARD_FAB2_LIB.BASEBOARD_FAB2(SCH_1):P3E_CPU0_PE1_PCH_TXP(8)
  U5D1  DR4 PE1_TX_DP<8> SKX_EXT_B_BGA1-IC,TBD    I84 @BASEBOARD_FAB2_LIB.BASEBOARD_FAB2(SCH_1):PAGE30
 C6B20    1      A CAP_0402-0.22UF,16V,10%,X7R,A3A   I173 @BASEBOARD_FAB2_LIB.BASEBOARD_FAB2(SCH_1):PAGE105
  C843    1      A CAP_0402-0.22UF,16V,10%,X7R,A3A    I47 @BASEBOARD_FAB2_LIB.BASEBOARD_FAB2(SCH_1):PAGE244

P3E_CPU0_PE1_PCH_TXP<9> @BASEBOARD_FAB2_LIB.BASEBOARD_FAB2(SCH_1):P3E_CPU0_PE1_PCH_TXP(9)
  U5D1  DU2 PE1_TX_DP<9> SKX_EXT_B_BGA1-IC,TBD    I84 @BASEBOARD_FAB2_LIB.BASEBOARD_FAB2(SCH_1):PAGE30
 C6B18    1      A CAP_0402-0.22UF,16V,10%,X7R,A3A   I153 @BASEBOARD_FAB2_LIB.BASEBOARD_FAB2(SCH_1):PAGE105
  C845    1      A CAP_0402-0.22UF,16V,10%,X7R,A3A    I35 @BASEBOARD_FAB2_LIB.BASEBOARD_FAB2(SCH_1):PAGE244

P3E_CPU0_PE1_SS_C_TXN<0> @BASEBOARD_FAB2_LIB.BASEBOARD_FAB2(SCH_1):P3E_CPU0_PE1_SS_C_TXN(0)
 C3P12    2      B CAP_0402-0.22UF,16V,10%,EMPTY,A   I415 @BASEBOARD_FAB2_LIB.BASEBOARD_FAB2(SCH_1):PAGE107
  J8G1  145  IO145 SCONN200_H68296001_SM-CONN,H68A    I78 @BASEBOARD_FAB2_LIB.BASEBOARD_FAB2(SCH_1):PAGE109

P3E_CPU0_PE1_SS_C_TXN<1> @BASEBOARD_FAB2_LIB.BASEBOARD_FAB2(SCH_1):P3E_CPU0_PE1_SS_C_TXN(1)
 C3P16    2      B CAP_0402-0.22UF,16V,10%,EMPTY,A   I422 @BASEBOARD_FAB2_LIB.BASEBOARD_FAB2(SCH_1):PAGE107
  J8G1  141  IO141 SCONN200_H68296001_SM-CONN,H68A    I78 @BASEBOARD_FAB2_LIB.BASEBOARD_FAB2(SCH_1):PAGE109

P3E_CPU0_PE1_SS_C_TXN<2> @BASEBOARD_FAB2_LIB.BASEBOARD_FAB2(SCH_1):P3E_CPU0_PE1_SS_C_TXN(2)
 C3P21    2      B CAP_0402-0.22UF,16V,10%,EMPTY,A   I423 @BASEBOARD_FAB2_LIB.BASEBOARD_FAB2(SCH_1):PAGE107
  J8G1  133  IO133 SCONN200_H68296001_SM-CONN,H68A    I78 @BASEBOARD_FAB2_LIB.BASEBOARD_FAB2(SCH_1):PAGE109

P3E_CPU0_PE1_SS_C_TXN<3> @BASEBOARD_FAB2_LIB.BASEBOARD_FAB2(SCH_1):P3E_CPU0_PE1_SS_C_TXN(3)
 C3P24    2      B CAP_0402-0.22UF,16V,10%,EMPTY,A   I424 @BASEBOARD_FAB2_LIB.BASEBOARD_FAB2(SCH_1):PAGE107
  J8G1  127  IO127 SCONN200_H68296001_SM-CONN,H68A    I78 @BASEBOARD_FAB2_LIB.BASEBOARD_FAB2(SCH_1):PAGE109

P3E_CPU0_PE1_SS_C_TXN<4> @BASEBOARD_FAB2_LIB.BASEBOARD_FAB2(SCH_1):P3E_CPU0_PE1_SS_C_TXN(4)
 C3P29    2      B CAP_0402-0.22UF,16V,10%,EMPTY,A   I437 @BASEBOARD_FAB2_LIB.BASEBOARD_FAB2(SCH_1):PAGE107
  J8G1  123  IO123 SCONN200_H68296001_SM-CONN,H68A    I78 @BASEBOARD_FAB2_LIB.BASEBOARD_FAB2(SCH_1):PAGE109

P3E_CPU0_PE1_SS_C_TXN<5> @BASEBOARD_FAB2_LIB.BASEBOARD_FAB2(SCH_1):P3E_CPU0_PE1_SS_C_TXN(5)
 C3P33    2      B CAP_0402-0.22UF,16V,10%,EMPTY,A   I439 @BASEBOARD_FAB2_LIB.BASEBOARD_FAB2(SCH_1):PAGE107
  J8G1  115  IO115 SCONN200_H68296001_SM-CONN,H68A    I78 @BASEBOARD_FAB2_LIB.BASEBOARD_FAB2(SCH_1):PAGE109

P3E_CPU0_PE1_SS_C_TXN<6> @BASEBOARD_FAB2_LIB.BASEBOARD_FAB2(SCH_1):P3E_CPU0_PE1_SS_C_TXN(6)
 C3P36    2      B CAP_0402-0.22UF,16V,10%,EMPTY,A   I438 @BASEBOARD_FAB2_LIB.BASEBOARD_FAB2(SCH_1):PAGE107
  J8G1  109  IO109 SCONN200_H68296001_SM-CONN,H68A    I78 @BASEBOARD_FAB2_LIB.BASEBOARD_FAB2(SCH_1):PAGE109

P3E_CPU0_PE1_SS_C_TXN<7> @BASEBOARD_FAB2_LIB.BASEBOARD_FAB2(SCH_1):P3E_CPU0_PE1_SS_C_TXN(7)
 C3P41    2      B CAP_0402-0.22UF,16V,10%,EMPTY,A   I448 @BASEBOARD_FAB2_LIB.BASEBOARD_FAB2(SCH_1):PAGE107
  J8G1  103  IO103 SCONN200_H68296001_SM-CONN,H68A    I78 @BASEBOARD_FAB2_LIB.BASEBOARD_FAB2(SCH_1):PAGE109

P3E_CPU0_PE1_SS_C_TXP<0> @BASEBOARD_FAB2_LIB.BASEBOARD_FAB2(SCH_1):P3E_CPU0_PE1_SS_C_TXP(0)
 C3P10    2      B CAP_0402-0.22UF,16V,10%,EMPTY,A   I417 @BASEBOARD_FAB2_LIB.BASEBOARD_FAB2(SCH_1):PAGE107
  J8G1  147  IO147 SCONN200_H68296001_SM-CONN,H68A    I78 @BASEBOARD_FAB2_LIB.BASEBOARD_FAB2(SCH_1):PAGE109

P3E_CPU0_PE1_SS_C_TXP<1> @BASEBOARD_FAB2_LIB.BASEBOARD_FAB2(SCH_1):P3E_CPU0_PE1_SS_C_TXP(1)
 C3P14    2      B CAP_0402-0.22UF,16V,10%,EMPTY,A   I431 @BASEBOARD_FAB2_LIB.BASEBOARD_FAB2(SCH_1):PAGE107
  J8G1  139  IO139 SCONN200_H68296001_SM-CONN,H68A    I78 @BASEBOARD_FAB2_LIB.BASEBOARD_FAB2(SCH_1):PAGE109

P3E_CPU0_PE1_SS_C_TXP<2> @BASEBOARD_FAB2_LIB.BASEBOARD_FAB2(SCH_1):P3E_CPU0_PE1_SS_C_TXP(2)
 C3P19    2      B CAP_0402-0.22UF,16V,10%,EMPTY,A   I427 @BASEBOARD_FAB2_LIB.BASEBOARD_FAB2(SCH_1):PAGE107
  J8G1  135  IO135 SCONN200_H68296001_SM-CONN,H68A    I78 @BASEBOARD_FAB2_LIB.BASEBOARD_FAB2(SCH_1):PAGE109

P3E_CPU0_PE1_SS_C_TXP<3> @BASEBOARD_FAB2_LIB.BASEBOARD_FAB2(SCH_1):P3E_CPU0_PE1_SS_C_TXP(3)
 C3P22    2      B CAP_0402-0.22UF,16V,10%,EMPTY,A   I435 @BASEBOARD_FAB2_LIB.BASEBOARD_FAB2(SCH_1):PAGE107
  J8G1  129  IO129 SCONN200_H68296001_SM-CONN,H68A    I78 @BASEBOARD_FAB2_LIB.BASEBOARD_FAB2(SCH_1):PAGE109

P3E_CPU0_PE1_SS_C_TXP<4> @BASEBOARD_FAB2_LIB.BASEBOARD_FAB2(SCH_1):P3E_CPU0_PE1_SS_C_TXP(4)
 C3P26    2      B CAP_0402-0.22UF,16V,10%,EMPTY,A   I444 @BASEBOARD_FAB2_LIB.BASEBOARD_FAB2(SCH_1):PAGE107
  J8G1  121  IO121 SCONN200_H68296001_SM-CONN,H68A    I78 @BASEBOARD_FAB2_LIB.BASEBOARD_FAB2(SCH_1):PAGE109

P3E_CPU0_PE1_SS_C_TXP<5> @BASEBOARD_FAB2_LIB.BASEBOARD_FAB2(SCH_1):P3E_CPU0_PE1_SS_C_TXP(5)
 C3P31    2      B CAP_0402-0.22UF,16V,10%,EMPTY,A   I452 @BASEBOARD_FAB2_LIB.BASEBOARD_FAB2(SCH_1):PAGE107
  J8G1  117  IO117 SCONN200_H68296001_SM-CONN,H68A    I78 @BASEBOARD_FAB2_LIB.BASEBOARD_FAB2(SCH_1):PAGE109

P3E_CPU0_PE1_SS_C_TXP<6> @BASEBOARD_FAB2_LIB.BASEBOARD_FAB2(SCH_1):P3E_CPU0_PE1_SS_C_TXP(6)
 C3P34    2      B CAP_0402-0.22UF,16V,10%,EMPTY,A   I447 @BASEBOARD_FAB2_LIB.BASEBOARD_FAB2(SCH_1):PAGE107
  J8G1  111  IO111 SCONN200_H68296001_SM-CONN,H68A    I78 @BASEBOARD_FAB2_LIB.BASEBOARD_FAB2(SCH_1):PAGE109

P3E_CPU0_PE1_SS_C_TXP<7> @BASEBOARD_FAB2_LIB.BASEBOARD_FAB2(SCH_1):P3E_CPU0_PE1_SS_C_TXP(7)
 C3P38    2      B CAP_0402-0.22UF,16V,10%,EMPTY,A   I455 @BASEBOARD_FAB2_LIB.BASEBOARD_FAB2(SCH_1):PAGE107
  J8G1  105  IO105 SCONN200_H68296001_SM-CONN,H68A    I78 @BASEBOARD_FAB2_LIB.BASEBOARD_FAB2(SCH_1):PAGE109

P3E_CPU0_PE1_SS_RXN<0> @BASEBOARD_FAB2_LIB.BASEBOARD_FAB2(SCH_1):P3E_CPU0_PE1_SS_RXN(0)
  U5D1  CW8 PE1_RX_DN<0> SKX_EXT_B_BGA1-IC,TBD    I84 @BASEBOARD_FAB2_LIB.BASEBOARD_FAB2(SCH_1):PAGE30
  C2U4    2      B CAP_0402-0.22UF,16V,10%,X7R,A3A   I257 @BASEBOARD_FAB2_LIB.BASEBOARD_FAB2(SCH_1):PAGE107
 R2U15    2      B RES_0402-0.0,5%,1/16W,EMPTY,G2A   I465 @BASEBOARD_FAB2_LIB.BASEBOARD_FAB2(SCH_1):PAGE107

P3E_CPU0_PE1_SS_RXN<1> @BASEBOARD_FAB2_LIB.BASEBOARD_FAB2(SCH_1):P3E_CPU0_PE1_SS_RXN(1)
  U5D1  DA8 PE1_RX_DN<1> SKX_EXT_B_BGA1-IC,TBD    I84 @BASEBOARD_FAB2_LIB.BASEBOARD_FAB2(SCH_1):PAGE30
  C2U6    2      B CAP_0402-0.22UF,16V,10%,X7R,A3A   I260 @BASEBOARD_FAB2_LIB.BASEBOARD_FAB2(SCH_1):PAGE107
 R2U17    2      B RES_0402-0.0,5%,1/16W,EMPTY,G2A   I464 @BASEBOARD_FAB2_LIB.BASEBOARD_FAB2(SCH_1):PAGE107

P3E_CPU0_PE1_SS_RXN<2> @BASEBOARD_FAB2_LIB.BASEBOARD_FAB2(SCH_1):P3E_CPU0_PE1_SS_RXN(2)
  U5D1  DC8 PE1_RX_DN<2> SKX_EXT_B_BGA1-IC,TBD    I84 @BASEBOARD_FAB2_LIB.BASEBOARD_FAB2(SCH_1):PAGE30
  C2U8    2      B CAP_0402-0.22UF,16V,10%,X7R,A3A   I264 @BASEBOARD_FAB2_LIB.BASEBOARD_FAB2(SCH_1):PAGE107
 R2U19    2      B RES_0402-0.0,5%,1/16W,EMPTY,G2A   I463 @BASEBOARD_FAB2_LIB.BASEBOARD_FAB2(SCH_1):PAGE107

P3E_CPU0_PE1_SS_RXN<3> @BASEBOARD_FAB2_LIB.BASEBOARD_FAB2(SCH_1):P3E_CPU0_PE1_SS_RXN(3)
  U5D1 DC10 PE1_RX_DN<3> SKX_EXT_B_BGA1-IC,TBD    I84 @BASEBOARD_FAB2_LIB.BASEBOARD_FAB2(SCH_1):PAGE30
 C2U10    2      B CAP_0402-0.22UF,16V,10%,X7R,A3A   I267 @BASEBOARD_FAB2_LIB.BASEBOARD_FAB2(SCH_1):PAGE107
 R2U21    2      B RES_0402-0.0,5%,1/16W,EMPTY,G2A   I462 @BASEBOARD_FAB2_LIB.BASEBOARD_FAB2(SCH_1):PAGE107

P3E_CPU0_PE1_SS_RXN<4> @BASEBOARD_FAB2_LIB.BASEBOARD_FAB2(SCH_1):P3E_CPU0_PE1_SS_RXN(4)
  U5D1 DE10 PE1_RX_DN<4> SKX_EXT_B_BGA1-IC,TBD    I84 @BASEBOARD_FAB2_LIB.BASEBOARD_FAB2(SCH_1):PAGE30
 C2U12    2      B CAP_0402-0.22UF,16V,10%,X7R,A3A   I265 @BASEBOARD_FAB2_LIB.BASEBOARD_FAB2(SCH_1):PAGE107
 R2U23    2      B RES_0402-0.0,5%,1/16W,EMPTY,G2A   I461 @BASEBOARD_FAB2_LIB.BASEBOARD_FAB2(SCH_1):PAGE107

P3E_CPU0_PE1_SS_RXN<5> @BASEBOARD_FAB2_LIB.BASEBOARD_FAB2(SCH_1):P3E_CPU0_PE1_SS_RXN(5)
  U5D1  DH9 PE1_RX_DN<5> SKX_EXT_B_BGA1-IC,TBD    I84 @BASEBOARD_FAB2_LIB.BASEBOARD_FAB2(SCH_1):PAGE30
 C2U14    2      B CAP_0402-0.22UF,16V,10%,X7R,A3A   I287 @BASEBOARD_FAB2_LIB.BASEBOARD_FAB2(SCH_1):PAGE107
 R2U25    2      B RES_0402-0.0,5%,1/16W,EMPTY,G2A   I460 @BASEBOARD_FAB2_LIB.BASEBOARD_FAB2(SCH_1):PAGE107

P3E_CPU0_PE1_SS_RXN<6> @BASEBOARD_FAB2_LIB.BASEBOARD_FAB2(SCH_1):P3E_CPU0_PE1_SS_RXN(6)
  U5D1  DK9 PE1_RX_DN<6> SKX_EXT_B_BGA1-IC,TBD    I84 @BASEBOARD_FAB2_LIB.BASEBOARD_FAB2(SCH_1):PAGE30
 C2U16    2      B CAP_0402-0.22UF,16V,10%,X7R,A3A   I286 @BASEBOARD_FAB2_LIB.BASEBOARD_FAB2(SCH_1):PAGE107
 R2U27    2      B RES_0402-0.0,5%,1/16W,EMPTY,G2A   I459 @BASEBOARD_FAB2_LIB.BASEBOARD_FAB2(SCH_1):PAGE107

P3E_CPU0_PE1_SS_RXN<7> @BASEBOARD_FAB2_LIB.BASEBOARD_FAB2(SCH_1):P3E_CPU0_PE1_SS_RXN(7)
  U5D1  DM9 PE1_RX_DN<7> SKX_EXT_B_BGA1-IC,TBD    I84 @BASEBOARD_FAB2_LIB.BASEBOARD_FAB2(SCH_1):PAGE30
 C2U18    2      B CAP_0402-0.22UF,16V,10%,X7R,A3A   I294 @BASEBOARD_FAB2_LIB.BASEBOARD_FAB2(SCH_1):PAGE107
 R2U29    2      B RES_0402-0.0,5%,1/16W,EMPTY,G2A   I458 @BASEBOARD_FAB2_LIB.BASEBOARD_FAB2(SCH_1):PAGE107

P3E_CPU0_PE1_SS_RXP<0> @BASEBOARD_FAB2_LIB.BASEBOARD_FAB2(SCH_1):P3E_CPU0_PE1_SS_RXP(0)
  U5D1  CU8 PE1_RX_DP<0> SKX_EXT_B_BGA1-IC,TBD    I84 @BASEBOARD_FAB2_LIB.BASEBOARD_FAB2(SCH_1):PAGE30
  C2U3    2      B CAP_0402-0.22UF,16V,10%,X7R,A3A   I272 @BASEBOARD_FAB2_LIB.BASEBOARD_FAB2(SCH_1):PAGE107
 R2U14    2      B RES_0402-0.0,5%,1/16W,EMPTY,G2A   I466 @BASEBOARD_FAB2_LIB.BASEBOARD_FAB2(SCH_1):PAGE107

P3E_CPU0_PE1_SS_RXP<1> @BASEBOARD_FAB2_LIB.BASEBOARD_FAB2(SCH_1):P3E_CPU0_PE1_SS_RXP(1)
  U5D1  CY7 PE1_RX_DP<1> SKX_EXT_B_BGA1-IC,TBD    I84 @BASEBOARD_FAB2_LIB.BASEBOARD_FAB2(SCH_1):PAGE30
  C2U5    2      B CAP_0402-0.22UF,16V,10%,X7R,A3A   I274 @BASEBOARD_FAB2_LIB.BASEBOARD_FAB2(SCH_1):PAGE107
 R2U16    2      B RES_0402-0.0,5%,1/16W,EMPTY,G2A   I467 @BASEBOARD_FAB2_LIB.BASEBOARD_FAB2(SCH_1):PAGE107

P3E_CPU0_PE1_SS_RXP<2> @BASEBOARD_FAB2_LIB.BASEBOARD_FAB2(SCH_1):P3E_CPU0_PE1_SS_RXP(2)
  U5D1  DB9 PE1_RX_DP<2> SKX_EXT_B_BGA1-IC,TBD    I84 @BASEBOARD_FAB2_LIB.BASEBOARD_FAB2(SCH_1):PAGE30
  C2U7    2      B CAP_0402-0.22UF,16V,10%,X7R,A3A   I277 @BASEBOARD_FAB2_LIB.BASEBOARD_FAB2(SCH_1):PAGE107
 R2U18    2      B RES_0402-0.0,5%,1/16W,EMPTY,G2A   I468 @BASEBOARD_FAB2_LIB.BASEBOARD_FAB2(SCH_1):PAGE107

P3E_CPU0_PE1_SS_RXP<3> @BASEBOARD_FAB2_LIB.BASEBOARD_FAB2(SCH_1):P3E_CPU0_PE1_SS_RXP(3)
  U5D1 DA10 PE1_RX_DP<3> SKX_EXT_B_BGA1-IC,TBD    I84 @BASEBOARD_FAB2_LIB.BASEBOARD_FAB2(SCH_1):PAGE30
  C2U9    2      B CAP_0402-0.22UF,16V,10%,X7R,A3A   I279 @BASEBOARD_FAB2_LIB.BASEBOARD_FAB2(SCH_1):PAGE107
 R2U20    2      B RES_0402-0.0,5%,1/16W,EMPTY,G2A   I469 @BASEBOARD_FAB2_LIB.BASEBOARD_FAB2(SCH_1):PAGE107

P3E_CPU0_PE1_SS_RXP<4> @BASEBOARD_FAB2_LIB.BASEBOARD_FAB2(SCH_1):P3E_CPU0_PE1_SS_RXP(4)
  U5D1  DD9 PE1_RX_DP<4> SKX_EXT_B_BGA1-IC,TBD    I84 @BASEBOARD_FAB2_LIB.BASEBOARD_FAB2(SCH_1):PAGE30
 C2U11    2      B CAP_0402-0.22UF,16V,10%,X7R,A3A   I278 @BASEBOARD_FAB2_LIB.BASEBOARD_FAB2(SCH_1):PAGE107
 R2U22    2      B RES_0402-0.0,5%,1/16W,EMPTY,G2A   I470 @BASEBOARD_FAB2_LIB.BASEBOARD_FAB2(SCH_1):PAGE107

P3E_CPU0_PE1_SS_RXP<5> @BASEBOARD_FAB2_LIB.BASEBOARD_FAB2(SCH_1):P3E_CPU0_PE1_SS_RXP(5)
  U5D1  DF9 PE1_RX_DP<5> SKX_EXT_B_BGA1-IC,TBD    I84 @BASEBOARD_FAB2_LIB.BASEBOARD_FAB2(SCH_1):PAGE30
 C2U13    2      B CAP_0402-0.22UF,16V,10%,X7R,A3A   I297 @BASEBOARD_FAB2_LIB.BASEBOARD_FAB2(SCH_1):PAGE107
 R2U24    2      B RES_0402-0.0,5%,1/16W,EMPTY,G2A   I471 @BASEBOARD_FAB2_LIB.BASEBOARD_FAB2(SCH_1):PAGE107

P3E_CPU0_PE1_SS_RXP<6> @BASEBOARD_FAB2_LIB.BASEBOARD_FAB2(SCH_1):P3E_CPU0_PE1_SS_RXP(6)
  U5D1  DJ8 PE1_RX_DP<6> SKX_EXT_B_BGA1-IC,TBD    I84 @BASEBOARD_FAB2_LIB.BASEBOARD_FAB2(SCH_1):PAGE30
 C2U15    2      B CAP_0402-0.22UF,16V,10%,X7R,A3A   I296 @BASEBOARD_FAB2_LIB.BASEBOARD_FAB2(SCH_1):PAGE107
 R2U26    2      B RES_0402-0.0,5%,1/16W,EMPTY,G2A   I472 @BASEBOARD_FAB2_LIB.BASEBOARD_FAB2(SCH_1):PAGE107

P3E_CPU0_PE1_SS_RXP<7> @BASEBOARD_FAB2_LIB.BASEBOARD_FAB2(SCH_1):P3E_CPU0_PE1_SS_RXP(7)
  U5D1 DL10 PE1_RX_DP<7> SKX_EXT_B_BGA1-IC,TBD    I84 @BASEBOARD_FAB2_LIB.BASEBOARD_FAB2(SCH_1):PAGE30
 C2U17    2      B CAP_0402-0.22UF,16V,10%,X7R,A3A   I300 @BASEBOARD_FAB2_LIB.BASEBOARD_FAB2(SCH_1):PAGE107
 R2U28    2      B RES_0402-0.0,5%,1/16W,EMPTY,G2A   I473 @BASEBOARD_FAB2_LIB.BASEBOARD_FAB2(SCH_1):PAGE107

P3E_CPU0_PE1_SS_R_RXN<0> @BASEBOARD_FAB2_LIB.BASEBOARD_FAB2(SCH_1):P3E_CPU0_PE1_SS_R_RXN(0)
 R2U15    1      A RES_0402-0.0,5%,1/16W,EMPTY,G2A   I465 @BASEBOARD_FAB2_LIB.BASEBOARD_FAB2(SCH_1):PAGE107
  J8G1  148  IO148 SCONN200_H68296001_SM-CONN,H68A    I78 @BASEBOARD_FAB2_LIB.BASEBOARD_FAB2(SCH_1):PAGE109

P3E_CPU0_PE1_SS_R_RXN<1> @BASEBOARD_FAB2_LIB.BASEBOARD_FAB2(SCH_1):P3E_CPU0_PE1_SS_R_RXN(1)
 R2U17    1      A RES_0402-0.0,5%,1/16W,EMPTY,G2A   I464 @BASEBOARD_FAB2_LIB.BASEBOARD_FAB2(SCH_1):PAGE107
  J8G1  142  IO142 SCONN200_H68296001_SM-CONN,H68A    I78 @BASEBOARD_FAB2_LIB.BASEBOARD_FAB2(SCH_1):PAGE109

P3E_CPU0_PE1_SS_R_RXN<2> @BASEBOARD_FAB2_LIB.BASEBOARD_FAB2(SCH_1):P3E_CPU0_PE1_SS_R_RXN(2)
 R2U19    1      A RES_0402-0.0,5%,1/16W,EMPTY,G2A   I463 @BASEBOARD_FAB2_LIB.BASEBOARD_FAB2(SCH_1):PAGE107
  J8G1  138  IO138 SCONN200_H68296001_SM-CONN,H68A    I78 @BASEBOARD_FAB2_LIB.BASEBOARD_FAB2(SCH_1):PAGE109

P3E_CPU0_PE1_SS_R_RXN<3> @BASEBOARD_FAB2_LIB.BASEBOARD_FAB2(SCH_1):P3E_CPU0_PE1_SS_R_RXN(3)
 R2U21    1      A RES_0402-0.0,5%,1/16W,EMPTY,G2A   I462 @BASEBOARD_FAB2_LIB.BASEBOARD_FAB2(SCH_1):PAGE107
  J8G1  130  IO130 SCONN200_H68296001_SM-CONN,H68A    I78 @BASEBOARD_FAB2_LIB.BASEBOARD_FAB2(SCH_1):PAGE109

P3E_CPU0_PE1_SS_R_RXN<4> @BASEBOARD_FAB2_LIB.BASEBOARD_FAB2(SCH_1):P3E_CPU0_PE1_SS_R_RXN(4)
 R2U23    1      A RES_0402-0.0,5%,1/16W,EMPTY,G2A   I461 @BASEBOARD_FAB2_LIB.BASEBOARD_FAB2(SCH_1):PAGE107
  J8G1  124  IO124 SCONN200_H68296001_SM-CONN,H68A    I78 @BASEBOARD_FAB2_LIB.BASEBOARD_FAB2(SCH_1):PAGE109

P3E_CPU0_PE1_SS_R_RXN<5> @BASEBOARD_FAB2_LIB.BASEBOARD_FAB2(SCH_1):P3E_CPU0_PE1_SS_R_RXN(5)
 R2U25    1      A RES_0402-0.0,5%,1/16W,EMPTY,G2A   I460 @BASEBOARD_FAB2_LIB.BASEBOARD_FAB2(SCH_1):PAGE107
  J8G1  118  IO118 SCONN200_H68296001_SM-CONN,H68A    I78 @BASEBOARD_FAB2_LIB.BASEBOARD_FAB2(SCH_1):PAGE109

P3E_CPU0_PE1_SS_R_RXN<6> @BASEBOARD_FAB2_LIB.BASEBOARD_FAB2(SCH_1):P3E_CPU0_PE1_SS_R_RXN(6)
 R2U27    1      A RES_0402-0.0,5%,1/16W,EMPTY,G2A   I459 @BASEBOARD_FAB2_LIB.BASEBOARD_FAB2(SCH_1):PAGE107
  J8G1  112  IO112 SCONN200_H68296001_SM-CONN,H68A    I78 @BASEBOARD_FAB2_LIB.BASEBOARD_FAB2(SCH_1):PAGE109

P3E_CPU0_PE1_SS_R_RXN<7> @BASEBOARD_FAB2_LIB.BASEBOARD_FAB2(SCH_1):P3E_CPU0_PE1_SS_R_RXN(7)
 R2U29    1      A RES_0402-0.0,5%,1/16W,EMPTY,G2A   I458 @BASEBOARD_FAB2_LIB.BASEBOARD_FAB2(SCH_1):PAGE107
  J8G1  106  IO106 SCONN200_H68296001_SM-CONN,H68A    I78 @BASEBOARD_FAB2_LIB.BASEBOARD_FAB2(SCH_1):PAGE109

P3E_CPU0_PE1_SS_R_RXP<0> @BASEBOARD_FAB2_LIB.BASEBOARD_FAB2(SCH_1):P3E_CPU0_PE1_SS_R_RXP(0)
 R2U14    1      A RES_0402-0.0,5%,1/16W,EMPTY,G2A   I466 @BASEBOARD_FAB2_LIB.BASEBOARD_FAB2(SCH_1):PAGE107
  J8G1  150  IO150 SCONN200_H68296001_SM-CONN,H68A    I78 @BASEBOARD_FAB2_LIB.BASEBOARD_FAB2(SCH_1):PAGE109

P3E_CPU0_PE1_SS_R_RXP<1> @BASEBOARD_FAB2_LIB.BASEBOARD_FAB2(SCH_1):P3E_CPU0_PE1_SS_R_RXP(1)
 R2U16    1      A RES_0402-0.0,5%,1/16W,EMPTY,G2A   I467 @BASEBOARD_FAB2_LIB.BASEBOARD_FAB2(SCH_1):PAGE107
  J8G1  144  IO144 SCONN200_H68296001_SM-CONN,H68A    I78 @BASEBOARD_FAB2_LIB.BASEBOARD_FAB2(SCH_1):PAGE109

P3E_CPU0_PE1_SS_R_RXP<2> @BASEBOARD_FAB2_LIB.BASEBOARD_FAB2(SCH_1):P3E_CPU0_PE1_SS_R_RXP(2)
 R2U18    1      A RES_0402-0.0,5%,1/16W,EMPTY,G2A   I468 @BASEBOARD_FAB2_LIB.BASEBOARD_FAB2(SCH_1):PAGE107
  J8G1  136  IO136 SCONN200_H68296001_SM-CONN,H68A    I78 @BASEBOARD_FAB2_LIB.BASEBOARD_FAB2(SCH_1):PAGE109

P3E_CPU0_PE1_SS_R_RXP<3> @BASEBOARD_FAB2_LIB.BASEBOARD_FAB2(SCH_1):P3E_CPU0_PE1_SS_R_RXP(3)
 R2U20    1      A RES_0402-0.0,5%,1/16W,EMPTY,G2A   I469 @BASEBOARD_FAB2_LIB.BASEBOARD_FAB2(SCH_1):PAGE107
  J8G1  132  IO132 SCONN200_H68296001_SM-CONN,H68A    I78 @BASEBOARD_FAB2_LIB.BASEBOARD_FAB2(SCH_1):PAGE109

P3E_CPU0_PE1_SS_R_RXP<4> @BASEBOARD_FAB2_LIB.BASEBOARD_FAB2(SCH_1):P3E_CPU0_PE1_SS_R_RXP(4)
 R2U22    1      A RES_0402-0.0,5%,1/16W,EMPTY,G2A   I470 @BASEBOARD_FAB2_LIB.BASEBOARD_FAB2(SCH_1):PAGE107
  J8G1  126  IO126 SCONN200_H68296001_SM-CONN,H68A    I78 @BASEBOARD_FAB2_LIB.BASEBOARD_FAB2(SCH_1):PAGE109

P3E_CPU0_PE1_SS_R_RXP<5> @BASEBOARD_FAB2_LIB.BASEBOARD_FAB2(SCH_1):P3E_CPU0_PE1_SS_R_RXP(5)
 R2U24    1      A RES_0402-0.0,5%,1/16W,EMPTY,G2A   I471 @BASEBOARD_FAB2_LIB.BASEBOARD_FAB2(SCH_1):PAGE107
  J8G1  120  IO120 SCONN200_H68296001_SM-CONN,H68A    I78 @BASEBOARD_FAB2_LIB.BASEBOARD_FAB2(SCH_1):PAGE109

P3E_CPU0_PE1_SS_R_RXP<6> @BASEBOARD_FAB2_LIB.BASEBOARD_FAB2(SCH_1):P3E_CPU0_PE1_SS_R_RXP(6)
 R2U26    1      A RES_0402-0.0,5%,1/16W,EMPTY,G2A   I472 @BASEBOARD_FAB2_LIB.BASEBOARD_FAB2(SCH_1):PAGE107
  J8G1  114  IO114 SCONN200_H68296001_SM-CONN,H68A    I78 @BASEBOARD_FAB2_LIB.BASEBOARD_FAB2(SCH_1):PAGE109

P3E_CPU0_PE1_SS_R_RXP<7> @BASEBOARD_FAB2_LIB.BASEBOARD_FAB2(SCH_1):P3E_CPU0_PE1_SS_R_RXP(7)
 R2U28    1      A RES_0402-0.0,5%,1/16W,EMPTY,G2A   I473 @BASEBOARD_FAB2_LIB.BASEBOARD_FAB2(SCH_1):PAGE107
  J8G1  108  IO108 SCONN200_H68296001_SM-CONN,H68A    I78 @BASEBOARD_FAB2_LIB.BASEBOARD_FAB2(SCH_1):PAGE109

P3E_CPU0_PE1_SS_TXN<0> @BASEBOARD_FAB2_LIB.BASEBOARD_FAB2(SCH_1):P3E_CPU0_PE1_SS_TXN(0)
  U5D1  DA2 PE1_TX_DN<0> SKX_EXT_B_BGA1-IC,TBD    I84 @BASEBOARD_FAB2_LIB.BASEBOARD_FAB2(SCH_1):PAGE30
 C3P13    1      A CAP_0402-0.22UF,16V,10%,X7R,A3A   I207 @BASEBOARD_FAB2_LIB.BASEBOARD_FAB2(SCH_1):PAGE107
 C3P12    1      A CAP_0402-0.22UF,16V,10%,EMPTY,A   I415 @BASEBOARD_FAB2_LIB.BASEBOARD_FAB2(SCH_1):PAGE107

P3E_CPU0_PE1_SS_TXN<1> @BASEBOARD_FAB2_LIB.BASEBOARD_FAB2(SCH_1):P3E_CPU0_PE1_SS_TXN(1)
  U5D1  DC2 PE1_TX_DN<1> SKX_EXT_B_BGA1-IC,TBD    I84 @BASEBOARD_FAB2_LIB.BASEBOARD_FAB2(SCH_1):PAGE30
 C3P17    1      A CAP_0402-0.22UF,16V,10%,X7R,A3A   I208 @BASEBOARD_FAB2_LIB.BASEBOARD_FAB2(SCH_1):PAGE107
 C3P16    1      A CAP_0402-0.22UF,16V,10%,EMPTY,A   I422 @BASEBOARD_FAB2_LIB.BASEBOARD_FAB2(SCH_1):PAGE107

P3E_CPU0_PE1_SS_TXN<2> @BASEBOARD_FAB2_LIB.BASEBOARD_FAB2(SCH_1):P3E_CPU0_PE1_SS_TXN(2)
  U5D1  DE2 PE1_TX_DN<2> SKX_EXT_B_BGA1-IC,TBD    I84 @BASEBOARD_FAB2_LIB.BASEBOARD_FAB2(SCH_1):PAGE30
 C3P20    1      A CAP_0402-0.22UF,16V,10%,X7R,A3A   I215 @BASEBOARD_FAB2_LIB.BASEBOARD_FAB2(SCH_1):PAGE107
 C3P21    1      A CAP_0402-0.22UF,16V,10%,EMPTY,A   I423 @BASEBOARD_FAB2_LIB.BASEBOARD_FAB2(SCH_1):PAGE107

P3E_CPU0_PE1_SS_TXN<3> @BASEBOARD_FAB2_LIB.BASEBOARD_FAB2(SCH_1):P3E_CPU0_PE1_SS_TXN(3)
  U5D1  DE4 PE1_TX_DN<3> SKX_EXT_B_BGA1-IC,TBD    I84 @BASEBOARD_FAB2_LIB.BASEBOARD_FAB2(SCH_1):PAGE30
 C3P25    1      A CAP_0402-0.22UF,16V,10%,X7R,A3A   I216 @BASEBOARD_FAB2_LIB.BASEBOARD_FAB2(SCH_1):PAGE107
 C3P24    1      A CAP_0402-0.22UF,16V,10%,EMPTY,A   I424 @BASEBOARD_FAB2_LIB.BASEBOARD_FAB2(SCH_1):PAGE107

P3E_CPU0_PE1_SS_TXN<4> @BASEBOARD_FAB2_LIB.BASEBOARD_FAB2(SCH_1):P3E_CPU0_PE1_SS_TXN(4)
  U5D1  DG4 PE1_TX_DN<4> SKX_EXT_B_BGA1-IC,TBD    I84 @BASEBOARD_FAB2_LIB.BASEBOARD_FAB2(SCH_1):PAGE30
 C3P28    1      A CAP_0402-0.22UF,16V,10%,X7R,A3A   I232 @BASEBOARD_FAB2_LIB.BASEBOARD_FAB2(SCH_1):PAGE107
 C3P29    1      A CAP_0402-0.22UF,16V,10%,EMPTY,A   I437 @BASEBOARD_FAB2_LIB.BASEBOARD_FAB2(SCH_1):PAGE107

P3E_CPU0_PE1_SS_TXN<5> @BASEBOARD_FAB2_LIB.BASEBOARD_FAB2(SCH_1):P3E_CPU0_PE1_SS_TXN(5)
  U5D1  DK3 PE1_TX_DN<5> SKX_EXT_B_BGA1-IC,TBD    I84 @BASEBOARD_FAB2_LIB.BASEBOARD_FAB2(SCH_1):PAGE30
 C3P32    1      A CAP_0402-0.22UF,16V,10%,X7R,A3A   I234 @BASEBOARD_FAB2_LIB.BASEBOARD_FAB2(SCH_1):PAGE107
 C3P33    1      A CAP_0402-0.22UF,16V,10%,EMPTY,A   I439 @BASEBOARD_FAB2_LIB.BASEBOARD_FAB2(SCH_1):PAGE107

P3E_CPU0_PE1_SS_TXN<6> @BASEBOARD_FAB2_LIB.BASEBOARD_FAB2(SCH_1):P3E_CPU0_PE1_SS_TXN(6)
  U5D1  DM3 PE1_TX_DN<6> SKX_EXT_B_BGA1-IC,TBD    I84 @BASEBOARD_FAB2_LIB.BASEBOARD_FAB2(SCH_1):PAGE30
 C3P37    1      A CAP_0402-0.22UF,16V,10%,X7R,A3A   I235 @BASEBOARD_FAB2_LIB.BASEBOARD_FAB2(SCH_1):PAGE107
 C3P36    1      A CAP_0402-0.22UF,16V,10%,EMPTY,A   I438 @BASEBOARD_FAB2_LIB.BASEBOARD_FAB2(SCH_1):PAGE107

P3E_CPU0_PE1_SS_TXN<7> @BASEBOARD_FAB2_LIB.BASEBOARD_FAB2(SCH_1):P3E_CPU0_PE1_SS_TXN(7)
  U5D1  DN4 PE1_TX_DN<7> SKX_EXT_B_BGA1-IC,TBD    I84 @BASEBOARD_FAB2_LIB.BASEBOARD_FAB2(SCH_1):PAGE30
 C3P40    1      A CAP_0402-0.22UF,16V,10%,X7R,A3A   I241 @BASEBOARD_FAB2_LIB.BASEBOARD_FAB2(SCH_1):PAGE107
 C3P41    1      A CAP_0402-0.22UF,16V,10%,EMPTY,A   I448 @BASEBOARD_FAB2_LIB.BASEBOARD_FAB2(SCH_1):PAGE107

P3E_CPU0_PE1_SS_TXP<0> @BASEBOARD_FAB2_LIB.BASEBOARD_FAB2(SCH_1):P3E_CPU0_PE1_SS_TXP(0)
  U5D1  CW2 PE1_TX_DP<0> SKX_EXT_B_BGA1-IC,TBD    I84 @BASEBOARD_FAB2_LIB.BASEBOARD_FAB2(SCH_1):PAGE30
 C3P11    1      A CAP_0402-0.22UF,16V,10%,X7R,A3A   I212 @BASEBOARD_FAB2_LIB.BASEBOARD_FAB2(SCH_1):PAGE107
 C3P10    1      A CAP_0402-0.22UF,16V,10%,EMPTY,A   I417 @BASEBOARD_FAB2_LIB.BASEBOARD_FAB2(SCH_1):PAGE107

P3E_CPU0_PE1_SS_TXP<1> @BASEBOARD_FAB2_LIB.BASEBOARD_FAB2(SCH_1):P3E_CPU0_PE1_SS_TXP(1)
  U5D1  DB1 PE1_TX_DP<1> SKX_EXT_B_BGA1-IC,TBD    I84 @BASEBOARD_FAB2_LIB.BASEBOARD_FAB2(SCH_1):PAGE30
 C3P15    1      A CAP_0402-0.22UF,16V,10%,X7R,A3A   I226 @BASEBOARD_FAB2_LIB.BASEBOARD_FAB2(SCH_1):PAGE107
 C3P14    1      A CAP_0402-0.22UF,16V,10%,EMPTY,A   I431 @BASEBOARD_FAB2_LIB.BASEBOARD_FAB2(SCH_1):PAGE107

P3E_CPU0_PE1_SS_TXP<2> @BASEBOARD_FAB2_LIB.BASEBOARD_FAB2(SCH_1):P3E_CPU0_PE1_SS_TXP(2)
  U5D1  DD3 PE1_TX_DP<2> SKX_EXT_B_BGA1-IC,TBD    I84 @BASEBOARD_FAB2_LIB.BASEBOARD_FAB2(SCH_1):PAGE30
 C3P18    1      A CAP_0402-0.22UF,16V,10%,X7R,A3A   I219 @BASEBOARD_FAB2_LIB.BASEBOARD_FAB2(SCH_1):PAGE107
 C3P19    1      A CAP_0402-0.22UF,16V,10%,EMPTY,A   I427 @BASEBOARD_FAB2_LIB.BASEBOARD_FAB2(SCH_1):PAGE107

P3E_CPU0_PE1_SS_TXP<3> @BASEBOARD_FAB2_LIB.BASEBOARD_FAB2(SCH_1):P3E_CPU0_PE1_SS_TXP(3)
  U5D1  DC4 PE1_TX_DP<3> SKX_EXT_B_BGA1-IC,TBD    I84 @BASEBOARD_FAB2_LIB.BASEBOARD_FAB2(SCH_1):PAGE30
 C3P23    1      A CAP_0402-0.22UF,16V,10%,X7R,A3A   I229 @BASEBOARD_FAB2_LIB.BASEBOARD_FAB2(SCH_1):PAGE107
 C3P22    1      A CAP_0402-0.22UF,16V,10%,EMPTY,A   I435 @BASEBOARD_FAB2_LIB.BASEBOARD_FAB2(SCH_1):PAGE107

P3E_CPU0_PE1_SS_TXP<4> @BASEBOARD_FAB2_LIB.BASEBOARD_FAB2(SCH_1):P3E_CPU0_PE1_SS_TXP(4)
  U5D1  DF3 PE1_TX_DP<4> SKX_EXT_B_BGA1-IC,TBD    I84 @BASEBOARD_FAB2_LIB.BASEBOARD_FAB2(SCH_1):PAGE30
 C3P27    1      A CAP_0402-0.22UF,16V,10%,X7R,A3A   I223 @BASEBOARD_FAB2_LIB.BASEBOARD_FAB2(SCH_1):PAGE107
 C3P26    1      A CAP_0402-0.22UF,16V,10%,EMPTY,A   I444 @BASEBOARD_FAB2_LIB.BASEBOARD_FAB2(SCH_1):PAGE107

P3E_CPU0_PE1_SS_TXP<5> @BASEBOARD_FAB2_LIB.BASEBOARD_FAB2(SCH_1):P3E_CPU0_PE1_SS_TXP(5)
  U5D1  DH3 PE1_TX_DP<5> SKX_EXT_B_BGA1-IC,TBD    I84 @BASEBOARD_FAB2_LIB.BASEBOARD_FAB2(SCH_1):PAGE30
 C3P30    1      A CAP_0402-0.22UF,16V,10%,X7R,A3A   I245 @BASEBOARD_FAB2_LIB.BASEBOARD_FAB2(SCH_1):PAGE107
 C3P31    1      A CAP_0402-0.22UF,16V,10%,EMPTY,A   I452 @BASEBOARD_FAB2_LIB.BASEBOARD_FAB2(SCH_1):PAGE107

P3E_CPU0_PE1_SS_TXP<6> @BASEBOARD_FAB2_LIB.BASEBOARD_FAB2(SCH_1):P3E_CPU0_PE1_SS_TXP(6)
  U5D1  DL2 PE1_TX_DP<6> SKX_EXT_B_BGA1-IC,TBD    I84 @BASEBOARD_FAB2_LIB.BASEBOARD_FAB2(SCH_1):PAGE30
 C3P35    1      A CAP_0402-0.22UF,16V,10%,X7R,A3A   I240 @BASEBOARD_FAB2_LIB.BASEBOARD_FAB2(SCH_1):PAGE107
 C3P34    1      A CAP_0402-0.22UF,16V,10%,EMPTY,A   I447 @BASEBOARD_FAB2_LIB.BASEBOARD_FAB2(SCH_1):PAGE107

P3E_CPU0_PE1_SS_TXP<7> @BASEBOARD_FAB2_LIB.BASEBOARD_FAB2(SCH_1):P3E_CPU0_PE1_SS_TXP(7)
  U5D1  DP3 PE1_TX_DP<7> SKX_EXT_B_BGA1-IC,TBD    I84 @BASEBOARD_FAB2_LIB.BASEBOARD_FAB2(SCH_1):PAGE30
 C3P39    1      A CAP_0402-0.22UF,16V,10%,X7R,A3A   I248 @BASEBOARD_FAB2_LIB.BASEBOARD_FAB2(SCH_1):PAGE107
 C3P38    1      A CAP_0402-0.22UF,16V,10%,EMPTY,A   I455 @BASEBOARD_FAB2_LIB.BASEBOARD_FAB2(SCH_1):PAGE107

P3E_CPU0_PE2_SS_C_TXN<0> @BASEBOARD_FAB2_LIB.BASEBOARD_FAB2(SCH_1):P3E_CPU0_PE2_SS_C_TXN(0)
 C8G10    2      B CAP_0402-0.22UF,16V,10%,X7R,A3A    I96 @BASEBOARD_FAB2_LIB.BASEBOARD_FAB2(SCH_1):PAGE105
  J8G1  151  IO151 SCONN200_H68296001_SM-CONN,H68A    I78 @BASEBOARD_FAB2_LIB.BASEBOARD_FAB2(SCH_1):PAGE109

P3E_CPU0_PE2_SS_C_TXN<10> @BASEBOARD_FAB2_LIB.BASEBOARD_FAB2(SCH_1):P3E_CPU0_PE2_SS_C_TXN(10)
 C7G16    2      B CAP_0402-0.22UF,16V,10%,X7R,A3A    I31 @BASEBOARD_FAB2_LIB.BASEBOARD_FAB2(SCH_1):PAGE105
 CONX8   15     15 SMC-CONN60A-22-GP_CONN-G7-SMC-A    I48 @BASEBOARD_FAB2_LIB.BASEBOARD_FAB2(SCH_1):PAGE245

P3E_CPU0_PE2_SS_C_TXN<11> @BASEBOARD_FAB2_LIB.BASEBOARD_FAB2(SCH_1):P3E_CPU0_PE2_SS_C_TXN(11)
 C7G13    2      B CAP_0402-0.22UF,16V,10%,X7R,A3A    I13 @BASEBOARD_FAB2_LIB.BASEBOARD_FAB2(SCH_1):PAGE105
 CONX8   23     23 SMC-CONN60A-22-GP_CONN-G7-SMC-A    I48 @BASEBOARD_FAB2_LIB.BASEBOARD_FAB2(SCH_1):PAGE245

P3E_CPU0_PE2_SS_C_TXN<12> @BASEBOARD_FAB2_LIB.BASEBOARD_FAB2(SCH_1):P3E_CPU0_PE2_SS_C_TXN(12)
 C7G12    2      B CAP_0402-0.22UF,16V,10%,X7R,A3A    I12 @BASEBOARD_FAB2_LIB.BASEBOARD_FAB2(SCH_1):PAGE105
 CONX8   27     27 SMC-CONN60A-22-GP_CONN-G7-SMC-A    I48 @BASEBOARD_FAB2_LIB.BASEBOARD_FAB2(SCH_1):PAGE245

P3E_CPU0_PE2_SS_C_TXN<13> @BASEBOARD_FAB2_LIB.BASEBOARD_FAB2(SCH_1):P3E_CPU0_PE2_SS_C_TXN(13)
 C7G10    2      B CAP_0402-0.22UF,16V,10%,X7R,A3A     I8 @BASEBOARD_FAB2_LIB.BASEBOARD_FAB2(SCH_1):PAGE105
 CONX8   33     33 SMC-CONN60A-22-GP_CONN-G7-SMC-A    I48 @BASEBOARD_FAB2_LIB.BASEBOARD_FAB2(SCH_1):PAGE245

P3E_CPU0_PE2_SS_C_TXN<14> @BASEBOARD_FAB2_LIB.BASEBOARD_FAB2(SCH_1):P3E_CPU0_PE2_SS_C_TXN(14)
  C7G7    2      B CAP_0402-0.22UF,16V,10%,X7R,A3A     I7 @BASEBOARD_FAB2_LIB.BASEBOARD_FAB2(SCH_1):PAGE105
 CONX8   41     41 SMC-CONN60A-22-GP_CONN-G7-SMC-A    I48 @BASEBOARD_FAB2_LIB.BASEBOARD_FAB2(SCH_1):PAGE245

P3E_CPU0_PE2_SS_C_TXN<15> @BASEBOARD_FAB2_LIB.BASEBOARD_FAB2(SCH_1):P3E_CPU0_PE2_SS_C_TXN(15)
  C7G6    2      B CAP_0402-0.22UF,16V,10%,X7R,A3A     I6 @BASEBOARD_FAB2_LIB.BASEBOARD_FAB2(SCH_1):PAGE105
 CONX8   45     45 SMC-CONN60A-22-GP_CONN-G7-SMC-A    I48 @BASEBOARD_FAB2_LIB.BASEBOARD_FAB2(SCH_1):PAGE245

P3E_CPU0_PE2_SS_C_TXN<1> @BASEBOARD_FAB2_LIB.BASEBOARD_FAB2(SCH_1):P3E_CPU0_PE2_SS_C_TXN(1)
  C8G7    2      B CAP_0402-0.22UF,16V,10%,X7R,A3A    I62 @BASEBOARD_FAB2_LIB.BASEBOARD_FAB2(SCH_1):PAGE105
  J8G1  159  IO159 SCONN200_H68296001_SM-CONN,H68A    I78 @BASEBOARD_FAB2_LIB.BASEBOARD_FAB2(SCH_1):PAGE109

P3E_CPU0_PE2_SS_C_TXN<2> @BASEBOARD_FAB2_LIB.BASEBOARD_FAB2(SCH_1):P3E_CPU0_PE2_SS_C_TXN(2)
  C8G6    2      B CAP_0402-0.22UF,16V,10%,X7R,A3A    I61 @BASEBOARD_FAB2_LIB.BASEBOARD_FAB2(SCH_1):PAGE105
  J8G1  163  IO163 SCONN200_H68296001_SM-CONN,H68A    I78 @BASEBOARD_FAB2_LIB.BASEBOARD_FAB2(SCH_1):PAGE109

P3E_CPU0_PE2_SS_C_TXN<3> @BASEBOARD_FAB2_LIB.BASEBOARD_FAB2(SCH_1):P3E_CPU0_PE2_SS_C_TXN(3)
  C8G4    2      B CAP_0402-0.22UF,16V,10%,X7R,A3A    I56 @BASEBOARD_FAB2_LIB.BASEBOARD_FAB2(SCH_1):PAGE105
  J8G1  169  IO169 SCONN200_H68296001_SM-CONN,H68A    I78 @BASEBOARD_FAB2_LIB.BASEBOARD_FAB2(SCH_1):PAGE109

P3E_CPU0_PE2_SS_C_TXN<4> @BASEBOARD_FAB2_LIB.BASEBOARD_FAB2(SCH_1):P3E_CPU0_PE2_SS_C_TXN(4)
  C8G2    2      B CAP_0402-0.22UF,16V,10%,X7R,A3A    I58 @BASEBOARD_FAB2_LIB.BASEBOARD_FAB2(SCH_1):PAGE105
  J8G1  175  IO175 SCONN200_H68296001_SM-CONN,H68A    I78 @BASEBOARD_FAB2_LIB.BASEBOARD_FAB2(SCH_1):PAGE109

P3E_CPU0_PE2_SS_C_TXN<5> @BASEBOARD_FAB2_LIB.BASEBOARD_FAB2(SCH_1):P3E_CPU0_PE2_SS_C_TXN(5)
 C7G26    2      B CAP_0402-0.22UF,16V,10%,X7R,A3A    I55 @BASEBOARD_FAB2_LIB.BASEBOARD_FAB2(SCH_1):PAGE105
  J8G1  181  IO181 SCONN200_H68296001_SM-CONN,H68A    I78 @BASEBOARD_FAB2_LIB.BASEBOARD_FAB2(SCH_1):PAGE109

P3E_CPU0_PE2_SS_C_TXN<6> @BASEBOARD_FAB2_LIB.BASEBOARD_FAB2(SCH_1):P3E_CPU0_PE2_SS_C_TXN(6)
 C7G24    2      B CAP_0402-0.22UF,16V,10%,X7R,A3A     I1 @BASEBOARD_FAB2_LIB.BASEBOARD_FAB2(SCH_1):PAGE105
  J8G1  187  IO187 SCONN200_H68296001_SM-CONN,H68A    I78 @BASEBOARD_FAB2_LIB.BASEBOARD_FAB2(SCH_1):PAGE109

P3E_CPU0_PE2_SS_C_TXN<7> @BASEBOARD_FAB2_LIB.BASEBOARD_FAB2(SCH_1):P3E_CPU0_PE2_SS_C_TXN(7)
 C7G22    2      B CAP_0402-0.22UF,16V,10%,X7R,A3A    I37 @BASEBOARD_FAB2_LIB.BASEBOARD_FAB2(SCH_1):PAGE105
  J8G1  193  IO193 SCONN200_H68296001_SM-CONN,H68A    I78 @BASEBOARD_FAB2_LIB.BASEBOARD_FAB2(SCH_1):PAGE109

P3E_CPU0_PE2_SS_C_TXN<8> @BASEBOARD_FAB2_LIB.BASEBOARD_FAB2(SCH_1):P3E_CPU0_PE2_SS_C_TXN(8)
 C7G20    2      B CAP_0402-0.22UF,16V,10%,X7R,A3A    I34 @BASEBOARD_FAB2_LIB.BASEBOARD_FAB2(SCH_1):PAGE105
 CONX8    5      5 SMC-CONN60A-22-GP_CONN-G7-SMC-A    I48 @BASEBOARD_FAB2_LIB.BASEBOARD_FAB2(SCH_1):PAGE245

P3E_CPU0_PE2_SS_C_TXN<9> @BASEBOARD_FAB2_LIB.BASEBOARD_FAB2(SCH_1):P3E_CPU0_PE2_SS_C_TXN(9)
 C7G18    2      B CAP_0402-0.22UF,16V,10%,X7R,A3A    I32 @BASEBOARD_FAB2_LIB.BASEBOARD_FAB2(SCH_1):PAGE105
 CONX8    9      9 SMC-CONN60A-22-GP_CONN-G7-SMC-A    I48 @BASEBOARD_FAB2_LIB.BASEBOARD_FAB2(SCH_1):PAGE245

P3E_CPU0_PE2_SS_C_TXP<0> @BASEBOARD_FAB2_LIB.BASEBOARD_FAB2(SCH_1):P3E_CPU0_PE2_SS_C_TXP(0)
  C8G9    2      B CAP_0402-0.22UF,16V,10%,X7R,A3A    I93 @BASEBOARD_FAB2_LIB.BASEBOARD_FAB2(SCH_1):PAGE105
  J8G1  153  IO153 SCONN200_H68296001_SM-CONN,H68A    I78 @BASEBOARD_FAB2_LIB.BASEBOARD_FAB2(SCH_1):PAGE109

P3E_CPU0_PE2_SS_C_TXP<10> @BASEBOARD_FAB2_LIB.BASEBOARD_FAB2(SCH_1):P3E_CPU0_PE2_SS_C_TXP(10)
 C7G15    2      B CAP_0402-0.22UF,16V,10%,X7R,A3A    I45 @BASEBOARD_FAB2_LIB.BASEBOARD_FAB2(SCH_1):PAGE105
 CONX8   17     17 SMC-CONN60A-22-GP_CONN-G7-SMC-A    I48 @BASEBOARD_FAB2_LIB.BASEBOARD_FAB2(SCH_1):PAGE245

P3E_CPU0_PE2_SS_C_TXP<11> @BASEBOARD_FAB2_LIB.BASEBOARD_FAB2(SCH_1):P3E_CPU0_PE2_SS_C_TXP(11)
 C7G14    2      B CAP_0402-0.22UF,16V,10%,X7R,A3A    I28 @BASEBOARD_FAB2_LIB.BASEBOARD_FAB2(SCH_1):PAGE105
 CONX8   21     21 SMC-CONN60A-22-GP_CONN-G7-SMC-A    I48 @BASEBOARD_FAB2_LIB.BASEBOARD_FAB2(SCH_1):PAGE245

P3E_CPU0_PE2_SS_C_TXP<12> @BASEBOARD_FAB2_LIB.BASEBOARD_FAB2(SCH_1):P3E_CPU0_PE2_SS_C_TXP(12)
 C7G11    2      B CAP_0402-0.22UF,16V,10%,X7R,A3A    I27 @BASEBOARD_FAB2_LIB.BASEBOARD_FAB2(SCH_1):PAGE105
 CONX8   29     29 SMC-CONN60A-22-GP_CONN-G7-SMC-A    I48 @BASEBOARD_FAB2_LIB.BASEBOARD_FAB2(SCH_1):PAGE245

P3E_CPU0_PE2_SS_C_TXP<13> @BASEBOARD_FAB2_LIB.BASEBOARD_FAB2(SCH_1):P3E_CPU0_PE2_SS_C_TXP(13)
  C7G9    2      B CAP_0402-0.22UF,16V,10%,X7R,A3A    I21 @BASEBOARD_FAB2_LIB.BASEBOARD_FAB2(SCH_1):PAGE105
 CONX8   35     35 SMC-CONN60A-22-GP_CONN-G7-SMC-A    I48 @BASEBOARD_FAB2_LIB.BASEBOARD_FAB2(SCH_1):PAGE245

P3E_CPU0_PE2_SS_C_TXP<14> @BASEBOARD_FAB2_LIB.BASEBOARD_FAB2(SCH_1):P3E_CPU0_PE2_SS_C_TXP(14)
  C7G8    2      B CAP_0402-0.22UF,16V,10%,X7R,A3A    I22 @BASEBOARD_FAB2_LIB.BASEBOARD_FAB2(SCH_1):PAGE105
 CONX8   39     39 SMC-CONN60A-22-GP_CONN-G7-SMC-A    I48 @BASEBOARD_FAB2_LIB.BASEBOARD_FAB2(SCH_1):PAGE245

P3E_CPU0_PE2_SS_C_TXP<15> @BASEBOARD_FAB2_LIB.BASEBOARD_FAB2(SCH_1):P3E_CPU0_PE2_SS_C_TXP(15)
  C7G5    2      B CAP_0402-0.22UF,16V,10%,X7R,A3A    I20 @BASEBOARD_FAB2_LIB.BASEBOARD_FAB2(SCH_1):PAGE105
 CONX8   47     47 SMC-CONN60A-22-GP_CONN-G7-SMC-A    I48 @BASEBOARD_FAB2_LIB.BASEBOARD_FAB2(SCH_1):PAGE245

P3E_CPU0_PE2_SS_C_TXP<1> @BASEBOARD_FAB2_LIB.BASEBOARD_FAB2(SCH_1):P3E_CPU0_PE2_SS_C_TXP(1)
  C8G8    2      B CAP_0402-0.22UF,16V,10%,X7R,A3A    I76 @BASEBOARD_FAB2_LIB.BASEBOARD_FAB2(SCH_1):PAGE105
  J8G1  157  IO157 SCONN200_H68296001_SM-CONN,H68A    I78 @BASEBOARD_FAB2_LIB.BASEBOARD_FAB2(SCH_1):PAGE109

P3E_CPU0_PE2_SS_C_TXP<2> @BASEBOARD_FAB2_LIB.BASEBOARD_FAB2(SCH_1):P3E_CPU0_PE2_SS_C_TXP(2)
  C8G5    2      B CAP_0402-0.22UF,16V,10%,X7R,A3A    I75 @BASEBOARD_FAB2_LIB.BASEBOARD_FAB2(SCH_1):PAGE105
  J8G1  165  IO165 SCONN200_H68296001_SM-CONN,H68A    I78 @BASEBOARD_FAB2_LIB.BASEBOARD_FAB2(SCH_1):PAGE109

P3E_CPU0_PE2_SS_C_TXP<3> @BASEBOARD_FAB2_LIB.BASEBOARD_FAB2(SCH_1):P3E_CPU0_PE2_SS_C_TXP(3)
  C8G3    2      B CAP_0402-0.22UF,16V,10%,X7R,A3A    I71 @BASEBOARD_FAB2_LIB.BASEBOARD_FAB2(SCH_1):PAGE105
  J8G1  171  IO171 SCONN200_H68296001_SM-CONN,H68A    I78 @BASEBOARD_FAB2_LIB.BASEBOARD_FAB2(SCH_1):PAGE109

P3E_CPU0_PE2_SS_C_TXP<4> @BASEBOARD_FAB2_LIB.BASEBOARD_FAB2(SCH_1):P3E_CPU0_PE2_SS_C_TXP(4)
  C8G1    2      B CAP_0402-0.22UF,16V,10%,X7R,A3A    I70 @BASEBOARD_FAB2_LIB.BASEBOARD_FAB2(SCH_1):PAGE105
  J8G1  177  IO177 SCONN200_H68296001_SM-CONN,H68A    I78 @BASEBOARD_FAB2_LIB.BASEBOARD_FAB2(SCH_1):PAGE109

P3E_CPU0_PE2_SS_C_TXP<5> @BASEBOARD_FAB2_LIB.BASEBOARD_FAB2(SCH_1):P3E_CPU0_PE2_SS_C_TXP(5)
 C7G25    2      B CAP_0402-0.22UF,16V,10%,X7R,A3A    I69 @BASEBOARD_FAB2_LIB.BASEBOARD_FAB2(SCH_1):PAGE105
  J8G1  183  IO183 SCONN200_H68296001_SM-CONN,H68A    I78 @BASEBOARD_FAB2_LIB.BASEBOARD_FAB2(SCH_1):PAGE109

P3E_CPU0_PE2_SS_C_TXP<6> @BASEBOARD_FAB2_LIB.BASEBOARD_FAB2(SCH_1):P3E_CPU0_PE2_SS_C_TXP(6)
 C7G23    2      B CAP_0402-0.22UF,16V,10%,X7R,A3A    I52 @BASEBOARD_FAB2_LIB.BASEBOARD_FAB2(SCH_1):PAGE105
  J8G1  189  IO189 SCONN200_H68296001_SM-CONN,H68A    I78 @BASEBOARD_FAB2_LIB.BASEBOARD_FAB2(SCH_1):PAGE109

P3E_CPU0_PE2_SS_C_TXP<7> @BASEBOARD_FAB2_LIB.BASEBOARD_FAB2(SCH_1):P3E_CPU0_PE2_SS_C_TXP(7)
 C7G21    2      B CAP_0402-0.22UF,16V,10%,X7R,A3A    I51 @BASEBOARD_FAB2_LIB.BASEBOARD_FAB2(SCH_1):PAGE105
  J8G1  195  IO195 SCONN200_H68296001_SM-CONN,H68A    I78 @BASEBOARD_FAB2_LIB.BASEBOARD_FAB2(SCH_1):PAGE109

P3E_CPU0_PE2_SS_C_TXP<8> @BASEBOARD_FAB2_LIB.BASEBOARD_FAB2(SCH_1):P3E_CPU0_PE2_SS_C_TXP(8)
 C7G19    2      B CAP_0402-0.22UF,16V,10%,X7R,A3A    I46 @BASEBOARD_FAB2_LIB.BASEBOARD_FAB2(SCH_1):PAGE105
 CONX8    3      3 SMC-CONN60A-22-GP_CONN-G7-SMC-A    I48 @BASEBOARD_FAB2_LIB.BASEBOARD_FAB2(SCH_1):PAGE245

P3E_CPU0_PE2_SS_C_TXP<9> @BASEBOARD_FAB2_LIB.BASEBOARD_FAB2(SCH_1):P3E_CPU0_PE2_SS_C_TXP(9)
 C7G17    2      B CAP_0402-0.22UF,16V,10%,X7R,A3A    I44 @BASEBOARD_FAB2_LIB.BASEBOARD_FAB2(SCH_1):PAGE105
 CONX8   11     11 SMC-CONN60A-22-GP_CONN-G7-SMC-A    I48 @BASEBOARD_FAB2_LIB.BASEBOARD_FAB2(SCH_1):PAGE245

P3E_CPU0_PE2_SS_RXN<0> @BASEBOARD_FAB2_LIB.BASEBOARD_FAB2(SCH_1):P3E_CPU0_PE2_SS_RXN(0)
  U5D1  CT9 PE2_RX_DN<0> SKX_EXT_B_BGA1-IC,TBD   I106 @BASEBOARD_FAB2_LIB.BASEBOARD_FAB2(SCH_1):PAGE31
  J8G1  154  IO154 SCONN200_H68296001_SM-CONN,H68A    I78 @BASEBOARD_FAB2_LIB.BASEBOARD_FAB2(SCH_1):PAGE109

P3E_CPU0_PE2_SS_RXN<10> @BASEBOARD_FAB2_LIB.BASEBOARD_FAB2(SCH_1):P3E_CPU0_PE2_SS_RXN(10)
  U5D1  BV7 PE2_RX_DN<10> SKX_EXT_B_BGA1-IC,TBD   I106 @BASEBOARD_FAB2_LIB.BASEBOARD_FAB2(SCH_1):PAGE31
 CONX8   18     18 SMC-CONN60A-22-GP_CONN-G7-SMC-A    I48 @BASEBOARD_FAB2_LIB.BASEBOARD_FAB2(SCH_1):PAGE245

P3E_CPU0_PE2_SS_RXN<11> @BASEBOARD_FAB2_LIB.BASEBOARD_FAB2(SCH_1):P3E_CPU0_PE2_SS_RXN(11)
  U5D1  BT7 PE2_RX_DN<11> SKX_EXT_B_BGA1-IC,TBD   I106 @BASEBOARD_FAB2_LIB.BASEBOARD_FAB2(SCH_1):PAGE31
 CONX8   24     24 SMC-CONN60A-22-GP_CONN-G7-SMC-A    I48 @BASEBOARD_FAB2_LIB.BASEBOARD_FAB2(SCH_1):PAGE245

P3E_CPU0_PE2_SS_RXN<12> @BASEBOARD_FAB2_LIB.BASEBOARD_FAB2(SCH_1):P3E_CPU0_PE2_SS_RXN(12)
  U5D1  BR8 PE2_RX_DN<12> SKX_EXT_B_BGA1-IC,TBD   I106 @BASEBOARD_FAB2_LIB.BASEBOARD_FAB2(SCH_1):PAGE31
 CONX8   30     30 SMC-CONN60A-22-GP_CONN-G7-SMC-A    I48 @BASEBOARD_FAB2_LIB.BASEBOARD_FAB2(SCH_1):PAGE245

P3E_CPU0_PE2_SS_RXN<13> @BASEBOARD_FAB2_LIB.BASEBOARD_FAB2(SCH_1):P3E_CPU0_PE2_SS_RXN(13)
  U5D1  BN8 PE2_RX_DN<13> SKX_EXT_B_BGA1-IC,TBD   I106 @BASEBOARD_FAB2_LIB.BASEBOARD_FAB2(SCH_1):PAGE31
 CONX8   38     38 SMC-CONN60A-22-GP_CONN-G7-SMC-A    I48 @BASEBOARD_FAB2_LIB.BASEBOARD_FAB2(SCH_1):PAGE245

P3E_CPU0_PE2_SS_RXN<14> @BASEBOARD_FAB2_LIB.BASEBOARD_FAB2(SCH_1):P3E_CPU0_PE2_SS_RXN(14)
  U5D1  BL8 PE2_RX_DN<14> SKX_EXT_B_BGA1-IC,TBD   I106 @BASEBOARD_FAB2_LIB.BASEBOARD_FAB2(SCH_1):PAGE31
 CONX8   42     42 SMC-CONN60A-22-GP_CONN-G7-SMC-A    I48 @BASEBOARD_FAB2_LIB.BASEBOARD_FAB2(SCH_1):PAGE245

P3E_CPU0_PE2_SS_RXN<15> @BASEBOARD_FAB2_LIB.BASEBOARD_FAB2(SCH_1):P3E_CPU0_PE2_SS_RXN(15)
  U5D1  BK9 PE2_RX_DN<15> SKX_EXT_B_BGA1-IC,TBD   I106 @BASEBOARD_FAB2_LIB.BASEBOARD_FAB2(SCH_1):PAGE31
 CONX8   48     48 SMC-CONN60A-22-GP_CONN-G7-SMC-A    I48 @BASEBOARD_FAB2_LIB.BASEBOARD_FAB2(SCH_1):PAGE245

P3E_CPU0_PE2_SS_RXN<1> @BASEBOARD_FAB2_LIB.BASEBOARD_FAB2(SCH_1):P3E_CPU0_PE2_SS_RXN(1)
  U5D1  CP9 PE2_RX_DN<1> SKX_EXT_B_BGA1-IC,TBD   I106 @BASEBOARD_FAB2_LIB.BASEBOARD_FAB2(SCH_1):PAGE31
  J8G1  160  IO160 SCONN200_H68296001_SM-CONN,H68A    I78 @BASEBOARD_FAB2_LIB.BASEBOARD_FAB2(SCH_1):PAGE109

P3E_CPU0_PE2_SS_RXN<2> @BASEBOARD_FAB2_LIB.BASEBOARD_FAB2(SCH_1):P3E_CPU0_PE2_SS_RXN(2)
  U5D1  CP7 PE2_RX_DN<2> SKX_EXT_B_BGA1-IC,TBD   I106 @BASEBOARD_FAB2_LIB.BASEBOARD_FAB2(SCH_1):PAGE31
  J8G1  168  IO168 SCONN200_H68296001_SM-CONN,H68A    I78 @BASEBOARD_FAB2_LIB.BASEBOARD_FAB2(SCH_1):PAGE109

P3E_CPU0_PE2_SS_RXN<3> @BASEBOARD_FAB2_LIB.BASEBOARD_FAB2(SCH_1):P3E_CPU0_PE2_SS_RXN(3)
  U5D1  CM7 PE2_RX_DN<3> SKX_EXT_B_BGA1-IC,TBD   I106 @BASEBOARD_FAB2_LIB.BASEBOARD_FAB2(SCH_1):PAGE31
  J8G1  172  IO172 SCONN200_H68296001_SM-CONN,H68A    I78 @BASEBOARD_FAB2_LIB.BASEBOARD_FAB2(SCH_1):PAGE109

P3E_CPU0_PE2_SS_RXN<4> @BASEBOARD_FAB2_LIB.BASEBOARD_FAB2(SCH_1):P3E_CPU0_PE2_SS_RXN(4)
  U5D1  CK7 PE2_RX_DN<4> SKX_EXT_B_BGA1-IC,TBD   I106 @BASEBOARD_FAB2_LIB.BASEBOARD_FAB2(SCH_1):PAGE31
  J8G1  178  IO178 SCONN200_H68296001_SM-CONN,H68A    I78 @BASEBOARD_FAB2_LIB.BASEBOARD_FAB2(SCH_1):PAGE109

P3E_CPU0_PE2_SS_RXN<5> @BASEBOARD_FAB2_LIB.BASEBOARD_FAB2(SCH_1):P3E_CPU0_PE2_SS_RXN(5)
  U5D1  CG8 PE2_RX_DN<5> SKX_EXT_B_BGA1-IC,TBD   I106 @BASEBOARD_FAB2_LIB.BASEBOARD_FAB2(SCH_1):PAGE31
  J8G1  184  IO184 SCONN200_H68296001_SM-CONN,H68A    I78 @BASEBOARD_FAB2_LIB.BASEBOARD_FAB2(SCH_1):PAGE109

P3E_CPU0_PE2_SS_RXN<6> @BASEBOARD_FAB2_LIB.BASEBOARD_FAB2(SCH_1):P3E_CPU0_PE2_SS_RXN(6)
  U5D1  CE6 PE2_RX_DN<6> SKX_EXT_B_BGA1-IC,TBD   I106 @BASEBOARD_FAB2_LIB.BASEBOARD_FAB2(SCH_1):PAGE31
  J8G1  192  IO192 SCONN200_H68296001_SM-CONN,H68A    I78 @BASEBOARD_FAB2_LIB.BASEBOARD_FAB2(SCH_1):PAGE109

P3E_CPU0_PE2_SS_RXN<7> @BASEBOARD_FAB2_LIB.BASEBOARD_FAB2(SCH_1):P3E_CPU0_PE2_SS_RXN(7)
  U5D1  CE8 PE2_RX_DN<7> SKX_EXT_B_BGA1-IC,TBD   I106 @BASEBOARD_FAB2_LIB.BASEBOARD_FAB2(SCH_1):PAGE31
  J8G1  196  IO196 SCONN200_H68296001_SM-CONN,H68A    I78 @BASEBOARD_FAB2_LIB.BASEBOARD_FAB2(SCH_1):PAGE109

P3E_CPU0_PE2_SS_RXN<8> @BASEBOARD_FAB2_LIB.BASEBOARD_FAB2(SCH_1):P3E_CPU0_PE2_SS_RXN(8)
  U5D1  BY9 PE2_RX_DN<8> SKX_EXT_B_BGA1-IC,TBD   I106 @BASEBOARD_FAB2_LIB.BASEBOARD_FAB2(SCH_1):PAGE31
 CONX8    6      6 SMC-CONN60A-22-GP_CONN-G7-SMC-A    I48 @BASEBOARD_FAB2_LIB.BASEBOARD_FAB2(SCH_1):PAGE245

P3E_CPU0_PE2_SS_RXN<9> @BASEBOARD_FAB2_LIB.BASEBOARD_FAB2(SCH_1):P3E_CPU0_PE2_SS_RXN(9)
  U5D1  BY7 PE2_RX_DN<9> SKX_EXT_B_BGA1-IC,TBD   I106 @BASEBOARD_FAB2_LIB.BASEBOARD_FAB2(SCH_1):PAGE31
 CONX8   12     12 SMC-CONN60A-22-GP_CONN-G7-SMC-A    I48 @BASEBOARD_FAB2_LIB.BASEBOARD_FAB2(SCH_1):PAGE245

P3E_CPU0_PE2_SS_RXP<0> @BASEBOARD_FAB2_LIB.BASEBOARD_FAB2(SCH_1):P3E_CPU0_PE2_SS_RXP(0)
  U5D1  CR8 PE2_RX_DP<0> SKX_EXT_B_BGA1-IC,TBD   I106 @BASEBOARD_FAB2_LIB.BASEBOARD_FAB2(SCH_1):PAGE31
  J8G1  156  IO156 SCONN200_H68296001_SM-CONN,H68A    I78 @BASEBOARD_FAB2_LIB.BASEBOARD_FAB2(SCH_1):PAGE109

P3E_CPU0_PE2_SS_RXP<10> @BASEBOARD_FAB2_LIB.BASEBOARD_FAB2(SCH_1):P3E_CPU0_PE2_SS_RXP(10)
  U5D1  BU6 PE2_RX_DP<10> SKX_EXT_B_BGA1-IC,TBD   I106 @BASEBOARD_FAB2_LIB.BASEBOARD_FAB2(SCH_1):PAGE31
 CONX8   20     20 SMC-CONN60A-22-GP_CONN-G7-SMC-A    I48 @BASEBOARD_FAB2_LIB.BASEBOARD_FAB2(SCH_1):PAGE245

P3E_CPU0_PE2_SS_RXP<11> @BASEBOARD_FAB2_LIB.BASEBOARD_FAB2(SCH_1):P3E_CPU0_PE2_SS_RXP(11)
  U5D1  BP7 PE2_RX_DP<11> SKX_EXT_B_BGA1-IC,TBD   I106 @BASEBOARD_FAB2_LIB.BASEBOARD_FAB2(SCH_1):PAGE31
 CONX8   26     26 SMC-CONN60A-22-GP_CONN-G7-SMC-A    I48 @BASEBOARD_FAB2_LIB.BASEBOARD_FAB2(SCH_1):PAGE245

P3E_CPU0_PE2_SS_RXP<12> @BASEBOARD_FAB2_LIB.BASEBOARD_FAB2(SCH_1):P3E_CPU0_PE2_SS_RXP(12)
  U5D1  BP9 PE2_RX_DP<12> SKX_EXT_B_BGA1-IC,TBD   I106 @BASEBOARD_FAB2_LIB.BASEBOARD_FAB2(SCH_1):PAGE31
 CONX8   32     32 SMC-CONN60A-22-GP_CONN-G7-SMC-A    I48 @BASEBOARD_FAB2_LIB.BASEBOARD_FAB2(SCH_1):PAGE245

P3E_CPU0_PE2_SS_RXP<13> @BASEBOARD_FAB2_LIB.BASEBOARD_FAB2(SCH_1):P3E_CPU0_PE2_SS_RXP(13)
  U5D1  BM7 PE2_RX_DP<13> SKX_EXT_B_BGA1-IC,TBD   I106 @BASEBOARD_FAB2_LIB.BASEBOARD_FAB2(SCH_1):PAGE31
 CONX8   36     36 SMC-CONN60A-22-GP_CONN-G7-SMC-A    I48 @BASEBOARD_FAB2_LIB.BASEBOARD_FAB2(SCH_1):PAGE245

P3E_CPU0_PE2_SS_RXP<14> @BASEBOARD_FAB2_LIB.BASEBOARD_FAB2(SCH_1):P3E_CPU0_PE2_SS_RXP(14)
  U5D1  BJ8 PE2_RX_DP<14> SKX_EXT_B_BGA1-IC,TBD   I106 @BASEBOARD_FAB2_LIB.BASEBOARD_FAB2(SCH_1):PAGE31
 CONX8   44     44 SMC-CONN60A-22-GP_CONN-G7-SMC-A    I48 @BASEBOARD_FAB2_LIB.BASEBOARD_FAB2(SCH_1):PAGE245

P3E_CPU0_PE2_SS_RXP<15> @BASEBOARD_FAB2_LIB.BASEBOARD_FAB2(SCH_1):P3E_CPU0_PE2_SS_RXP(15)
  U5D1 BJ10 PE2_RX_DP<15> SKX_EXT_B_BGA1-IC,TBD   I106 @BASEBOARD_FAB2_LIB.BASEBOARD_FAB2(SCH_1):PAGE31
 CONX8   50     50 SMC-CONN60A-22-GP_CONN-G7-SMC-A    I48 @BASEBOARD_FAB2_LIB.BASEBOARD_FAB2(SCH_1):PAGE245

P3E_CPU0_PE2_SS_RXP<1> @BASEBOARD_FAB2_LIB.BASEBOARD_FAB2(SCH_1):P3E_CPU0_PE2_SS_RXP(1)
  U5D1  CM9 PE2_RX_DP<1> SKX_EXT_B_BGA1-IC,TBD   I106 @BASEBOARD_FAB2_LIB.BASEBOARD_FAB2(SCH_1):PAGE31
  J8G1  162  IO162 SCONN200_H68296001_SM-CONN,H68A    I78 @BASEBOARD_FAB2_LIB.BASEBOARD_FAB2(SCH_1):PAGE109

P3E_CPU0_PE2_SS_RXP<2> @BASEBOARD_FAB2_LIB.BASEBOARD_FAB2(SCH_1):P3E_CPU0_PE2_SS_RXP(2)
  U5D1  CN8 PE2_RX_DP<2> SKX_EXT_B_BGA1-IC,TBD   I106 @BASEBOARD_FAB2_LIB.BASEBOARD_FAB2(SCH_1):PAGE31
  J8G1  166  IO166 SCONN200_H68296001_SM-CONN,H68A    I78 @BASEBOARD_FAB2_LIB.BASEBOARD_FAB2(SCH_1):PAGE109

P3E_CPU0_PE2_SS_RXP<3> @BASEBOARD_FAB2_LIB.BASEBOARD_FAB2(SCH_1):P3E_CPU0_PE2_SS_RXP(3)
  U5D1  CL6 PE2_RX_DP<3> SKX_EXT_B_BGA1-IC,TBD   I106 @BASEBOARD_FAB2_LIB.BASEBOARD_FAB2(SCH_1):PAGE31
  J8G1  174  IO174 SCONN200_H68296001_SM-CONN,H68A    I78 @BASEBOARD_FAB2_LIB.BASEBOARD_FAB2(SCH_1):PAGE109

P3E_CPU0_PE2_SS_RXP<4> @BASEBOARD_FAB2_LIB.BASEBOARD_FAB2(SCH_1):P3E_CPU0_PE2_SS_RXP(4)
  U5D1  CH7 PE2_RX_DP<4> SKX_EXT_B_BGA1-IC,TBD   I106 @BASEBOARD_FAB2_LIB.BASEBOARD_FAB2(SCH_1):PAGE31
  J8G1  180  IO180 SCONN200_H68296001_SM-CONN,H68A    I78 @BASEBOARD_FAB2_LIB.BASEBOARD_FAB2(SCH_1):PAGE109

P3E_CPU0_PE2_SS_RXP<5> @BASEBOARD_FAB2_LIB.BASEBOARD_FAB2(SCH_1):P3E_CPU0_PE2_SS_RXP(5)
  U5D1  CF7 PE2_RX_DP<5> SKX_EXT_B_BGA1-IC,TBD   I106 @BASEBOARD_FAB2_LIB.BASEBOARD_FAB2(SCH_1):PAGE31
  J8G1  186  IO186 SCONN200_H68296001_SM-CONN,H68A    I78 @BASEBOARD_FAB2_LIB.BASEBOARD_FAB2(SCH_1):PAGE109

P3E_CPU0_PE2_SS_RXP<6> @BASEBOARD_FAB2_LIB.BASEBOARD_FAB2(SCH_1):P3E_CPU0_PE2_SS_RXP(6)
  U5D1  CD7 PE2_RX_DP<6> SKX_EXT_B_BGA1-IC,TBD   I106 @BASEBOARD_FAB2_LIB.BASEBOARD_FAB2(SCH_1):PAGE31
  J8G1  190  IO190 SCONN200_H68296001_SM-CONN,H68A    I78 @BASEBOARD_FAB2_LIB.BASEBOARD_FAB2(SCH_1):PAGE109

P3E_CPU0_PE2_SS_RXP<7> @BASEBOARD_FAB2_LIB.BASEBOARD_FAB2(SCH_1):P3E_CPU0_PE2_SS_RXP(7)
  U5D1  CC8 PE2_RX_DP<7> SKX_EXT_B_BGA1-IC,TBD   I106 @BASEBOARD_FAB2_LIB.BASEBOARD_FAB2(SCH_1):PAGE31
  J8G1  198  IO198 SCONN200_H68296001_SM-CONN,H68A    I78 @BASEBOARD_FAB2_LIB.BASEBOARD_FAB2(SCH_1):PAGE109

P3E_CPU0_PE2_SS_RXP<8> @BASEBOARD_FAB2_LIB.BASEBOARD_FAB2(SCH_1):P3E_CPU0_PE2_SS_RXP(8)
  U5D1  BV9 PE2_RX_DP<8> SKX_EXT_B_BGA1-IC,TBD   I106 @BASEBOARD_FAB2_LIB.BASEBOARD_FAB2(SCH_1):PAGE31
 CONX8    8      8 SMC-CONN60A-22-GP_CONN-G7-SMC-A    I48 @BASEBOARD_FAB2_LIB.BASEBOARD_FAB2(SCH_1):PAGE245

P3E_CPU0_PE2_SS_RXP<9> @BASEBOARD_FAB2_LIB.BASEBOARD_FAB2(SCH_1):P3E_CPU0_PE2_SS_RXP(9)
  U5D1  BW8 PE2_RX_DP<9> SKX_EXT_B_BGA1-IC,TBD   I106 @BASEBOARD_FAB2_LIB.BASEBOARD_FAB2(SCH_1):PAGE31
 CONX8   14     14 SMC-CONN60A-22-GP_CONN-G7-SMC-A    I48 @BASEBOARD_FAB2_LIB.BASEBOARD_FAB2(SCH_1):PAGE245

P3E_CPU0_PE2_SS_TXN<0> @BASEBOARD_FAB2_LIB.BASEBOARD_FAB2(SCH_1):P3E_CPU0_PE2_SS_TXN(0)
  U5D1  CY3 PE2_TX_DN<0> SKX_EXT_B_BGA1-IC,TBD   I106 @BASEBOARD_FAB2_LIB.BASEBOARD_FAB2(SCH_1):PAGE31
 C8G10    1      A CAP_0402-0.22UF,16V,10%,X7R,A3A    I96 @BASEBOARD_FAB2_LIB.BASEBOARD_FAB2(SCH_1):PAGE105

P3E_CPU0_PE2_SS_TXN<10> @BASEBOARD_FAB2_LIB.BASEBOARD_FAB2(SCH_1):P3E_CPU0_PE2_SS_TXN(10)
  U5D1  CA4 PE2_TX_DN<10> SKX_EXT_B_BGA1-IC,TBD   I106 @BASEBOARD_FAB2_LIB.BASEBOARD_FAB2(SCH_1):PAGE31
 C7G16    1      A CAP_0402-0.22UF,16V,10%,X7R,A3A    I31 @BASEBOARD_FAB2_LIB.BASEBOARD_FAB2(SCH_1):PAGE105

P3E_CPU0_PE2_SS_TXN<11> @BASEBOARD_FAB2_LIB.BASEBOARD_FAB2(SCH_1):P3E_CPU0_PE2_SS_TXN(11)
  U5D1  BW4 PE2_TX_DN<11> SKX_EXT_B_BGA1-IC,TBD   I106 @BASEBOARD_FAB2_LIB.BASEBOARD_FAB2(SCH_1):PAGE31
 C7G13    1      A CAP_0402-0.22UF,16V,10%,X7R,A3A    I13 @BASEBOARD_FAB2_LIB.BASEBOARD_FAB2(SCH_1):PAGE105

P3E_CPU0_PE2_SS_TXN<12> @BASEBOARD_FAB2_LIB.BASEBOARD_FAB2(SCH_1):P3E_CPU0_PE2_SS_TXN(12)
  U5D1  BU4 PE2_TX_DN<12> SKX_EXT_B_BGA1-IC,TBD   I106 @BASEBOARD_FAB2_LIB.BASEBOARD_FAB2(SCH_1):PAGE31
 C7G12    1      A CAP_0402-0.22UF,16V,10%,X7R,A3A    I12 @BASEBOARD_FAB2_LIB.BASEBOARD_FAB2(SCH_1):PAGE105

P3E_CPU0_PE2_SS_TXN<13> @BASEBOARD_FAB2_LIB.BASEBOARD_FAB2(SCH_1):P3E_CPU0_PE2_SS_TXN(13)
  U5D1  BP5 PE2_TX_DN<13> SKX_EXT_B_BGA1-IC,TBD   I106 @BASEBOARD_FAB2_LIB.BASEBOARD_FAB2(SCH_1):PAGE31
 C7G10    1      A CAP_0402-0.22UF,16V,10%,X7R,A3A     I8 @BASEBOARD_FAB2_LIB.BASEBOARD_FAB2(SCH_1):PAGE105

P3E_CPU0_PE2_SS_TXN<14> @BASEBOARD_FAB2_LIB.BASEBOARD_FAB2(SCH_1):P3E_CPU0_PE2_SS_TXN(14)
  U5D1  BL4 PE2_TX_DN<14> SKX_EXT_B_BGA1-IC,TBD   I106 @BASEBOARD_FAB2_LIB.BASEBOARD_FAB2(SCH_1):PAGE31
  C7G7    1      A CAP_0402-0.22UF,16V,10%,X7R,A3A     I7 @BASEBOARD_FAB2_LIB.BASEBOARD_FAB2(SCH_1):PAGE105

P3E_CPU0_PE2_SS_TXN<15> @BASEBOARD_FAB2_LIB.BASEBOARD_FAB2(SCH_1):P3E_CPU0_PE2_SS_TXN(15)
  U5D1  BM5 PE2_TX_DN<15> SKX_EXT_B_BGA1-IC,TBD   I106 @BASEBOARD_FAB2_LIB.BASEBOARD_FAB2(SCH_1):PAGE31
  C7G6    1      A CAP_0402-0.22UF,16V,10%,X7R,A3A     I6 @BASEBOARD_FAB2_LIB.BASEBOARD_FAB2(SCH_1):PAGE105

P3E_CPU0_PE2_SS_TXN<1> @BASEBOARD_FAB2_LIB.BASEBOARD_FAB2(SCH_1):P3E_CPU0_PE2_SS_TXN(1)
  U5D1  CV3 PE2_TX_DN<1> SKX_EXT_B_BGA1-IC,TBD   I106 @BASEBOARD_FAB2_LIB.BASEBOARD_FAB2(SCH_1):PAGE31
  C8G7    1      A CAP_0402-0.22UF,16V,10%,X7R,A3A    I62 @BASEBOARD_FAB2_LIB.BASEBOARD_FAB2(SCH_1):PAGE105

P3E_CPU0_PE2_SS_TXN<2> @BASEBOARD_FAB2_LIB.BASEBOARD_FAB2(SCH_1):P3E_CPU0_PE2_SS_TXN(2)
  U5D1  CT1 PE2_TX_DN<2> SKX_EXT_B_BGA1-IC,TBD   I106 @BASEBOARD_FAB2_LIB.BASEBOARD_FAB2(SCH_1):PAGE31
  C8G6    1      A CAP_0402-0.22UF,16V,10%,X7R,A3A    I61 @BASEBOARD_FAB2_LIB.BASEBOARD_FAB2(SCH_1):PAGE105

P3E_CPU0_PE2_SS_TXN<3> @BASEBOARD_FAB2_LIB.BASEBOARD_FAB2(SCH_1):P3E_CPU0_PE2_SS_TXN(3)
  U5D1  CT3 PE2_TX_DN<3> SKX_EXT_B_BGA1-IC,TBD   I106 @BASEBOARD_FAB2_LIB.BASEBOARD_FAB2(SCH_1):PAGE31
  C8G4    1      A CAP_0402-0.22UF,16V,10%,X7R,A3A    I56 @BASEBOARD_FAB2_LIB.BASEBOARD_FAB2(SCH_1):PAGE105

P3E_CPU0_PE2_SS_TXN<4> @BASEBOARD_FAB2_LIB.BASEBOARD_FAB2(SCH_1):P3E_CPU0_PE2_SS_TXN(4)
  U5D1  CM1 PE2_TX_DN<4> SKX_EXT_B_BGA1-IC,TBD   I106 @BASEBOARD_FAB2_LIB.BASEBOARD_FAB2(SCH_1):PAGE31
  C8G2    1      A CAP_0402-0.22UF,16V,10%,X7R,A3A    I58 @BASEBOARD_FAB2_LIB.BASEBOARD_FAB2(SCH_1):PAGE105

P3E_CPU0_PE2_SS_TXN<5> @BASEBOARD_FAB2_LIB.BASEBOARD_FAB2(SCH_1):P3E_CPU0_PE2_SS_TXN(5)
  U5D1  CL2 PE2_TX_DN<5> SKX_EXT_B_BGA1-IC,TBD   I106 @BASEBOARD_FAB2_LIB.BASEBOARD_FAB2(SCH_1):PAGE31
 C7G26    1      A CAP_0402-0.22UF,16V,10%,X7R,A3A    I55 @BASEBOARD_FAB2_LIB.BASEBOARD_FAB2(SCH_1):PAGE105

P3E_CPU0_PE2_SS_TXN<6> @BASEBOARD_FAB2_LIB.BASEBOARD_FAB2(SCH_1):P3E_CPU0_PE2_SS_TXN(6)
  U5D1  CG2 PE2_TX_DN<6> SKX_EXT_B_BGA1-IC,TBD   I106 @BASEBOARD_FAB2_LIB.BASEBOARD_FAB2(SCH_1):PAGE31
 C7G24    1      A CAP_0402-0.22UF,16V,10%,X7R,A3A     I1 @BASEBOARD_FAB2_LIB.BASEBOARD_FAB2(SCH_1):PAGE105

P3E_CPU0_PE2_SS_TXN<7> @BASEBOARD_FAB2_LIB.BASEBOARD_FAB2(SCH_1):P3E_CPU0_PE2_SS_TXN(7)
  U5D1  CF3 PE2_TX_DN<7> SKX_EXT_B_BGA1-IC,TBD   I106 @BASEBOARD_FAB2_LIB.BASEBOARD_FAB2(SCH_1):PAGE31
 C7G22    1      A CAP_0402-0.22UF,16V,10%,X7R,A3A    I37 @BASEBOARD_FAB2_LIB.BASEBOARD_FAB2(SCH_1):PAGE105

P3E_CPU0_PE2_SS_TXN<8> @BASEBOARD_FAB2_LIB.BASEBOARD_FAB2(SCH_1):P3E_CPU0_PE2_SS_TXN(8)
  U5D1  CC2 PE2_TX_DN<8> SKX_EXT_B_BGA1-IC,TBD   I106 @BASEBOARD_FAB2_LIB.BASEBOARD_FAB2(SCH_1):PAGE31
 C7G20    1      A CAP_0402-0.22UF,16V,10%,X7R,A3A    I34 @BASEBOARD_FAB2_LIB.BASEBOARD_FAB2(SCH_1):PAGE105

P3E_CPU0_PE2_SS_TXN<9> @BASEBOARD_FAB2_LIB.BASEBOARD_FAB2(SCH_1):P3E_CPU0_PE2_SS_TXN(9)
  U5D1  CB3 PE2_TX_DN<9> SKX_EXT_B_BGA1-IC,TBD   I106 @BASEBOARD_FAB2_LIB.BASEBOARD_FAB2(SCH_1):PAGE31
 C7G18    1      A CAP_0402-0.22UF,16V,10%,X7R,A3A    I32 @BASEBOARD_FAB2_LIB.BASEBOARD_FAB2(SCH_1):PAGE105

P3E_CPU0_PE2_SS_TXP<0> @BASEBOARD_FAB2_LIB.BASEBOARD_FAB2(SCH_1):P3E_CPU0_PE2_SS_TXP(0)
  U5D1  CW4 PE2_TX_DP<0> SKX_EXT_B_BGA1-IC,TBD   I106 @BASEBOARD_FAB2_LIB.BASEBOARD_FAB2(SCH_1):PAGE31
  C8G9    1      A CAP_0402-0.22UF,16V,10%,X7R,A3A    I93 @BASEBOARD_FAB2_LIB.BASEBOARD_FAB2(SCH_1):PAGE105

P3E_CPU0_PE2_SS_TXP<10> @BASEBOARD_FAB2_LIB.BASEBOARD_FAB2(SCH_1):P3E_CPU0_PE2_SS_TXP(10)
  U5D1  BY5 PE2_TX_DP<10> SKX_EXT_B_BGA1-IC,TBD   I106 @BASEBOARD_FAB2_LIB.BASEBOARD_FAB2(SCH_1):PAGE31
 C7G15    1      A CAP_0402-0.22UF,16V,10%,X7R,A3A    I45 @BASEBOARD_FAB2_LIB.BASEBOARD_FAB2(SCH_1):PAGE105

P3E_CPU0_PE2_SS_TXP<11> @BASEBOARD_FAB2_LIB.BASEBOARD_FAB2(SCH_1):P3E_CPU0_PE2_SS_TXP(11)
  U5D1  BV3 PE2_TX_DP<11> SKX_EXT_B_BGA1-IC,TBD   I106 @BASEBOARD_FAB2_LIB.BASEBOARD_FAB2(SCH_1):PAGE31
 C7G14    1      A CAP_0402-0.22UF,16V,10%,X7R,A3A    I28 @BASEBOARD_FAB2_LIB.BASEBOARD_FAB2(SCH_1):PAGE105

P3E_CPU0_PE2_SS_TXP<12> @BASEBOARD_FAB2_LIB.BASEBOARD_FAB2(SCH_1):P3E_CPU0_PE2_SS_TXP(12)
  U5D1  BR4 PE2_TX_DP<12> SKX_EXT_B_BGA1-IC,TBD   I106 @BASEBOARD_FAB2_LIB.BASEBOARD_FAB2(SCH_1):PAGE31
 C7G11    1      A CAP_0402-0.22UF,16V,10%,X7R,A3A    I27 @BASEBOARD_FAB2_LIB.BASEBOARD_FAB2(SCH_1):PAGE105

P3E_CPU0_PE2_SS_TXP<13> @BASEBOARD_FAB2_LIB.BASEBOARD_FAB2(SCH_1):P3E_CPU0_PE2_SS_TXP(13)
  U5D1  BN4 PE2_TX_DP<13> SKX_EXT_B_BGA1-IC,TBD   I106 @BASEBOARD_FAB2_LIB.BASEBOARD_FAB2(SCH_1):PAGE31
  C7G9    1      A CAP_0402-0.22UF,16V,10%,X7R,A3A    I21 @BASEBOARD_FAB2_LIB.BASEBOARD_FAB2(SCH_1):PAGE105

P3E_CPU0_PE2_SS_TXP<14> @BASEBOARD_FAB2_LIB.BASEBOARD_FAB2(SCH_1):P3E_CPU0_PE2_SS_TXP(14)
  U5D1  BM3 PE2_TX_DP<14> SKX_EXT_B_BGA1-IC,TBD   I106 @BASEBOARD_FAB2_LIB.BASEBOARD_FAB2(SCH_1):PAGE31
  C7G8    1      A CAP_0402-0.22UF,16V,10%,X7R,A3A    I22 @BASEBOARD_FAB2_LIB.BASEBOARD_FAB2(SCH_1):PAGE105

P3E_CPU0_PE2_SS_TXP<15> @BASEBOARD_FAB2_LIB.BASEBOARD_FAB2(SCH_1):P3E_CPU0_PE2_SS_TXP(15)
  U5D1  BK5 PE2_TX_DP<15> SKX_EXT_B_BGA1-IC,TBD   I106 @BASEBOARD_FAB2_LIB.BASEBOARD_FAB2(SCH_1):PAGE31
  C7G5    1      A CAP_0402-0.22UF,16V,10%,X7R,A3A    I20 @BASEBOARD_FAB2_LIB.BASEBOARD_FAB2(SCH_1):PAGE105

P3E_CPU0_PE2_SS_TXP<1> @BASEBOARD_FAB2_LIB.BASEBOARD_FAB2(SCH_1):P3E_CPU0_PE2_SS_TXP(1)
  U5D1  CU2 PE2_TX_DP<1> SKX_EXT_B_BGA1-IC,TBD   I106 @BASEBOARD_FAB2_LIB.BASEBOARD_FAB2(SCH_1):PAGE31
  C8G8    1      A CAP_0402-0.22UF,16V,10%,X7R,A3A    I76 @BASEBOARD_FAB2_LIB.BASEBOARD_FAB2(SCH_1):PAGE105

P3E_CPU0_PE2_SS_TXP<2> @BASEBOARD_FAB2_LIB.BASEBOARD_FAB2(SCH_1):P3E_CPU0_PE2_SS_TXP(2)
  U5D1  CR2 PE2_TX_DP<2> SKX_EXT_B_BGA1-IC,TBD   I106 @BASEBOARD_FAB2_LIB.BASEBOARD_FAB2(SCH_1):PAGE31
  C8G5    1      A CAP_0402-0.22UF,16V,10%,X7R,A3A    I75 @BASEBOARD_FAB2_LIB.BASEBOARD_FAB2(SCH_1):PAGE105

P3E_CPU0_PE2_SS_TXP<3> @BASEBOARD_FAB2_LIB.BASEBOARD_FAB2(SCH_1):P3E_CPU0_PE2_SS_TXP(3)
  U5D1  CP3 PE2_TX_DP<3> SKX_EXT_B_BGA1-IC,TBD   I106 @BASEBOARD_FAB2_LIB.BASEBOARD_FAB2(SCH_1):PAGE31
  C8G3    1      A CAP_0402-0.22UF,16V,10%,X7R,A3A    I71 @BASEBOARD_FAB2_LIB.BASEBOARD_FAB2(SCH_1):PAGE105

P3E_CPU0_PE2_SS_TXP<4> @BASEBOARD_FAB2_LIB.BASEBOARD_FAB2(SCH_1):P3E_CPU0_PE2_SS_TXP(4)
  U5D1  CK1 PE2_TX_DP<4> SKX_EXT_B_BGA1-IC,TBD   I106 @BASEBOARD_FAB2_LIB.BASEBOARD_FAB2(SCH_1):PAGE31
  C8G1    1      A CAP_0402-0.22UF,16V,10%,X7R,A3A    I70 @BASEBOARD_FAB2_LIB.BASEBOARD_FAB2(SCH_1):PAGE105

P3E_CPU0_PE2_SS_TXP<5> @BASEBOARD_FAB2_LIB.BASEBOARD_FAB2(SCH_1):P3E_CPU0_PE2_SS_TXP(5)
  U5D1  CK3 PE2_TX_DP<5> SKX_EXT_B_BGA1-IC,TBD   I106 @BASEBOARD_FAB2_LIB.BASEBOARD_FAB2(SCH_1):PAGE31
 C7G25    1      A CAP_0402-0.22UF,16V,10%,X7R,A3A    I69 @BASEBOARD_FAB2_LIB.BASEBOARD_FAB2(SCH_1):PAGE105

P3E_CPU0_PE2_SS_TXP<6> @BASEBOARD_FAB2_LIB.BASEBOARD_FAB2(SCH_1):P3E_CPU0_PE2_SS_TXP(6)
  U5D1  CE2 PE2_TX_DP<6> SKX_EXT_B_BGA1-IC,TBD   I106 @BASEBOARD_FAB2_LIB.BASEBOARD_FAB2(SCH_1):PAGE31
 C7G23    1      A CAP_0402-0.22UF,16V,10%,X7R,A3A    I52 @BASEBOARD_FAB2_LIB.BASEBOARD_FAB2(SCH_1):PAGE105

P3E_CPU0_PE2_SS_TXP<7> @BASEBOARD_FAB2_LIB.BASEBOARD_FAB2(SCH_1):P3E_CPU0_PE2_SS_TXP(7)
  U5D1  CE4 PE2_TX_DP<7> SKX_EXT_B_BGA1-IC,TBD   I106 @BASEBOARD_FAB2_LIB.BASEBOARD_FAB2(SCH_1):PAGE31
 C7G21    1      A CAP_0402-0.22UF,16V,10%,X7R,A3A    I51 @BASEBOARD_FAB2_LIB.BASEBOARD_FAB2(SCH_1):PAGE105

P3E_CPU0_PE2_SS_TXP<8> @BASEBOARD_FAB2_LIB.BASEBOARD_FAB2(SCH_1):P3E_CPU0_PE2_SS_TXP(8)
  U5D1  CD3 PE2_TX_DP<8> SKX_EXT_B_BGA1-IC,TBD   I106 @BASEBOARD_FAB2_LIB.BASEBOARD_FAB2(SCH_1):PAGE31
 C7G19    1      A CAP_0402-0.22UF,16V,10%,X7R,A3A    I46 @BASEBOARD_FAB2_LIB.BASEBOARD_FAB2(SCH_1):PAGE105

P3E_CPU0_PE2_SS_TXP<9> @BASEBOARD_FAB2_LIB.BASEBOARD_FAB2(SCH_1):P3E_CPU0_PE2_SS_TXP(9)
  U5D1  BY3 PE2_TX_DP<9> SKX_EXT_B_BGA1-IC,TBD   I106 @BASEBOARD_FAB2_LIB.BASEBOARD_FAB2(SCH_1):PAGE31
 C7G17    1      A CAP_0402-0.22UF,16V,10%,X7R,A3A    I44 @BASEBOARD_FAB2_LIB.BASEBOARD_FAB2(SCH_1):PAGE105

P3E_CPU0_PE3_OCP_RXN<0> @BASEBOARD_FAB2_LIB.BASEBOARD_FAB2(SCH_1):P3E_CPU0_PE3_OCP_RXN(0)
  U5D1 EA18 PE3_RX_DN<0> SKX_EXT_B_BGA1-IC,TBD    I89 @BASEBOARD_FAB2_LIB.BASEBOARD_FAB2(SCH_1):PAGE32
  J8E3   63   IO63 SCONN80_E67482007_SM-CONN,E674A   I119 @BASEBOARD_FAB2_LIB.BASEBOARD_FAB2(SCH_1):PAGE187

P3E_CPU0_PE3_OCP_RXN<10> @BASEBOARD_FAB2_LIB.BASEBOARD_FAB2(SCH_1):P3E_CPU0_PE3_OCP_RXN(10)
  U5D1 DG12 PE3_RX_DN<10> SKX_EXT_B_BGA1-IC,TBD    I89 @BASEBOARD_FAB2_LIB.BASEBOARD_FAB2(SCH_1):PAGE32
  J9B3  101  IO101 SCONN120_A28699018_SM-SCONN,A2A   I336 @BASEBOARD_FAB2_LIB.BASEBOARD_FAB2(SCH_1):PAGE186

P3E_CPU0_PE3_OCP_RXN<11> @BASEBOARD_FAB2_LIB.BASEBOARD_FAB2(SCH_1):P3E_CPU0_PE3_OCP_RXN(11)
  U5D1 DG10 PE3_RX_DN<11> SKX_EXT_B_BGA1-IC,TBD    I89 @BASEBOARD_FAB2_LIB.BASEBOARD_FAB2(SCH_1):PAGE32
  J9B3   93   IO93 SCONN120_A28699018_SM-SCONN,A2A   I336 @BASEBOARD_FAB2_LIB.BASEBOARD_FAB2(SCH_1):PAGE186

P3E_CPU0_PE3_OCP_RXN<12> @BASEBOARD_FAB2_LIB.BASEBOARD_FAB2(SCH_1):P3E_CPU0_PE3_OCP_RXN(12)
  U5D1 DD13 PE3_RX_DN<12> SKX_EXT_B_BGA1-IC,TBD    I89 @BASEBOARD_FAB2_LIB.BASEBOARD_FAB2(SCH_1):PAGE32
  J9B3   85   IO85 SCONN120_A28699018_SM-SCONN,A2A   I336 @BASEBOARD_FAB2_LIB.BASEBOARD_FAB2(SCH_1):PAGE186

P3E_CPU0_PE3_OCP_RXN<13> @BASEBOARD_FAB2_LIB.BASEBOARD_FAB2(SCH_1):P3E_CPU0_PE3_OCP_RXN(13)
  U5D1 DB11 PE3_RX_DN<13> SKX_EXT_B_BGA1-IC,TBD    I89 @BASEBOARD_FAB2_LIB.BASEBOARD_FAB2(SCH_1):PAGE32
  J9B3   77   IO77 SCONN120_A28699018_SM-SCONN,A2A   I336 @BASEBOARD_FAB2_LIB.BASEBOARD_FAB2(SCH_1):PAGE186

P3E_CPU0_PE3_OCP_RXN<14> @BASEBOARD_FAB2_LIB.BASEBOARD_FAB2(SCH_1):P3E_CPU0_PE3_OCP_RXN(14)
  U5D1 CY11 PE3_RX_DN<14> SKX_EXT_B_BGA1-IC,TBD    I89 @BASEBOARD_FAB2_LIB.BASEBOARD_FAB2(SCH_1):PAGE32
  J9B3   69   IO69 SCONN120_A28699018_SM-SCONN,A2A   I336 @BASEBOARD_FAB2_LIB.BASEBOARD_FAB2(SCH_1):PAGE186

P3E_CPU0_PE3_OCP_RXN<15> @BASEBOARD_FAB2_LIB.BASEBOARD_FAB2(SCH_1):P3E_CPU0_PE3_OCP_RXN(15)
  U5D1  CV9 PE3_RX_DN<15> SKX_EXT_B_BGA1-IC,TBD    I89 @BASEBOARD_FAB2_LIB.BASEBOARD_FAB2(SCH_1):PAGE32
  J9B3   61   IO61 SCONN120_A28699018_SM-SCONN,A2A   I336 @BASEBOARD_FAB2_LIB.BASEBOARD_FAB2(SCH_1):PAGE186

P3E_CPU0_PE3_OCP_RXN<1> @BASEBOARD_FAB2_LIB.BASEBOARD_FAB2(SCH_1):P3E_CPU0_PE3_OCP_RXN(1)
  U5D1 DW18 PE3_RX_DN<1> SKX_EXT_B_BGA1-IC,TBD    I89 @BASEBOARD_FAB2_LIB.BASEBOARD_FAB2(SCH_1):PAGE32
  J8E3   55   IO55 SCONN80_E67482007_SM-CONN,E674A   I119 @BASEBOARD_FAB2_LIB.BASEBOARD_FAB2(SCH_1):PAGE187

P3E_CPU0_PE3_OCP_RXN<2> @BASEBOARD_FAB2_LIB.BASEBOARD_FAB2(SCH_1):P3E_CPU0_PE3_OCP_RXN(2)
  U5D1 DW16 PE3_RX_DN<2> SKX_EXT_B_BGA1-IC,TBD    I89 @BASEBOARD_FAB2_LIB.BASEBOARD_FAB2(SCH_1):PAGE32
  J8E3   47   IO47 SCONN80_E67482007_SM-CONN,E674A   I119 @BASEBOARD_FAB2_LIB.BASEBOARD_FAB2(SCH_1):PAGE187

P3E_CPU0_PE3_OCP_RXN<3> @BASEBOARD_FAB2_LIB.BASEBOARD_FAB2(SCH_1):P3E_CPU0_PE3_OCP_RXN(3)
  U5D1 DT19 PE3_RX_DN<3> SKX_EXT_B_BGA1-IC,TBD    I89 @BASEBOARD_FAB2_LIB.BASEBOARD_FAB2(SCH_1):PAGE32
  J8E3   39   IO39 SCONN80_E67482007_SM-CONN,E674A   I119 @BASEBOARD_FAB2_LIB.BASEBOARD_FAB2(SCH_1):PAGE187

P3E_CPU0_PE3_OCP_RXN<4> @BASEBOARD_FAB2_LIB.BASEBOARD_FAB2(SCH_1):P3E_CPU0_PE3_OCP_RXN(4)
  U5D1 DR16 PE3_RX_DN<4> SKX_EXT_B_BGA1-IC,TBD    I89 @BASEBOARD_FAB2_LIB.BASEBOARD_FAB2(SCH_1):PAGE32
  J8E3   29   IO29 SCONN80_E67482007_SM-CONN,E674A   I119 @BASEBOARD_FAB2_LIB.BASEBOARD_FAB2(SCH_1):PAGE187

P3E_CPU0_PE3_OCP_RXN<5> @BASEBOARD_FAB2_LIB.BASEBOARD_FAB2(SCH_1):P3E_CPU0_PE3_OCP_RXN(5)
  U5D1 DR14 PE3_RX_DN<5> SKX_EXT_B_BGA1-IC,TBD    I89 @BASEBOARD_FAB2_LIB.BASEBOARD_FAB2(SCH_1):PAGE32
  J8E3   21   IO21 SCONN80_E67482007_SM-CONN,E674A   I119 @BASEBOARD_FAB2_LIB.BASEBOARD_FAB2(SCH_1):PAGE187

P3E_CPU0_PE3_OCP_RXN<6> @BASEBOARD_FAB2_LIB.BASEBOARD_FAB2(SCH_1):P3E_CPU0_PE3_OCP_RXN(6)
  U5D1 DN14 PE3_RX_DN<6> SKX_EXT_B_BGA1-IC,TBD    I89 @BASEBOARD_FAB2_LIB.BASEBOARD_FAB2(SCH_1):PAGE32
  J8E3   13   IO13 SCONN80_E67482007_SM-CONN,E674A   I119 @BASEBOARD_FAB2_LIB.BASEBOARD_FAB2(SCH_1):PAGE187

P3E_CPU0_PE3_OCP_RXN<7> @BASEBOARD_FAB2_LIB.BASEBOARD_FAB2(SCH_1):P3E_CPU0_PE3_OCP_RXN(7)
  U5D1 DL14 PE3_RX_DN<7> SKX_EXT_B_BGA1-IC,TBD    I89 @BASEBOARD_FAB2_LIB.BASEBOARD_FAB2(SCH_1):PAGE32
  J8E3    7    IO7 SCONN80_E67482007_SM-CONN,E674A   I119 @BASEBOARD_FAB2_LIB.BASEBOARD_FAB2(SCH_1):PAGE187

P3E_CPU0_PE3_OCP_RXN<8> @BASEBOARD_FAB2_LIB.BASEBOARD_FAB2(SCH_1):P3E_CPU0_PE3_OCP_RXN(8)
  U5D1 DL12 PE3_RX_DN<8> SKX_EXT_B_BGA1-IC,TBD    I89 @BASEBOARD_FAB2_LIB.BASEBOARD_FAB2(SCH_1):PAGE32
  J9B3  117  IO117 SCONN120_A28699018_SM-SCONN,A2A   I336 @BASEBOARD_FAB2_LIB.BASEBOARD_FAB2(SCH_1):PAGE186

P3E_CPU0_PE3_OCP_RXN<9> @BASEBOARD_FAB2_LIB.BASEBOARD_FAB2(SCH_1):P3E_CPU0_PE3_OCP_RXN(9)
  U5D1 DJ12 PE3_RX_DN<9> SKX_EXT_B_BGA1-IC,TBD    I89 @BASEBOARD_FAB2_LIB.BASEBOARD_FAB2(SCH_1):PAGE32
  J9B3  109  IO109 SCONN120_A28699018_SM-SCONN,A2A   I336 @BASEBOARD_FAB2_LIB.BASEBOARD_FAB2(SCH_1):PAGE186

P3E_CPU0_PE3_OCP_RXP<0> @BASEBOARD_FAB2_LIB.BASEBOARD_FAB2(SCH_1):P3E_CPU0_PE3_OCP_RXP(0)
  U5D1 DY17 PE3_RX_DP<0> SKX_EXT_B_BGA1-IC,TBD    I89 @BASEBOARD_FAB2_LIB.BASEBOARD_FAB2(SCH_1):PAGE32
  J8E3   61   IO61 SCONN80_E67482007_SM-CONN,E674A   I119 @BASEBOARD_FAB2_LIB.BASEBOARD_FAB2(SCH_1):PAGE187

P3E_CPU0_PE3_OCP_RXP<10> @BASEBOARD_FAB2_LIB.BASEBOARD_FAB2(SCH_1):P3E_CPU0_PE3_OCP_RXP(10)
  U5D1 DE12 PE3_RX_DP<10> SKX_EXT_B_BGA1-IC,TBD    I89 @BASEBOARD_FAB2_LIB.BASEBOARD_FAB2(SCH_1):PAGE32
  J9B3   99   IO99 SCONN120_A28699018_SM-SCONN,A2A   I336 @BASEBOARD_FAB2_LIB.BASEBOARD_FAB2(SCH_1):PAGE186

P3E_CPU0_PE3_OCP_RXP<11> @BASEBOARD_FAB2_LIB.BASEBOARD_FAB2(SCH_1):P3E_CPU0_PE3_OCP_RXP(11)
  U5D1 DF11 PE3_RX_DP<11> SKX_EXT_B_BGA1-IC,TBD    I89 @BASEBOARD_FAB2_LIB.BASEBOARD_FAB2(SCH_1):PAGE32
  J9B3   91   IO91 SCONN120_A28699018_SM-SCONN,A2A   I336 @BASEBOARD_FAB2_LIB.BASEBOARD_FAB2(SCH_1):PAGE186

P3E_CPU0_PE3_OCP_RXP<12> @BASEBOARD_FAB2_LIB.BASEBOARD_FAB2(SCH_1):P3E_CPU0_PE3_OCP_RXP(12)
  U5D1 DC12 PE3_RX_DP<12> SKX_EXT_B_BGA1-IC,TBD    I89 @BASEBOARD_FAB2_LIB.BASEBOARD_FAB2(SCH_1):PAGE32
  J9B3   83   IO83 SCONN120_A28699018_SM-SCONN,A2A   I336 @BASEBOARD_FAB2_LIB.BASEBOARD_FAB2(SCH_1):PAGE186

P3E_CPU0_PE3_OCP_RXP<13> @BASEBOARD_FAB2_LIB.BASEBOARD_FAB2(SCH_1):P3E_CPU0_PE3_OCP_RXP(13)
  U5D1 DA12 PE3_RX_DP<13> SKX_EXT_B_BGA1-IC,TBD    I89 @BASEBOARD_FAB2_LIB.BASEBOARD_FAB2(SCH_1):PAGE32
  J9B3   75   IO75 SCONN120_A28699018_SM-SCONN,A2A   I336 @BASEBOARD_FAB2_LIB.BASEBOARD_FAB2(SCH_1):PAGE186

P3E_CPU0_PE3_OCP_RXP<14> @BASEBOARD_FAB2_LIB.BASEBOARD_FAB2(SCH_1):P3E_CPU0_PE3_OCP_RXP(14)
  U5D1 CW10 PE3_RX_DP<14> SKX_EXT_B_BGA1-IC,TBD    I89 @BASEBOARD_FAB2_LIB.BASEBOARD_FAB2(SCH_1):PAGE32
  J9B3   67   IO67 SCONN120_A28699018_SM-SCONN,A2A   I336 @BASEBOARD_FAB2_LIB.BASEBOARD_FAB2(SCH_1):PAGE186

P3E_CPU0_PE3_OCP_RXP<15> @BASEBOARD_FAB2_LIB.BASEBOARD_FAB2(SCH_1):P3E_CPU0_PE3_OCP_RXP(15)
  U5D1 CU10 PE3_RX_DP<15> SKX_EXT_B_BGA1-IC,TBD    I89 @BASEBOARD_FAB2_LIB.BASEBOARD_FAB2(SCH_1):PAGE32
  J9B3   59   IO59 SCONN120_A28699018_SM-SCONN,A2A   I336 @BASEBOARD_FAB2_LIB.BASEBOARD_FAB2(SCH_1):PAGE186

P3E_CPU0_PE3_OCP_RXP<1> @BASEBOARD_FAB2_LIB.BASEBOARD_FAB2(SCH_1):P3E_CPU0_PE3_OCP_RXP(1)
  U5D1 DU18 PE3_RX_DP<1> SKX_EXT_B_BGA1-IC,TBD    I89 @BASEBOARD_FAB2_LIB.BASEBOARD_FAB2(SCH_1):PAGE32
  J8E3   53   IO53 SCONN80_E67482007_SM-CONN,E674A   I119 @BASEBOARD_FAB2_LIB.BASEBOARD_FAB2(SCH_1):PAGE187

P3E_CPU0_PE3_OCP_RXP<2> @BASEBOARD_FAB2_LIB.BASEBOARD_FAB2(SCH_1):P3E_CPU0_PE3_OCP_RXP(2)
  U5D1 DV17 PE3_RX_DP<2> SKX_EXT_B_BGA1-IC,TBD    I89 @BASEBOARD_FAB2_LIB.BASEBOARD_FAB2(SCH_1):PAGE32
  J8E3   45   IO45 SCONN80_E67482007_SM-CONN,E674A   I119 @BASEBOARD_FAB2_LIB.BASEBOARD_FAB2(SCH_1):PAGE187

P3E_CPU0_PE3_OCP_RXP<3> @BASEBOARD_FAB2_LIB.BASEBOARD_FAB2(SCH_1):P3E_CPU0_PE3_OCP_RXP(3)
  U5D1 DR18 PE3_RX_DP<3> SKX_EXT_B_BGA1-IC,TBD    I89 @BASEBOARD_FAB2_LIB.BASEBOARD_FAB2(SCH_1):PAGE32
  J8E3   37   IO37 SCONN80_E67482007_SM-CONN,E674A   I119 @BASEBOARD_FAB2_LIB.BASEBOARD_FAB2(SCH_1):PAGE187

P3E_CPU0_PE3_OCP_RXP<4> @BASEBOARD_FAB2_LIB.BASEBOARD_FAB2(SCH_1):P3E_CPU0_PE3_OCP_RXP(4)
  U5D1 DN16 PE3_RX_DP<4> SKX_EXT_B_BGA1-IC,TBD    I89 @BASEBOARD_FAB2_LIB.BASEBOARD_FAB2(SCH_1):PAGE32
  J8E3   31   IO31 SCONN80_E67482007_SM-CONN,E674A   I119 @BASEBOARD_FAB2_LIB.BASEBOARD_FAB2(SCH_1):PAGE187

P3E_CPU0_PE3_OCP_RXP<5> @BASEBOARD_FAB2_LIB.BASEBOARD_FAB2(SCH_1):P3E_CPU0_PE3_OCP_RXP(5)
  U5D1 DP15 PE3_RX_DP<5> SKX_EXT_B_BGA1-IC,TBD    I89 @BASEBOARD_FAB2_LIB.BASEBOARD_FAB2(SCH_1):PAGE32
  J8E3   23   IO23 SCONN80_E67482007_SM-CONN,E674A   I119 @BASEBOARD_FAB2_LIB.BASEBOARD_FAB2(SCH_1):PAGE187

P3E_CPU0_PE3_OCP_RXP<6> @BASEBOARD_FAB2_LIB.BASEBOARD_FAB2(SCH_1):P3E_CPU0_PE3_OCP_RXP(6)
  U5D1 DM13 PE3_RX_DP<6> SKX_EXT_B_BGA1-IC,TBD    I89 @BASEBOARD_FAB2_LIB.BASEBOARD_FAB2(SCH_1):PAGE32
  J8E3   15   IO15 SCONN80_E67482007_SM-CONN,E674A   I119 @BASEBOARD_FAB2_LIB.BASEBOARD_FAB2(SCH_1):PAGE187

P3E_CPU0_PE3_OCP_RXP<7> @BASEBOARD_FAB2_LIB.BASEBOARD_FAB2(SCH_1):P3E_CPU0_PE3_OCP_RXP(7)
  U5D1 DJ14 PE3_RX_DP<7> SKX_EXT_B_BGA1-IC,TBD    I89 @BASEBOARD_FAB2_LIB.BASEBOARD_FAB2(SCH_1):PAGE32
  J8E3    5    IO5 SCONN80_E67482007_SM-CONN,E674A   I119 @BASEBOARD_FAB2_LIB.BASEBOARD_FAB2(SCH_1):PAGE187

P3E_CPU0_PE3_OCP_RXP<8> @BASEBOARD_FAB2_LIB.BASEBOARD_FAB2(SCH_1):P3E_CPU0_PE3_OCP_RXP(8)
  U5D1 DK13 PE3_RX_DP<8> SKX_EXT_B_BGA1-IC,TBD    I89 @BASEBOARD_FAB2_LIB.BASEBOARD_FAB2(SCH_1):PAGE32
  J9B3  115  IO115 SCONN120_A28699018_SM-SCONN,A2A   I336 @BASEBOARD_FAB2_LIB.BASEBOARD_FAB2(SCH_1):PAGE186

P3E_CPU0_PE3_OCP_RXP<9> @BASEBOARD_FAB2_LIB.BASEBOARD_FAB2(SCH_1):P3E_CPU0_PE3_OCP_RXP(9)
  U5D1 DH11 PE3_RX_DP<9> SKX_EXT_B_BGA1-IC,TBD    I89 @BASEBOARD_FAB2_LIB.BASEBOARD_FAB2(SCH_1):PAGE32
  J9B3  107  IO107 SCONN120_A28699018_SM-SCONN,A2A   I336 @BASEBOARD_FAB2_LIB.BASEBOARD_FAB2(SCH_1):PAGE186

P3E_CPU0_PE3_OCP_TXN<0> @BASEBOARD_FAB2_LIB.BASEBOARD_FAB2(SCH_1):P3E_CPU0_PE3_OCP_TXN(0)
  U5D1 EE14 PE3_TX_DN<0> SKX_EXT_B_BGA1-IC,TBD    I89 @BASEBOARD_FAB2_LIB.BASEBOARD_FAB2(SCH_1):PAGE32
  C1R1    1      A CAP_0402-0.22UF,16V,10%,X7R,A3A    I29 @BASEBOARD_FAB2_LIB.BASEBOARD_FAB2(SCH_1):PAGE106

P3E_CPU0_PE3_OCP_TXN<10> @BASEBOARD_FAB2_LIB.BASEBOARD_FAB2(SCH_1):P3E_CPU0_PE3_OCP_TXN(10)
  U5D1  DL6 PE3_TX_DN<10> SKX_EXT_B_BGA1-IC,TBD    I89 @BASEBOARD_FAB2_LIB.BASEBOARD_FAB2(SCH_1):PAGE32
 C1M17    1      A CAP_0402-0.22UF,16V,10%,X7R,A3A    I92 @BASEBOARD_FAB2_LIB.BASEBOARD_FAB2(SCH_1):PAGE106

P3E_CPU0_PE3_OCP_TXN<11> @BASEBOARD_FAB2_LIB.BASEBOARD_FAB2(SCH_1):P3E_CPU0_PE3_OCP_TXN(11)
  U5D1  DJ4 PE3_TX_DN<11> SKX_EXT_B_BGA1-IC,TBD    I89 @BASEBOARD_FAB2_LIB.BASEBOARD_FAB2(SCH_1):PAGE32
 C1M15    1      A CAP_0402-0.22UF,16V,10%,X7R,A3A    I95 @BASEBOARD_FAB2_LIB.BASEBOARD_FAB2(SCH_1):PAGE106

P3E_CPU0_PE3_OCP_TXN<12> @BASEBOARD_FAB2_LIB.BASEBOARD_FAB2(SCH_1):P3E_CPU0_PE3_OCP_TXN(12)
  U5D1  DJ6 PE3_TX_DN<12> SKX_EXT_B_BGA1-IC,TBD    I89 @BASEBOARD_FAB2_LIB.BASEBOARD_FAB2(SCH_1):PAGE32
 C1M13    1      A CAP_0402-0.22UF,16V,10%,X7R,A3A   I111 @BASEBOARD_FAB2_LIB.BASEBOARD_FAB2(SCH_1):PAGE106

P3E_CPU0_PE3_OCP_TXN<13> @BASEBOARD_FAB2_LIB.BASEBOARD_FAB2(SCH_1):P3E_CPU0_PE3_OCP_TXN(13)
  U5D1  DD5 PE3_TX_DN<13> SKX_EXT_B_BGA1-IC,TBD    I89 @BASEBOARD_FAB2_LIB.BASEBOARD_FAB2(SCH_1):PAGE32
 C1M11    1      A CAP_0402-0.22UF,16V,10%,X7R,A3A   I117 @BASEBOARD_FAB2_LIB.BASEBOARD_FAB2(SCH_1):PAGE106

P3E_CPU0_PE3_OCP_TXN<14> @BASEBOARD_FAB2_LIB.BASEBOARD_FAB2(SCH_1):P3E_CPU0_PE3_OCP_TXN(14)
  U5D1  DB5 PE3_TX_DN<14> SKX_EXT_B_BGA1-IC,TBD    I89 @BASEBOARD_FAB2_LIB.BASEBOARD_FAB2(SCH_1):PAGE32
  C1M9    1      A CAP_0402-0.22UF,16V,10%,X7R,A3A   I114 @BASEBOARD_FAB2_LIB.BASEBOARD_FAB2(SCH_1):PAGE106

P3E_CPU0_PE3_OCP_TXN<15> @BASEBOARD_FAB2_LIB.BASEBOARD_FAB2(SCH_1):P3E_CPU0_PE3_OCP_TXN(15)
  U5D1  CY5 PE3_TX_DN<15> SKX_EXT_B_BGA1-IC,TBD    I89 @BASEBOARD_FAB2_LIB.BASEBOARD_FAB2(SCH_1):PAGE32
  C1M7    1      A CAP_0402-0.22UF,16V,10%,X7R,A3A   I122 @BASEBOARD_FAB2_LIB.BASEBOARD_FAB2(SCH_1):PAGE106

P3E_CPU0_PE3_OCP_TXN<1> @BASEBOARD_FAB2_LIB.BASEBOARD_FAB2(SCH_1):P3E_CPU0_PE3_OCP_TXN(1)
  U5D1 EE12 PE3_TX_DN<1> SKX_EXT_B_BGA1-IC,TBD    I89 @BASEBOARD_FAB2_LIB.BASEBOARD_FAB2(SCH_1):PAGE32
  C1R3    1      A CAP_0402-0.22UF,16V,10%,X7R,A3A    I37 @BASEBOARD_FAB2_LIB.BASEBOARD_FAB2(SCH_1):PAGE106

P3E_CPU0_PE3_OCP_TXN<2> @BASEBOARD_FAB2_LIB.BASEBOARD_FAB2(SCH_1):P3E_CPU0_PE3_OCP_TXN(2)
  U5D1 EC12 PE3_TX_DN<2> SKX_EXT_B_BGA1-IC,TBD    I89 @BASEBOARD_FAB2_LIB.BASEBOARD_FAB2(SCH_1):PAGE32
  C1R5    1      A CAP_0402-0.22UF,16V,10%,X7R,A3A    I59 @BASEBOARD_FAB2_LIB.BASEBOARD_FAB2(SCH_1):PAGE106

P3E_CPU0_PE3_OCP_TXN<3> @BASEBOARD_FAB2_LIB.BASEBOARD_FAB2(SCH_1):P3E_CPU0_PE3_OCP_TXN(3)
  U5D1 DY11 PE3_TX_DN<3> SKX_EXT_B_BGA1-IC,TBD    I89 @BASEBOARD_FAB2_LIB.BASEBOARD_FAB2(SCH_1):PAGE32
  C1R7    1      A CAP_0402-0.22UF,16V,10%,X7R,A3A    I70 @BASEBOARD_FAB2_LIB.BASEBOARD_FAB2(SCH_1):PAGE106

P3E_CPU0_PE3_OCP_TXN<4> @BASEBOARD_FAB2_LIB.BASEBOARD_FAB2(SCH_1):P3E_CPU0_PE3_OCP_TXN(4)
  U5D1  EB9 PE3_TX_DN<4> SKX_EXT_B_BGA1-IC,TBD    I89 @BASEBOARD_FAB2_LIB.BASEBOARD_FAB2(SCH_1):PAGE32
  C1R9    1      A CAP_0402-0.22UF,16V,10%,X7R,A3A   I134 @BASEBOARD_FAB2_LIB.BASEBOARD_FAB2(SCH_1):PAGE106

P3E_CPU0_PE3_OCP_TXN<5> @BASEBOARD_FAB2_LIB.BASEBOARD_FAB2(SCH_1):P3E_CPU0_PE3_OCP_TXN(5)
  U5D1 DW10 PE3_TX_DN<5> SKX_EXT_B_BGA1-IC,TBD    I89 @BASEBOARD_FAB2_LIB.BASEBOARD_FAB2(SCH_1):PAGE32
 C2R13    1      A CAP_0402-0.22UF,16V,10%,X7R,A3A   I137 @BASEBOARD_FAB2_LIB.BASEBOARD_FAB2(SCH_1):PAGE106

P3E_CPU0_PE3_OCP_TXN<6> @BASEBOARD_FAB2_LIB.BASEBOARD_FAB2(SCH_1):P3E_CPU0_PE3_OCP_TXN(6)
  U5D1  DU8 PE3_TX_DN<6> SKX_EXT_B_BGA1-IC,TBD    I89 @BASEBOARD_FAB2_LIB.BASEBOARD_FAB2(SCH_1):PAGE32
  C2R7    1      A CAP_0402-0.22UF,16V,10%,X7R,A3A   I123 @BASEBOARD_FAB2_LIB.BASEBOARD_FAB2(SCH_1):PAGE106

P3E_CPU0_PE3_OCP_TXN<7> @BASEBOARD_FAB2_LIB.BASEBOARD_FAB2(SCH_1):P3E_CPU0_PE3_OCP_TXN(7)
  U5D1  DR8 PE3_TX_DN<7> SKX_EXT_B_BGA1-IC,TBD    I89 @BASEBOARD_FAB2_LIB.BASEBOARD_FAB2(SCH_1):PAGE32
  C2R9    1      A CAP_0402-0.22UF,16V,10%,X7R,A3A   I147 @BASEBOARD_FAB2_LIB.BASEBOARD_FAB2(SCH_1):PAGE106

P3E_CPU0_PE3_OCP_TXN<8> @BASEBOARD_FAB2_LIB.BASEBOARD_FAB2(SCH_1):P3E_CPU0_PE3_OCP_TXN(8)
  U5D1  DM7 PE3_TX_DN<8> SKX_EXT_B_BGA1-IC,TBD    I89 @BASEBOARD_FAB2_LIB.BASEBOARD_FAB2(SCH_1):PAGE32
 C2M15    1      A CAP_0402-0.22UF,16V,10%,X7R,A3A    I86 @BASEBOARD_FAB2_LIB.BASEBOARD_FAB2(SCH_1):PAGE106

P3E_CPU0_PE3_OCP_TXN<9> @BASEBOARD_FAB2_LIB.BASEBOARD_FAB2(SCH_1):P3E_CPU0_PE3_OCP_TXN(9)
  U5D1  DP5 PE3_TX_DN<9> SKX_EXT_B_BGA1-IC,TBD    I89 @BASEBOARD_FAB2_LIB.BASEBOARD_FAB2(SCH_1):PAGE32
 C1M19    1      A CAP_0402-0.22UF,16V,10%,X7R,A3A    I90 @BASEBOARD_FAB2_LIB.BASEBOARD_FAB2(SCH_1):PAGE106

P3E_CPU0_PE3_OCP_TXP<0> @BASEBOARD_FAB2_LIB.BASEBOARD_FAB2(SCH_1):P3E_CPU0_PE3_OCP_TXP(0)
  U5D1 EC14 PE3_TX_DP<0> SKX_EXT_B_BGA1-IC,TBD    I89 @BASEBOARD_FAB2_LIB.BASEBOARD_FAB2(SCH_1):PAGE32
  C1R2    1      A CAP_0402-0.22UF,16V,10%,X7R,A3A    I10 @BASEBOARD_FAB2_LIB.BASEBOARD_FAB2(SCH_1):PAGE106

P3E_CPU0_PE3_OCP_TXP<10> @BASEBOARD_FAB2_LIB.BASEBOARD_FAB2(SCH_1):P3E_CPU0_PE3_OCP_TXP(10)
  U5D1  DK5 PE3_TX_DP<10> SKX_EXT_B_BGA1-IC,TBD    I89 @BASEBOARD_FAB2_LIB.BASEBOARD_FAB2(SCH_1):PAGE32
 C1M16    1      A CAP_0402-0.22UF,16V,10%,X7R,A3A    I82 @BASEBOARD_FAB2_LIB.BASEBOARD_FAB2(SCH_1):PAGE106

P3E_CPU0_PE3_OCP_TXP<11> @BASEBOARD_FAB2_LIB.BASEBOARD_FAB2(SCH_1):P3E_CPU0_PE3_OCP_TXP(11)
  U5D1  DH5 PE3_TX_DP<11> SKX_EXT_B_BGA1-IC,TBD    I89 @BASEBOARD_FAB2_LIB.BASEBOARD_FAB2(SCH_1):PAGE32
 C1M14    1      A CAP_0402-0.22UF,16V,10%,X7R,A3A    I85 @BASEBOARD_FAB2_LIB.BASEBOARD_FAB2(SCH_1):PAGE106

P3E_CPU0_PE3_OCP_TXP<12> @BASEBOARD_FAB2_LIB.BASEBOARD_FAB2(SCH_1):P3E_CPU0_PE3_OCP_TXP(12)
  U5D1  DG6 PE3_TX_DP<12> SKX_EXT_B_BGA1-IC,TBD    I89 @BASEBOARD_FAB2_LIB.BASEBOARD_FAB2(SCH_1):PAGE32
 C1M12    1      A CAP_0402-0.22UF,16V,10%,X7R,A3A   I100 @BASEBOARD_FAB2_LIB.BASEBOARD_FAB2(SCH_1):PAGE106

P3E_CPU0_PE3_OCP_TXP<13> @BASEBOARD_FAB2_LIB.BASEBOARD_FAB2(SCH_1):P3E_CPU0_PE3_OCP_TXP(13)
  U5D1  DC6 PE3_TX_DP<13> SKX_EXT_B_BGA1-IC,TBD    I89 @BASEBOARD_FAB2_LIB.BASEBOARD_FAB2(SCH_1):PAGE32
 C1M10    1      A CAP_0402-0.22UF,16V,10%,X7R,A3A   I102 @BASEBOARD_FAB2_LIB.BASEBOARD_FAB2(SCH_1):PAGE106

P3E_CPU0_PE3_OCP_TXP<14> @BASEBOARD_FAB2_LIB.BASEBOARD_FAB2(SCH_1):P3E_CPU0_PE3_OCP_TXP(14)
  U5D1  DA4 PE3_TX_DP<14> SKX_EXT_B_BGA1-IC,TBD    I89 @BASEBOARD_FAB2_LIB.BASEBOARD_FAB2(SCH_1):PAGE32
  C1M8    1      A CAP_0402-0.22UF,16V,10%,X7R,A3A   I105 @BASEBOARD_FAB2_LIB.BASEBOARD_FAB2(SCH_1):PAGE106

P3E_CPU0_PE3_OCP_TXP<15> @BASEBOARD_FAB2_LIB.BASEBOARD_FAB2(SCH_1):P3E_CPU0_PE3_OCP_TXP(15)
  U5D1  CV5 PE3_TX_DP<15> SKX_EXT_B_BGA1-IC,TBD    I89 @BASEBOARD_FAB2_LIB.BASEBOARD_FAB2(SCH_1):PAGE32
  C1M6    1      A CAP_0402-0.22UF,16V,10%,X7R,A3A   I109 @BASEBOARD_FAB2_LIB.BASEBOARD_FAB2(SCH_1):PAGE106

P3E_CPU0_PE3_OCP_TXP<1> @BASEBOARD_FAB2_LIB.BASEBOARD_FAB2(SCH_1):P3E_CPU0_PE3_OCP_TXP(1)
  U5D1 ED13 PE3_TX_DP<1> SKX_EXT_B_BGA1-IC,TBD    I89 @BASEBOARD_FAB2_LIB.BASEBOARD_FAB2(SCH_1):PAGE32
  C1R4    1      A CAP_0402-0.22UF,16V,10%,X7R,A3A    I26 @BASEBOARD_FAB2_LIB.BASEBOARD_FAB2(SCH_1):PAGE106

P3E_CPU0_PE3_OCP_TXP<2> @BASEBOARD_FAB2_LIB.BASEBOARD_FAB2(SCH_1):P3E_CPU0_PE3_OCP_TXP(2)
  U5D1 EB11 PE3_TX_DP<2> SKX_EXT_B_BGA1-IC,TBD    I89 @BASEBOARD_FAB2_LIB.BASEBOARD_FAB2(SCH_1):PAGE32
  C1R6    1      A CAP_0402-0.22UF,16V,10%,X7R,A3A    I40 @BASEBOARD_FAB2_LIB.BASEBOARD_FAB2(SCH_1):PAGE106

P3E_CPU0_PE3_OCP_TXP<3> @BASEBOARD_FAB2_LIB.BASEBOARD_FAB2(SCH_1):P3E_CPU0_PE3_OCP_TXP(3)
  U5D1 EA10 PE3_TX_DP<3> SKX_EXT_B_BGA1-IC,TBD    I89 @BASEBOARD_FAB2_LIB.BASEBOARD_FAB2(SCH_1):PAGE32
  C1R8    1      A CAP_0402-0.22UF,16V,10%,X7R,A3A    I55 @BASEBOARD_FAB2_LIB.BASEBOARD_FAB2(SCH_1):PAGE106

P3E_CPU0_PE3_OCP_TXP<4> @BASEBOARD_FAB2_LIB.BASEBOARD_FAB2(SCH_1):P3E_CPU0_PE3_OCP_TXP(4)
  U5D1  DY9 PE3_TX_DP<4> SKX_EXT_B_BGA1-IC,TBD    I89 @BASEBOARD_FAB2_LIB.BASEBOARD_FAB2(SCH_1):PAGE32
 C1R10    1      A CAP_0402-0.22UF,16V,10%,X7R,A3A   I128 @BASEBOARD_FAB2_LIB.BASEBOARD_FAB2(SCH_1):PAGE106

P3E_CPU0_PE3_OCP_TXP<5> @BASEBOARD_FAB2_LIB.BASEBOARD_FAB2(SCH_1):P3E_CPU0_PE3_OCP_TXP(5)
  U5D1  DV9 PE3_TX_DP<5> SKX_EXT_B_BGA1-IC,TBD    I89 @BASEBOARD_FAB2_LIB.BASEBOARD_FAB2(SCH_1):PAGE32
 C2R14    1      A CAP_0402-0.22UF,16V,10%,X7R,A3A   I130 @BASEBOARD_FAB2_LIB.BASEBOARD_FAB2(SCH_1):PAGE106

P3E_CPU0_PE3_OCP_TXP<6> @BASEBOARD_FAB2_LIB.BASEBOARD_FAB2(SCH_1):P3E_CPU0_PE3_OCP_TXP(6)
  U5D1  DT9 PE3_TX_DP<6> SKX_EXT_B_BGA1-IC,TBD    I89 @BASEBOARD_FAB2_LIB.BASEBOARD_FAB2(SCH_1):PAGE32
  C2R8    1      A CAP_0402-0.22UF,16V,10%,X7R,A3A   I141 @BASEBOARD_FAB2_LIB.BASEBOARD_FAB2(SCH_1):PAGE106

P3E_CPU0_PE3_OCP_TXP<7> @BASEBOARD_FAB2_LIB.BASEBOARD_FAB2(SCH_1):P3E_CPU0_PE3_OCP_TXP(7)
  U5D1  DP7 PE3_TX_DP<7> SKX_EXT_B_BGA1-IC,TBD    I89 @BASEBOARD_FAB2_LIB.BASEBOARD_FAB2(SCH_1):PAGE32
 C2R10    1      A CAP_0402-0.22UF,16V,10%,X7R,A3A   I142 @BASEBOARD_FAB2_LIB.BASEBOARD_FAB2(SCH_1):PAGE106

P3E_CPU0_PE3_OCP_TXP<8> @BASEBOARD_FAB2_LIB.BASEBOARD_FAB2(SCH_1):P3E_CPU0_PE3_OCP_TXP(8)
  U5D1  DN6 PE3_TX_DP<8> SKX_EXT_B_BGA1-IC,TBD    I89 @BASEBOARD_FAB2_LIB.BASEBOARD_FAB2(SCH_1):PAGE32
 C2M14    1      A CAP_0402-0.22UF,16V,10%,X7R,A3A    I76 @BASEBOARD_FAB2_LIB.BASEBOARD_FAB2(SCH_1):PAGE106

P3E_CPU0_PE3_OCP_TXP<9> @BASEBOARD_FAB2_LIB.BASEBOARD_FAB2(SCH_1):P3E_CPU0_PE3_OCP_TXP(9)
  U5D1  DM5 PE3_TX_DP<9> SKX_EXT_B_BGA1-IC,TBD    I89 @BASEBOARD_FAB2_LIB.BASEBOARD_FAB2(SCH_1):PAGE32
 C1M18    1      A CAP_0402-0.22UF,16V,10%,X7R,A3A    I78 @BASEBOARD_FAB2_LIB.BASEBOARD_FAB2(SCH_1):PAGE106

P3E_CPU1_PE3_MP_C_TXN<0> @BASEBOARD_FAB2_LIB.BASEBOARD_FAB2(SCH_1):P3E_CPU1_PE3_MP_C_TXN(0)
  J1F1   B8   IOB8 CONN76_H22707001_THMT1-CONN,H2A   I111 @BASEBOARD_FAB2_LIB.BASEBOARD_FAB2(SCH_1):PAGE181
 C1F20    1      A CAP_0402-0.22UF,16V,10%,X7R,A3A   I166 @BASEBOARD_FAB2_LIB.BASEBOARD_FAB2(SCH_1):PAGE181

P3E_CPU1_PE3_MP_C_TXN<10> @BASEBOARD_FAB2_LIB.BASEBOARD_FAB2(SCH_1):P3E_CPU1_PE3_MP_C_TXN(10)
  C9N2    1      A CAP_0402-0.22UF,16V,10%,X7R,A3A    I15 @BASEBOARD_FAB2_LIB.BASEBOARD_FAB2(SCH_1):PAGE182
  J1C1   I8   IOI8 CONN76_H22707001_THMT1-CONN,H2A    I18 @BASEBOARD_FAB2_LIB.BASEBOARD_FAB2(SCH_1):PAGE182

P3E_CPU1_PE3_MP_C_TXN<11> @BASEBOARD_FAB2_LIB.BASEBOARD_FAB2(SCH_1):P3E_CPU1_PE3_MP_C_TXN(11)
  J1C1   A7   IOA7 CONN76_H22707001_THMT1-CONN,H2A    I18 @BASEBOARD_FAB2_LIB.BASEBOARD_FAB2(SCH_1):PAGE182
  C9N3    1      A CAP_0402-0.22UF,16V,10%,X7R,A3A    I51 @BASEBOARD_FAB2_LIB.BASEBOARD_FAB2(SCH_1):PAGE182

P3E_CPU1_PE3_MP_C_TXN<12> @BASEBOARD_FAB2_LIB.BASEBOARD_FAB2(SCH_1):P3E_CPU1_PE3_MP_C_TXN(12)
  J1C1   D7   IOD7 CONN76_H22707001_THMT1-CONN,H2A    I18 @BASEBOARD_FAB2_LIB.BASEBOARD_FAB2(SCH_1):PAGE182
 C9N16    1      A CAP_0402-0.22UF,16V,10%,X7R,A3A    I52 @BASEBOARD_FAB2_LIB.BASEBOARD_FAB2(SCH_1):PAGE182

P3E_CPU1_PE3_MP_C_TXN<13> @BASEBOARD_FAB2_LIB.BASEBOARD_FAB2(SCH_1):P3E_CPU1_PE3_MP_C_TXN(13)
  J1C1   G7   IOG7 CONN76_H22707001_THMT1-CONN,H2A    I18 @BASEBOARD_FAB2_LIB.BASEBOARD_FAB2(SCH_1):PAGE182
  C9N6    1      A CAP_0402-0.22UF,16V,10%,X7R,A3A    I81 @BASEBOARD_FAB2_LIB.BASEBOARD_FAB2(SCH_1):PAGE182

P3E_CPU1_PE3_MP_C_TXN<14> @BASEBOARD_FAB2_LIB.BASEBOARD_FAB2(SCH_1):P3E_CPU1_PE3_MP_C_TXN(14)
  J1C1   E6   IOE6 CONN76_H22707001_THMT1-CONN,H2A    I18 @BASEBOARD_FAB2_LIB.BASEBOARD_FAB2(SCH_1):PAGE182
  C9N8    1      A CAP_0402-0.22UF,16V,10%,X7R,A3A    I50 @BASEBOARD_FAB2_LIB.BASEBOARD_FAB2(SCH_1):PAGE182

P3E_CPU1_PE3_MP_C_TXN<15> @BASEBOARD_FAB2_LIB.BASEBOARD_FAB2(SCH_1):P3E_CPU1_PE3_MP_C_TXN(15)
  J1C1   H6   IOH6 CONN76_H22707001_THMT1-CONN,H2A    I18 @BASEBOARD_FAB2_LIB.BASEBOARD_FAB2(SCH_1):PAGE182
  C9N9    1      A CAP_0402-0.22UF,16V,10%,X7R,A3A    I49 @BASEBOARD_FAB2_LIB.BASEBOARD_FAB2(SCH_1):PAGE182

P3E_CPU1_PE3_MP_C_TXN<1> @BASEBOARD_FAB2_LIB.BASEBOARD_FAB2(SCH_1):P3E_CPU1_PE3_MP_C_TXN(1)
  J1F1   E8   IOE8 CONN76_H22707001_THMT1-CONN,H2A   I111 @BASEBOARD_FAB2_LIB.BASEBOARD_FAB2(SCH_1):PAGE181
 C1F16    1      A CAP_0402-0.22UF,16V,10%,X7R,A3A   I172 @BASEBOARD_FAB2_LIB.BASEBOARD_FAB2(SCH_1):PAGE181

P3E_CPU1_PE3_MP_C_TXN<2> @BASEBOARD_FAB2_LIB.BASEBOARD_FAB2(SCH_1):P3E_CPU1_PE3_MP_C_TXN(2)
  J1F1   H8   IOH8 CONN76_H22707001_THMT1-CONN,H2A   I111 @BASEBOARD_FAB2_LIB.BASEBOARD_FAB2(SCH_1):PAGE181
 C1F15    1      A CAP_0402-0.22UF,16V,10%,X7R,A3A   I174 @BASEBOARD_FAB2_LIB.BASEBOARD_FAB2(SCH_1):PAGE181

P3E_CPU1_PE3_MP_C_TXN<3> @BASEBOARD_FAB2_LIB.BASEBOARD_FAB2(SCH_1):P3E_CPU1_PE3_MP_C_TXN(3)
  J1F1   A7   IOA7 CONN76_H22707001_THMT1-CONN,H2A   I111 @BASEBOARD_FAB2_LIB.BASEBOARD_FAB2(SCH_1):PAGE181
 C1F13    1      A CAP_0402-0.22UF,16V,10%,X7R,A3A   I163 @BASEBOARD_FAB2_LIB.BASEBOARD_FAB2(SCH_1):PAGE181

P3E_CPU1_PE3_MP_C_TXN<4> @BASEBOARD_FAB2_LIB.BASEBOARD_FAB2(SCH_1):P3E_CPU1_PE3_MP_C_TXN(4)
  J1F1   D7   IOD7 CONN76_H22707001_THMT1-CONN,H2A   I111 @BASEBOARD_FAB2_LIB.BASEBOARD_FAB2(SCH_1):PAGE181
 C1F10    1      A CAP_0402-0.22UF,16V,10%,X7R,A3A   I164 @BASEBOARD_FAB2_LIB.BASEBOARD_FAB2(SCH_1):PAGE181

P3E_CPU1_PE3_MP_C_TXN<5> @BASEBOARD_FAB2_LIB.BASEBOARD_FAB2(SCH_1):P3E_CPU1_PE3_MP_C_TXN(5)
  J1F1   H7   IOH7 CONN76_H22707001_THMT1-CONN,H2A   I111 @BASEBOARD_FAB2_LIB.BASEBOARD_FAB2(SCH_1):PAGE181
  C1F8    1      A CAP_0402-0.22UF,16V,10%,X7R,A3A   I170 @BASEBOARD_FAB2_LIB.BASEBOARD_FAB2(SCH_1):PAGE181

P3E_CPU1_PE3_MP_C_TXN<6> @BASEBOARD_FAB2_LIB.BASEBOARD_FAB2(SCH_1):P3E_CPU1_PE3_MP_C_TXN(6)
  J1F1   E6   IOE6 CONN76_H22707001_THMT1-CONN,H2A   I111 @BASEBOARD_FAB2_LIB.BASEBOARD_FAB2(SCH_1):PAGE181
  C1F4    1      A CAP_0402-0.22UF,16V,10%,X7R,A3A   I160 @BASEBOARD_FAB2_LIB.BASEBOARD_FAB2(SCH_1):PAGE181

P3E_CPU1_PE3_MP_C_TXN<7> @BASEBOARD_FAB2_LIB.BASEBOARD_FAB2(SCH_1):P3E_CPU1_PE3_MP_C_TXN(7)
  J1F1   I6   IOI6 CONN76_H22707001_THMT1-CONN,H2A   I111 @BASEBOARD_FAB2_LIB.BASEBOARD_FAB2(SCH_1):PAGE181
  C1F3    1      A CAP_0402-0.22UF,16V,10%,X7R,A3A   I167 @BASEBOARD_FAB2_LIB.BASEBOARD_FAB2(SCH_1):PAGE181

P3E_CPU1_PE3_MP_C_TXN<8> @BASEBOARD_FAB2_LIB.BASEBOARD_FAB2(SCH_1):P3E_CPU1_PE3_MP_C_TXN(8)
 C9N18    1      A CAP_0402-0.22UF,16V,10%,X7R,A3A     I9 @BASEBOARD_FAB2_LIB.BASEBOARD_FAB2(SCH_1):PAGE182
  J1C1   B8   IOB8 CONN76_H22707001_THMT1-CONN,H2A    I18 @BASEBOARD_FAB2_LIB.BASEBOARD_FAB2(SCH_1):PAGE182

P3E_CPU1_PE3_MP_C_TXN<9> @BASEBOARD_FAB2_LIB.BASEBOARD_FAB2(SCH_1):P3E_CPU1_PE3_MP_C_TXN(9)
 C9N15    1      A CAP_0402-0.22UF,16V,10%,X7R,A3A    I13 @BASEBOARD_FAB2_LIB.BASEBOARD_FAB2(SCH_1):PAGE182
  J1C1   E8   IOE8 CONN76_H22707001_THMT1-CONN,H2A    I18 @BASEBOARD_FAB2_LIB.BASEBOARD_FAB2(SCH_1):PAGE182

P3E_CPU1_PE3_MP_C_TXP<0> @BASEBOARD_FAB2_LIB.BASEBOARD_FAB2(SCH_1):P3E_CPU1_PE3_MP_C_TXP(0)
  J1F1   C8   IOC8 CONN76_H22707001_THMT1-CONN,H2A   I111 @BASEBOARD_FAB2_LIB.BASEBOARD_FAB2(SCH_1):PAGE181
 C1F18    1      A CAP_0402-0.22UF,16V,10%,X7R,A3A   I171 @BASEBOARD_FAB2_LIB.BASEBOARD_FAB2(SCH_1):PAGE181

P3E_CPU1_PE3_MP_C_TXP<10> @BASEBOARD_FAB2_LIB.BASEBOARD_FAB2(SCH_1):P3E_CPU1_PE3_MP_C_TXP(10)
  C9N1    1      A CAP_0402-0.22UF,16V,10%,X7R,A3A    I14 @BASEBOARD_FAB2_LIB.BASEBOARD_FAB2(SCH_1):PAGE182
  J1C1   H8   IOH8 CONN76_H22707001_THMT1-CONN,H2A    I18 @BASEBOARD_FAB2_LIB.BASEBOARD_FAB2(SCH_1):PAGE182

P3E_CPU1_PE3_MP_C_TXP<11> @BASEBOARD_FAB2_LIB.BASEBOARD_FAB2(SCH_1):P3E_CPU1_PE3_MP_C_TXP(11)
  J1C1   B7   IOB7 CONN76_H22707001_THMT1-CONN,H2A    I18 @BASEBOARD_FAB2_LIB.BASEBOARD_FAB2(SCH_1):PAGE182
  C9N4    1      A CAP_0402-0.22UF,16V,10%,X7R,A3A    I55 @BASEBOARD_FAB2_LIB.BASEBOARD_FAB2(SCH_1):PAGE182

P3E_CPU1_PE3_MP_C_TXP<12> @BASEBOARD_FAB2_LIB.BASEBOARD_FAB2(SCH_1):P3E_CPU1_PE3_MP_C_TXP(12)
  J1C1   E7   IOE7 CONN76_H22707001_THMT1-CONN,H2A    I18 @BASEBOARD_FAB2_LIB.BASEBOARD_FAB2(SCH_1):PAGE182
 C9N14    1      A CAP_0402-0.22UF,16V,10%,X7R,A3A    I56 @BASEBOARD_FAB2_LIB.BASEBOARD_FAB2(SCH_1):PAGE182

P3E_CPU1_PE3_MP_C_TXP<13> @BASEBOARD_FAB2_LIB.BASEBOARD_FAB2(SCH_1):P3E_CPU1_PE3_MP_C_TXP(13)
  J1C1   H7   IOH7 CONN76_H22707001_THMT1-CONN,H2A    I18 @BASEBOARD_FAB2_LIB.BASEBOARD_FAB2(SCH_1):PAGE182
  C9N5    1      A CAP_0402-0.22UF,16V,10%,X7R,A3A    I83 @BASEBOARD_FAB2_LIB.BASEBOARD_FAB2(SCH_1):PAGE182

P3E_CPU1_PE3_MP_C_TXP<14> @BASEBOARD_FAB2_LIB.BASEBOARD_FAB2(SCH_1):P3E_CPU1_PE3_MP_C_TXP(14)
  J1C1   F6   IOF6 CONN76_H22707001_THMT1-CONN,H2A    I18 @BASEBOARD_FAB2_LIB.BASEBOARD_FAB2(SCH_1):PAGE182
 C9N10    1      A CAP_0402-0.22UF,16V,10%,X7R,A3A    I53 @BASEBOARD_FAB2_LIB.BASEBOARD_FAB2(SCH_1):PAGE182

P3E_CPU1_PE3_MP_C_TXP<15> @BASEBOARD_FAB2_LIB.BASEBOARD_FAB2(SCH_1):P3E_CPU1_PE3_MP_C_TXP(15)
  J1C1   I6   IOI6 CONN76_H22707001_THMT1-CONN,H2A    I18 @BASEBOARD_FAB2_LIB.BASEBOARD_FAB2(SCH_1):PAGE182
  C9N7    1      A CAP_0402-0.22UF,16V,10%,X7R,A3A    I54 @BASEBOARD_FAB2_LIB.BASEBOARD_FAB2(SCH_1):PAGE182

P3E_CPU1_PE3_MP_C_TXP<1> @BASEBOARD_FAB2_LIB.BASEBOARD_FAB2(SCH_1):P3E_CPU1_PE3_MP_C_TXP(1)
  J1F1   F8   IOF8 CONN76_H22707001_THMT1-CONN,H2A   I111 @BASEBOARD_FAB2_LIB.BASEBOARD_FAB2(SCH_1):PAGE181
 C1F17    1      A CAP_0402-0.22UF,16V,10%,X7R,A3A   I173 @BASEBOARD_FAB2_LIB.BASEBOARD_FAB2(SCH_1):PAGE181

P3E_CPU1_PE3_MP_C_TXP<2> @BASEBOARD_FAB2_LIB.BASEBOARD_FAB2(SCH_1):P3E_CPU1_PE3_MP_C_TXP(2)
  J1F1   I8   IOI8 CONN76_H22707001_THMT1-CONN,H2A   I111 @BASEBOARD_FAB2_LIB.BASEBOARD_FAB2(SCH_1):PAGE181
 C1F14    1      A CAP_0402-0.22UF,16V,10%,X7R,A3A   I175 @BASEBOARD_FAB2_LIB.BASEBOARD_FAB2(SCH_1):PAGE181

P3E_CPU1_PE3_MP_C_TXP<3> @BASEBOARD_FAB2_LIB.BASEBOARD_FAB2(SCH_1):P3E_CPU1_PE3_MP_C_TXP(3)
  J1F1   B7   IOB7 CONN76_H22707001_THMT1-CONN,H2A   I111 @BASEBOARD_FAB2_LIB.BASEBOARD_FAB2(SCH_1):PAGE181
 C1F12    1      A CAP_0402-0.22UF,16V,10%,X7R,A3A   I168 @BASEBOARD_FAB2_LIB.BASEBOARD_FAB2(SCH_1):PAGE181

P3E_CPU1_PE3_MP_C_TXP<4> @BASEBOARD_FAB2_LIB.BASEBOARD_FAB2(SCH_1):P3E_CPU1_PE3_MP_C_TXP(4)
  J1F1   E7   IOE7 CONN76_H22707001_THMT1-CONN,H2A   I111 @BASEBOARD_FAB2_LIB.BASEBOARD_FAB2(SCH_1):PAGE181
 C1F11    1      A CAP_0402-0.22UF,16V,10%,X7R,A3A   I169 @BASEBOARD_FAB2_LIB.BASEBOARD_FAB2(SCH_1):PAGE181

P3E_CPU1_PE3_MP_C_TXP<5> @BASEBOARD_FAB2_LIB.BASEBOARD_FAB2(SCH_1):P3E_CPU1_PE3_MP_C_TXP(5)
  J1F1   G7   IOG7 CONN76_H22707001_THMT1-CONN,H2A   I111 @BASEBOARD_FAB2_LIB.BASEBOARD_FAB2(SCH_1):PAGE181
  C1F6    1      A CAP_0402-0.22UF,16V,10%,X7R,A3A   I165 @BASEBOARD_FAB2_LIB.BASEBOARD_FAB2(SCH_1):PAGE181

P3E_CPU1_PE3_MP_C_TXP<6> @BASEBOARD_FAB2_LIB.BASEBOARD_FAB2(SCH_1):P3E_CPU1_PE3_MP_C_TXP(6)
  J1F1   F6   IOF6 CONN76_H22707001_THMT1-CONN,H2A   I111 @BASEBOARD_FAB2_LIB.BASEBOARD_FAB2(SCH_1):PAGE181
  C1F5    1      A CAP_0402-0.22UF,16V,10%,X7R,A3A   I161 @BASEBOARD_FAB2_LIB.BASEBOARD_FAB2(SCH_1):PAGE181

P3E_CPU1_PE3_MP_C_TXP<7> @BASEBOARD_FAB2_LIB.BASEBOARD_FAB2(SCH_1):P3E_CPU1_PE3_MP_C_TXP(7)
  J1F1   H6   IOH6 CONN76_H22707001_THMT1-CONN,H2A   I111 @BASEBOARD_FAB2_LIB.BASEBOARD_FAB2(SCH_1):PAGE181
  C1F2    1      A CAP_0402-0.22UF,16V,10%,X7R,A3A   I162 @BASEBOARD_FAB2_LIB.BASEBOARD_FAB2(SCH_1):PAGE181

P3E_CPU1_PE3_MP_C_TXP<8> @BASEBOARD_FAB2_LIB.BASEBOARD_FAB2(SCH_1):P3E_CPU1_PE3_MP_C_TXP(8)
 C9N17    1      A CAP_0402-0.22UF,16V,10%,X7R,A3A    I12 @BASEBOARD_FAB2_LIB.BASEBOARD_FAB2(SCH_1):PAGE182
  J1C1   C8   IOC8 CONN76_H22707001_THMT1-CONN,H2A    I18 @BASEBOARD_FAB2_LIB.BASEBOARD_FAB2(SCH_1):PAGE182

P3E_CPU1_PE3_MP_C_TXP<9> @BASEBOARD_FAB2_LIB.BASEBOARD_FAB2(SCH_1):P3E_CPU1_PE3_MP_C_TXP(9)
 C9N12    1      A CAP_0402-0.22UF,16V,10%,X7R,A3A    I16 @BASEBOARD_FAB2_LIB.BASEBOARD_FAB2(SCH_1):PAGE182
  J1C1   F8   IOF8 CONN76_H22707001_THMT1-CONN,H2A    I18 @BASEBOARD_FAB2_LIB.BASEBOARD_FAB2(SCH_1):PAGE182

P3E_CPU1_PE3_MP_RXN<0> @BASEBOARD_FAB2_LIB.BASEBOARD_FAB2(SCH_1):P3E_CPU1_PE3_MP_RXN(0)
  U2D1 EA18 PE3_RX_DN<0> SKX_EXT_B_BGA1-IC,TBD    I84 @BASEBOARD_FAB2_LIB.BASEBOARD_FAB2(SCH_1):PAGE66
  J1F1   A1   IOA1 CONN76_H22707001_THMT1-CONN,H2A   I111 @BASEBOARD_FAB2_LIB.BASEBOARD_FAB2(SCH_1):PAGE181

P3E_CPU1_PE3_MP_RXN<10> @BASEBOARD_FAB2_LIB.BASEBOARD_FAB2(SCH_1):P3E_CPU1_PE3_MP_RXN(10)
  U2D1 DG12 PE3_RX_DN<10> SKX_EXT_B_BGA1-IC,TBD    I84 @BASEBOARD_FAB2_LIB.BASEBOARD_FAB2(SCH_1):PAGE66
  J1C1   H1   IOH1 CONN76_H22707001_THMT1-CONN,H2A    I18 @BASEBOARD_FAB2_LIB.BASEBOARD_FAB2(SCH_1):PAGE182

P3E_CPU1_PE3_MP_RXN<11> @BASEBOARD_FAB2_LIB.BASEBOARD_FAB2(SCH_1):P3E_CPU1_PE3_MP_RXN(11)
  U2D1 DG10 PE3_RX_DN<11> SKX_EXT_B_BGA1-IC,TBD    I84 @BASEBOARD_FAB2_LIB.BASEBOARD_FAB2(SCH_1):PAGE66
  J1C1   B2   IOB2 CONN76_H22707001_THMT1-CONN,H2A    I18 @BASEBOARD_FAB2_LIB.BASEBOARD_FAB2(SCH_1):PAGE182

P3E_CPU1_PE3_MP_RXN<12> @BASEBOARD_FAB2_LIB.BASEBOARD_FAB2(SCH_1):P3E_CPU1_PE3_MP_RXN(12)
  U2D1 DC12 PE3_RX_DP<12> SKX_EXT_B_BGA1-IC,TBD    I84 @BASEBOARD_FAB2_LIB.BASEBOARD_FAB2(SCH_1):PAGE66
  J1C1   E2   IOE2 CONN76_H22707001_THMT1-CONN,H2A    I18 @BASEBOARD_FAB2_LIB.BASEBOARD_FAB2(SCH_1):PAGE182

P3E_CPU1_PE3_MP_RXN<13> @BASEBOARD_FAB2_LIB.BASEBOARD_FAB2(SCH_1):P3E_CPU1_PE3_MP_RXN(13)
  U2D1 DB11 PE3_RX_DN<13> SKX_EXT_B_BGA1-IC,TBD    I84 @BASEBOARD_FAB2_LIB.BASEBOARD_FAB2(SCH_1):PAGE66
  J1C1   I2   IOI2 CONN76_H22707001_THMT1-CONN,H2A    I18 @BASEBOARD_FAB2_LIB.BASEBOARD_FAB2(SCH_1):PAGE182

P3E_CPU1_PE3_MP_RXN<14> @BASEBOARD_FAB2_LIB.BASEBOARD_FAB2(SCH_1):P3E_CPU1_PE3_MP_RXN(14)
  U2D1 CY11 PE3_RX_DN<14> SKX_EXT_B_BGA1-IC,TBD    I84 @BASEBOARD_FAB2_LIB.BASEBOARD_FAB2(SCH_1):PAGE66
  J1C1   B3   IOB3 CONN76_H22707001_THMT1-CONN,H2A    I18 @BASEBOARD_FAB2_LIB.BASEBOARD_FAB2(SCH_1):PAGE182

P3E_CPU1_PE3_MP_RXN<15> @BASEBOARD_FAB2_LIB.BASEBOARD_FAB2(SCH_1):P3E_CPU1_PE3_MP_RXN(15)
  U2D1  CV9 PE3_RX_DN<15> SKX_EXT_B_BGA1-IC,TBD    I84 @BASEBOARD_FAB2_LIB.BASEBOARD_FAB2(SCH_1):PAGE66
  J1C1   D3   IOD3 CONN76_H22707001_THMT1-CONN,H2A    I18 @BASEBOARD_FAB2_LIB.BASEBOARD_FAB2(SCH_1):PAGE182

P3E_CPU1_PE3_MP_RXN<1> @BASEBOARD_FAB2_LIB.BASEBOARD_FAB2(SCH_1):P3E_CPU1_PE3_MP_RXN(1)
  U2D1 DW18 PE3_RX_DN<1> SKX_EXT_B_BGA1-IC,TBD    I84 @BASEBOARD_FAB2_LIB.BASEBOARD_FAB2(SCH_1):PAGE66
  J1F1   D1   IOD1 CONN76_H22707001_THMT1-CONN,H2A   I111 @BASEBOARD_FAB2_LIB.BASEBOARD_FAB2(SCH_1):PAGE181

P3E_CPU1_PE3_MP_RXN<2> @BASEBOARD_FAB2_LIB.BASEBOARD_FAB2(SCH_1):P3E_CPU1_PE3_MP_RXN(2)
  U2D1 DW16 PE3_RX_DN<2> SKX_EXT_B_BGA1-IC,TBD    I84 @BASEBOARD_FAB2_LIB.BASEBOARD_FAB2(SCH_1):PAGE66
  J1F1   H1   IOH1 CONN76_H22707001_THMT1-CONN,H2A   I111 @BASEBOARD_FAB2_LIB.BASEBOARD_FAB2(SCH_1):PAGE181

P3E_CPU1_PE3_MP_RXN<3> @BASEBOARD_FAB2_LIB.BASEBOARD_FAB2(SCH_1):P3E_CPU1_PE3_MP_RXN(3)
  U2D1 DT19 PE3_RX_DN<3> SKX_EXT_B_BGA1-IC,TBD    I84 @BASEBOARD_FAB2_LIB.BASEBOARD_FAB2(SCH_1):PAGE66
  J1F1   B2   IOB2 CONN76_H22707001_THMT1-CONN,H2A   I111 @BASEBOARD_FAB2_LIB.BASEBOARD_FAB2(SCH_1):PAGE181

P3E_CPU1_PE3_MP_RXN<4> @BASEBOARD_FAB2_LIB.BASEBOARD_FAB2(SCH_1):P3E_CPU1_PE3_MP_RXN(4)
  U2D1 DR16 PE3_RX_DN<4> SKX_EXT_B_BGA1-IC,TBD    I84 @BASEBOARD_FAB2_LIB.BASEBOARD_FAB2(SCH_1):PAGE66
  J1F1   E2   IOE2 CONN76_H22707001_THMT1-CONN,H2A   I111 @BASEBOARD_FAB2_LIB.BASEBOARD_FAB2(SCH_1):PAGE181

P3E_CPU1_PE3_MP_RXN<5> @BASEBOARD_FAB2_LIB.BASEBOARD_FAB2(SCH_1):P3E_CPU1_PE3_MP_RXN(5)
  U2D1 DR14 PE3_RX_DN<5> SKX_EXT_B_BGA1-IC,TBD    I84 @BASEBOARD_FAB2_LIB.BASEBOARD_FAB2(SCH_1):PAGE66
  J1F1   I2   IOI2 CONN76_H22707001_THMT1-CONN,H2A   I111 @BASEBOARD_FAB2_LIB.BASEBOARD_FAB2(SCH_1):PAGE181

P3E_CPU1_PE3_MP_RXN<6> @BASEBOARD_FAB2_LIB.BASEBOARD_FAB2(SCH_1):P3E_CPU1_PE3_MP_RXN(6)
  U2D1 DN14 PE3_RX_DN<6> SKX_EXT_B_BGA1-IC,TBD    I84 @BASEBOARD_FAB2_LIB.BASEBOARD_FAB2(SCH_1):PAGE66
  J1F1   B3   IOB3 CONN76_H22707001_THMT1-CONN,H2A   I111 @BASEBOARD_FAB2_LIB.BASEBOARD_FAB2(SCH_1):PAGE181

P3E_CPU1_PE3_MP_RXN<7> @BASEBOARD_FAB2_LIB.BASEBOARD_FAB2(SCH_1):P3E_CPU1_PE3_MP_RXN(7)
  U2D1 DL14 PE3_RX_DN<7> SKX_EXT_B_BGA1-IC,TBD    I84 @BASEBOARD_FAB2_LIB.BASEBOARD_FAB2(SCH_1):PAGE66
  J1F1   D3   IOD3 CONN76_H22707001_THMT1-CONN,H2A   I111 @BASEBOARD_FAB2_LIB.BASEBOARD_FAB2(SCH_1):PAGE181

P3E_CPU1_PE3_MP_RXN<8> @BASEBOARD_FAB2_LIB.BASEBOARD_FAB2(SCH_1):P3E_CPU1_PE3_MP_RXN(8)
  U2D1 DL12 PE3_RX_DN<8> SKX_EXT_B_BGA1-IC,TBD    I84 @BASEBOARD_FAB2_LIB.BASEBOARD_FAB2(SCH_1):PAGE66
  J1C1   A1   IOA1 CONN76_H22707001_THMT1-CONN,H2A    I18 @BASEBOARD_FAB2_LIB.BASEBOARD_FAB2(SCH_1):PAGE182

P3E_CPU1_PE3_MP_RXN<9> @BASEBOARD_FAB2_LIB.BASEBOARD_FAB2(SCH_1):P3E_CPU1_PE3_MP_RXN(9)
  U2D1 DJ12 PE3_RX_DN<9> SKX_EXT_B_BGA1-IC,TBD    I84 @BASEBOARD_FAB2_LIB.BASEBOARD_FAB2(SCH_1):PAGE66
  J1C1   D1   IOD1 CONN76_H22707001_THMT1-CONN,H2A    I18 @BASEBOARD_FAB2_LIB.BASEBOARD_FAB2(SCH_1):PAGE182

P3E_CPU1_PE3_MP_RXP<0> @BASEBOARD_FAB2_LIB.BASEBOARD_FAB2(SCH_1):P3E_CPU1_PE3_MP_RXP(0)
  U2D1 DY17 PE3_RX_DP<0> SKX_EXT_B_BGA1-IC,TBD    I84 @BASEBOARD_FAB2_LIB.BASEBOARD_FAB2(SCH_1):PAGE66
  J1F1   B1   IOB1 CONN76_H22707001_THMT1-CONN,H2A   I111 @BASEBOARD_FAB2_LIB.BASEBOARD_FAB2(SCH_1):PAGE181

P3E_CPU1_PE3_MP_RXP<10> @BASEBOARD_FAB2_LIB.BASEBOARD_FAB2(SCH_1):P3E_CPU1_PE3_MP_RXP(10)
  U2D1 DE12 PE3_RX_DP<10> SKX_EXT_B_BGA1-IC,TBD    I84 @BASEBOARD_FAB2_LIB.BASEBOARD_FAB2(SCH_1):PAGE66
  J1C1   G1   IOG1 CONN76_H22707001_THMT1-CONN,H2A    I18 @BASEBOARD_FAB2_LIB.BASEBOARD_FAB2(SCH_1):PAGE182

P3E_CPU1_PE3_MP_RXP<11> @BASEBOARD_FAB2_LIB.BASEBOARD_FAB2(SCH_1):P3E_CPU1_PE3_MP_RXP(11)
  U2D1 DF11 PE3_RX_DP<11> SKX_EXT_B_BGA1-IC,TBD    I84 @BASEBOARD_FAB2_LIB.BASEBOARD_FAB2(SCH_1):PAGE66
  J1C1   C2   IOC2 CONN76_H22707001_THMT1-CONN,H2A    I18 @BASEBOARD_FAB2_LIB.BASEBOARD_FAB2(SCH_1):PAGE182

P3E_CPU1_PE3_MP_RXP<12> @BASEBOARD_FAB2_LIB.BASEBOARD_FAB2(SCH_1):P3E_CPU1_PE3_MP_RXP(12)
  U2D1 DD13 PE3_RX_DN<12> SKX_EXT_B_BGA1-IC,TBD    I84 @BASEBOARD_FAB2_LIB.BASEBOARD_FAB2(SCH_1):PAGE66
  J1C1   F2   IOF2 CONN76_H22707001_THMT1-CONN,H2A    I18 @BASEBOARD_FAB2_LIB.BASEBOARD_FAB2(SCH_1):PAGE182

P3E_CPU1_PE3_MP_RXP<13> @BASEBOARD_FAB2_LIB.BASEBOARD_FAB2(SCH_1):P3E_CPU1_PE3_MP_RXP(13)
  U2D1 DA12 PE3_RX_DP<13> SKX_EXT_B_BGA1-IC,TBD    I84 @BASEBOARD_FAB2_LIB.BASEBOARD_FAB2(SCH_1):PAGE66
  J1C1   H2   IOH2 CONN76_H22707001_THMT1-CONN,H2A    I18 @BASEBOARD_FAB2_LIB.BASEBOARD_FAB2(SCH_1):PAGE182

P3E_CPU1_PE3_MP_RXP<14> @BASEBOARD_FAB2_LIB.BASEBOARD_FAB2(SCH_1):P3E_CPU1_PE3_MP_RXP(14)
  U2D1 CW10 PE3_RX_DP<14> SKX_EXT_B_BGA1-IC,TBD    I84 @BASEBOARD_FAB2_LIB.BASEBOARD_FAB2(SCH_1):PAGE66
  J1C1   A3   IOA3 CONN76_H22707001_THMT1-CONN,H2A    I18 @BASEBOARD_FAB2_LIB.BASEBOARD_FAB2(SCH_1):PAGE182

P3E_CPU1_PE3_MP_RXP<15> @BASEBOARD_FAB2_LIB.BASEBOARD_FAB2(SCH_1):P3E_CPU1_PE3_MP_RXP(15)
  U2D1 CU10 PE3_RX_DP<15> SKX_EXT_B_BGA1-IC,TBD    I84 @BASEBOARD_FAB2_LIB.BASEBOARD_FAB2(SCH_1):PAGE66
  J1C1   E3   IOE3 CONN76_H22707001_THMT1-CONN,H2A    I18 @BASEBOARD_FAB2_LIB.BASEBOARD_FAB2(SCH_1):PAGE182

P3E_CPU1_PE3_MP_RXP<1> @BASEBOARD_FAB2_LIB.BASEBOARD_FAB2(SCH_1):P3E_CPU1_PE3_MP_RXP(1)
  U2D1 DU18 PE3_RX_DP<1> SKX_EXT_B_BGA1-IC,TBD    I84 @BASEBOARD_FAB2_LIB.BASEBOARD_FAB2(SCH_1):PAGE66
  J1F1   E1   IOE1 CONN76_H22707001_THMT1-CONN,H2A   I111 @BASEBOARD_FAB2_LIB.BASEBOARD_FAB2(SCH_1):PAGE181

P3E_CPU1_PE3_MP_RXP<2> @BASEBOARD_FAB2_LIB.BASEBOARD_FAB2(SCH_1):P3E_CPU1_PE3_MP_RXP(2)
  U2D1 DV17 PE3_RX_DP<2> SKX_EXT_B_BGA1-IC,TBD    I84 @BASEBOARD_FAB2_LIB.BASEBOARD_FAB2(SCH_1):PAGE66
  J1F1   G1   IOG1 CONN76_H22707001_THMT1-CONN,H2A   I111 @BASEBOARD_FAB2_LIB.BASEBOARD_FAB2(SCH_1):PAGE181

P3E_CPU1_PE3_MP_RXP<3> @BASEBOARD_FAB2_LIB.BASEBOARD_FAB2(SCH_1):P3E_CPU1_PE3_MP_RXP(3)
  U2D1 DR18 PE3_RX_DP<3> SKX_EXT_B_BGA1-IC,TBD    I84 @BASEBOARD_FAB2_LIB.BASEBOARD_FAB2(SCH_1):PAGE66
  J1F1   C2   IOC2 CONN76_H22707001_THMT1-CONN,H2A   I111 @BASEBOARD_FAB2_LIB.BASEBOARD_FAB2(SCH_1):PAGE181

P3E_CPU1_PE3_MP_RXP<4> @BASEBOARD_FAB2_LIB.BASEBOARD_FAB2(SCH_1):P3E_CPU1_PE3_MP_RXP(4)
  U2D1 DN16 PE3_RX_DP<4> SKX_EXT_B_BGA1-IC,TBD    I84 @BASEBOARD_FAB2_LIB.BASEBOARD_FAB2(SCH_1):PAGE66
  J1F1   F2   IOF2 CONN76_H22707001_THMT1-CONN,H2A   I111 @BASEBOARD_FAB2_LIB.BASEBOARD_FAB2(SCH_1):PAGE181

P3E_CPU1_PE3_MP_RXP<5> @BASEBOARD_FAB2_LIB.BASEBOARD_FAB2(SCH_1):P3E_CPU1_PE3_MP_RXP(5)
  U2D1 DP15 PE3_RX_DP<5> SKX_EXT_B_BGA1-IC,TBD    I84 @BASEBOARD_FAB2_LIB.BASEBOARD_FAB2(SCH_1):PAGE66
  J1F1   H2   IOH2 CONN76_H22707001_THMT1-CONN,H2A   I111 @BASEBOARD_FAB2_LIB.BASEBOARD_FAB2(SCH_1):PAGE181

P3E_CPU1_PE3_MP_RXP<6> @BASEBOARD_FAB2_LIB.BASEBOARD_FAB2(SCH_1):P3E_CPU1_PE3_MP_RXP(6)
  U2D1 DM13 PE3_RX_DP<6> SKX_EXT_B_BGA1-IC,TBD    I84 @BASEBOARD_FAB2_LIB.BASEBOARD_FAB2(SCH_1):PAGE66
  J1F1   A3   IOA3 CONN76_H22707001_THMT1-CONN,H2A   I111 @BASEBOARD_FAB2_LIB.BASEBOARD_FAB2(SCH_1):PAGE181

P3E_CPU1_PE3_MP_RXP<7> @BASEBOARD_FAB2_LIB.BASEBOARD_FAB2(SCH_1):P3E_CPU1_PE3_MP_RXP(7)
  U2D1 DJ14 PE3_RX_DP<7> SKX_EXT_B_BGA1-IC,TBD    I84 @BASEBOARD_FAB2_LIB.BASEBOARD_FAB2(SCH_1):PAGE66
  J1F1   E3   IOE3 CONN76_H22707001_THMT1-CONN,H2A   I111 @BASEBOARD_FAB2_LIB.BASEBOARD_FAB2(SCH_1):PAGE181

P3E_CPU1_PE3_MP_RXP<8> @BASEBOARD_FAB2_LIB.BASEBOARD_FAB2(SCH_1):P3E_CPU1_PE3_MP_RXP(8)
  U2D1 DK13 PE3_RX_DP<8> SKX_EXT_B_BGA1-IC,TBD    I84 @BASEBOARD_FAB2_LIB.BASEBOARD_FAB2(SCH_1):PAGE66
  J1C1   B1   IOB1 CONN76_H22707001_THMT1-CONN,H2A    I18 @BASEBOARD_FAB2_LIB.BASEBOARD_FAB2(SCH_1):PAGE182

P3E_CPU1_PE3_MP_RXP<9> @BASEBOARD_FAB2_LIB.BASEBOARD_FAB2(SCH_1):P3E_CPU1_PE3_MP_RXP(9)
  U2D1 DH11 PE3_RX_DP<9> SKX_EXT_B_BGA1-IC,TBD    I84 @BASEBOARD_FAB2_LIB.BASEBOARD_FAB2(SCH_1):PAGE66
  J1C1   E1   IOE1 CONN76_H22707001_THMT1-CONN,H2A    I18 @BASEBOARD_FAB2_LIB.BASEBOARD_FAB2(SCH_1):PAGE182

P3E_CPU1_PE3_MP_TXN<0> @BASEBOARD_FAB2_LIB.BASEBOARD_FAB2(SCH_1):P3E_CPU1_PE3_MP_TXN(0)
  U2D1 EE14 PE3_TX_DN<0> SKX_EXT_B_BGA1-IC,TBD    I84 @BASEBOARD_FAB2_LIB.BASEBOARD_FAB2(SCH_1):PAGE66
 C1F20    2      B CAP_0402-0.22UF,16V,10%,X7R,A3A   I166 @BASEBOARD_FAB2_LIB.BASEBOARD_FAB2(SCH_1):PAGE181

P3E_CPU1_PE3_MP_TXN<10> @BASEBOARD_FAB2_LIB.BASEBOARD_FAB2(SCH_1):P3E_CPU1_PE3_MP_TXN(10)
  U2D1  DL6 PE3_TX_DN<10> SKX_EXT_B_BGA1-IC,TBD    I84 @BASEBOARD_FAB2_LIB.BASEBOARD_FAB2(SCH_1):PAGE66
  C9N2    2      B CAP_0402-0.22UF,16V,10%,X7R,A3A    I15 @BASEBOARD_FAB2_LIB.BASEBOARD_FAB2(SCH_1):PAGE182

P3E_CPU1_PE3_MP_TXN<11> @BASEBOARD_FAB2_LIB.BASEBOARD_FAB2(SCH_1):P3E_CPU1_PE3_MP_TXN(11)
  U2D1  DJ4 PE3_TX_DN<11> SKX_EXT_B_BGA1-IC,TBD    I84 @BASEBOARD_FAB2_LIB.BASEBOARD_FAB2(SCH_1):PAGE66
  C9N3    2      B CAP_0402-0.22UF,16V,10%,X7R,A3A    I51 @BASEBOARD_FAB2_LIB.BASEBOARD_FAB2(SCH_1):PAGE182

P3E_CPU1_PE3_MP_TXN<12> @BASEBOARD_FAB2_LIB.BASEBOARD_FAB2(SCH_1):P3E_CPU1_PE3_MP_TXN(12)
  U2D1  DJ6 PE3_TX_DN<12> SKX_EXT_B_BGA1-IC,TBD    I84 @BASEBOARD_FAB2_LIB.BASEBOARD_FAB2(SCH_1):PAGE66
 C9N16    2      B CAP_0402-0.22UF,16V,10%,X7R,A3A    I52 @BASEBOARD_FAB2_LIB.BASEBOARD_FAB2(SCH_1):PAGE182

P3E_CPU1_PE3_MP_TXN<13> @BASEBOARD_FAB2_LIB.BASEBOARD_FAB2(SCH_1):P3E_CPU1_PE3_MP_TXN(13)
  U2D1  DD5 PE3_TX_DN<13> SKX_EXT_B_BGA1-IC,TBD    I84 @BASEBOARD_FAB2_LIB.BASEBOARD_FAB2(SCH_1):PAGE66
  C9N6    2      B CAP_0402-0.22UF,16V,10%,X7R,A3A    I81 @BASEBOARD_FAB2_LIB.BASEBOARD_FAB2(SCH_1):PAGE182

P3E_CPU1_PE3_MP_TXN<14> @BASEBOARD_FAB2_LIB.BASEBOARD_FAB2(SCH_1):P3E_CPU1_PE3_MP_TXN(14)
  U2D1  DB5 PE3_TX_DN<14> SKX_EXT_B_BGA1-IC,TBD    I84 @BASEBOARD_FAB2_LIB.BASEBOARD_FAB2(SCH_1):PAGE66
  C9N8    2      B CAP_0402-0.22UF,16V,10%,X7R,A3A    I50 @BASEBOARD_FAB2_LIB.BASEBOARD_FAB2(SCH_1):PAGE182

P3E_CPU1_PE3_MP_TXN<15> @BASEBOARD_FAB2_LIB.BASEBOARD_FAB2(SCH_1):P3E_CPU1_PE3_MP_TXN(15)
  U2D1  CY5 PE3_TX_DN<15> SKX_EXT_B_BGA1-IC,TBD    I84 @BASEBOARD_FAB2_LIB.BASEBOARD_FAB2(SCH_1):PAGE66
  C9N9    2      B CAP_0402-0.22UF,16V,10%,X7R,A3A    I49 @BASEBOARD_FAB2_LIB.BASEBOARD_FAB2(SCH_1):PAGE182

P3E_CPU1_PE3_MP_TXN<1> @BASEBOARD_FAB2_LIB.BASEBOARD_FAB2(SCH_1):P3E_CPU1_PE3_MP_TXN(1)
  U2D1 EE12 PE3_TX_DN<1> SKX_EXT_B_BGA1-IC,TBD    I84 @BASEBOARD_FAB2_LIB.BASEBOARD_FAB2(SCH_1):PAGE66
 C1F16    2      B CAP_0402-0.22UF,16V,10%,X7R,A3A   I172 @BASEBOARD_FAB2_LIB.BASEBOARD_FAB2(SCH_1):PAGE181

P3E_CPU1_PE3_MP_TXN<2> @BASEBOARD_FAB2_LIB.BASEBOARD_FAB2(SCH_1):P3E_CPU1_PE3_MP_TXN(2)
  U2D1 EC12 PE3_TX_DN<2> SKX_EXT_B_BGA1-IC,TBD    I84 @BASEBOARD_FAB2_LIB.BASEBOARD_FAB2(SCH_1):PAGE66
 C1F15    2      B CAP_0402-0.22UF,16V,10%,X7R,A3A   I174 @BASEBOARD_FAB2_LIB.BASEBOARD_FAB2(SCH_1):PAGE181

P3E_CPU1_PE3_MP_TXN<3> @BASEBOARD_FAB2_LIB.BASEBOARD_FAB2(SCH_1):P3E_CPU1_PE3_MP_TXN(3)
  U2D1 DY11 PE3_TX_DN<3> SKX_EXT_B_BGA1-IC,TBD    I84 @BASEBOARD_FAB2_LIB.BASEBOARD_FAB2(SCH_1):PAGE66
 C1F13    2      B CAP_0402-0.22UF,16V,10%,X7R,A3A   I163 @BASEBOARD_FAB2_LIB.BASEBOARD_FAB2(SCH_1):PAGE181

P3E_CPU1_PE3_MP_TXN<4> @BASEBOARD_FAB2_LIB.BASEBOARD_FAB2(SCH_1):P3E_CPU1_PE3_MP_TXN(4)
  U2D1  EB9 PE3_TX_DN<4> SKX_EXT_B_BGA1-IC,TBD    I84 @BASEBOARD_FAB2_LIB.BASEBOARD_FAB2(SCH_1):PAGE66
 C1F10    2      B CAP_0402-0.22UF,16V,10%,X7R,A3A   I164 @BASEBOARD_FAB2_LIB.BASEBOARD_FAB2(SCH_1):PAGE181

P3E_CPU1_PE3_MP_TXN<5> @BASEBOARD_FAB2_LIB.BASEBOARD_FAB2(SCH_1):P3E_CPU1_PE3_MP_TXN(5)
  U2D1 DW10 PE3_TX_DN<5> SKX_EXT_B_BGA1-IC,TBD    I84 @BASEBOARD_FAB2_LIB.BASEBOARD_FAB2(SCH_1):PAGE66
  C1F8    2      B CAP_0402-0.22UF,16V,10%,X7R,A3A   I170 @BASEBOARD_FAB2_LIB.BASEBOARD_FAB2(SCH_1):PAGE181

P3E_CPU1_PE3_MP_TXN<6> @BASEBOARD_FAB2_LIB.BASEBOARD_FAB2(SCH_1):P3E_CPU1_PE3_MP_TXN(6)
  U2D1  DU8 PE3_TX_DN<6> SKX_EXT_B_BGA1-IC,TBD    I84 @BASEBOARD_FAB2_LIB.BASEBOARD_FAB2(SCH_1):PAGE66
  C1F4    2      B CAP_0402-0.22UF,16V,10%,X7R,A3A   I160 @BASEBOARD_FAB2_LIB.BASEBOARD_FAB2(SCH_1):PAGE181

P3E_CPU1_PE3_MP_TXN<7> @BASEBOARD_FAB2_LIB.BASEBOARD_FAB2(SCH_1):P3E_CPU1_PE3_MP_TXN(7)
  U2D1  DR8 PE3_TX_DN<7> SKX_EXT_B_BGA1-IC,TBD    I84 @BASEBOARD_FAB2_LIB.BASEBOARD_FAB2(SCH_1):PAGE66
  C1F3    2      B CAP_0402-0.22UF,16V,10%,X7R,A3A   I167 @BASEBOARD_FAB2_LIB.BASEBOARD_FAB2(SCH_1):PAGE181

P3E_CPU1_PE3_MP_TXN<8> @BASEBOARD_FAB2_LIB.BASEBOARD_FAB2(SCH_1):P3E_CPU1_PE3_MP_TXN(8)
  U2D1  DM7 PE3_TX_DN<8> SKX_EXT_B_BGA1-IC,TBD    I84 @BASEBOARD_FAB2_LIB.BASEBOARD_FAB2(SCH_1):PAGE66
 C9N18    2      B CAP_0402-0.22UF,16V,10%,X7R,A3A     I9 @BASEBOARD_FAB2_LIB.BASEBOARD_FAB2(SCH_1):PAGE182

P3E_CPU1_PE3_MP_TXN<9> @BASEBOARD_FAB2_LIB.BASEBOARD_FAB2(SCH_1):P3E_CPU1_PE3_MP_TXN(9)
  U2D1  DP5 PE3_TX_DN<9> SKX_EXT_B_BGA1-IC,TBD    I84 @BASEBOARD_FAB2_LIB.BASEBOARD_FAB2(SCH_1):PAGE66
 C9N15    2      B CAP_0402-0.22UF,16V,10%,X7R,A3A    I13 @BASEBOARD_FAB2_LIB.BASEBOARD_FAB2(SCH_1):PAGE182

P3E_CPU1_PE3_MP_TXP<0> @BASEBOARD_FAB2_LIB.BASEBOARD_FAB2(SCH_1):P3E_CPU1_PE3_MP_TXP(0)
  U2D1 EC14 PE3_TX_DP<0> SKX_EXT_B_BGA1-IC,TBD    I84 @BASEBOARD_FAB2_LIB.BASEBOARD_FAB2(SCH_1):PAGE66
 C1F18    2      B CAP_0402-0.22UF,16V,10%,X7R,A3A   I171 @BASEBOARD_FAB2_LIB.BASEBOARD_FAB2(SCH_1):PAGE181

P3E_CPU1_PE3_MP_TXP<10> @BASEBOARD_FAB2_LIB.BASEBOARD_FAB2(SCH_1):P3E_CPU1_PE3_MP_TXP(10)
  U2D1  DK5 PE3_TX_DP<10> SKX_EXT_B_BGA1-IC,TBD    I84 @BASEBOARD_FAB2_LIB.BASEBOARD_FAB2(SCH_1):PAGE66
  C9N1    2      B CAP_0402-0.22UF,16V,10%,X7R,A3A    I14 @BASEBOARD_FAB2_LIB.BASEBOARD_FAB2(SCH_1):PAGE182

P3E_CPU1_PE3_MP_TXP<11> @BASEBOARD_FAB2_LIB.BASEBOARD_FAB2(SCH_1):P3E_CPU1_PE3_MP_TXP(11)
  U2D1  DH5 PE3_TX_DP<11> SKX_EXT_B_BGA1-IC,TBD    I84 @BASEBOARD_FAB2_LIB.BASEBOARD_FAB2(SCH_1):PAGE66
  C9N4    2      B CAP_0402-0.22UF,16V,10%,X7R,A3A    I55 @BASEBOARD_FAB2_LIB.BASEBOARD_FAB2(SCH_1):PAGE182

P3E_CPU1_PE3_MP_TXP<12> @BASEBOARD_FAB2_LIB.BASEBOARD_FAB2(SCH_1):P3E_CPU1_PE3_MP_TXP(12)
  U2D1  DG6 PE3_TX_DP<12> SKX_EXT_B_BGA1-IC,TBD    I84 @BASEBOARD_FAB2_LIB.BASEBOARD_FAB2(SCH_1):PAGE66
 C9N14    2      B CAP_0402-0.22UF,16V,10%,X7R,A3A    I56 @BASEBOARD_FAB2_LIB.BASEBOARD_FAB2(SCH_1):PAGE182

P3E_CPU1_PE3_MP_TXP<13> @BASEBOARD_FAB2_LIB.BASEBOARD_FAB2(SCH_1):P3E_CPU1_PE3_MP_TXP(13)
  U2D1  DC6 PE3_TX_DP<13> SKX_EXT_B_BGA1-IC,TBD    I84 @BASEBOARD_FAB2_LIB.BASEBOARD_FAB2(SCH_1):PAGE66
  C9N5    2      B CAP_0402-0.22UF,16V,10%,X7R,A3A    I83 @BASEBOARD_FAB2_LIB.BASEBOARD_FAB2(SCH_1):PAGE182

P3E_CPU1_PE3_MP_TXP<14> @BASEBOARD_FAB2_LIB.BASEBOARD_FAB2(SCH_1):P3E_CPU1_PE3_MP_TXP(14)
  U2D1  DA4 PE3_TX_DP<14> SKX_EXT_B_BGA1-IC,TBD    I84 @BASEBOARD_FAB2_LIB.BASEBOARD_FAB2(SCH_1):PAGE66
 C9N10    2      B CAP_0402-0.22UF,16V,10%,X7R,A3A    I53 @BASEBOARD_FAB2_LIB.BASEBOARD_FAB2(SCH_1):PAGE182

P3E_CPU1_PE3_MP_TXP<15> @BASEBOARD_FAB2_LIB.BASEBOARD_FAB2(SCH_1):P3E_CPU1_PE3_MP_TXP(15)
  U2D1  CV5 PE3_TX_DP<15> SKX_EXT_B_BGA1-IC,TBD    I84 @BASEBOARD_FAB2_LIB.BASEBOARD_FAB2(SCH_1):PAGE66
  C9N7    2      B CAP_0402-0.22UF,16V,10%,X7R,A3A    I54 @BASEBOARD_FAB2_LIB.BASEBOARD_FAB2(SCH_1):PAGE182

P3E_CPU1_PE3_MP_TXP<1> @BASEBOARD_FAB2_LIB.BASEBOARD_FAB2(SCH_1):P3E_CPU1_PE3_MP_TXP(1)
  U2D1 ED13 PE3_TX_DP<1> SKX_EXT_B_BGA1-IC,TBD    I84 @BASEBOARD_FAB2_LIB.BASEBOARD_FAB2(SCH_1):PAGE66
 C1F17    2      B CAP_0402-0.22UF,16V,10%,X7R,A3A   I173 @BASEBOARD_FAB2_LIB.BASEBOARD_FAB2(SCH_1):PAGE181

P3E_CPU1_PE3_MP_TXP<2> @BASEBOARD_FAB2_LIB.BASEBOARD_FAB2(SCH_1):P3E_CPU1_PE3_MP_TXP(2)
  U2D1 EB11 PE3_TX_DP<2> SKX_EXT_B_BGA1-IC,TBD    I84 @BASEBOARD_FAB2_LIB.BASEBOARD_FAB2(SCH_1):PAGE66
 C1F14    2      B CAP_0402-0.22UF,16V,10%,X7R,A3A   I175 @BASEBOARD_FAB2_LIB.BASEBOARD_FAB2(SCH_1):PAGE181

P3E_CPU1_PE3_MP_TXP<3> @BASEBOARD_FAB2_LIB.BASEBOARD_FAB2(SCH_1):P3E_CPU1_PE3_MP_TXP(3)
  U2D1 EA10 PE3_TX_DP<3> SKX_EXT_B_BGA1-IC,TBD    I84 @BASEBOARD_FAB2_LIB.BASEBOARD_FAB2(SCH_1):PAGE66
 C1F12    2      B CAP_0402-0.22UF,16V,10%,X7R,A3A   I168 @BASEBOARD_FAB2_LIB.BASEBOARD_FAB2(SCH_1):PAGE181

P3E_CPU1_PE3_MP_TXP<4> @BASEBOARD_FAB2_LIB.BASEBOARD_FAB2(SCH_1):P3E_CPU1_PE3_MP_TXP(4)
  U2D1  DY9 PE3_TX_DP<4> SKX_EXT_B_BGA1-IC,TBD    I84 @BASEBOARD_FAB2_LIB.BASEBOARD_FAB2(SCH_1):PAGE66
 C1F11    2      B CAP_0402-0.22UF,16V,10%,X7R,A3A   I169 @BASEBOARD_FAB2_LIB.BASEBOARD_FAB2(SCH_1):PAGE181

P3E_CPU1_PE3_MP_TXP<5> @BASEBOARD_FAB2_LIB.BASEBOARD_FAB2(SCH_1):P3E_CPU1_PE3_MP_TXP(5)
  U2D1  DV9 PE3_TX_DP<5> SKX_EXT_B_BGA1-IC,TBD    I84 @BASEBOARD_FAB2_LIB.BASEBOARD_FAB2(SCH_1):PAGE66
  C1F6    2      B CAP_0402-0.22UF,16V,10%,X7R,A3A   I165 @BASEBOARD_FAB2_LIB.BASEBOARD_FAB2(SCH_1):PAGE181

P3E_CPU1_PE3_MP_TXP<6> @BASEBOARD_FAB2_LIB.BASEBOARD_FAB2(SCH_1):P3E_CPU1_PE3_MP_TXP(6)
  U2D1  DT9 PE3_TX_DP<6> SKX_EXT_B_BGA1-IC,TBD    I84 @BASEBOARD_FAB2_LIB.BASEBOARD_FAB2(SCH_1):PAGE66
  C1F5    2      B CAP_0402-0.22UF,16V,10%,X7R,A3A   I161 @BASEBOARD_FAB2_LIB.BASEBOARD_FAB2(SCH_1):PAGE181

P3E_CPU1_PE3_MP_TXP<7> @BASEBOARD_FAB2_LIB.BASEBOARD_FAB2(SCH_1):P3E_CPU1_PE3_MP_TXP(7)
  U2D1  DP7 PE3_TX_DP<7> SKX_EXT_B_BGA1-IC,TBD    I84 @BASEBOARD_FAB2_LIB.BASEBOARD_FAB2(SCH_1):PAGE66
  C1F2    2      B CAP_0402-0.22UF,16V,10%,X7R,A3A   I162 @BASEBOARD_FAB2_LIB.BASEBOARD_FAB2(SCH_1):PAGE181

P3E_CPU1_PE3_MP_TXP<8> @BASEBOARD_FAB2_LIB.BASEBOARD_FAB2(SCH_1):P3E_CPU1_PE3_MP_TXP(8)
  U2D1  DN6 PE3_TX_DP<8> SKX_EXT_B_BGA1-IC,TBD    I84 @BASEBOARD_FAB2_LIB.BASEBOARD_FAB2(SCH_1):PAGE66
 C9N17    2      B CAP_0402-0.22UF,16V,10%,X7R,A3A    I12 @BASEBOARD_FAB2_LIB.BASEBOARD_FAB2(SCH_1):PAGE182

P3E_CPU1_PE3_MP_TXP<9> @BASEBOARD_FAB2_LIB.BASEBOARD_FAB2(SCH_1):P3E_CPU1_PE3_MP_TXP(9)
  U2D1  DM5 PE3_TX_DP<9> SKX_EXT_B_BGA1-IC,TBD    I84 @BASEBOARD_FAB2_LIB.BASEBOARD_FAB2(SCH_1):PAGE66
 C9N12    2      B CAP_0402-0.22UF,16V,10%,X7R,A3A    I16 @BASEBOARD_FAB2_LIB.BASEBOARD_FAB2(SCH_1):PAGE182

P3E_OCP_CPU0_PE3_C_TXN<0> @BASEBOARD_FAB2_LIB.BASEBOARD_FAB2(SCH_1):P3E_OCP_CPU0_PE3_C_TXN(0)
  C1R1    2      B CAP_0402-0.22UF,16V,10%,X7R,A3A    I29 @BASEBOARD_FAB2_LIB.BASEBOARD_FAB2(SCH_1):PAGE106
  J8E3   68   IO68 SCONN80_E67482007_SM-CONN,E674A   I119 @BASEBOARD_FAB2_LIB.BASEBOARD_FAB2(SCH_1):PAGE187

P3E_OCP_CPU0_PE3_C_TXN<10> @BASEBOARD_FAB2_LIB.BASEBOARD_FAB2(SCH_1):P3E_OCP_CPU0_PE3_C_TXN(10)
 C1M17    2      B CAP_0402-0.22UF,16V,10%,X7R,A3A    I92 @BASEBOARD_FAB2_LIB.BASEBOARD_FAB2(SCH_1):PAGE106
  J9B3   98   IO98 SCONN120_A28699018_SM-SCONN,A2A   I336 @BASEBOARD_FAB2_LIB.BASEBOARD_FAB2(SCH_1):PAGE186

P3E_OCP_CPU0_PE3_C_TXN<11> @BASEBOARD_FAB2_LIB.BASEBOARD_FAB2(SCH_1):P3E_OCP_CPU0_PE3_C_TXN(11)
 C1M15    2      B CAP_0402-0.22UF,16V,10%,X7R,A3A    I95 @BASEBOARD_FAB2_LIB.BASEBOARD_FAB2(SCH_1):PAGE106
  J9B3   90   IO90 SCONN120_A28699018_SM-SCONN,A2A   I336 @BASEBOARD_FAB2_LIB.BASEBOARD_FAB2(SCH_1):PAGE186

P3E_OCP_CPU0_PE3_C_TXN<12> @BASEBOARD_FAB2_LIB.BASEBOARD_FAB2(SCH_1):P3E_OCP_CPU0_PE3_C_TXN(12)
 C1M13    2      B CAP_0402-0.22UF,16V,10%,X7R,A3A   I111 @BASEBOARD_FAB2_LIB.BASEBOARD_FAB2(SCH_1):PAGE106
  J9B3   82   IO82 SCONN120_A28699018_SM-SCONN,A2A   I336 @BASEBOARD_FAB2_LIB.BASEBOARD_FAB2(SCH_1):PAGE186

P3E_OCP_CPU0_PE3_C_TXN<13> @BASEBOARD_FAB2_LIB.BASEBOARD_FAB2(SCH_1):P3E_OCP_CPU0_PE3_C_TXN(13)
 C1M11    2      B CAP_0402-0.22UF,16V,10%,X7R,A3A   I117 @BASEBOARD_FAB2_LIB.BASEBOARD_FAB2(SCH_1):PAGE106
  J9B3   74   IO74 SCONN120_A28699018_SM-SCONN,A2A   I336 @BASEBOARD_FAB2_LIB.BASEBOARD_FAB2(SCH_1):PAGE186

P3E_OCP_CPU0_PE3_C_TXN<14> @BASEBOARD_FAB2_LIB.BASEBOARD_FAB2(SCH_1):P3E_OCP_CPU0_PE3_C_TXN(14)
  C1M9    2      B CAP_0402-0.22UF,16V,10%,X7R,A3A   I114 @BASEBOARD_FAB2_LIB.BASEBOARD_FAB2(SCH_1):PAGE106
  J9B3   66   IO66 SCONN120_A28699018_SM-SCONN,A2A   I336 @BASEBOARD_FAB2_LIB.BASEBOARD_FAB2(SCH_1):PAGE186

P3E_OCP_CPU0_PE3_C_TXN<15> @BASEBOARD_FAB2_LIB.BASEBOARD_FAB2(SCH_1):P3E_OCP_CPU0_PE3_C_TXN(15)
  C1M7    2      B CAP_0402-0.22UF,16V,10%,X7R,A3A   I122 @BASEBOARD_FAB2_LIB.BASEBOARD_FAB2(SCH_1):PAGE106
  J9B3   58   IO58 SCONN120_A28699018_SM-SCONN,A2A   I336 @BASEBOARD_FAB2_LIB.BASEBOARD_FAB2(SCH_1):PAGE186

P3E_OCP_CPU0_PE3_C_TXN<1> @BASEBOARD_FAB2_LIB.BASEBOARD_FAB2(SCH_1):P3E_OCP_CPU0_PE3_C_TXN(1)
  C1R3    2      B CAP_0402-0.22UF,16V,10%,X7R,A3A    I37 @BASEBOARD_FAB2_LIB.BASEBOARD_FAB2(SCH_1):PAGE106
  J8E3   60   IO60 SCONN80_E67482007_SM-CONN,E674A   I119 @BASEBOARD_FAB2_LIB.BASEBOARD_FAB2(SCH_1):PAGE187

P3E_OCP_CPU0_PE3_C_TXN<2> @BASEBOARD_FAB2_LIB.BASEBOARD_FAB2(SCH_1):P3E_OCP_CPU0_PE3_C_TXN(2)
  C1R5    2      B CAP_0402-0.22UF,16V,10%,X7R,A3A    I59 @BASEBOARD_FAB2_LIB.BASEBOARD_FAB2(SCH_1):PAGE106
  J8E3   52   IO52 SCONN80_E67482007_SM-CONN,E674A   I119 @BASEBOARD_FAB2_LIB.BASEBOARD_FAB2(SCH_1):PAGE187

P3E_OCP_CPU0_PE3_C_TXN<3> @BASEBOARD_FAB2_LIB.BASEBOARD_FAB2(SCH_1):P3E_OCP_CPU0_PE3_C_TXN(3)
  C1R7    2      B CAP_0402-0.22UF,16V,10%,X7R,A3A    I70 @BASEBOARD_FAB2_LIB.BASEBOARD_FAB2(SCH_1):PAGE106
  J8E3   44   IO44 SCONN80_E67482007_SM-CONN,E674A   I119 @BASEBOARD_FAB2_LIB.BASEBOARD_FAB2(SCH_1):PAGE187

P3E_OCP_CPU0_PE3_C_TXN<4> @BASEBOARD_FAB2_LIB.BASEBOARD_FAB2(SCH_1):P3E_OCP_CPU0_PE3_C_TXN(4)
  C1R9    2      B CAP_0402-0.22UF,16V,10%,X7R,A3A   I134 @BASEBOARD_FAB2_LIB.BASEBOARD_FAB2(SCH_1):PAGE106
  J8E3   36   IO36 SCONN80_E67482007_SM-CONN,E674A   I119 @BASEBOARD_FAB2_LIB.BASEBOARD_FAB2(SCH_1):PAGE187

P3E_OCP_CPU0_PE3_C_TXN<5> @BASEBOARD_FAB2_LIB.BASEBOARD_FAB2(SCH_1):P3E_OCP_CPU0_PE3_C_TXN(5)
 C2R13    2      B CAP_0402-0.22UF,16V,10%,X7R,A3A   I137 @BASEBOARD_FAB2_LIB.BASEBOARD_FAB2(SCH_1):PAGE106
  J8E3   28   IO28 SCONN80_E67482007_SM-CONN,E674A   I119 @BASEBOARD_FAB2_LIB.BASEBOARD_FAB2(SCH_1):PAGE187

P3E_OCP_CPU0_PE3_C_TXN<6> @BASEBOARD_FAB2_LIB.BASEBOARD_FAB2(SCH_1):P3E_OCP_CPU0_PE3_C_TXN(6)
  C2R7    2      B CAP_0402-0.22UF,16V,10%,X7R,A3A   I123 @BASEBOARD_FAB2_LIB.BASEBOARD_FAB2(SCH_1):PAGE106
  J8E3   20   IO20 SCONN80_E67482007_SM-CONN,E674A   I119 @BASEBOARD_FAB2_LIB.BASEBOARD_FAB2(SCH_1):PAGE187

P3E_OCP_CPU0_PE3_C_TXN<7> @BASEBOARD_FAB2_LIB.BASEBOARD_FAB2(SCH_1):P3E_OCP_CPU0_PE3_C_TXN(7)
  C2R9    2      B CAP_0402-0.22UF,16V,10%,X7R,A3A   I147 @BASEBOARD_FAB2_LIB.BASEBOARD_FAB2(SCH_1):PAGE106
  J8E3   12   IO12 SCONN80_E67482007_SM-CONN,E674A   I119 @BASEBOARD_FAB2_LIB.BASEBOARD_FAB2(SCH_1):PAGE187

P3E_OCP_CPU0_PE3_C_TXN<8> @BASEBOARD_FAB2_LIB.BASEBOARD_FAB2(SCH_1):P3E_OCP_CPU0_PE3_C_TXN(8)
 C2M15    2      B CAP_0402-0.22UF,16V,10%,X7R,A3A    I86 @BASEBOARD_FAB2_LIB.BASEBOARD_FAB2(SCH_1):PAGE106
  J9B3  114  IO114 SCONN120_A28699018_SM-SCONN,A2A   I336 @BASEBOARD_FAB2_LIB.BASEBOARD_FAB2(SCH_1):PAGE186

P3E_OCP_CPU0_PE3_C_TXN<9> @BASEBOARD_FAB2_LIB.BASEBOARD_FAB2(SCH_1):P3E_OCP_CPU0_PE3_C_TXN(9)
 C1M19    2      B CAP_0402-0.22UF,16V,10%,X7R,A3A    I90 @BASEBOARD_FAB2_LIB.BASEBOARD_FAB2(SCH_1):PAGE106
  J9B3  106  IO106 SCONN120_A28699018_SM-SCONN,A2A   I336 @BASEBOARD_FAB2_LIB.BASEBOARD_FAB2(SCH_1):PAGE186

P3E_OCP_CPU0_PE3_C_TXP<0> @BASEBOARD_FAB2_LIB.BASEBOARD_FAB2(SCH_1):P3E_OCP_CPU0_PE3_C_TXP(0)
  C1R2    2      B CAP_0402-0.22UF,16V,10%,X7R,A3A    I10 @BASEBOARD_FAB2_LIB.BASEBOARD_FAB2(SCH_1):PAGE106
  J8E3   66   IO66 SCONN80_E67482007_SM-CONN,E674A   I119 @BASEBOARD_FAB2_LIB.BASEBOARD_FAB2(SCH_1):PAGE187

P3E_OCP_CPU0_PE3_C_TXP<10> @BASEBOARD_FAB2_LIB.BASEBOARD_FAB2(SCH_1):P3E_OCP_CPU0_PE3_C_TXP(10)
 C1M16    2      B CAP_0402-0.22UF,16V,10%,X7R,A3A    I82 @BASEBOARD_FAB2_LIB.BASEBOARD_FAB2(SCH_1):PAGE106
  J9B3   96   IO96 SCONN120_A28699018_SM-SCONN,A2A   I336 @BASEBOARD_FAB2_LIB.BASEBOARD_FAB2(SCH_1):PAGE186

P3E_OCP_CPU0_PE3_C_TXP<11> @BASEBOARD_FAB2_LIB.BASEBOARD_FAB2(SCH_1):P3E_OCP_CPU0_PE3_C_TXP(11)
 C1M14    2      B CAP_0402-0.22UF,16V,10%,X7R,A3A    I85 @BASEBOARD_FAB2_LIB.BASEBOARD_FAB2(SCH_1):PAGE106
  J9B3   88   IO88 SCONN120_A28699018_SM-SCONN,A2A   I336 @BASEBOARD_FAB2_LIB.BASEBOARD_FAB2(SCH_1):PAGE186

P3E_OCP_CPU0_PE3_C_TXP<12> @BASEBOARD_FAB2_LIB.BASEBOARD_FAB2(SCH_1):P3E_OCP_CPU0_PE3_C_TXP(12)
 C1M12    2      B CAP_0402-0.22UF,16V,10%,X7R,A3A   I100 @BASEBOARD_FAB2_LIB.BASEBOARD_FAB2(SCH_1):PAGE106
  J9B3   80   IO80 SCONN120_A28699018_SM-SCONN,A2A   I336 @BASEBOARD_FAB2_LIB.BASEBOARD_FAB2(SCH_1):PAGE186

P3E_OCP_CPU0_PE3_C_TXP<13> @BASEBOARD_FAB2_LIB.BASEBOARD_FAB2(SCH_1):P3E_OCP_CPU0_PE3_C_TXP(13)
 C1M10    2      B CAP_0402-0.22UF,16V,10%,X7R,A3A   I102 @BASEBOARD_FAB2_LIB.BASEBOARD_FAB2(SCH_1):PAGE106
  J9B3   72   IO72 SCONN120_A28699018_SM-SCONN,A2A   I336 @BASEBOARD_FAB2_LIB.BASEBOARD_FAB2(SCH_1):PAGE186

P3E_OCP_CPU0_PE3_C_TXP<14> @BASEBOARD_FAB2_LIB.BASEBOARD_FAB2(SCH_1):P3E_OCP_CPU0_PE3_C_TXP(14)
  C1M8    2      B CAP_0402-0.22UF,16V,10%,X7R,A3A   I105 @BASEBOARD_FAB2_LIB.BASEBOARD_FAB2(SCH_1):PAGE106
  J9B3   64   IO64 SCONN120_A28699018_SM-SCONN,A2A   I336 @BASEBOARD_FAB2_LIB.BASEBOARD_FAB2(SCH_1):PAGE186

P3E_OCP_CPU0_PE3_C_TXP<15> @BASEBOARD_FAB2_LIB.BASEBOARD_FAB2(SCH_1):P3E_OCP_CPU0_PE3_C_TXP(15)
  C1M6    2      B CAP_0402-0.22UF,16V,10%,X7R,A3A   I109 @BASEBOARD_FAB2_LIB.BASEBOARD_FAB2(SCH_1):PAGE106
  J9B3   56   IO56 SCONN120_A28699018_SM-SCONN,A2A   I336 @BASEBOARD_FAB2_LIB.BASEBOARD_FAB2(SCH_1):PAGE186

P3E_OCP_CPU0_PE3_C_TXP<1> @BASEBOARD_FAB2_LIB.BASEBOARD_FAB2(SCH_1):P3E_OCP_CPU0_PE3_C_TXP(1)
  C1R4    2      B CAP_0402-0.22UF,16V,10%,X7R,A3A    I26 @BASEBOARD_FAB2_LIB.BASEBOARD_FAB2(SCH_1):PAGE106
  J8E3   58   IO58 SCONN80_E67482007_SM-CONN,E674A   I119 @BASEBOARD_FAB2_LIB.BASEBOARD_FAB2(SCH_1):PAGE187

P3E_OCP_CPU0_PE3_C_TXP<2> @BASEBOARD_FAB2_LIB.BASEBOARD_FAB2(SCH_1):P3E_OCP_CPU0_PE3_C_TXP(2)
  C1R6    2      B CAP_0402-0.22UF,16V,10%,X7R,A3A    I40 @BASEBOARD_FAB2_LIB.BASEBOARD_FAB2(SCH_1):PAGE106
  J8E3   50   IO50 SCONN80_E67482007_SM-CONN,E674A   I119 @BASEBOARD_FAB2_LIB.BASEBOARD_FAB2(SCH_1):PAGE187

P3E_OCP_CPU0_PE3_C_TXP<3> @BASEBOARD_FAB2_LIB.BASEBOARD_FAB2(SCH_1):P3E_OCP_CPU0_PE3_C_TXP(3)
  C1R8    2      B CAP_0402-0.22UF,16V,10%,X7R,A3A    I55 @BASEBOARD_FAB2_LIB.BASEBOARD_FAB2(SCH_1):PAGE106
  J8E3   42   IO42 SCONN80_E67482007_SM-CONN,E674A   I119 @BASEBOARD_FAB2_LIB.BASEBOARD_FAB2(SCH_1):PAGE187

P3E_OCP_CPU0_PE3_C_TXP<4> @BASEBOARD_FAB2_LIB.BASEBOARD_FAB2(SCH_1):P3E_OCP_CPU0_PE3_C_TXP(4)
 C1R10    2      B CAP_0402-0.22UF,16V,10%,X7R,A3A   I128 @BASEBOARD_FAB2_LIB.BASEBOARD_FAB2(SCH_1):PAGE106
  J8E3   34   IO34 SCONN80_E67482007_SM-CONN,E674A   I119 @BASEBOARD_FAB2_LIB.BASEBOARD_FAB2(SCH_1):PAGE187

P3E_OCP_CPU0_PE3_C_TXP<5> @BASEBOARD_FAB2_LIB.BASEBOARD_FAB2(SCH_1):P3E_OCP_CPU0_PE3_C_TXP(5)
 C2R14    2      B CAP_0402-0.22UF,16V,10%,X7R,A3A   I130 @BASEBOARD_FAB2_LIB.BASEBOARD_FAB2(SCH_1):PAGE106
  J8E3   26   IO26 SCONN80_E67482007_SM-CONN,E674A   I119 @BASEBOARD_FAB2_LIB.BASEBOARD_FAB2(SCH_1):PAGE187

P3E_OCP_CPU0_PE3_C_TXP<6> @BASEBOARD_FAB2_LIB.BASEBOARD_FAB2(SCH_1):P3E_OCP_CPU0_PE3_C_TXP(6)
  C2R8    2      B CAP_0402-0.22UF,16V,10%,X7R,A3A   I141 @BASEBOARD_FAB2_LIB.BASEBOARD_FAB2(SCH_1):PAGE106
  J8E3   18   IO18 SCONN80_E67482007_SM-CONN,E674A   I119 @BASEBOARD_FAB2_LIB.BASEBOARD_FAB2(SCH_1):PAGE187

P3E_OCP_CPU0_PE3_C_TXP<7> @BASEBOARD_FAB2_LIB.BASEBOARD_FAB2(SCH_1):P3E_OCP_CPU0_PE3_C_TXP(7)
 C2R10    2      B CAP_0402-0.22UF,16V,10%,X7R,A3A   I142 @BASEBOARD_FAB2_LIB.BASEBOARD_FAB2(SCH_1):PAGE106
  J8E3   10   IO10 SCONN80_E67482007_SM-CONN,E674A   I119 @BASEBOARD_FAB2_LIB.BASEBOARD_FAB2(SCH_1):PAGE187

P3E_OCP_CPU0_PE3_C_TXP<8> @BASEBOARD_FAB2_LIB.BASEBOARD_FAB2(SCH_1):P3E_OCP_CPU0_PE3_C_TXP(8)
 C2M14    2      B CAP_0402-0.22UF,16V,10%,X7R,A3A    I76 @BASEBOARD_FAB2_LIB.BASEBOARD_FAB2(SCH_1):PAGE106
  J9B3  112  IO112 SCONN120_A28699018_SM-SCONN,A2A   I336 @BASEBOARD_FAB2_LIB.BASEBOARD_FAB2(SCH_1):PAGE186

P3E_OCP_CPU0_PE3_C_TXP<9> @BASEBOARD_FAB2_LIB.BASEBOARD_FAB2(SCH_1):P3E_OCP_CPU0_PE3_C_TXP(9)
 C1M18    2      B CAP_0402-0.22UF,16V,10%,X7R,A3A    I78 @BASEBOARD_FAB2_LIB.BASEBOARD_FAB2(SCH_1):PAGE106
  J9B3  104  IO104 SCONN120_A28699018_SM-SCONN,A2A   I336 @BASEBOARD_FAB2_LIB.BASEBOARD_FAB2(SCH_1):PAGE186

P3E_PCH_M2_RX_DN<1> @BASEBOARD_FAB2_LIB.BASEBOARD_FAB2(SCH_1):P3E_PCH_M2_RX_DN(1)
  U7C1 AY72 USB3_8_PCIE1_RXN LBG_CORE_QAT_EXT_D_BGA1-IC,H91A   I220 @BASEBOARD_FAB2_LIB.BASEBOARD_FAB2(SCH_1):PAGE116
  J8F1   29  PERN1 SCONN75K_H17033002_SMT1-SCONN,A    I53 @BASEBOARD_FAB2_LIB.BASEBOARD_FAB2(SCH_1):PAGE185

P3E_PCH_M2_RX_DN<2> @BASEBOARD_FAB2_LIB.BASEBOARD_FAB2(SCH_1):P3E_PCH_M2_RX_DN(2)
  U7C1 AW71 USB3_9_PCIE2_RXN LBG_CORE_QAT_EXT_D_BGA1-IC,H91A   I220 @BASEBOARD_FAB2_LIB.BASEBOARD_FAB2(SCH_1):PAGE116
  J8F1   17  PERN2 SCONN75K_H17033002_SMT1-SCONN,A    I53 @BASEBOARD_FAB2_LIB.BASEBOARD_FAB2(SCH_1):PAGE185

P3E_PCH_M2_RX_DN<3> @BASEBOARD_FAB2_LIB.BASEBOARD_FAB2(SCH_1):P3E_PCH_M2_RX_DN(3)
  U7C1 AV72 USB3_10_PCIE3_GBE_RXN LBG_CORE_QAT_EXT_D_BGA1-IC,H91A   I220 @BASEBOARD_FAB2_LIB.BASEBOARD_FAB2(SCH_1):PAGE116
  J8F1    5  PERN3 SCONN75K_H17033002_SMT1-SCONN,A    I53 @BASEBOARD_FAB2_LIB.BASEBOARD_FAB2(SCH_1):PAGE185

P3E_PCH_M2_RX_DP<1> @BASEBOARD_FAB2_LIB.BASEBOARD_FAB2(SCH_1):P3E_PCH_M2_RX_DP(1)
  U7C1 AY70 USB3_8_PCIE1_RXP LBG_CORE_QAT_EXT_D_BGA1-IC,H91A   I220 @BASEBOARD_FAB2_LIB.BASEBOARD_FAB2(SCH_1):PAGE116
  J8F1   31  PERP1 SCONN75K_H17033002_SMT1-SCONN,A    I53 @BASEBOARD_FAB2_LIB.BASEBOARD_FAB2(SCH_1):PAGE185

P3E_PCH_M2_RX_DP<2> @BASEBOARD_FAB2_LIB.BASEBOARD_FAB2(SCH_1):P3E_PCH_M2_RX_DP(2)
  U7C1 AW69 USB3_9_PCIE2_RXP LBG_CORE_QAT_EXT_D_BGA1-IC,H91A   I220 @BASEBOARD_FAB2_LIB.BASEBOARD_FAB2(SCH_1):PAGE116
  J8F1   19  PERP2 SCONN75K_H17033002_SMT1-SCONN,A    I53 @BASEBOARD_FAB2_LIB.BASEBOARD_FAB2(SCH_1):PAGE185

P3E_PCH_M2_RX_DP<3> @BASEBOARD_FAB2_LIB.BASEBOARD_FAB2(SCH_1):P3E_PCH_M2_RX_DP(3)
  U7C1 AV70 USB3_10_PCIE3_GBE_RXP LBG_CORE_QAT_EXT_D_BGA1-IC,H91A   I220 @BASEBOARD_FAB2_LIB.BASEBOARD_FAB2(SCH_1):PAGE116
  J8F1    7  PERP3 SCONN75K_H17033002_SMT1-SCONN,A    I53 @BASEBOARD_FAB2_LIB.BASEBOARD_FAB2(SCH_1):PAGE185

P3E_PCH_M2_SATA6G_RX_R_DN @BASEBOARD_FAB2_LIB.BASEBOARD_FAB2(SCH_1):P3E_PCH_M2_SATA6G_RX_R_DN
  J8F1   43 PERP0_SATA_BN SCONN75K_H17033002_SMT1-SCONN,A    I53 @BASEBOARD_FAB2_LIB.BASEBOARD_FAB2(SCH_1):PAGE185
 C8F15    2      B CAP_A_0402V-0.01UF,25V,10%,EMPA    I90 @BASEBOARD_FAB2_LIB.BASEBOARD_FAB2(SCH_1):PAGE185
 R8F21    2      B RES_0402-0.0,5%,1/16W,CHIP,G21A   I106 @BASEBOARD_FAB2_LIB.BASEBOARD_FAB2(SCH_1):PAGE185

P3E_PCH_M2_SATA6G_RX_R_DP @BASEBOARD_FAB2_LIB.BASEBOARD_FAB2(SCH_1):P3E_PCH_M2_SATA6G_RX_R_DP
  J8F1   41 PERN0_SATA_BP SCONN75K_H17033002_SMT1-SCONN,A    I53 @BASEBOARD_FAB2_LIB.BASEBOARD_FAB2(SCH_1):PAGE185
 C8F13    2      B CAP_A_0402V-0.01UF,25V,10%,EMPA    I99 @BASEBOARD_FAB2_LIB.BASEBOARD_FAB2(SCH_1):PAGE185
 R8F18    2      B RES_0402-0.0,5%,1/16W,CHIP,G21A   I105 @BASEBOARD_FAB2_LIB.BASEBOARD_FAB2(SCH_1):PAGE185

P3E_PCH_M2_SATA6G_TX_R_DN @BASEBOARD_FAB2_LIB.BASEBOARD_FAB2(SCH_1):P3E_PCH_M2_SATA6G_TX_R_DN
  J8F1   47 PETN0_SATA_AN SCONN75K_H17033002_SMT1-SCONN,A    I53 @BASEBOARD_FAB2_LIB.BASEBOARD_FAB2(SCH_1):PAGE185
 C8F11    2      B CAP_A_0402V-0.01UF,25V,10%,EMPA    I97 @BASEBOARD_FAB2_LIB.BASEBOARD_FAB2(SCH_1):PAGE185
 C8F12    2      B CAP_0402-0.22UF,16V,10%,X7R,A3A    I98 @BASEBOARD_FAB2_LIB.BASEBOARD_FAB2(SCH_1):PAGE185

P3E_PCH_M2_SATA6G_TX_R_DP @BASEBOARD_FAB2_LIB.BASEBOARD_FAB2(SCH_1):P3E_PCH_M2_SATA6G_TX_R_DP
  J8F1   49 PETP0_SATA_AP SCONN75K_H17033002_SMT1-SCONN,A    I53 @BASEBOARD_FAB2_LIB.BASEBOARD_FAB2(SCH_1):PAGE185
  C8F6    2      B CAP_A_0402V-0.01UF,25V,10%,EMPA    I95 @BASEBOARD_FAB2_LIB.BASEBOARD_FAB2(SCH_1):PAGE185
  C8F7    2      B CAP_0402-0.22UF,16V,10%,X7R,A3A    I96 @BASEBOARD_FAB2_LIB.BASEBOARD_FAB2(SCH_1):PAGE185

P3E_PCH_M2_TX_C_DN<1> @BASEBOARD_FAB2_LIB.BASEBOARD_FAB2(SCH_1):P3E_PCH_M2_TX_C_DN(1)
  J8F1   35  PETN1 SCONN75K_H17033002_SMT1-SCONN,A    I53 @BASEBOARD_FAB2_LIB.BASEBOARD_FAB2(SCH_1):PAGE185
 C2T11    1      A CAP_0402-0.22UF,16V,10%,X7R,A3A    I62 @BASEBOARD_FAB2_LIB.BASEBOARD_FAB2(SCH_1):PAGE185

P3E_PCH_M2_TX_C_DN<2> @BASEBOARD_FAB2_LIB.BASEBOARD_FAB2(SCH_1):P3E_PCH_M2_TX_C_DN(2)
  J8F1   23  PETN2 SCONN75K_H17033002_SMT1-SCONN,A    I53 @BASEBOARD_FAB2_LIB.BASEBOARD_FAB2(SCH_1):PAGE185
 C2T14    1      A CAP_0402-0.22UF,16V,10%,X7R,A3A    I65 @BASEBOARD_FAB2_LIB.BASEBOARD_FAB2(SCH_1):PAGE185

P3E_PCH_M2_TX_C_DN<3> @BASEBOARD_FAB2_LIB.BASEBOARD_FAB2(SCH_1):P3E_PCH_M2_TX_C_DN(3)
  J8F1   11  PETN3 SCONN75K_H17033002_SMT1-SCONN,A    I53 @BASEBOARD_FAB2_LIB.BASEBOARD_FAB2(SCH_1):PAGE185
 C2T23    1      A CAP_0402-0.22UF,16V,10%,X7R,A3A    I67 @BASEBOARD_FAB2_LIB.BASEBOARD_FAB2(SCH_1):PAGE185

P3E_PCH_M2_TX_C_DP<1> @BASEBOARD_FAB2_LIB.BASEBOARD_FAB2(SCH_1):P3E_PCH_M2_TX_C_DP(1)
  J8F1   37  PETP1 SCONN75K_H17033002_SMT1-SCONN,A    I53 @BASEBOARD_FAB2_LIB.BASEBOARD_FAB2(SCH_1):PAGE185
 C2T10    1      A CAP_0402-0.22UF,16V,10%,X7R,A3A    I63 @BASEBOARD_FAB2_LIB.BASEBOARD_FAB2(SCH_1):PAGE185

P3E_PCH_M2_TX_C_DP<2> @BASEBOARD_FAB2_LIB.BASEBOARD_FAB2(SCH_1):P3E_PCH_M2_TX_C_DP(2)
  J8F1   25  PETP2 SCONN75K_H17033002_SMT1-SCONN,A    I53 @BASEBOARD_FAB2_LIB.BASEBOARD_FAB2(SCH_1):PAGE185
 C2T13    1      A CAP_0402-0.22UF,16V,10%,X7R,A3A    I64 @BASEBOARD_FAB2_LIB.BASEBOARD_FAB2(SCH_1):PAGE185

P3E_PCH_M2_TX_C_DP<3> @BASEBOARD_FAB2_LIB.BASEBOARD_FAB2(SCH_1):P3E_PCH_M2_TX_C_DP(3)
  J8F1   13  PETP3 SCONN75K_H17033002_SMT1-SCONN,A    I53 @BASEBOARD_FAB2_LIB.BASEBOARD_FAB2(SCH_1):PAGE185
 C2T20    1      A CAP_0402-0.22UF,16V,10%,X7R,A3A    I66 @BASEBOARD_FAB2_LIB.BASEBOARD_FAB2(SCH_1):PAGE185

P3E_PCH_M2_TX_DN<1> @BASEBOARD_FAB2_LIB.BASEBOARD_FAB2(SCH_1):P3E_PCH_M2_TX_DN(1)
  U7C1 BM65 USB3_8_PCIE1_TXN LBG_CORE_QAT_EXT_D_BGA1-IC,H91A   I220 @BASEBOARD_FAB2_LIB.BASEBOARD_FAB2(SCH_1):PAGE116
 C2T11    2      B CAP_0402-0.22UF,16V,10%,X7R,A3A    I62 @BASEBOARD_FAB2_LIB.BASEBOARD_FAB2(SCH_1):PAGE185

P3E_PCH_M2_TX_DN<2> @BASEBOARD_FAB2_LIB.BASEBOARD_FAB2(SCH_1):P3E_PCH_M2_TX_DN(2)
  U7C1 BK65 USB3_9_PCIE2_TXN LBG_CORE_QAT_EXT_D_BGA1-IC,H91A   I220 @BASEBOARD_FAB2_LIB.BASEBOARD_FAB2(SCH_1):PAGE116
 C2T14    2      B CAP_0402-0.22UF,16V,10%,X7R,A3A    I65 @BASEBOARD_FAB2_LIB.BASEBOARD_FAB2(SCH_1):PAGE185

P3E_PCH_M2_TX_DN<3> @BASEBOARD_FAB2_LIB.BASEBOARD_FAB2(SCH_1):P3E_PCH_M2_TX_DN(3)
  U7C1 BH61 USB3_10_PCIE3_GBE_TXN LBG_CORE_QAT_EXT_D_BGA1-IC,H91A   I220 @BASEBOARD_FAB2_LIB.BASEBOARD_FAB2(SCH_1):PAGE116
 C2T23    2      B CAP_0402-0.22UF,16V,10%,X7R,A3A    I67 @BASEBOARD_FAB2_LIB.BASEBOARD_FAB2(SCH_1):PAGE185

P3E_PCH_M2_TX_DP<1> @BASEBOARD_FAB2_LIB.BASEBOARD_FAB2(SCH_1):P3E_PCH_M2_TX_DP(1)
  U7C1 BR65 USB3_8_PCIE1_TXP LBG_CORE_QAT_EXT_D_BGA1-IC,H91A   I220 @BASEBOARD_FAB2_LIB.BASEBOARD_FAB2(SCH_1):PAGE116
 C2T10    2      B CAP_0402-0.22UF,16V,10%,X7R,A3A    I63 @BASEBOARD_FAB2_LIB.BASEBOARD_FAB2(SCH_1):PAGE185

P3E_PCH_M2_TX_DP<2> @BASEBOARD_FAB2_LIB.BASEBOARD_FAB2(SCH_1):P3E_PCH_M2_TX_DP(2)
  U7C1 BL66 USB3_9_PCIE2_TXP LBG_CORE_QAT_EXT_D_BGA1-IC,H91A   I220 @BASEBOARD_FAB2_LIB.BASEBOARD_FAB2(SCH_1):PAGE116
 C2T13    2      B CAP_0402-0.22UF,16V,10%,X7R,A3A    I64 @BASEBOARD_FAB2_LIB.BASEBOARD_FAB2(SCH_1):PAGE185

P3E_PCH_M2_TX_DP<3> @BASEBOARD_FAB2_LIB.BASEBOARD_FAB2(SCH_1):P3E_PCH_M2_TX_DP(3)
  U7C1 BK61 USB3_10_PCIE3_GBE_TXP LBG_CORE_QAT_EXT_D_BGA1-IC,H91A   I220 @BASEBOARD_FAB2_LIB.BASEBOARD_FAB2(SCH_1):PAGE116
 C2T20    2      B CAP_0402-0.22UF,16V,10%,X7R,A3A    I66 @BASEBOARD_FAB2_LIB.BASEBOARD_FAB2(SCH_1):PAGE185

P3E_PCH_RX_0_DN @BASEBOARD_FAB2_LIB.BASEBOARD_FAB2(SCH_1):P3E_PCH_RX_0_DN
  U7C1 BA71 USB3_7_PCIE0_RXN LBG_CORE_QAT_EXT_D_BGA1-IC,H91A   I220 @BASEBOARD_FAB2_LIB.BASEBOARD_FAB2(SCH_1):PAGE116
 R8F21    1      A RES_0402-0.0,5%,1/16W,CHIP,G21A   I106 @BASEBOARD_FAB2_LIB.BASEBOARD_FAB2(SCH_1):PAGE185

P3E_PCH_RX_0_DP @BASEBOARD_FAB2_LIB.BASEBOARD_FAB2(SCH_1):P3E_PCH_RX_0_DP
  U7C1 BA69 USB3_7_PCIE0_RXP LBG_CORE_QAT_EXT_D_BGA1-IC,H91A   I220 @BASEBOARD_FAB2_LIB.BASEBOARD_FAB2(SCH_1):PAGE116
 R8F18    1      A RES_0402-0.0,5%,1/16W,CHIP,G21A   I105 @BASEBOARD_FAB2_LIB.BASEBOARD_FAB2(SCH_1):PAGE185

P3E_PCH_TX_0_DN @BASEBOARD_FAB2_LIB.BASEBOARD_FAB2(SCH_1):P3E_PCH_TX_0_DN
  U7C1 BR61 USB3_7_PCIE0_TXN LBG_CORE_QAT_EXT_D_BGA1-IC,H91A   I220 @BASEBOARD_FAB2_LIB.BASEBOARD_FAB2(SCH_1):PAGE116
 C8F12    1      A CAP_0402-0.22UF,16V,10%,X7R,A3A    I98 @BASEBOARD_FAB2_LIB.BASEBOARD_FAB2(SCH_1):PAGE185

P3E_PCH_TX_0_DP @BASEBOARD_FAB2_LIB.BASEBOARD_FAB2(SCH_1):P3E_PCH_TX_0_DP
  U7C1 BN63 USB3_7_PCIE0_TXP LBG_CORE_QAT_EXT_D_BGA1-IC,H91A   I220 @BASEBOARD_FAB2_LIB.BASEBOARD_FAB2(SCH_1):PAGE116
  C8F7    1      A CAP_0402-0.22UF,16V,10%,X7R,A3A    I96 @BASEBOARD_FAB2_LIB.BASEBOARD_FAB2(SCH_1):PAGE185

P3V3 @BASEBOARD_FAB2_LIB.BASEBOARD_FAB2(SCH_1):P3V3
  J8B1   18   IO18 SCONN24_H46321001_SM-SCONN,H46A     I1 @BASEBOARD_FAB2_LIB.BASEBOARD_FAB2(SCH_1):PAGE91
  J8B1   20   IO20 SCONN24_H46321001_SM-SCONN,H46A     I1 @BASEBOARD_FAB2_LIB.BASEBOARD_FAB2(SCH_1):PAGE91
  U3P2   14    VCC GTL2014_SM-IC,D66151-001     I1 @BASEBOARD_FAB2_LIB.BASEBOARD_FAB2(SCH_1):PAGE92
  U7D2   14    VCC GTL2014_SM-IC,D66151-001    I32 @BASEBOARD_FAB2_LIB.BASEBOARD_FAB2(SCH_1):PAGE92
  C7D4    1      A CAP_0402-1.0UF,16V,10%,X6S,D97A    I79 @BASEBOARD_FAB2_LIB.BASEBOARD_FAB2(SCH_1):PAGE92
 C3P50    1      A CAP_0402-1.0UF,16V,10%,X6S,D97A    I84 @BASEBOARD_FAB2_LIB.BASEBOARD_FAB2(SCH_1):PAGE92
  U2T4   14    VCC GTL2014_SM-IC,D66151-001    I30 @BASEBOARD_FAB2_LIB.BASEBOARD_FAB2(SCH_1):PAGE93
 C2T33    1      A CAP_A_0402V-1.0UF,6.3V,10%,X6SA    I72 @BASEBOARD_FAB2_LIB.BASEBOARD_FAB2(SCH_1):PAGE93
  R7G7    1      A RES_0402-4.75K,1%,1/16W,CHIP,GA    I51 @BASEBOARD_FAB2_LIB.BASEBOARD_FAB2(SCH_1):PAGE94
  R3R4    1      A RES_0402-4.75K,1%,1/16W,CHIP,GA    I66 @BASEBOARD_FAB2_LIB.BASEBOARD_FAB2(SCH_1):PAGE94
 R3R10    1      A RES_0402-4.75K,1%,1/16W,CHIP,GA    I79 @BASEBOARD_FAB2_LIB.BASEBOARD_FAB2(SCH_1):PAGE94
  R6M4    1      A RES_0402-4.75K,1%,1/16W,CHIP,GA    I82 @BASEBOARD_FAB2_LIB.BASEBOARD_FAB2(SCH_1):PAGE94
 R7E10    1      A RES_0402-4.75K,1%,1/16W,CHIP,GA    I62 @BASEBOARD_FAB2_LIB.BASEBOARD_FAB2(SCH_1):PAGE95
 R7E11    1      A RES_0402-4.75K,1%,1/16W,CHIP,GA    I72 @BASEBOARD_FAB2_LIB.BASEBOARD_FAB2(SCH_1):PAGE95
  R7E7    1      A RES_0402-4.75K,1%,1/16W,CHIP,GA   I106 @BASEBOARD_FAB2_LIB.BASEBOARD_FAB2(SCH_1):PAGE95
 FB6P1    1      A FERRITE_SMLF-600,FB,656554-043     I8 @BASEBOARD_FAB2_LIB.BASEBOARD_FAB2(SCH_1):PAGE102
 R6P48    1      A RES_0402-4.75K,1%,1/16W,CHIP,GA    I91 @BASEBOARD_FAB2_LIB.BASEBOARD_FAB2(SCH_1):PAGE102
 R4D69    1      A RES_0402-4.75K,1%,1/16W,CHIP,GA    I93 @BASEBOARD_FAB2_LIB.BASEBOARD_FAB2(SCH_1):PAGE102
 R4D70    1      A RES_0402-4.75K,1%,1/16W,CHIP,GA    I94 @BASEBOARD_FAB2_LIB.BASEBOARD_FAB2(SCH_1):PAGE102
  C6F1    1      A CAP_A_0402V-0.1UF,16V,10%,X7R,A    I25 @BASEBOARD_FAB2_LIB.BASEBOARD_FAB2(SCH_1):PAGE104
  C3F2    1      A CAP_A_0402V-0.1UF,16V,10%,X7R,A    I34 @BASEBOARD_FAB2_LIB.BASEBOARD_FAB2(SCH_1):PAGE104
  Y6F1    6    VCC OSC_C_6P10-156.25MHZ,OSC,G6383A    I71 @BASEBOARD_FAB2_LIB.BASEBOARD_FAB2(SCH_1):PAGE104
  Y3F1    6    VCC OSC_C_6P10-156.25MHZ,OSC,G6383A    I72 @BASEBOARD_FAB2_LIB.BASEBOARD_FAB2(SCH_1):PAGE104
 C2U21    1      A CAP_A_0402V-0.1UF,16V,10%,X7R,A     I5 @BASEBOARD_FAB2_LIB.BASEBOARD_FAB2(SCH_1):PAGE108
 C2U25    1      A CAP_A_0402V-0.1UF,16V,10%,X7R,A     I7 @BASEBOARD_FAB2_LIB.BASEBOARD_FAB2(SCH_1):PAGE108
  J8G1   21   IO21 SCONN200_H68296001_SM-CONN,H68A   I258 @BASEBOARD_FAB2_LIB.BASEBOARD_FAB2(SCH_1):PAGE108
  J8G1   22   IO22 SCONN200_H68296001_SM-CONN,H68A   I258 @BASEBOARD_FAB2_LIB.BASEBOARD_FAB2(SCH_1):PAGE108
  J8G1   23   IO23 SCONN200_H68296001_SM-CONN,H68A   I258 @BASEBOARD_FAB2_LIB.BASEBOARD_FAB2(SCH_1):PAGE108
  J8G1   24   IO24 SCONN200_H68296001_SM-CONN,H68A   I258 @BASEBOARD_FAB2_LIB.BASEBOARD_FAB2(SCH_1):PAGE108
 R7E21    1      A RES_0402-4.75K,1%,1/16W,CHIP,GA   I343 @BASEBOARD_FAB2_LIB.BASEBOARD_FAB2(SCH_1):PAGE108
  Q9A1    3   C<0> NPN_DUAL_SSOPLF-MBT3904,EMPTY,A    I94 @BASEBOARD_FAB2_LIB.BASEBOARD_FAB2(SCH_1):PAGE111
  R9A1    1      A RES_0402-1.00K,1%,1/16W,EMPTY,A    I95 @BASEBOARD_FAB2_LIB.BASEBOARD_FAB2(SCH_1):PAGE111
  U9G1   14    VCC GTL2014_SM-IC,D66151-001     I1 @BASEBOARD_FAB2_LIB.BASEBOARD_FAB2(SCH_1):PAGE152
 C1U19    1      A CAP_0402-1.0UF,16V,10%,X6S,D97A    I18 @BASEBOARD_FAB2_LIB.BASEBOARD_FAB2(SCH_1):PAGE152
 R2N27    1      A RES_0402-4.75K,1%,1/16W,CHIP,GA    I97 @BASEBOARD_FAB2_LIB.BASEBOARD_FAB2(SCH_1):PAGE157
 R1U26    1      A RES_0402-5.11K,1%,1/16W,CHIP,GA   I148 @BASEBOARD_FAB2_LIB.BASEBOARD_FAB2(SCH_1):PAGE169
 R2L23    1      A RES_0402-2.0K,1%,1/16W,CHIP,G2A   I261 @BASEBOARD_FAB2_LIB.BASEBOARD_FAB2(SCH_1):PAGE173
 R2L21    1      A RES_0402-2.0K,1%,1/16W,CHIP,G2A   I263 @BASEBOARD_FAB2_LIB.BASEBOARD_FAB2(SCH_1):PAGE173
  R1L1    1      A RES_0402-2.0K,1%,1/16W,CHIP,G2A    I25 @BASEBOARD_FAB2_LIB.BASEBOARD_FAB2(SCH_1):PAGE174
 R1M12    1      A RES_0402-10.0K,1%,1/16W,CHIP,GA     I8 @BASEBOARD_FAB2_LIB.BASEBOARD_FAB2(SCH_1):PAGE177
 R1M11    1      A RES_0402-10.0K,1%,1/16W,CHIP,GA     I9 @BASEBOARD_FAB2_LIB.BASEBOARD_FAB2(SCH_1):PAGE177
  C1M3    1      A CAP_A_0402V-1.0UF,6.3V,10%,X6SA    I20 @BASEBOARD_FAB2_LIB.BASEBOARD_FAB2(SCH_1):PAGE177
 R1L21    1      A RES_0402-64.9,1.0%,1/16W,CHIP,A    I43 @BASEBOARD_FAB2_LIB.BASEBOARD_FAB2(SCH_1):PAGE177
  J8F1    2 3_3V<0> SCONN75K_H17033002_SMT1-SCONN,A    I53 @BASEBOARD_FAB2_LIB.BASEBOARD_FAB2(SCH_1):PAGE185
  J8F1    4 3_3V<1> SCONN75K_H17033002_SMT1-SCONN,A    I53 @BASEBOARD_FAB2_LIB.BASEBOARD_FAB2(SCH_1):PAGE185
  J8F1   12 3_3V<2> SCONN75K_H17033002_SMT1-SCONN,A    I53 @BASEBOARD_FAB2_LIB.BASEBOARD_FAB2(SCH_1):PAGE185
  J8F1   14 3_3V<3> SCONN75K_H17033002_SMT1-SCONN,A    I53 @BASEBOARD_FAB2_LIB.BASEBOARD_FAB2(SCH_1):PAGE185
  J8F1   16 3_3V<4> SCONN75K_H17033002_SMT1-SCONN,A    I53 @BASEBOARD_FAB2_LIB.BASEBOARD_FAB2(SCH_1):PAGE185
  J8F1   18 3_3V<5> SCONN75K_H17033002_SMT1-SCONN,A    I53 @BASEBOARD_FAB2_LIB.BASEBOARD_FAB2(SCH_1):PAGE185
  J8F1   70 3_3V<6> SCONN75K_H17033002_SMT1-SCONN,A    I53 @BASEBOARD_FAB2_LIB.BASEBOARD_FAB2(SCH_1):PAGE185
  J8F1   72 3_3V<7> SCONN75K_H17033002_SMT1-SCONN,A    I53 @BASEBOARD_FAB2_LIB.BASEBOARD_FAB2(SCH_1):PAGE185
  J8F1   74 3_3V<8> SCONN75K_H17033002_SMT1-SCONN,A    I53 @BASEBOARD_FAB2_LIB.BASEBOARD_FAB2(SCH_1):PAGE185
 R2P15    1      A RES_0402-10.0K,1%,1/16W,CHIP,GA   I111 @BASEBOARD_FAB2_LIB.BASEBOARD_FAB2(SCH_1):PAGE185
 C2T29    1      A CAP_A_0402V-0.1UF,16V,10%,X7R,A   I120 @BASEBOARD_FAB2_LIB.BASEBOARD_FAB2(SCH_1):PAGE185
 C2T26    1      A CAP_A_0402V-0.1UF,16V,10%,X7R,A   I123 @BASEBOARD_FAB2_LIB.BASEBOARD_FAB2(SCH_1):PAGE185
 C2T21    1      A CAP_A_0402V-0.1UF,16V,10%,X7R,A   I124 @BASEBOARD_FAB2_LIB.BASEBOARD_FAB2(SCH_1):PAGE185
 C2T16    1      A CAP_A_0402V-0.1UF,16V,10%,X7R,A   I126 @BASEBOARD_FAB2_LIB.BASEBOARD_FAB2(SCH_1):PAGE185
 C2T15    1      A CAP_A_0402V-0.1UF,16V,10%,X7R,A   I127 @BASEBOARD_FAB2_LIB.BASEBOARD_FAB2(SCH_1):PAGE185
 C2T24    1      A CAP_A_0402V-0.1UF,16V,10%,X7R,A   I129 @BASEBOARD_FAB2_LIB.BASEBOARD_FAB2(SCH_1):PAGE185
  C2T2    1      A CAP_A_0402V-0.1UF,16V,10%,X7R,A   I131 @BASEBOARD_FAB2_LIB.BASEBOARD_FAB2(SCH_1):PAGE185
  C2T4    1      A CAP_A_0402V-0.1UF,16V,10%,X7R,A   I132 @BASEBOARD_FAB2_LIB.BASEBOARD_FAB2(SCH_1):PAGE185
  C2T5    1      A CAP_A_0402V-0.1UF,16V,10%,X7R,A   I135 @BASEBOARD_FAB2_LIB.BASEBOARD_FAB2(SCH_1):PAGE185
 R8F36    1      A RES_0402-10.0K,1%,1/16W,CHIP,GA   I136 @BASEBOARD_FAB2_LIB.BASEBOARD_FAB2(SCH_1):PAGE185
 C1M24    1      A CAP_A_0402V-0.1UF,16V,10%,X7R,A    I10 @BASEBOARD_FAB2_LIB.BASEBOARD_FAB2(SCH_1):PAGE186
 C1M21    1      A CAP_A_0402V-1.0UF,6.3V,10%,X6SA   I334 @BASEBOARD_FAB2_LIB.BASEBOARD_FAB2(SCH_1):PAGE186
  J9B3   18   IO18 SCONN120_A28699018_SM-SCONN,A2A   I336 @BASEBOARD_FAB2_LIB.BASEBOARD_FAB2(SCH_1):PAGE186
  J9B3   19   IO19 SCONN120_A28699018_SM-SCONN,A2A   I336 @BASEBOARD_FAB2_LIB.BASEBOARD_FAB2(SCH_1):PAGE186
  J9B3   20   IO20 SCONN120_A28699018_SM-SCONN,A2A   I336 @BASEBOARD_FAB2_LIB.BASEBOARD_FAB2(SCH_1):PAGE186
  J9B3   21   IO21 SCONN120_A28699018_SM-SCONN,A2A   I336 @BASEBOARD_FAB2_LIB.BASEBOARD_FAB2(SCH_1):PAGE186
  J9B3   22   IO22 SCONN120_A28699018_SM-SCONN,A2A   I336 @BASEBOARD_FAB2_LIB.BASEBOARD_FAB2(SCH_1):PAGE186
  J9B3   23   IO23 SCONN120_A28699018_SM-SCONN,A2A   I336 @BASEBOARD_FAB2_LIB.BASEBOARD_FAB2(SCH_1):PAGE186
  J9B3   24   IO24 SCONN120_A28699018_SM-SCONN,A2A   I336 @BASEBOARD_FAB2_LIB.BASEBOARD_FAB2(SCH_1):PAGE186
  J9B3   25   IO25 SCONN120_A28699018_SM-SCONN,A2A   I336 @BASEBOARD_FAB2_LIB.BASEBOARD_FAB2(SCH_1):PAGE186
  J4B2   D1   IOD1 SCONN120_H61426002_SM-CONN,H61A    I46 @BASEBOARD_FAB2_LIB.BASEBOARD_FAB2(SCH_1):PAGE193
  J6B1   D1   IOD1 SCONN120_H61426002_SM-CONN,H61A    I56 @BASEBOARD_FAB2_LIB.BASEBOARD_FAB2(SCH_1):PAGE194
  U1L3    3    VCC ADM809_SMLF-IC,D23047-001-GND=A    I80 @BASEBOARD_FAB2_LIB.BASEBOARD_FAB2(SCH_1):PAGE196
 C1L16    1      A CAP_A_0402V-0.1UF,16V,10%,X7R,A    I81 @BASEBOARD_FAB2_LIB.BASEBOARD_FAB2(SCH_1):PAGE196
 EU2T1    6      S SLG55021_SM-IC,G56246-001     I1 @BASEBOARD_FAB2_LIB.BASEBOARD_FAB2(SCH_1):PAGE198
 C2U19    1      A CAP_A_0402V-0.1UF,16V,10%,X7R,A    I46 @BASEBOARD_FAB2_LIB.BASEBOARD_FAB2(SCH_1):PAGE198
  C2U2    1      A CAP_0805-10UF,16V,10%,X6S,C953A    I47 @BASEBOARD_FAB2_LIB.BASEBOARD_FAB2(SCH_1):PAGE198
  Q8G1    1    SRC MOSFET_N_LCC3-BSZ019N03LS,NFETA    I85 @BASEBOARD_FAB2_LIB.BASEBOARD_FAB2(SCH_1):PAGE198
  R6U4    1      A RES_0402-0.0,5%,1/16W,CHIP,G21A    I28 @BASEBOARD_FAB2_LIB.BASEBOARD_FAB2(SCH_1):PAGE221
 R6U15    1      A RES_0402-1.0M,1%,1/16W,EMPTY,GA    I37 @BASEBOARD_FAB2_LIB.BASEBOARD_FAB2(SCH_1):PAGE221
 R4G18    1      A RES_0402-10.0K,1%,1/16W,CHIP,GA    I45 @BASEBOARD_FAB2_LIB.BASEBOARD_FAB2(SCH_1):PAGE221
  R6L9    1      A RES_0402-10.0K,1%,1/16W,CHIP,GA    I19 @BASEBOARD_FAB2_LIB.BASEBOARD_FAB2(SCH_1):PAGE222
 R6L11    1      A RES_0402-0.0,5%,1/16W,CHIP,G21A    I30 @BASEBOARD_FAB2_LIB.BASEBOARD_FAB2(SCH_1):PAGE222
  R6L4    1      A RES_0402-1.0M,1%,1/16W,EMPTY,GA    I37 @BASEBOARD_FAB2_LIB.BASEBOARD_FAB2(SCH_1):PAGE222
 R4G17    1      A RES_0402-10.0K,1%,1/16W,CHIP,GA    I14 @BASEBOARD_FAB2_LIB.BASEBOARD_FAB2(SCH_1):PAGE229
  R6U7    1      A RES_0402-0.0,5%,1/16W,CHIP,G21A    I32 @BASEBOARD_FAB2_LIB.BASEBOARD_FAB2(SCH_1):PAGE229
  R6U3    1      A RES_0402-1.0M,1%,1/16W,EMPTY,GA    I34 @BASEBOARD_FAB2_LIB.BASEBOARD_FAB2(SCH_1):PAGE229
  R4A5    1      A RES_0402-10.0K,1%,1/16W,CHIP,GA    I17 @BASEBOARD_FAB2_LIB.BASEBOARD_FAB2(SCH_1):PAGE230
  R6L8    1      A RES_0402-0.0,5%,1/16W,CHIP,G21A    I30 @BASEBOARD_FAB2_LIB.BASEBOARD_FAB2(SCH_1):PAGE230
  R6L5    1      A RES_0402-1.0M,1%,1/16W,EMPTY,GA    I37 @BASEBOARD_FAB2_LIB.BASEBOARD_FAB2(SCH_1):PAGE230

P3V3_DB1200 @BASEBOARD_FAB2_LIB.BASEBOARD_FAB2(SCH_1):P3V3_DB1200
 EU4D2   24 VDD<0> NB3W1200L_LCC-IC,H13585-001     I1 @BASEBOARD_FAB2_LIB.BASEBOARD_FAB2(SCH_1):PAGE102
 EU4D2   40 VDD<1> NB3W1200L_LCC-IC,H13585-001     I1 @BASEBOARD_FAB2_LIB.BASEBOARD_FAB2(SCH_1):PAGE102
 EU4D2   57 VDD<2> NB3W1200L_LCC-IC,H13585-001     I1 @BASEBOARD_FAB2_LIB.BASEBOARD_FAB2(SCH_1):PAGE102
 EU4D2   25 VDDIO<0> NB3W1200L_LCC-IC,H13585-001     I1 @BASEBOARD_FAB2_LIB.BASEBOARD_FAB2(SCH_1):PAGE102
 EU4D2   32 VDDIO<1> NB3W1200L_LCC-IC,H13585-001     I1 @BASEBOARD_FAB2_LIB.BASEBOARD_FAB2(SCH_1):PAGE102
 EU4D2   49 VDDIO<2> NB3W1200L_LCC-IC,H13585-001     I1 @BASEBOARD_FAB2_LIB.BASEBOARD_FAB2(SCH_1):PAGE102
 EU4D2   56 VDDIO<3> NB3W1200L_LCC-IC,H13585-001     I1 @BASEBOARD_FAB2_LIB.BASEBOARD_FAB2(SCH_1):PAGE102
 FB6P1    2      B FERRITE_SMLF-600,FB,656554-043     I8 @BASEBOARD_FAB2_LIB.BASEBOARD_FAB2(SCH_1):PAGE102
 C3D22    1      A CAP_0805-10UF,16V,10%,X7R,G106A    I10 @BASEBOARD_FAB2_LIB.BASEBOARD_FAB2(SCH_1):PAGE102
  C6P4    1      A CAP_A_0402V-0.1UF,16V,10%,X7R,A    I11 @BASEBOARD_FAB2_LIB.BASEBOARD_FAB2(SCH_1):PAGE102
  C6P6    1      A CAP_A_0402V-0.1UF,16V,10%,X7R,A    I12 @BASEBOARD_FAB2_LIB.BASEBOARD_FAB2(SCH_1):PAGE102
 C6P10    1      A CAP_A_0402V-0.1UF,16V,10%,X7R,A    I13 @BASEBOARD_FAB2_LIB.BASEBOARD_FAB2(SCH_1):PAGE102
  C6P5    1      A CAP_A_0402V-0.1UF,16V,10%,X7R,A    I14 @BASEBOARD_FAB2_LIB.BASEBOARD_FAB2(SCH_1):PAGE102
 C6P12    1      A CAP_A_0402V-0.1UF,16V,10%,X7R,A    I15 @BASEBOARD_FAB2_LIB.BASEBOARD_FAB2(SCH_1):PAGE102
 C6P11    1      A CAP_A_0402V-0.1UF,16V,10%,X7R,A    I16 @BASEBOARD_FAB2_LIB.BASEBOARD_FAB2(SCH_1):PAGE102
 R3D14    1      A RES_0603-2.2,1.0%,1/10W,CHIP,GA    I21 @BASEBOARD_FAB2_LIB.BASEBOARD_FAB2(SCH_1):PAGE102
 R6P25    1      A RES_0603-2.2,1.0%,1/10W,CHIP,GA    I26 @BASEBOARD_FAB2_LIB.BASEBOARD_FAB2(SCH_1):PAGE102
 R4D38    1      A RES_0402-10.0K,1%,1/16W,EMPTY,A    I37 @BASEBOARD_FAB2_LIB.BASEBOARD_FAB2(SCH_1):PAGE102
 R4D35    1      A RES_0402-10.0K,1%,1/16W,EMPTY,A    I38 @BASEBOARD_FAB2_LIB.BASEBOARD_FAB2(SCH_1):PAGE102
 R4D40    1      A RES_0402-4.75K,1%,1/16W,CHIP,GA    I45 @BASEBOARD_FAB2_LIB.BASEBOARD_FAB2(SCH_1):PAGE102
 R4D41    1      A RES_0402-4.75K,1%,1/16W,CHIP,GA    I53 @BASEBOARD_FAB2_LIB.BASEBOARD_FAB2(SCH_1):PAGE102
  C6P9    1      A CAP_A_0402V-0.1UF,16V,10%,X7R,A    I79 @BASEBOARD_FAB2_LIB.BASEBOARD_FAB2(SCH_1):PAGE102

P3V3_DB1200_A @BASEBOARD_FAB2_LIB.BASEBOARD_FAB2(SCH_1):P3V3_DB1200_A
 EU4D2    1   VDDA NB3W1200L_LCC-IC,H13585-001     I1 @BASEBOARD_FAB2_LIB.BASEBOARD_FAB2(SCH_1):PAGE102
 C4D24    1      A CAP_A_0402V-0.1UF,16V,10%,X7R,A    I18 @BASEBOARD_FAB2_LIB.BASEBOARD_FAB2(SCH_1):PAGE102
 C4D23    1      A CAP_A_0402V-1.0UF,6.3V,10%,X6SA    I19 @BASEBOARD_FAB2_LIB.BASEBOARD_FAB2(SCH_1):PAGE102
 R3D14    2      B RES_0603-2.2,1.0%,1/10W,CHIP,GA    I21 @BASEBOARD_FAB2_LIB.BASEBOARD_FAB2(SCH_1):PAGE102

P3V3_DB1200_R @BASEBOARD_FAB2_LIB.BASEBOARD_FAB2(SCH_1):P3V3_DB1200_R
 EU4D2    8   VDDR NB3W1200L_LCC-IC,H13585-001     I1 @BASEBOARD_FAB2_LIB.BASEBOARD_FAB2(SCH_1):PAGE102
 R6P25    2      B RES_0603-2.2,1.0%,1/10W,CHIP,GA    I26 @BASEBOARD_FAB2_LIB.BASEBOARD_FAB2(SCH_1):PAGE102
 C4D22    1      A CAP_A_0402V-0.1UF,16V,10%,X7R,A    I28 @BASEBOARD_FAB2_LIB.BASEBOARD_FAB2(SCH_1):PAGE102
 C4D27    1      A CAP_A_0402V-1.0UF,6.3V,10%,X6SA    I30 @BASEBOARD_FAB2_LIB.BASEBOARD_FAB2(SCH_1):PAGE102

P3V3_FB_ADC128_VCC @BASEBOARD_FAB2_LIB.BASEBOARD_FAB2(SCH_1):P3V3_FB_ADC128_VCC
 EU9G1    5     VP ADC128D818_SM-IC,H63642-001    I52 @BASEBOARD_FAB2_LIB.BASEBOARD_FAB2(SCH_1):PAGE165
 C9G19    1      A CAP_A_0402V-0.1UF,16V,10%,X7R,A    I61 @BASEBOARD_FAB2_LIB.BASEBOARD_FAB2(SCH_1):PAGE165
 C1U20    1      A CAP_0805-10UF,16V,10%,X7R,G106A    I67 @BASEBOARD_FAB2_LIB.BASEBOARD_FAB2(SCH_1):PAGE165
 FB1U2    2      B FERRITE_SMLF-60,FB,693286-001    I79 @BASEBOARD_FAB2_LIB.BASEBOARD_FAB2(SCH_1):PAGE165

P3V3_RTC_STBY @BASEBOARD_FAB2_LIB.BASEBOARD_FAB2(SCH_1):P3V3_RTC_STBY
  U7C1 AJ27 VCCPRTC LBG_CORE_QAT_EXT_D_BGA1-IC,H91A    I63 @BASEBOARD_FAB2_LIB.BASEBOARD_FAB2(SCH_1):PAGE122
 R7C10    1      A RES_0402-20.0K,1%,1/16W,CHIP,GA    I13 @BASEBOARD_FAB2_LIB.BASEBOARD_FAB2(SCH_1):PAGE137
  R3N4    1      A RES_0402-20.0K,1%,1/16W,CHIP,GA    I19 @BASEBOARD_FAB2_LIB.BASEBOARD_FAB2(SCH_1):PAGE137
 CR2U1    3      C DIODE2A_DUAL_SMLF-BAS70-05,DIOA    I53 @BASEBOARD_FAB2_LIB.BASEBOARD_FAB2(SCH_1):PAGE196
 C2U26    1      A CAP_A_0402V-1.0UF,6.3V,10%,X6SA   I102 @BASEBOARD_FAB2_LIB.BASEBOARD_FAB2(SCH_1):PAGE196

P3V3_STBY @BASEBOARD_FAB2_LIB.BASEBOARD_FAB2(SCH_1):P3V3_STBY
  R5N2    1      A RES_0402-1.8K,1%,1/16W,CHIP,G2A   I227 @BASEBOARD_FAB2_LIB.BASEBOARD_FAB2(SCH_1):PAGE21
  R5N1    1      A RES_0402-10.0K,1%,1/16W,CHIP,GA   I238 @BASEBOARD_FAB2_LIB.BASEBOARD_FAB2(SCH_1):PAGE21
  R5N5    1      A RES_0402-10.0K,1%,1/16W,CHIP,GA   I239 @BASEBOARD_FAB2_LIB.BASEBOARD_FAB2(SCH_1):PAGE21
  R5N3    1      A RES_0402-10.0K,1%,1/16W,CHIP,GA   I240 @BASEBOARD_FAB2_LIB.BASEBOARD_FAB2(SCH_1):PAGE21
  R5N4    1      A RES_0402-1.8K,1%,1/16W,CHIP,G2A   I241 @BASEBOARD_FAB2_LIB.BASEBOARD_FAB2(SCH_1):PAGE21
  R4R5    1      A RES_0402-4.75K,1%,1/16W,CHIP,GA   I258 @BASEBOARD_FAB2_LIB.BASEBOARD_FAB2(SCH_1):PAGE21
  U5D1 CY55  VCC33 SKX_EXT_B_BGA1-IC,TBD    I34 @BASEBOARD_FAB2_LIB.BASEBOARD_FAB2(SCH_1):PAGE38
  R8N1    1      A RES_0402-1.8K,1%,1/16W,CHIP,G2A   I157 @BASEBOARD_FAB2_LIB.BASEBOARD_FAB2(SCH_1):PAGE55
  R8N4    1      A RES_0402-1.8K,1%,1/16W,CHIP,G2A   I158 @BASEBOARD_FAB2_LIB.BASEBOARD_FAB2(SCH_1):PAGE55
  R8N3    1      A RES_0402-10.0K,1%,1/16W,CHIP,GA   I159 @BASEBOARD_FAB2_LIB.BASEBOARD_FAB2(SCH_1):PAGE55
  R8N5    1      A RES_0402-10.0K,1%,1/16W,CHIP,GA   I160 @BASEBOARD_FAB2_LIB.BASEBOARD_FAB2(SCH_1):PAGE55
  R8N2    1      A RES_0402-10.0K,1%,1/16W,CHIP,GA   I161 @BASEBOARD_FAB2_LIB.BASEBOARD_FAB2(SCH_1):PAGE55
 R6P39    1      A RES_0402-4.75K,1%,1/16W,CHIP,GA   I181 @BASEBOARD_FAB2_LIB.BASEBOARD_FAB2(SCH_1):PAGE55
  U2D1 CY55  VCC33 SKX_EXT_B_BGA1-IC,TBD    I33 @BASEBOARD_FAB2_LIB.BASEBOARD_FAB2(SCH_1):PAGE72
 R8D29    1      A RES_0402-4.75K,1%,1/16W,CHIP,GA    I26 @BASEBOARD_FAB2_LIB.BASEBOARD_FAB2(SCH_1):PAGE89
 R8D31    1      A RES_0402-4.75K,1%,1/16W,CHIP,GA    I27 @BASEBOARD_FAB2_LIB.BASEBOARD_FAB2(SCH_1):PAGE89
  R4U1    1      A RES_0402-4.75K,1%,1/16W,CHIP,GA    I91 @BASEBOARD_FAB2_LIB.BASEBOARD_FAB2(SCH_1):PAGE94
  C7E3    1      A CAP_A_0402V-0.1UF,16V,10%,X7R,A    I92 @BASEBOARD_FAB2_LIB.BASEBOARD_FAB2(SCH_1):PAGE95
  C7E4    1      A CAP_A_0402V-0.1UF,16V,10%,X7R,A   I115 @BASEBOARD_FAB2_LIB.BASEBOARD_FAB2(SCH_1):PAGE95
 R3P36    1      A RES_0402-1.00K,1%,1/16W,CHIP,GA    I36 @BASEBOARD_FAB2_LIB.BASEBOARD_FAB2(SCH_1):PAGE96
  U3P1   14    VCC GTL2014_SM-IC,D66151-001    I42 @BASEBOARD_FAB2_LIB.BASEBOARD_FAB2(SCH_1):PAGE96
  U4C2   14    VCC GTL2014_SM-IC,D66151-001    I46 @BASEBOARD_FAB2_LIB.BASEBOARD_FAB2(SCH_1):PAGE96
  R4C8    1      A RES_0402-1.00K,1%,1/16W,CHIP,GA    I55 @BASEBOARD_FAB2_LIB.BASEBOARD_FAB2(SCH_1):PAGE96
 C3P42    1      A CAP_A_0402V-1.0UF,6.3V,10%,X6SA    I73 @BASEBOARD_FAB2_LIB.BASEBOARD_FAB2(SCH_1):PAGE96
  C4C3    1      A CAP_A_0402V-1.0UF,6.3V,10%,X6SA    I75 @BASEBOARD_FAB2_LIB.BASEBOARD_FAB2(SCH_1):PAGE96
 FB2T2    1      A FERRITE_SMLF-600,FB,656554-043   I114 @BASEBOARD_FAB2_LIB.BASEBOARD_FAB2(SCH_1):PAGE101
 C2T28    1      A CAP_A_0402V-1.0UF,6.3V,10%,X6SA   I116 @BASEBOARD_FAB2_LIB.BASEBOARD_FAB2(SCH_1):PAGE101
  J8G1   25   IO25 SCONN200_H68296001_SM-CONN,H68A   I258 @BASEBOARD_FAB2_LIB.BASEBOARD_FAB2(SCH_1):PAGE108
 C2U23    1      A CAP_A_0402V-0.1UF,16V,10%,X7R,A   I315 @BASEBOARD_FAB2_LIB.BASEBOARD_FAB2(SCH_1):PAGE108
 C2U22    1      A CAP_A_0402V-0.1UF,16V,10%,X7R,A   I318 @BASEBOARD_FAB2_LIB.BASEBOARD_FAB2(SCH_1):PAGE108
 R1L13    2      B RES_0402-1.00K,1%,1/16W,CHIP,GA     I6 @BASEBOARD_FAB2_LIB.BASEBOARD_FAB2(SCH_1):PAGE111
 R9A14    2      B RES_0402-1.00K,1%,1/16W,CHIP,GA    I11 @BASEBOARD_FAB2_LIB.BASEBOARD_FAB2(SCH_1):PAGE111
 R1L23    2      B RES_0402-1.00K,1%,1/16W,CHIP,GA    I13 @BASEBOARD_FAB2_LIB.BASEBOARD_FAB2(SCH_1):PAGE111
 R1L28    1      A RES_0402-4.75K,1%,1/16W,CHIP,GA    I66 @BASEBOARD_FAB2_LIB.BASEBOARD_FAB2(SCH_1):PAGE111
 C1L11    1      A CAP_A_0402V-0.1UF,16V,10%,X7R,A    I87 @BASEBOARD_FAB2_LIB.BASEBOARD_FAB2(SCH_1):PAGE111
  U1M7    5    VCC NC7SB3157_SMLF-IC,C99406-001    I40 @BASEBOARD_FAB2_LIB.BASEBOARD_FAB2(SCH_1):PAGE112
 C1M36    1      A CAP_A_0402V-0.01UF,25V,10%,X7RA    I42 @BASEBOARD_FAB2_LIB.BASEBOARD_FAB2(SCH_1):PAGE112
 C1M37    1      A CAP_A_0402V-1.0UF,6.3V,10%,X6SA    I47 @BASEBOARD_FAB2_LIB.BASEBOARD_FAB2(SCH_1):PAGE112
 C1M30    1      A CAP_A_0402V-0.01UF,25V,10%,X7RA   I131 @BASEBOARD_FAB2_LIB.BASEBOARD_FAB2(SCH_1):PAGE112
  C1L1    1      A CAP_0402-1.0UF,16V,10%,X6S,D97A   I136 @BASEBOARD_FAB2_LIB.BASEBOARD_FAB2(SCH_1):PAGE112
 C1L19    1      A CAP_0402-1.0UF,16V,10%,X6S,D97A   I140 @BASEBOARD_FAB2_LIB.BASEBOARD_FAB2(SCH_1):PAGE112
  U1M2    5    VCC NC7SB3157_SMLF-IC,C99406-001   I107 @BASEBOARD_FAB2_LIB.BASEBOARD_FAB2(SCH_1):PAGE113
 C1M31    1      A CAP_A_0402V-0.01UF,25V,10%,X7RA   I116 @BASEBOARD_FAB2_LIB.BASEBOARD_FAB2(SCH_1):PAGE113
 C1M32    1      A CAP_A_0402V-1.0UF,6.3V,10%,X6SA   I117 @BASEBOARD_FAB2_LIB.BASEBOARD_FAB2(SCH_1):PAGE113
 C1M28    1      A CAP_A_0402V-0.01UF,25V,10%,X7RA   I119 @BASEBOARD_FAB2_LIB.BASEBOARD_FAB2(SCH_1):PAGE113
  U2M1    5    VCC NC7SB3157_SMLF-IC,C99406-001   I255 @BASEBOARD_FAB2_LIB.BASEBOARD_FAB2(SCH_1):PAGE113
 C1M34    1      A CAP_A_0402V-0.01UF,25V,10%,X7RA   I265 @BASEBOARD_FAB2_LIB.BASEBOARD_FAB2(SCH_1):PAGE113
 C1M35    1      A CAP_A_0402V-0.01UF,25V,10%,X7RA   I266 @BASEBOARD_FAB2_LIB.BASEBOARD_FAB2(SCH_1):PAGE113
 C1L20    1      A CAP_A_0402V-0.01UF,25V,10%,X7RA   I267 @BASEBOARD_FAB2_LIB.BASEBOARD_FAB2(SCH_1):PAGE113
 R3N13    1      A RES_0402-4.75K,1%,1/16W,CHIP,GA    I71 @BASEBOARD_FAB2_LIB.BASEBOARD_FAB2(SCH_1):PAGE118
  R2N6    1      A RES_0402-10.0K,1%,1/16W,CHIP,GA   I128 @BASEBOARD_FAB2_LIB.BASEBOARD_FAB2(SCH_1):PAGE118
  C7D1    1      A CAP_A_0402V-0.1UF,16V,10%,X7R,A   I136 @BASEBOARD_FAB2_LIB.BASEBOARD_FAB2(SCH_1):PAGE118
 R7C23    1      A RES_0402-10.0K,1%,1/16W,CHIP,GA   I144 @BASEBOARD_FAB2_LIB.BASEBOARD_FAB2(SCH_1):PAGE118
 R9A20    2      B RES_0402-221,1.0%,1/16W,CHIP,GA   I178 @BASEBOARD_FAB2_LIB.BASEBOARD_FAB2(SCH_1):PAGE119
 R9A18    1      A RES_0402-4.75K,1%,1/16W,CHIP,GA   I183 @BASEBOARD_FAB2_LIB.BASEBOARD_FAB2(SCH_1):PAGE119
 R9A21    1      A RES_0402-4.75K,1%,1/16W,CHIP,GA   I186 @BASEBOARD_FAB2_LIB.BASEBOARD_FAB2(SCH_1):PAGE119
 R2U48    1      A RES_0402-4.75K,1%,1/16W,CHIP,GA   I213 @BASEBOARD_FAB2_LIB.BASEBOARD_FAB2(SCH_1):PAGE119
 R3N10    1      A RES_0402-10.0K,1%,1/16W,CHIP,GA    I37 @BASEBOARD_FAB2_LIB.BASEBOARD_FAB2(SCH_1):PAGE121
  U7C1 BA46 VCCP_3P3<0> LBG_CORE_QAT_EXT_D_BGA1-IC,H91A    I63 @BASEBOARD_FAB2_LIB.BASEBOARD_FAB2(SCH_1):PAGE122
  U7C1 BA45 VCCP_3P3<1> LBG_CORE_QAT_EXT_D_BGA1-IC,H91A    I63 @BASEBOARD_FAB2_LIB.BASEBOARD_FAB2(SCH_1):PAGE122
  U7C1 AD24 VCCP_3P3<2> LBG_CORE_QAT_EXT_D_BGA1-IC,H91A    I63 @BASEBOARD_FAB2_LIB.BASEBOARD_FAB2(SCH_1):PAGE122
  U7C1 AN24 VCCP_3P3<5> LBG_CORE_QAT_EXT_D_BGA1-IC,H91A    I63 @BASEBOARD_FAB2_LIB.BASEBOARD_FAB2(SCH_1):PAGE122
  U7C1 AH24 VCCPDSW_3P3 LBG_CORE_QAT_EXT_D_BGA1-IC,H91A    I63 @BASEBOARD_FAB2_LIB.BASEBOARD_FAB2(SCH_1):PAGE122
  U7C1 AW24 VCCPGPPA LBG_CORE_QAT_EXT_D_BGA1-IC,H91A    I63 @BASEBOARD_FAB2_LIB.BASEBOARD_FAB2(SCH_1):PAGE122
  U7C1 BE26 VCCPGPPB LBG_CORE_QAT_EXT_D_BGA1-IC,H91A    I63 @BASEBOARD_FAB2_LIB.BASEBOARD_FAB2(SCH_1):PAGE122
  U7C1 BE40 VCCPGPPC LBG_CORE_QAT_EXT_D_BGA1-IC,H91A    I63 @BASEBOARD_FAB2_LIB.BASEBOARD_FAB2(SCH_1):PAGE122
  U7C1 BA43 VCCPGPPD LBG_CORE_QAT_EXT_D_BGA1-IC,H91A    I63 @BASEBOARD_FAB2_LIB.BASEBOARD_FAB2(SCH_1):PAGE122
  U7C1 BE44 VCCPGPPE LBG_CORE_QAT_EXT_D_BGA1-IC,H91A    I63 @BASEBOARD_FAB2_LIB.BASEBOARD_FAB2(SCH_1):PAGE122
  U7C1 AU27 VCCPGPPF LBG_CORE_QAT_EXT_D_BGA1-IC,H91A    I63 @BASEBOARD_FAB2_LIB.BASEBOARD_FAB2(SCH_1):PAGE122
  U7C1 BA26 VCCPGPPG LBG_CORE_QAT_EXT_D_BGA1-IC,H91A    I63 @BASEBOARD_FAB2_LIB.BASEBOARD_FAB2(SCH_1):PAGE122
  U7C1 BA24 VCCPGPPH LBG_CORE_QAT_EXT_D_BGA1-IC,H91A    I63 @BASEBOARD_FAB2_LIB.BASEBOARD_FAB2(SCH_1):PAGE122
  U7C1 BB26 VCCPGPPJ LBG_CORE_QAT_EXT_D_BGA1-IC,H91A    I63 @BASEBOARD_FAB2_LIB.BASEBOARD_FAB2(SCH_1):PAGE122
  U7C1 AU24 VCCPGPPK LBG_CORE_QAT_EXT_D_BGA1-IC,H91A    I63 @BASEBOARD_FAB2_LIB.BASEBOARD_FAB2(SCH_1):PAGE122
  U7C1 AG29 VCCPRTCPRIM_3P3 LBG_CORE_QAT_EXT_D_BGA1-IC,H91A    I63 @BASEBOARD_FAB2_LIB.BASEBOARD_FAB2(SCH_1):PAGE122
  U7C1 AR24 VCCPSPI LBG_CORE_QAT_EXT_D_BGA1-IC,H91A    I63 @BASEBOARD_FAB2_LIB.BASEBOARD_FAB2(SCH_1):PAGE122
  U7C1 BA48 VCCPUSBDSW_3P3 LBG_CORE_QAT_EXT_D_BGA1-IC,H91A    I63 @BASEBOARD_FAB2_LIB.BASEBOARD_FAB2(SCH_1):PAGE122
  R8E6    1      A RES_0402-1.00K,1%,1/16W,EMPTY,A    I21 @BASEBOARD_FAB2_LIB.BASEBOARD_FAB2(SCH_1):PAGE125
 R8C18    1      A RES_0402-1.00K,1%,1/16W,CHIP,GA    I40 @BASEBOARD_FAB2_LIB.BASEBOARD_FAB2(SCH_1):PAGE125
 R8D13    1      A RES_0402-10.0K,1%,1/16W,CHIP,GA    I52 @BASEBOARD_FAB2_LIB.BASEBOARD_FAB2(SCH_1):PAGE125
 R7D13    1      A RES_0402-8.2K,1%,1/16W,EMPTY,GA    I60 @BASEBOARD_FAB2_LIB.BASEBOARD_FAB2(SCH_1):PAGE125
 R8D16    1      A RES_0402-10.0K,1%,1/16W,EMPTY,A    I71 @BASEBOARD_FAB2_LIB.BASEBOARD_FAB2(SCH_1):PAGE125
  R3N2    1      A RES_0402-4.75K,1%,1/16W,EMPTY,A    I72 @BASEBOARD_FAB2_LIB.BASEBOARD_FAB2(SCH_1):PAGE125
 R2U30    1      A RES_0402-4.75K,1%,1/16W,CHIP,GA    I76 @BASEBOARD_FAB2_LIB.BASEBOARD_FAB2(SCH_1):PAGE125
 R3N17    1      A RES_0402-1.00K,1%,1/16W,EMPTY,A    I78 @BASEBOARD_FAB2_LIB.BASEBOARD_FAB2(SCH_1):PAGE125
 R2N14    1      A RES_0402-1.00K,1%,1/16W,EMPTY,A    I83 @BASEBOARD_FAB2_LIB.BASEBOARD_FAB2(SCH_1):PAGE125
 R2N10    1      A RES_0402-4.75K,1%,1/16W,CHIP,GA    I10 @BASEBOARD_FAB2_LIB.BASEBOARD_FAB2(SCH_1):PAGE126
 R1D35    1      A RES_0402-4.75K,1%,1/16W,CHIP,GA    I12 @BASEBOARD_FAB2_LIB.BASEBOARD_FAB2(SCH_1):PAGE126
  R8C9    1      A RES_0402-4.75K,1%,1/16W,CHIP,GA    I20 @BASEBOARD_FAB2_LIB.BASEBOARD_FAB2(SCH_1):PAGE126
 R3P62    1      A RES_0402-4.75K,1%,1/16W,EMPTY,A    I22 @BASEBOARD_FAB2_LIB.BASEBOARD_FAB2(SCH_1):PAGE126
  C7D2    1      A CAP_0603-10UF,6.3V,20%,X6S,E15A     I2 @BASEBOARD_FAB2_LIB.BASEBOARD_FAB2(SCH_1):PAGE130
 C2N26    1      A CAP_A_0402V-1.0UF,6.3V,10%,X6SA     I4 @BASEBOARD_FAB2_LIB.BASEBOARD_FAB2(SCH_1):PAGE130
 C2N19    1      A CAP_A_0402V-1.0UF,6.3V,10%,X6SA     I7 @BASEBOARD_FAB2_LIB.BASEBOARD_FAB2(SCH_1):PAGE130
 C2N24    1      A CAP_0603-10UF,6.3V,20%,X6S,E15A     I8 @BASEBOARD_FAB2_LIB.BASEBOARD_FAB2(SCH_1):PAGE130
 C2N22    1      A CAP_0603-10UF,6.3V,20%,X6S,E15A     I9 @BASEBOARD_FAB2_LIB.BASEBOARD_FAB2(SCH_1):PAGE130
 C2N20    1      A CAP_A_0402V-1.0UF,6.3V,10%,X6SA    I12 @BASEBOARD_FAB2_LIB.BASEBOARD_FAB2(SCH_1):PAGE130
 C2N21    1      A CAP_0603-10UF,6.3V,20%,X6S,E15A    I15 @BASEBOARD_FAB2_LIB.BASEBOARD_FAB2(SCH_1):PAGE130
  C8C3    1      A CAP_0603-10UF,6.3V,20%,X6S,E15A    I19 @BASEBOARD_FAB2_LIB.BASEBOARD_FAB2(SCH_1):PAGE130
  C8C4    1      A CAP_0603-10UF,6.3V,20%,X6S,E15A    I20 @BASEBOARD_FAB2_LIB.BASEBOARD_FAB2(SCH_1):PAGE130
  C8C5    1      A CAP_0603-10UF,6.3V,20%,X6S,E15A    I21 @BASEBOARD_FAB2_LIB.BASEBOARD_FAB2(SCH_1):PAGE130
  C8C6    1      A CAP_0603-10UF,6.3V,20%,X6S,E15A    I22 @BASEBOARD_FAB2_LIB.BASEBOARD_FAB2(SCH_1):PAGE130
 C2N23    1      A CAP_0603-10UF,6.3V,20%,X6S,E15A    I24 @BASEBOARD_FAB2_LIB.BASEBOARD_FAB2(SCH_1):PAGE130
 C2N14    1      A CAP_0603-10UF,6.3V,20%,X6S,E15A    I25 @BASEBOARD_FAB2_LIB.BASEBOARD_FAB2(SCH_1):PAGE130
 C2N17    1      A CAP_0603-10UF,6.3V,20%,X6S,E15A    I28 @BASEBOARD_FAB2_LIB.BASEBOARD_FAB2(SCH_1):PAGE130
 C2N18    1      A CAP_A_0402V-1.0UF,6.3V,10%,X6SA    I29 @BASEBOARD_FAB2_LIB.BASEBOARD_FAB2(SCH_1):PAGE130
 C2N25    1      A CAP_A_0402V-1.0UF,6.3V,10%,X6SA    I34 @BASEBOARD_FAB2_LIB.BASEBOARD_FAB2(SCH_1):PAGE130
 C2M16    1      A CAP_A_0402V-1.0UF,6.3V,10%,X6SA    I37 @BASEBOARD_FAB2_LIB.BASEBOARD_FAB2(SCH_1):PAGE130
 C3N23    1      A CAP_A_0402V-1.0UF,6.3V,10%,X6SA    I42 @BASEBOARD_FAB2_LIB.BASEBOARD_FAB2(SCH_1):PAGE130
  R7D8    1      A RES_0402-10.0K,1%,1/16W,CHIP,GA   I200 @BASEBOARD_FAB2_LIB.BASEBOARD_FAB2(SCH_1):PAGE133
 R7D10    1      A RES_0402-10.0K,1%,1/16W,CHIP,GA   I202 @BASEBOARD_FAB2_LIB.BASEBOARD_FAB2(SCH_1):PAGE133
 R7D12    1      A RES_0402-10.0K,1%,1/16W,CHIP,GA   I237 @BASEBOARD_FAB2_LIB.BASEBOARD_FAB2(SCH_1):PAGE133
  R7D3    1      A RES_0402-4.75K,1%,1/16W,CHIP,GA   I243 @BASEBOARD_FAB2_LIB.BASEBOARD_FAB2(SCH_1):PAGE133
  R7D4    1      A RES_0402-10.0K,1%,1/16W,CHIP,GA   I245 @BASEBOARD_FAB2_LIB.BASEBOARD_FAB2(SCH_1):PAGE133
 R2N16    1      A RES_0402-10.0K,1%,1/16W,CHIP,GA   I247 @BASEBOARD_FAB2_LIB.BASEBOARD_FAB2(SCH_1):PAGE133
  R2R5    1      A RES_0402-1.00K,1%,1/16W,CHIP,GA   I258 @BASEBOARD_FAB2_LIB.BASEBOARD_FAB2(SCH_1):PAGE133
  R2N9    1      A RES_0402-10.0K,1%,1/16W,CHIP,GA   I267 @BASEBOARD_FAB2_LIB.BASEBOARD_FAB2(SCH_1):PAGE133
 R8B23    1      A RES_0402-1.00K,1%,1/16W,CHIP,GA   I280 @BASEBOARD_FAB2_LIB.BASEBOARD_FAB2(SCH_1):PAGE133
 R8B30    1      A RES_0402-1.00K,1%,1/16W,CHIP,GA   I282 @BASEBOARD_FAB2_LIB.BASEBOARD_FAB2(SCH_1):PAGE133
  R2M4    1      A RES_0402-1.00K,1%,1/16W,CHIP,GA   I284 @BASEBOARD_FAB2_LIB.BASEBOARD_FAB2(SCH_1):PAGE133
  R8C4    1      A RES_0402-1.00K,1%,1/16W,CHIP,GA   I286 @BASEBOARD_FAB2_LIB.BASEBOARD_FAB2(SCH_1):PAGE133
  R7B6    1      A RES_0402-10.0K,1%,1/16W,CHIP,GA   I295 @BASEBOARD_FAB2_LIB.BASEBOARD_FAB2(SCH_1):PAGE133
  R7C8    1      A RES_0402-10.0K,1%,1/16W,CHIP,GA   I296 @BASEBOARD_FAB2_LIB.BASEBOARD_FAB2(SCH_1):PAGE133
  R7C5    1      A RES_0402-10.0K,1%,1/16W,CHIP,GA   I297 @BASEBOARD_FAB2_LIB.BASEBOARD_FAB2(SCH_1):PAGE133
 R8D14    1      A RES_0402-4.75K,1%,1/16W,CHIP,GA   I301 @BASEBOARD_FAB2_LIB.BASEBOARD_FAB2(SCH_1):PAGE133
  R8C6    1      A RES_0402-4.75K,1%,1/16W,CHIP,GA   I303 @BASEBOARD_FAB2_LIB.BASEBOARD_FAB2(SCH_1):PAGE133
  R8C2    1      A RES_0402-4.75K,1%,1/16W,CHIP,GA   I304 @BASEBOARD_FAB2_LIB.BASEBOARD_FAB2(SCH_1):PAGE133
  R7D6    1      A RES_0402-4.75K,1%,1/16W,CHIP,GA   I306 @BASEBOARD_FAB2_LIB.BASEBOARD_FAB2(SCH_1):PAGE133
 R8B31    1      A RES_0402-4.75K,1%,1/16W,CHIP,GA   I307 @BASEBOARD_FAB2_LIB.BASEBOARD_FAB2(SCH_1):PAGE133
  R2N7    1      A RES_0402-4.75K,1%,1/16W,CHIP,GA   I309 @BASEBOARD_FAB2_LIB.BASEBOARD_FAB2(SCH_1):PAGE133
  R8C1    1      A RES_0402-4.75K,1%,1/16W,CHIP,GA   I326 @BASEBOARD_FAB2_LIB.BASEBOARD_FAB2(SCH_1):PAGE133
  R8C7    1      A RES_0402-4.75K,1%,1/16W,CHIP,GA   I327 @BASEBOARD_FAB2_LIB.BASEBOARD_FAB2(SCH_1):PAGE133
  R7D7    1      A RES_0402-1.00K,1%,1/16W,CHIP,GA   I331 @BASEBOARD_FAB2_LIB.BASEBOARD_FAB2(SCH_1):PAGE133
  R7D2    1      A RES_0402-1.00K,1%,1/16W,CHIP,GA   I332 @BASEBOARD_FAB2_LIB.BASEBOARD_FAB2(SCH_1):PAGE133
 R8C25    1      A RES_0402-4.75K,1%,1/16W,CHIP,GA   I333 @BASEBOARD_FAB2_LIB.BASEBOARD_FAB2(SCH_1):PAGE133
 R2N32    1      A RES_0402-4.75K,1%,1/16W,CHIP,GA   I341 @BASEBOARD_FAB2_LIB.BASEBOARD_FAB2(SCH_1):PAGE133
  R2M8    1      A RES_0402-1.5K,1%,1/16W,CHIP,G2A   I349 @BASEBOARD_FAB2_LIB.BASEBOARD_FAB2(SCH_1):PAGE133
 R2N29    1      A RES_0402-1.5K,1%,1/16W,CHIP,G2A   I352 @BASEBOARD_FAB2_LIB.BASEBOARD_FAB2(SCH_1):PAGE133
  R8E3    1      A RES_0402-10.0K,1%,1/16W,CHIP,GA   I355 @BASEBOARD_FAB2_LIB.BASEBOARD_FAB2(SCH_1):PAGE133
 R2P22    1      A RES_0402-10.0K,1%,1/16W,CHIP,GA   I360 @BASEBOARD_FAB2_LIB.BASEBOARD_FAB2(SCH_1):PAGE133
 R8D44    1      A RES_0402-10.0K,1%,1/16W,CHIP,GA   I362 @BASEBOARD_FAB2_LIB.BASEBOARD_FAB2(SCH_1):PAGE133
 R2P17    1      A RES_0402-4.75K,1%,1/16W,CHIP,GA     I3 @BASEBOARD_FAB2_LIB.BASEBOARD_FAB2(SCH_1):PAGE134
 R2P19    1      A RES_0402-10.0K,1%,1/16W,CHIP,GA   I107 @BASEBOARD_FAB2_LIB.BASEBOARD_FAB2(SCH_1):PAGE135
 R2N23    1      A RES_0402-10.0K,1%,1/16W,CHIP,GA   I112 @BASEBOARD_FAB2_LIB.BASEBOARD_FAB2(SCH_1):PAGE135
 R9A12    2      B RES_0402-2.21K,1%,1/16W,CHIP,GA   I117 @BASEBOARD_FAB2_LIB.BASEBOARD_FAB2(SCH_1):PAGE135
 R8D21    1      A RES_0402-1.00K,1%,1/16W,CHIP,GA   I120 @BASEBOARD_FAB2_LIB.BASEBOARD_FAB2(SCH_1):PAGE135
 R7D30    1      A RES_0402-4.75K,1%,1/16W,CHIP,GA   I121 @BASEBOARD_FAB2_LIB.BASEBOARD_FAB2(SCH_1):PAGE135
 R9A16    2      B RES_0402-2.21K,1%,1/16W,CHIP,GA   I129 @BASEBOARD_FAB2_LIB.BASEBOARD_FAB2(SCH_1):PAGE135
 R7G26    1      A RES_0402-10.0K,1%,1/16W,CHIP,GA   I101 @BASEBOARD_FAB2_LIB.BASEBOARD_FAB2(SCH_1):PAGE136
  C8E8    1      A CAP_A_0402V-0.1UF,16V,10%,X7R,A   I128 @BASEBOARD_FAB2_LIB.BASEBOARD_FAB2(SCH_1):PAGE136
 R8E14    1      A RES_0402-4.75K,1%,1/16W,CHIP,GA   I133 @BASEBOARD_FAB2_LIB.BASEBOARD_FAB2(SCH_1):PAGE136
 R7G31    1      A RES_0402-1.00K,1%,1/16W,CHIP,GA   I139 @BASEBOARD_FAB2_LIB.BASEBOARD_FAB2(SCH_1):PAGE136
 R2N28    1      A RES_0402-10.0K,1%,1/16W,CHIP,GA   I147 @BASEBOARD_FAB2_LIB.BASEBOARD_FAB2(SCH_1):PAGE136
 R7G27    1      A RES_0402-1.00K,1%,1/16W,CHIP,GA   I155 @BASEBOARD_FAB2_LIB.BASEBOARD_FAB2(SCH_1):PAGE136
 R7C13    1      A RES_0402-10.0K,1%,1/16W,CHIP,GA    I67 @BASEBOARD_FAB2_LIB.BASEBOARD_FAB2(SCH_1):PAGE137
 R2T53    1      A RES_0402-665,1.0%,1/16W,CHIP,GA    I83 @BASEBOARD_FAB2_LIB.BASEBOARD_FAB2(SCH_1):PAGE138
 R2T54    1      A RES_0402-665,1.0%,1/16W,CHIP,GA    I84 @BASEBOARD_FAB2_LIB.BASEBOARD_FAB2(SCH_1):PAGE138
 R8D17    1      A RES_0402-1.37K,1%,1/16W,CHIP,GA    I87 @BASEBOARD_FAB2_LIB.BASEBOARD_FAB2(SCH_1):PAGE138
 R8D15    1      A RES_0402-1.37K,1%,1/16W,CHIP,GA    I88 @BASEBOARD_FAB2_LIB.BASEBOARD_FAB2(SCH_1):PAGE138
  R2N8    1      A RES_0402-665,1.0%,1/16W,CHIP,GA    I89 @BASEBOARD_FAB2_LIB.BASEBOARD_FAB2(SCH_1):PAGE138
  R2N5    1      A RES_0402-665,1.0%,1/16W,CHIP,GA    I90 @BASEBOARD_FAB2_LIB.BASEBOARD_FAB2(SCH_1):PAGE138
 R8C16    1      A RES_0402-2.0K,1%,1/16W,CHIP,G2A    I91 @BASEBOARD_FAB2_LIB.BASEBOARD_FAB2(SCH_1):PAGE138
 R8C15    1      A RES_0402-2.0K,1%,1/16W,CHIP,G2A    I92 @BASEBOARD_FAB2_LIB.BASEBOARD_FAB2(SCH_1):PAGE138
 R8B24    1      A RES_0402-3.3K,5%,1/16W,CHIP,G2A    I95 @BASEBOARD_FAB2_LIB.BASEBOARD_FAB2(SCH_1):PAGE138
 R8B26    1      A RES_0402-3.3K,5%,1/16W,CHIP,G2A    I96 @BASEBOARD_FAB2_LIB.BASEBOARD_FAB2(SCH_1):PAGE138
 R2U11    1      A RES_0402-665,1.0%,1/16W,CHIP,GA    I97 @BASEBOARD_FAB2_LIB.BASEBOARD_FAB2(SCH_1):PAGE138
  R2U3    1      A RES_0402-665,1.0%,1/16W,CHIP,GA    I98 @BASEBOARD_FAB2_LIB.BASEBOARD_FAB2(SCH_1):PAGE138
 EU9E1   64 VDD3P3<0> SPRINGVILLE_SM1-IC,G47144-004    I72 @BASEBOARD_FAB2_LIB.BASEBOARD_FAB2(SCH_1):PAGE139
 EU9E1   41 VDD3P3<2> SPRINGVILLE_SM1-IC,G47144-004    I72 @BASEBOARD_FAB2_LIB.BASEBOARD_FAB2(SCH_1):PAGE139
 EU9E1   27 VDD3P3<3> SPRINGVILLE_SM1-IC,G47144-004    I72 @BASEBOARD_FAB2_LIB.BASEBOARD_FAB2(SCH_1):PAGE139
 EU9E1   10 VDD3P3<4> SPRINGVILLE_SM1-IC,G47144-004    I72 @BASEBOARD_FAB2_LIB.BASEBOARD_FAB2(SCH_1):PAGE139
 C1R22    1      A CAP_0603-10UF,6.3V,20%,X6S,E15A   I136 @BASEBOARD_FAB2_LIB.BASEBOARD_FAB2(SCH_1):PAGE139
  C9F2    1      A CAP_1210-47UF,16V,20%,EMPTY,D3A   I140 @BASEBOARD_FAB2_LIB.BASEBOARD_FAB2(SCH_1):PAGE139
 C1R13    1      A CAP_0603-10UF,6.3V,20%,X6S,E15A   I142 @BASEBOARD_FAB2_LIB.BASEBOARD_FAB2(SCH_1):PAGE139
 C1R20    1      A CAP_A_0402V-0.1UF,16V,10%,X7R,A   I143 @BASEBOARD_FAB2_LIB.BASEBOARD_FAB2(SCH_1):PAGE139
  C1T3    1      A CAP_A_0402V-0.1UF,16V,10%,X7R,A   I144 @BASEBOARD_FAB2_LIB.BASEBOARD_FAB2(SCH_1):PAGE139
 C1R14    1      A CAP_A_0402V-0.1UF,16V,10%,X7R,A   I145 @BASEBOARD_FAB2_LIB.BASEBOARD_FAB2(SCH_1):PAGE139
 C1R21    1      A CAP_A_0402V-0.1UF,16V,10%,X7R,A   I146 @BASEBOARD_FAB2_LIB.BASEBOARD_FAB2(SCH_1):PAGE139
  R9F5    1      A RES_0402-3.32K,1%,1/16W,CHIP,GA   I173 @BASEBOARD_FAB2_LIB.BASEBOARD_FAB2(SCH_1):PAGE139
  R9E2    1      A RES_0402-10.0K,1%,1/16W,CHIP,GA   I177 @BASEBOARD_FAB2_LIB.BASEBOARD_FAB2(SCH_1):PAGE139
  R9E3    1      A RES_0402-10.0K,1%,1/16W,CHIP,GA   I178 @BASEBOARD_FAB2_LIB.BASEBOARD_FAB2(SCH_1):PAGE139
  R9E1    1      A RES_0402-10.0K,1%,1/16W,CHIP,GA   I179 @BASEBOARD_FAB2_LIB.BASEBOARD_FAB2(SCH_1):PAGE139
 R9E22    2      B RES_0402-10.0K,1%,1/16W,CHIP,GA   I181 @BASEBOARD_FAB2_LIB.BASEBOARD_FAB2(SCH_1):PAGE139
  R9E7    1      A RES_0402-3.32K,1%,1/16W,CHIP,GA   I193 @BASEBOARD_FAB2_LIB.BASEBOARD_FAB2(SCH_1):PAGE139
  R9E4    1      A RES_0402-10.0K,1%,1/16W,CHIP,GA   I200 @BASEBOARD_FAB2_LIB.BASEBOARD_FAB2(SCH_1):PAGE139
 R1T34    1      A RES_0603-0,5.0%,1/10W,CHIP,G22A   I239 @BASEBOARD_FAB2_LIB.BASEBOARD_FAB2(SCH_1):PAGE139
  U9E1    8    VCC M25PE16_SM-IC,H77797-001     I1 @BASEBOARD_FAB2_LIB.BASEBOARD_FAB2(SCH_1):PAGE140
 C1R25    1      A CAP_A_0402V-0.1UF,16V,10%,X7R,A     I3 @BASEBOARD_FAB2_LIB.BASEBOARD_FAB2(SCH_1):PAGE140
  R1R9    1      A RES_0402-3.32K,1%,1/16W,CHIP,GA    I10 @BASEBOARD_FAB2_LIB.BASEBOARD_FAB2(SCH_1):PAGE140
  R1R3    1      A RES_0402-3.32K,1%,1/16W,CHIP,GA    I11 @BASEBOARD_FAB2_LIB.BASEBOARD_FAB2(SCH_1):PAGE140
  R1R7    1      A RES_0402-20.0K,1%,1/16W,CHIP,GA    I12 @BASEBOARD_FAB2_LIB.BASEBOARD_FAB2(SCH_1):PAGE140
  C9G7    1      A CAP_A_0402V-0.1UF,16V,10%,X7R,A    I33 @BASEBOARD_FAB2_LIB.BASEBOARD_FAB2(SCH_1):PAGE141
  C9G2    1      A CAP_0402LF-470PF,50V,10%,X7R,AA    I36 @BASEBOARD_FAB2_LIB.BASEBOARD_FAB2(SCH_1):PAGE141
  R9G4    2      B RES_0402-0.0,5%,1/16W,CHIP,G21A    I56 @BASEBOARD_FAB2_LIB.BASEBOARD_FAB2(SCH_1):PAGE141
 JA9G1   L2     L2 CONN17_H71061002_PIP1-CONN,H71A   I109 @BASEBOARD_FAB2_LIB.BASEBOARD_FAB2(SCH_1):PAGE141
 R8E23    2      B RES_0402-4.75K,1%,1/16W,CHIP,GA     I3 @BASEBOARD_FAB2_LIB.BASEBOARD_FAB2(SCH_1):PAGE142
  C8E5    1      A CAP_A_0402V-0.1UF,16V,10%,X7R,A    I20 @BASEBOARD_FAB2_LIB.BASEBOARD_FAB2(SCH_1):PAGE142
 R8E30    1      A RES_0402-10.0K,1%,1/16W,CHIP,GA    I23 @BASEBOARD_FAB2_LIB.BASEBOARD_FAB2(SCH_1):PAGE142
 R8E36    1      A RES_0402-10.0K,1%,1/16W,CHIP,GA    I28 @BASEBOARD_FAB2_LIB.BASEBOARD_FAB2(SCH_1):PAGE142
  R7F6    1      A RES_0402-4.75K,1%,1/16W,EMPTY,A    I90 @BASEBOARD_FAB2_LIB.BASEBOARD_FAB2(SCH_1):PAGE153
  R7F5    1      A RES_0402-4.75K,1%,1/16W,CHIP,GA    I94 @BASEBOARD_FAB2_LIB.BASEBOARD_FAB2(SCH_1):PAGE153
  C7F2    1      A CAP_A_0402V-1.0UF,6.3V,10%,X6SA   I130 @BASEBOARD_FAB2_LIB.BASEBOARD_FAB2(SCH_1):PAGE153
  C7F1    1      A CAP_A_0402V-0.01UF,25V,10%,X7RA   I131 @BASEBOARD_FAB2_LIB.BASEBOARD_FAB2(SCH_1):PAGE153
  C3T5    1      A CAP_A_0402V-0.01UF,25V,10%,X7RA   I136 @BASEBOARD_FAB2_LIB.BASEBOARD_FAB2(SCH_1):PAGE153
  C3T4    1      A CAP_A_0402V-1.0UF,6.3V,10%,X6SA   I138 @BASEBOARD_FAB2_LIB.BASEBOARD_FAB2(SCH_1):PAGE153
 R7F32    1      A RES_0402-10.0K,1%,1/16W,CHIP,GA   I140 @BASEBOARD_FAB2_LIB.BASEBOARD_FAB2(SCH_1):PAGE153
  U7F1    2    VCC W25Q256_XSOI-IC,H25002-001   I146 @BASEBOARD_FAB2_LIB.BASEBOARD_FAB2(SCH_1):PAGE153
  R3T3    1      A RES_0402-4.75K,1%,1/16W,EMPTY,A   I150 @BASEBOARD_FAB2_LIB.BASEBOARD_FAB2(SCH_1):PAGE153
  R3T5    1      A RES_0402-4.75K,1%,1/16W,CHIP,GA   I152 @BASEBOARD_FAB2_LIB.BASEBOARD_FAB2(SCH_1):PAGE153
  U3T1    2    VCC W25Q256_XSOI-IC,H25002-001   I165 @BASEBOARD_FAB2_LIB.BASEBOARD_FAB2(SCH_1):PAGE153
 R7F28    1      A RES_0402-10.0K,1%,1/16W,CHIP,GA   I168 @BASEBOARD_FAB2_LIB.BASEBOARD_FAB2(SCH_1):PAGE153
  R3T4    1      A RES_0402-10.0K,1%,1/16W,CHIP,GA   I174 @BASEBOARD_FAB2_LIB.BASEBOARD_FAB2(SCH_1):PAGE153
 R3T12    1      A RES_0402-10.0K,1%,1/16W,CHIP,GA   I178 @BASEBOARD_FAB2_LIB.BASEBOARD_FAB2(SCH_1):PAGE153
 C8E18    1      A CAP_A_0402V-0.1UF,16V,10%,X7R,A    I14 @BASEBOARD_FAB2_LIB.BASEBOARD_FAB2(SCH_1):PAGE154
  U8F1   16    VCC PI3B3257A_TSSOPLF-IC,E16801-001    I74 @BASEBOARD_FAB2_LIB.BASEBOARD_FAB2(SCH_1):PAGE154
  U2T1   16    VCC PI3B3257A_TSSOPLF-IC,E16801-001    I75 @BASEBOARD_FAB2_LIB.BASEBOARD_FAB2(SCH_1):PAGE154
  C2T1    1      A CAP_A_0402V-0.1UF,16V,10%,X7R,A    I94 @BASEBOARD_FAB2_LIB.BASEBOARD_FAB2(SCH_1):PAGE154
 R2T11    1      A RES_0402-4.75K,1%,1/16W,CHIP,GA   I105 @BASEBOARD_FAB2_LIB.BASEBOARD_FAB2(SCH_1):PAGE154
  R2T8    1      A RES_0402-10.0K,1%,1/16W,CHIP,GA   I106 @BASEBOARD_FAB2_LIB.BASEBOARD_FAB2(SCH_1):PAGE154
  R2T6    1      A RES_0402-4.75K,1%,1/16W,CHIP,GA   I127 @BASEBOARD_FAB2_LIB.BASEBOARD_FAB2(SCH_1):PAGE154
 C2T12    1      A CAP_A_0402V-0.1UF,16V,10%,X7R,A   I132 @BASEBOARD_FAB2_LIB.BASEBOARD_FAB2(SCH_1):PAGE154
  C2T8    1      A CAP_A_0402V-0.1UF,16V,10%,X7R,A   I135 @BASEBOARD_FAB2_LIB.BASEBOARD_FAB2(SCH_1):PAGE154
  R9A7    1      A RES_0402-2.21K,1%,1/16W,CHIP,GA    I80 @BASEBOARD_FAB2_LIB.BASEBOARD_FAB2(SCH_1):PAGE155
 C1T56    1      A CAP_A_0402V-0.1UF,16V,10%,X7R,A   I184 @BASEBOARD_FAB2_LIB.BASEBOARD_FAB2(SCH_1):PAGE155
 R2T34    1      A RES_0402-4.75K,1%,1/16W,CHIP,GA   I206 @BASEBOARD_FAB2_LIB.BASEBOARD_FAB2(SCH_1):PAGE156
 R2T35    1      A RES_0402-4.75K,1%,1/16W,CHIP,GA   I207 @BASEBOARD_FAB2_LIB.BASEBOARD_FAB2(SCH_1):PAGE156
 R2T22    1      A RES_0402-10.0K,1%,1/16W,CHIP,GA   I210 @BASEBOARD_FAB2_LIB.BASEBOARD_FAB2(SCH_1):PAGE156
 R8F26    1      A RES_0402-10.0K,1%,1/16W,CHIP,GA   I211 @BASEBOARD_FAB2_LIB.BASEBOARD_FAB2(SCH_1):PAGE156
 R8E22    1      A RES_0402-4.75K,1%,1/16W,CHIP,GA   I215 @BASEBOARD_FAB2_LIB.BASEBOARD_FAB2(SCH_1):PAGE156
  R2U2    1      A RES_0402-4.75K,1%,1/16W,CHIP,GA   I265 @BASEBOARD_FAB2_LIB.BASEBOARD_FAB2(SCH_1):PAGE156
  R8G2    1      A RES_0402-4.75K,1%,1/16W,CHIP,GA   I267 @BASEBOARD_FAB2_LIB.BASEBOARD_FAB2(SCH_1):PAGE156
 C2T35    1      A CAP_A_0402V-0.1UF,16V,10%,X7R,A   I273 @BASEBOARD_FAB2_LIB.BASEBOARD_FAB2(SCH_1):PAGE156
 C8F16    1      A CAP_A_0402V-0.1UF,16V,10%,X7R,A   I275 @BASEBOARD_FAB2_LIB.BASEBOARD_FAB2(SCH_1):PAGE156
 R1C34    1      A RES_0402-10.0K,1%,1/16W,CHIP,GA   I320 @BASEBOARD_FAB2_LIB.BASEBOARD_FAB2(SCH_1):PAGE156
 R3P54    1      A RES_0402-3.32K,1%,1/16W,EMPTY,A   I331 @BASEBOARD_FAB2_LIB.BASEBOARD_FAB2(SCH_1):PAGE156
 R1C35    1      A RES_0402-3.32K,1%,1/16W,EMPTY,A   I336 @BASEBOARD_FAB2_LIB.BASEBOARD_FAB2(SCH_1):PAGE156
 R8F23    1      A RES_0402-2.21K,1%,1/16W,CHIP,GA   I296 @BASEBOARD_FAB2_LIB.BASEBOARD_FAB2(SCH_1):PAGE157
 R2T29    1      A RES_0402-2.21K,1%,1/16W,CHIP,GA   I298 @BASEBOARD_FAB2_LIB.BASEBOARD_FAB2(SCH_1):PAGE157
 R8F24    1      A RES_0402-4.75K,1%,1/16W,CHIP,GA   I316 @BASEBOARD_FAB2_LIB.BASEBOARD_FAB2(SCH_1):PAGE157
  R2T5    1      A RES_0402-1.00K,1%,1/16W,CHIP,GA   I326 @BASEBOARD_FAB2_LIB.BASEBOARD_FAB2(SCH_1):PAGE157
  R2T7    1      A RES_0402-1.00K,1%,1/16W,CHIP,GA   I327 @BASEBOARD_FAB2_LIB.BASEBOARD_FAB2(SCH_1):PAGE157
 R8D25    1      A RES_0402-4.75K,1%,1/16W,CHIP,GA   I335 @BASEBOARD_FAB2_LIB.BASEBOARD_FAB2(SCH_1):PAGE157
 R3N12    1      A RES_0402-4.75K,1%,1/16W,CHIP,GA   I342 @BASEBOARD_FAB2_LIB.BASEBOARD_FAB2(SCH_1):PAGE157
 R3N11    1      A RES_0402-4.75K,1%,1/16W,CHIP,GA   I344 @BASEBOARD_FAB2_LIB.BASEBOARD_FAB2(SCH_1):PAGE157
  R2M2    1      A RES_0402-4.75K,1%,1/16W,CHIP,GA   I346 @BASEBOARD_FAB2_LIB.BASEBOARD_FAB2(SCH_1):PAGE157
  R2M5    1      A RES_0402-4.75K,1%,1/16W,CHIP,GA   I348 @BASEBOARD_FAB2_LIB.BASEBOARD_FAB2(SCH_1):PAGE157
 R8E19    1      A RES_0402-4.75K,1%,1/16W,EMPTY,A   I361 @BASEBOARD_FAB2_LIB.BASEBOARD_FAB2(SCH_1):PAGE157
  R2U4    1      A RES_0402-4.75K,1%,1/16W,CHIP,GA   I367 @BASEBOARD_FAB2_LIB.BASEBOARD_FAB2(SCH_1):PAGE157
  C2T3    1      A CAP_A_0402V-0.1UF,16V,10%,X7R,A   I370 @BASEBOARD_FAB2_LIB.BASEBOARD_FAB2(SCH_1):PAGE157
  C8D1    1      A CAP_A_0402V-0.1UF,16V,10%,X7R,A   I376 @BASEBOARD_FAB2_LIB.BASEBOARD_FAB2(SCH_1):PAGE157
  R1L7    1      A RES_0402-4.75K,1%,1/16W,CHIP,GA   I382 @BASEBOARD_FAB2_LIB.BASEBOARD_FAB2(SCH_1):PAGE157
 R8E32    1      A RES_0402-4.75K,1%,1/16W,CHIP,GA   I385 @BASEBOARD_FAB2_LIB.BASEBOARD_FAB2(SCH_1):PAGE157
 C1T10    1      A CAP_A_0402V-0.1UF,16V,10%,X7R,A    I70 @BASEBOARD_FAB2_LIB.BASEBOARD_FAB2(SCH_1):PAGE158
  U9F2    8    VCC FSA3357_SM-IC,C63273-001    I74 @BASEBOARD_FAB2_LIB.BASEBOARD_FAB2(SCH_1):PAGE158
  U9F1    8    VCC FSA3357_SM-IC,C63273-001    I75 @BASEBOARD_FAB2_LIB.BASEBOARD_FAB2(SCH_1):PAGE158
 C1T11    1      A CAP_A_0402V-0.1UF,16V,10%,X7R,A    I97 @BASEBOARD_FAB2_LIB.BASEBOARD_FAB2(SCH_1):PAGE158
 R1L43    2      B RES_0402-330,5%,1/16W,CHIP,G21A   I131 @BASEBOARD_FAB2_LIB.BASEBOARD_FAB2(SCH_1):PAGE158
 R1L44    2      B RES_0402-330,5%,1/16W,CHIP,G21A   I136 @BASEBOARD_FAB2_LIB.BASEBOARD_FAB2(SCH_1):PAGE158
  R8G3    1      A RES_0402-2.26K,1.0%,1/16W,EMPTA   I210 @BASEBOARD_FAB2_LIB.BASEBOARD_FAB2(SCH_1):PAGE159
  R8G6    1      A RES_0402-2.26K,1.0%,1/16W,EMPTA   I212 @BASEBOARD_FAB2_LIB.BASEBOARD_FAB2(SCH_1):PAGE159
  R2U5    1      A RES_0402-2.26K,1.0%,1/16W,CHIPA   I214 @BASEBOARD_FAB2_LIB.BASEBOARD_FAB2(SCH_1):PAGE159
 R2U13    1      A RES_0402-2.26K,1.0%,1/16W,CHIPA   I216 @BASEBOARD_FAB2_LIB.BASEBOARD_FAB2(SCH_1):PAGE159
  R1T3    1      A RES_0402-665,1.0%,1/16W,CHIP,GA    I46 @BASEBOARD_FAB2_LIB.BASEBOARD_FAB2(SCH_1):PAGE160
  R1T2    1      A RES_0402-665,1.0%,1/16W,CHIP,GA    I49 @BASEBOARD_FAB2_LIB.BASEBOARD_FAB2(SCH_1):PAGE160
  R1F1    1      A RES_0402-4.75K,1%,1/16W,CHIP,GA    I45 @BASEBOARD_FAB2_LIB.BASEBOARD_FAB2(SCH_1):PAGE161
 R1B21    1      A RES_0402-4.75K,1%,1/16W,CHIP,GA    I70 @BASEBOARD_FAB2_LIB.BASEBOARD_FAB2(SCH_1):PAGE161
 C2U27    1      A CAP_A_0402V-0.1UF,16V,10%,X7R,A    I90 @BASEBOARD_FAB2_LIB.BASEBOARD_FAB2(SCH_1):PAGE161
 C2U28    1      A CAP_A_0402V-0.1UF,16V,10%,X7R,A    I93 @BASEBOARD_FAB2_LIB.BASEBOARD_FAB2(SCH_1):PAGE161
 C1E22    1      A CAP_A_0402V-0.1UF,16V,10%,X7R,A   I113 @BASEBOARD_FAB2_LIB.BASEBOARD_FAB2(SCH_1):PAGE161
 R1E11    1      A RES_0402-10.0K,1%,1/16W,EMPTY,A   I120 @BASEBOARD_FAB2_LIB.BASEBOARD_FAB2(SCH_1):PAGE161
 R1B24    1      A RES_0402-4.75K,1%,1/16W,CHIP,GA   I126 @BASEBOARD_FAB2_LIB.BASEBOARD_FAB2(SCH_1):PAGE161
  R9T5    1      A RES_0402-4.75K,1%,1/16W,CHIP,GA   I135 @BASEBOARD_FAB2_LIB.BASEBOARD_FAB2(SCH_1):PAGE161
 R8F16    1      A RES_0402-4.75K,1%,1/16W,EMPTY,A     I8 @BASEBOARD_FAB2_LIB.BASEBOARD_FAB2(SCH_1):PAGE162
 R8F14    1      A RES_0402-4.75K,1%,1/16W,CHIP,GA     I9 @BASEBOARD_FAB2_LIB.BASEBOARD_FAB2(SCH_1):PAGE162
 R8F34    1      A RES_0402-4.75K,1%,1/16W,CHIP,GA    I22 @BASEBOARD_FAB2_LIB.BASEBOARD_FAB2(SCH_1):PAGE162
 R8F13    1      A RES_0402-4.75K,1%,1/16W,CHIP,GA    I23 @BASEBOARD_FAB2_LIB.BASEBOARD_FAB2(SCH_1):PAGE162
  C8F5    1      A CAP_A_0402V-0.01UF,25V,10%,X7RA    I28 @BASEBOARD_FAB2_LIB.BASEBOARD_FAB2(SCH_1):PAGE162
  C8F4    1      A CAP_A_0402V-1.0UF,6.3V,10%,X6SA    I30 @BASEBOARD_FAB2_LIB.BASEBOARD_FAB2(SCH_1):PAGE162
  U8F2    2    VCC W25Q128_SKT16-IC,H12709-001    I32 @BASEBOARD_FAB2_LIB.BASEBOARD_FAB2(SCH_1):PAGE162
  U1B2    8   VCCB PCA9517_SM-IC,G77073-001-GND=GA     I1 @BASEBOARD_FAB2_LIB.BASEBOARD_FAB2(SCH_1):PAGE163
  C9M7    1      A CAP_A_0402V-0.1UF,16V,10%,X7R,A    I12 @BASEBOARD_FAB2_LIB.BASEBOARD_FAB2(SCH_1):PAGE163
 R9M17    1      A RES_0402-2.0K,1%,1/16W,CHIP,G2A    I15 @BASEBOARD_FAB2_LIB.BASEBOARD_FAB2(SCH_1):PAGE163
 R9M16    1      A RES_0402-2.0K,1%,1/16W,CHIP,G2A    I16 @BASEBOARD_FAB2_LIB.BASEBOARD_FAB2(SCH_1):PAGE163
  R1T5    1      A RES_0402-2.7K,1%,1/16W,EMPTY,GA    I11 @BASEBOARD_FAB2_LIB.BASEBOARD_FAB2(SCH_1):PAGE164
  R1T6    1      A RES_0402-2.7K,1%,1/16W,EMPTY,GA    I13 @BASEBOARD_FAB2_LIB.BASEBOARD_FAB2(SCH_1):PAGE164
  R1T4    1      A RES_0402-2.7K,1%,1/16W,CHIP,G2A    I14 @BASEBOARD_FAB2_LIB.BASEBOARD_FAB2(SCH_1):PAGE164
 R1U21    1      A RES_0402-2.7K,1%,1/16W,CHIP,G2A    I24 @BASEBOARD_FAB2_LIB.BASEBOARD_FAB2(SCH_1):PAGE164
 R1U24    1      A RES_0402-2.7K,1%,1/16W,EMPTY,GA    I25 @BASEBOARD_FAB2_LIB.BASEBOARD_FAB2(SCH_1):PAGE164
 R1U22    1      A RES_0402-2.7K,1%,1/16W,CHIP,G2A    I27 @BASEBOARD_FAB2_LIB.BASEBOARD_FAB2(SCH_1):PAGE164
 R1U23    1      A RES_0402-2.7K,1%,1/16W,EMPTY,GA    I28 @BASEBOARD_FAB2_LIB.BASEBOARD_FAB2(SCH_1):PAGE164
 R2N17    1      A RES_0402-2.7K,1%,1/16W,EMPTY,GA    I29 @BASEBOARD_FAB2_LIB.BASEBOARD_FAB2(SCH_1):PAGE164
 R9G23    1      A RES_0402-4.75K,1%,1/16W,EMPTY,A    I57 @BASEBOARD_FAB2_LIB.BASEBOARD_FAB2(SCH_1):PAGE165
 R9G25    1      A RES_0402-4.75K,1%,1/16W,EMPTY,A    I58 @BASEBOARD_FAB2_LIB.BASEBOARD_FAB2(SCH_1):PAGE165
 R9G21    1      A RES_0402-4.75K,1%,1/16W,CHIP,GA    I69 @BASEBOARD_FAB2_LIB.BASEBOARD_FAB2(SCH_1):PAGE165
 FB1U2    1      A FERRITE_SMLF-60,FB,693286-001    I79 @BASEBOARD_FAB2_LIB.BASEBOARD_FAB2(SCH_1):PAGE165
  U9B4    8     VP TMP421_TSSOP-IC,G62962-001     I1 @BASEBOARD_FAB2_LIB.BASEBOARD_FAB2(SCH_1):PAGE167
  U1E1    8     VP TMP421_TSSOP-IC,G62962-001    I30 @BASEBOARD_FAB2_LIB.BASEBOARD_FAB2(SCH_1):PAGE167
  R1E9    1      A RES_0402-1.00K,1%,1/16W,CHIP,GA    I34 @BASEBOARD_FAB2_LIB.BASEBOARD_FAB2(SCH_1):PAGE167
  R9B6    1      A RES_0402-1.00K,1%,1/16W,CHIP,GA    I35 @BASEBOARD_FAB2_LIB.BASEBOARD_FAB2(SCH_1):PAGE167
 R1E10    1      A RES_0402-1.00K,1%,1/16W,CHIP,GA    I38 @BASEBOARD_FAB2_LIB.BASEBOARD_FAB2(SCH_1):PAGE167
  C9B7    1      A CAP_A_0402V-0.1UF,16V,10%,X7R,A    I39 @BASEBOARD_FAB2_LIB.BASEBOARD_FAB2(SCH_1):PAGE167
 C9R14    1      A CAP_A_0402V-0.1UF,16V,10%,X7R,A    I41 @BASEBOARD_FAB2_LIB.BASEBOARD_FAB2(SCH_1):PAGE167
 C9R13    1      A CAP_A_0402V-0.1UF,16V,10%,X7R,A    I42 @BASEBOARD_FAB2_LIB.BASEBOARD_FAB2(SCH_1):PAGE167
 R8D28    1      A RES_0402-1.00K,1%,1/16W,CHIP,GA    I70 @BASEBOARD_FAB2_LIB.BASEBOARD_FAB2(SCH_1):PAGE167
 R2U38    1      A RES_0402-665,1.0%,1/16W,CHIP,GA    I80 @BASEBOARD_FAB2_LIB.BASEBOARD_FAB2(SCH_1):PAGE167
 R2U39    1      A RES_0402-665,1.0%,1/16W,CHIP,GA    I83 @BASEBOARD_FAB2_LIB.BASEBOARD_FAB2(SCH_1):PAGE167
 R1L36    1      A RES_0402-1.00K,1%,1/16W,CHIP,GA    I11 @BASEBOARD_FAB2_LIB.BASEBOARD_FAB2(SCH_1):PAGE168
 R1L38    1      A RES_0402-1.00K,1%,1/16W,CHIP,GA    I22 @BASEBOARD_FAB2_LIB.BASEBOARD_FAB2(SCH_1):PAGE168
 R1U39    1      A RES_0402-5.11K,1%,1/16W,CHIP,GA    I88 @BASEBOARD_FAB2_LIB.BASEBOARD_FAB2(SCH_1):PAGE169
 R1U49    1      A RES_0402-2.7K,1%,1/16W,CHIP,G2A   I163 @BASEBOARD_FAB2_LIB.BASEBOARD_FAB2(SCH_1):PAGE169
 R9G35    1      A RES_0402-2.7K,1%,1/16W,CHIP,G2A   I164 @BASEBOARD_FAB2_LIB.BASEBOARD_FAB2(SCH_1):PAGE169
  R2P3    1      A RES_0402-4.75K,1%,1/16W,CHIP,GA     I2 @BASEBOARD_FAB2_LIB.BASEBOARD_FAB2(SCH_1):PAGE170
  C2P1    1      A CAP_A_0402V-0.1UF,16V,10%,X7R,A     I8 @BASEBOARD_FAB2_LIB.BASEBOARD_FAB2(SCH_1):PAGE170
 C1R27    1      A CAP_A_0402V-0.1UF,16V,10%,X7R,A    I30 @BASEBOARD_FAB2_LIB.BASEBOARD_FAB2(SCH_1):PAGE170
  C8D2    1      A CAP_A_0402V-0.1UF,16V,10%,X7R,A    I33 @BASEBOARD_FAB2_LIB.BASEBOARD_FAB2(SCH_1):PAGE170
  C8E2    1      A CAP_A_0402V-0.1UF,16V,10%,X7R,A    I40 @BASEBOARD_FAB2_LIB.BASEBOARD_FAB2(SCH_1):PAGE170
 C1R28    1      A CAP_A_0402V-0.1UF,16V,10%,X7R,A    I49 @BASEBOARD_FAB2_LIB.BASEBOARD_FAB2(SCH_1):PAGE170
  R2P8    1      A RES_0402-560,5%,1/16W,CHIP,G21A    I52 @BASEBOARD_FAB2_LIB.BASEBOARD_FAB2(SCH_1):PAGE170
  R2T3    1      A RES_0402-4.75K,1%,1/16W,CHIP,GA    I54 @BASEBOARD_FAB2_LIB.BASEBOARD_FAB2(SCH_1):PAGE170
  R2P5    1      A RES_0402-4.75K,1%,1/16W,CHIP,GA    I56 @BASEBOARD_FAB2_LIB.BASEBOARD_FAB2(SCH_1):PAGE170
 R2P13    1      A RES_0402-4.75K,1%,1/16W,CHIP,GA    I61 @BASEBOARD_FAB2_LIB.BASEBOARD_FAB2(SCH_1):PAGE170
  R9F3    1      A RES_0402-4.75K,1%,1/16W,CHIP,GA    I65 @BASEBOARD_FAB2_LIB.BASEBOARD_FAB2(SCH_1):PAGE170
 R8D26    1      A RES_0402-4.75K,1%,1/16W,CHIP,GA    I71 @BASEBOARD_FAB2_LIB.BASEBOARD_FAB2(SCH_1):PAGE170
  R1R5    1      A RES_0402-4.75K,1%,1/16W,CHIP,GA    I73 @BASEBOARD_FAB2_LIB.BASEBOARD_FAB2(SCH_1):PAGE170
 R1L27    1      A RES_0402-4.75K,1%,1/16W,CHIP,GA     I5 @BASEBOARD_FAB2_LIB.BASEBOARD_FAB2(SCH_1):PAGE175
 R1L19    1      A RES_0402-4.75K,1%,1/16W,EMPTY,A    I24 @BASEBOARD_FAB2_LIB.BASEBOARD_FAB2(SCH_1):PAGE175
 C1L17    1      A CAP_A_0402V-0.1UF,16V,10%,X7R,A    I37 @BASEBOARD_FAB2_LIB.BASEBOARD_FAB2(SCH_1):PAGE175
  C1L9    1      A CAP_A_0402V-0.1UF,16V,10%,X7R,A    I38 @BASEBOARD_FAB2_LIB.BASEBOARD_FAB2(SCH_1):PAGE175
  C9A3    1      A CAP_A_0402V-0.1UF,16V,10%,X7R,A    I40 @BASEBOARD_FAB2_LIB.BASEBOARD_FAB2(SCH_1):PAGE175
 R1L33    2      B RES_0402-221,1.0%,1/16W,CHIP,GA    I45 @BASEBOARD_FAB2_LIB.BASEBOARD_FAB2(SCH_1):PAGE175
 R1M24    1      A RES_0402-10.0K,1%,1/16W,CHIP,GA   I105 @BASEBOARD_FAB2_LIB.BASEBOARD_FAB2(SCH_1):PAGE176
 R9F28    1      A RES_0402-221,1.0%,1/16W,CHIP,GA    I72 @BASEBOARD_FAB2_LIB.BASEBOARD_FAB2(SCH_1):PAGE177
 R9F30    1      A RES_0402-4.75K,1%,1/16W,CHIP,GA    I76 @BASEBOARD_FAB2_LIB.BASEBOARD_FAB2(SCH_1):PAGE177
 R9F52    1      A RES_0402-4.75K,1%,1/16W,CHIP,GA    I82 @BASEBOARD_FAB2_LIB.BASEBOARD_FAB2(SCH_1):PAGE177
 R2L12    1      A RES_0402-2.0K,1%,1/16W,CHIP,G2A     I2 @BASEBOARD_FAB2_LIB.BASEBOARD_FAB2(SCH_1):PAGE178
 R2L15    1      A RES_0402-2.0K,1%,1/16W,CHIP,G2A    I12 @BASEBOARD_FAB2_LIB.BASEBOARD_FAB2(SCH_1):PAGE178
 R2L11    1      A RES_0402-2.0K,1%,1/16W,CHIP,G2A    I13 @BASEBOARD_FAB2_LIB.BASEBOARD_FAB2(SCH_1):PAGE178
  R2L6    1      A RES_0402-2.0K,1%,1/16W,CHIP,G2A    I17 @BASEBOARD_FAB2_LIB.BASEBOARD_FAB2(SCH_1):PAGE178
  R2L4    1      A RES_0402-2.0K,1%,1/16W,CHIP,G2A    I18 @BASEBOARD_FAB2_LIB.BASEBOARD_FAB2(SCH_1):PAGE178
  R2L5    1      A RES_0402-2.0K,1%,1/16W,CHIP,G2A    I20 @BASEBOARD_FAB2_LIB.BASEBOARD_FAB2(SCH_1):PAGE178
  J1F3    1    IO1 CONN8_H62179001_PIP-CONN,H6217A   I189 @BASEBOARD_FAB2_LIB.BASEBOARD_FAB2(SCH_1):PAGE181
  R7D5    1      A RES_0402-2.26K,1.0%,1/16W,CHIPA   I199 @BASEBOARD_FAB2_LIB.BASEBOARD_FAB2(SCH_1):PAGE181
  R7D9    1      A RES_0402-2.26K,1.0%,1/16W,CHIPA   I200 @BASEBOARD_FAB2_LIB.BASEBOARD_FAB2(SCH_1):PAGE181
 R3P61    1      A RES_0402-2.26K,1.0%,1/16W,CHIPA   I201 @BASEBOARD_FAB2_LIB.BASEBOARD_FAB2(SCH_1):PAGE181
  C8E1    1      A CAP_A_0402V-0.1UF,16V,10%,X7R,A   I253 @BASEBOARD_FAB2_LIB.BASEBOARD_FAB2(SCH_1):PAGE181
 EU9F3   29    VDD PI7C9X1172_QFN-IC,H66899-001     I1 @BASEBOARD_FAB2_LIB.BASEBOARD_FAB2(SCH_1):PAGE183
 R9F47    1      A RES_0402-4.75K,1%,1/16W,CHIP,GA     I4 @BASEBOARD_FAB2_LIB.BASEBOARD_FAB2(SCH_1):PAGE183
 C9F19    1      A CAP_A_0402V-0.1UF,16V,10%,X7R,A     I7 @BASEBOARD_FAB2_LIB.BASEBOARD_FAB2(SCH_1):PAGE183
 R9F48    1      A RES_0402-4.75K,1%,1/16W,EMPTY,A    I13 @BASEBOARD_FAB2_LIB.BASEBOARD_FAB2(SCH_1):PAGE183
 R9F49    1      A RES_0402-4.75K,1%,1/16W,EMPTY,A    I14 @BASEBOARD_FAB2_LIB.BASEBOARD_FAB2(SCH_1):PAGE183
 R9F55    1      A RES_0402-4.75K,1%,1/16W,CHIP,GA    I30 @BASEBOARD_FAB2_LIB.BASEBOARD_FAB2(SCH_1):PAGE183
  J8E1    7    IO7 SCONN11_H67026001_SM-CONN,H670A    I87 @BASEBOARD_FAB2_LIB.BASEBOARD_FAB2(SCH_1):PAGE184
 R2P16    1      A RES_0402-10.0K,1%,1/16W,CHIP,GA   I113 @BASEBOARD_FAB2_LIB.BASEBOARD_FAB2(SCH_1):PAGE185
  C2P9    1      A CAP_A_0402V-0.1UF,16V,10%,X7R,A   I117 @BASEBOARD_FAB2_LIB.BASEBOARD_FAB2(SCH_1):PAGE185
 C1M20    1      A CAP_A_0402V-0.1UF,16V,10%,X7R,A   I270 @BASEBOARD_FAB2_LIB.BASEBOARD_FAB2(SCH_1):PAGE186
 C1M25    1      A CAP_A_0402V-1.0UF,6.3V,10%,X6SA   I335 @BASEBOARD_FAB2_LIB.BASEBOARD_FAB2(SCH_1):PAGE186
  J9B3   12   IO12 SCONN120_A28699018_SM-SCONN,A2A   I336 @BASEBOARD_FAB2_LIB.BASEBOARD_FAB2(SCH_1):PAGE186
  J9B3   13   IO13 SCONN120_A28699018_SM-SCONN,A2A   I336 @BASEBOARD_FAB2_LIB.BASEBOARD_FAB2(SCH_1):PAGE186
 R1R18    1      A RES_0402-2.21K,1%,1/16W,CHIP,GA    I88 @BASEBOARD_FAB2_LIB.BASEBOARD_FAB2(SCH_1):PAGE188
 R1R19    1      A RES_0402-2.21K,1%,1/16W,CHIP,GA    I89 @BASEBOARD_FAB2_LIB.BASEBOARD_FAB2(SCH_1):PAGE188
 R1R21    1      A RES_0402-2.21K,1%,1/16W,CHIP,GA    I90 @BASEBOARD_FAB2_LIB.BASEBOARD_FAB2(SCH_1):PAGE188
 R1R20    1      A RES_0402-2.21K,1%,1/16W,CHIP,GA    I91 @BASEBOARD_FAB2_LIB.BASEBOARD_FAB2(SCH_1):PAGE188
 R1R22    1      A RES_0402-2.21K,1%,1/16W,CHIP,GA    I92 @BASEBOARD_FAB2_LIB.BASEBOARD_FAB2(SCH_1):PAGE188
 R1R16    1      A RES_0402-2.21K,1%,1/16W,CHIP,GA    I93 @BASEBOARD_FAB2_LIB.BASEBOARD_FAB2(SCH_1):PAGE188
 R1R17    1      A RES_0402-2.21K,1%,1/16W,CHIP,GA    I94 @BASEBOARD_FAB2_LIB.BASEBOARD_FAB2(SCH_1):PAGE188
 R1R23    1      A RES_0402-2.21K,1%,1/16W,CHIP,GA    I95 @BASEBOARD_FAB2_LIB.BASEBOARD_FAB2(SCH_1):PAGE188
 R3R15    1      A RES_0402-1.00K,1%,1/16W,CHIP,GA    I44 @BASEBOARD_FAB2_LIB.BASEBOARD_FAB2(SCH_1):PAGE189
 CR3U1    2      A DIODE_SMLF-1N5819HW,IC,D55839-A    I49 @BASEBOARD_FAB2_LIB.BASEBOARD_FAB2(SCH_1):PAGE189
 R8G20    1      A RES_0402-10.0K,1%,1/16W,CHIP,GA    I50 @BASEBOARD_FAB2_LIB.BASEBOARD_FAB2(SCH_1):PAGE189
 R7G23    1      A RES_0402-10.0K,1%,1/16W,CHIP,GA    I51 @BASEBOARD_FAB2_LIB.BASEBOARD_FAB2(SCH_1):PAGE189
 R7G22    1      A RES_0402-10.0K,1%,1/16W,CHIP,GA    I53 @BASEBOARD_FAB2_LIB.BASEBOARD_FAB2(SCH_1):PAGE189
  R2R7    1      A RES_0402-4.75K,1%,1/16W,CHIP,GA   I172 @BASEBOARD_FAB2_LIB.BASEBOARD_FAB2(SCH_1):PAGE191
 R7D42    1      A RES_0402-4.75K,1%,1/16W,CHIP,GA   I193 @BASEBOARD_FAB2_LIB.BASEBOARD_FAB2(SCH_1):PAGE191
  C2P8    1      A CAP_A_0402V-0.01UF,25V,10%,X7RA     I1 @BASEBOARD_FAB2_LIB.BASEBOARD_FAB2(SCH_1):PAGE192
  C2P5    1      A CAP_A_0402V-0.1UF,16V,10%,X7R,A     I3 @BASEBOARD_FAB2_LIB.BASEBOARD_FAB2(SCH_1):PAGE192
  C3R1    1      A CAP_A_0402V-0.1UF,16V,10%,X7R,A     I4 @BASEBOARD_FAB2_LIB.BASEBOARD_FAB2(SCH_1):PAGE192
 C3P43    1      A CAP_A_0402V-0.1UF,16V,10%,X7R,A     I6 @BASEBOARD_FAB2_LIB.BASEBOARD_FAB2(SCH_1):PAGE192
  C3R3    1      A CAP_A_0402V-0.1UF,16V,10%,X7R,A     I7 @BASEBOARD_FAB2_LIB.BASEBOARD_FAB2(SCH_1):PAGE192
  C2R1    1      A CAP_A_0402V-0.1UF,16V,10%,X7R,A     I8 @BASEBOARD_FAB2_LIB.BASEBOARD_FAB2(SCH_1):PAGE192
  C2P2    1      A CAP_A_0402V-0.1UF,16V,10%,X7R,A     I9 @BASEBOARD_FAB2_LIB.BASEBOARD_FAB2(SCH_1):PAGE192
  C3R2    1      A CAP_A_0402V-0.1UF,16V,10%,X7R,A    I10 @BASEBOARD_FAB2_LIB.BASEBOARD_FAB2(SCH_1):PAGE192
 C3P51    1      A CAP_A_0402V-0.1UF,16V,10%,X7R,A    I11 @BASEBOARD_FAB2_LIB.BASEBOARD_FAB2(SCH_1):PAGE192
 C3P47    1      A CAP_A_0402V-0.1UF,16V,10%,X7R,A    I12 @BASEBOARD_FAB2_LIB.BASEBOARD_FAB2(SCH_1):PAGE192
  U8D7   A1 VCC<0> LCMXO2_A_256BGA-IC,H63395-001    I14 @BASEBOARD_FAB2_LIB.BASEBOARD_FAB2(SCH_1):PAGE192
  U8D7  A16 VCC<1> LCMXO2_A_256BGA-IC,H63395-001    I14 @BASEBOARD_FAB2_LIB.BASEBOARD_FAB2(SCH_1):PAGE192
  U8D7   T1 VCC<2> LCMXO2_A_256BGA-IC,H63395-001    I14 @BASEBOARD_FAB2_LIB.BASEBOARD_FAB2(SCH_1):PAGE192
  U8D7  T16 VCC<3> LCMXO2_A_256BGA-IC,H63395-001    I14 @BASEBOARD_FAB2_LIB.BASEBOARD_FAB2(SCH_1):PAGE192
  U8D7   G7 VCC<4> LCMXO2_A_256BGA-IC,H63395-001    I14 @BASEBOARD_FAB2_LIB.BASEBOARD_FAB2(SCH_1):PAGE192
  U8D7  G10 VCC<5> LCMXO2_A_256BGA-IC,H63395-001    I14 @BASEBOARD_FAB2_LIB.BASEBOARD_FAB2(SCH_1):PAGE192
  U8D7   K7 VCC<6> LCMXO2_A_256BGA-IC,H63395-001    I14 @BASEBOARD_FAB2_LIB.BASEBOARD_FAB2(SCH_1):PAGE192
  U8D7  K10 VCC<7> LCMXO2_A_256BGA-IC,H63395-001    I14 @BASEBOARD_FAB2_LIB.BASEBOARD_FAB2(SCH_1):PAGE192
  U8D7   G8 VCCIO0<0> LCMXO2_A_256BGA-IC,H63395-001    I14 @BASEBOARD_FAB2_LIB.BASEBOARD_FAB2(SCH_1):PAGE192
  U8D7  D12 VCCIO0<1> LCMXO2_A_256BGA-IC,H63395-001    I14 @BASEBOARD_FAB2_LIB.BASEBOARD_FAB2(SCH_1):PAGE192
  U8D7   G9 VCCIO0<2> LCMXO2_A_256BGA-IC,H63395-001    I14 @BASEBOARD_FAB2_LIB.BASEBOARD_FAB2(SCH_1):PAGE192
  U8D7   D5 VCCIO0<3> LCMXO2_A_256BGA-IC,H63395-001    I14 @BASEBOARD_FAB2_LIB.BASEBOARD_FAB2(SCH_1):PAGE192
  U8D7  E13 VCCIO1<0> LCMXO2_A_256BGA-IC,H63395-001    I14 @BASEBOARD_FAB2_LIB.BASEBOARD_FAB2(SCH_1):PAGE192
  U8D7  H10 VCCIO1<1> LCMXO2_A_256BGA-IC,H63395-001    I14 @BASEBOARD_FAB2_LIB.BASEBOARD_FAB2(SCH_1):PAGE192
  U8D7  J10 VCCIO1<2> LCMXO2_A_256BGA-IC,H63395-001    I14 @BASEBOARD_FAB2_LIB.BASEBOARD_FAB2(SCH_1):PAGE192
  U8D7  M13 VCCIO1<3> LCMXO2_A_256BGA-IC,H63395-001    I14 @BASEBOARD_FAB2_LIB.BASEBOARD_FAB2(SCH_1):PAGE192
  U8D7   K9 VCCIO2<0> LCMXO2_A_256BGA-IC,H63395-001    I14 @BASEBOARD_FAB2_LIB.BASEBOARD_FAB2(SCH_1):PAGE192
  U8D7  N12 VCCIO2<1> LCMXO2_A_256BGA-IC,H63395-001    I14 @BASEBOARD_FAB2_LIB.BASEBOARD_FAB2(SCH_1):PAGE192
  U8D7   K8 VCCIO2<2> LCMXO2_A_256BGA-IC,H63395-001    I14 @BASEBOARD_FAB2_LIB.BASEBOARD_FAB2(SCH_1):PAGE192
  U8D7   N5 VCCIO2<3> LCMXO2_A_256BGA-IC,H63395-001    I14 @BASEBOARD_FAB2_LIB.BASEBOARD_FAB2(SCH_1):PAGE192
  U8D7   M4 VCCIO3<0> LCMXO2_A_256BGA-IC,H63395-001    I14 @BASEBOARD_FAB2_LIB.BASEBOARD_FAB2(SCH_1):PAGE192
  U8D7   J7 VCCIO4<0> LCMXO2_A_256BGA-IC,H63395-001    I14 @BASEBOARD_FAB2_LIB.BASEBOARD_FAB2(SCH_1):PAGE192
  U8D7   H7 VCCIO4<1> LCMXO2_A_256BGA-IC,H63395-001    I14 @BASEBOARD_FAB2_LIB.BASEBOARD_FAB2(SCH_1):PAGE192
  U8D7   E4 VCCIO5<0> LCMXO2_A_256BGA-IC,H63395-001    I14 @BASEBOARD_FAB2_LIB.BASEBOARD_FAB2(SCH_1):PAGE192
  C2R5    1      A CAP_A_0402V-0.1UF,16V,10%,X7R,A    I15 @BASEBOARD_FAB2_LIB.BASEBOARD_FAB2(SCH_1):PAGE192
  C2P4    1      A CAP_A_0402V-0.1UF,16V,10%,X7R,A    I16 @BASEBOARD_FAB2_LIB.BASEBOARD_FAB2(SCH_1):PAGE192
 C3P52    1      A CAP_A_0402V-0.1UF,16V,10%,X7R,A    I17 @BASEBOARD_FAB2_LIB.BASEBOARD_FAB2(SCH_1):PAGE192
  C2P6    1      A CAP_A_0402V-0.1UF,16V,10%,X7R,A    I18 @BASEBOARD_FAB2_LIB.BASEBOARD_FAB2(SCH_1):PAGE192
  C2R3    1      A CAP_A_0402V-0.1UF,16V,10%,X7R,A    I19 @BASEBOARD_FAB2_LIB.BASEBOARD_FAB2(SCH_1):PAGE192
  C2P7    1      A CAP_A_0402V-0.1UF,16V,10%,X7R,A    I20 @BASEBOARD_FAB2_LIB.BASEBOARD_FAB2(SCH_1):PAGE192
  C2R4    1      A CAP_A_0402V-0.1UF,16V,10%,X7R,A    I21 @BASEBOARD_FAB2_LIB.BASEBOARD_FAB2(SCH_1):PAGE192
  C2P3    1      A CAP_A_0402V-0.1UF,16V,10%,X7R,A    I22 @BASEBOARD_FAB2_LIB.BASEBOARD_FAB2(SCH_1):PAGE192
 C3P44    1      A CAP_A_0402V-0.1UF,16V,10%,X7R,A    I23 @BASEBOARD_FAB2_LIB.BASEBOARD_FAB2(SCH_1):PAGE192
 C3P48    1      A CAP_A_0402V-0.1UF,16V,10%,X7R,A    I25 @BASEBOARD_FAB2_LIB.BASEBOARD_FAB2(SCH_1):PAGE192
  C2R2    1      A CAP_A_0402V-0.1UF,16V,10%,X7R,A    I28 @BASEBOARD_FAB2_LIB.BASEBOARD_FAB2(SCH_1):PAGE192
  R7E6    1      A RES_0402-10.0K,1%,1/16W,CHIP,GA    I33 @BASEBOARD_FAB2_LIB.BASEBOARD_FAB2(SCH_1):PAGE192
  R2R1    1      A RES_0402-10.0K,1%,1/16W,CHIP,GA    I34 @BASEBOARD_FAB2_LIB.BASEBOARD_FAB2(SCH_1):PAGE192
  R7E5    1      A RES_0402-10.0K,1%,1/16W,CHIP,GA    I38 @BASEBOARD_FAB2_LIB.BASEBOARD_FAB2(SCH_1):PAGE192
  R2R3    1      A RES_0402-10.0K,1%,1/16W,CHIP,GA    I41 @BASEBOARD_FAB2_LIB.BASEBOARD_FAB2(SCH_1):PAGE192
 R7E18    1      A RES_0402-4.75K,1%,1/16W,CHIP,GA    I55 @BASEBOARD_FAB2_LIB.BASEBOARD_FAB2(SCH_1):PAGE192
 R7E19    1      A RES_0402-1.00K,1%,1/16W,EMPTY,A    I57 @BASEBOARD_FAB2_LIB.BASEBOARD_FAB2(SCH_1):PAGE192
  J4B2  A11  IOA11 SCONN120_H61426002_SM-CONN,H61A    I46 @BASEBOARD_FAB2_LIB.BASEBOARD_FAB2(SCH_1):PAGE193
  J4B2  B11  IOB11 SCONN120_H61426002_SM-CONN,H61A    I46 @BASEBOARD_FAB2_LIB.BASEBOARD_FAB2(SCH_1):PAGE193
  J4B2  C11  IOC11 SCONN120_H61426002_SM-CONN,H61A    I46 @BASEBOARD_FAB2_LIB.BASEBOARD_FAB2(SCH_1):PAGE193
  J6B1  A11  IOA11 SCONN120_H61426002_SM-CONN,H61A    I56 @BASEBOARD_FAB2_LIB.BASEBOARD_FAB2(SCH_1):PAGE194
  J6B1  B11  IOB11 SCONN120_H61426002_SM-CONN,H61A    I56 @BASEBOARD_FAB2_LIB.BASEBOARD_FAB2(SCH_1):PAGE194
  J6B1  C11  IOC11 SCONN120_H61426002_SM-CONN,H61A    I56 @BASEBOARD_FAB2_LIB.BASEBOARD_FAB2(SCH_1):PAGE194
 CR2U1    1     A1 DIODE2A_DUAL_SMLF-BAS70-05,DIOA    I53 @BASEBOARD_FAB2_LIB.BASEBOARD_FAB2(SCH_1):PAGE196
 R3P44    1      A RES_0402-4.75K,1%,1/16W,CHIP,GA    I59 @BASEBOARD_FAB2_LIB.BASEBOARD_FAB2(SCH_1):PAGE196
  U7D3    6    VCC ADM1085_SMT-IC,H46130-001    I70 @BASEBOARD_FAB2_LIB.BASEBOARD_FAB2(SCH_1):PAGE196
 R3P50    1      A RES_0402-10.0K,1%,1/16W,EMPTY,A    I71 @BASEBOARD_FAB2_LIB.BASEBOARD_FAB2(SCH_1):PAGE196
 C3P46    1      A CAP_A_0402V-0.1UF,16V,10%,X7R,A    I72 @BASEBOARD_FAB2_LIB.BASEBOARD_FAB2(SCH_1):PAGE196
  U8D8    2    VDD TPS3700_SM-IC,H69492-001   I104 @BASEBOARD_FAB2_LIB.BASEBOARD_FAB2(SCH_1):PAGE196
  C8D4    1      A CAP_A_0402V-0.1UF,16V,10%,X7R,A   I105 @BASEBOARD_FAB2_LIB.BASEBOARD_FAB2(SCH_1):PAGE196
 R8D41    1      A RES_0402-10.0K,1%,1/16W,CHIP,GA   I120 @BASEBOARD_FAB2_LIB.BASEBOARD_FAB2(SCH_1):PAGE196
 R2P18    1      A RES_0402-10.0K,1%,1/16W,CHIP,GA   I121 @BASEBOARD_FAB2_LIB.BASEBOARD_FAB2(SCH_1):PAGE196
 R2P21    1      A RES_0402-10.0K,1%,1/16W,CHIP,GA   I122 @BASEBOARD_FAB2_LIB.BASEBOARD_FAB2(SCH_1):PAGE196
 EU2T1    5      D SLG55021_SM-IC,G56246-001     I1 @BASEBOARD_FAB2_LIB.BASEBOARD_FAB2(SCH_1):PAGE198
 C2T36    1      A CAP_A_0402V-0.1UF,16V,10%,X7R,A    I43 @BASEBOARD_FAB2_LIB.BASEBOARD_FAB2(SCH_1):PAGE198
  C2U1    1      A CAP_0805-10UF,16V,10%,X6S,C953A    I44 @BASEBOARD_FAB2_LIB.BASEBOARD_FAB2(SCH_1):PAGE198
 R8E12    1      A RES_0402-4.75K,1%,1/16W,EMPTY,A    I78 @BASEBOARD_FAB2_LIB.BASEBOARD_FAB2(SCH_1):PAGE198
  Q8G1    5    DRN MOSFET_N_LCC3-BSZ019N03LS,NFETA    I85 @BASEBOARD_FAB2_LIB.BASEBOARD_FAB2(SCH_1):PAGE198
 R9P20    1      A RES_0402-2.7K,1%,1/16W,CHIP,G2A    I86 @BASEBOARD_FAB2_LIB.BASEBOARD_FAB2(SCH_1):PAGE200
  R9P6    1      A RES_0402-10.0K,1%,1/16W,CHIP,GA   I149 @BASEBOARD_FAB2_LIB.BASEBOARD_FAB2(SCH_1):PAGE200
 R1D22    1      A RES_0402-10.0K,1%,1/16W,CHIP,GA   I158 @BASEBOARD_FAB2_LIB.BASEBOARD_FAB2(SCH_1):PAGE200
 R1D10    1      A RES_0402-10.0K,1%,1/16W,CHIP,GA   I189 @BASEBOARD_FAB2_LIB.BASEBOARD_FAB2(SCH_1):PAGE200
 R1D23    1      A RES_0402-10.0K,1%,1/16W,CHIP,GA   I191 @BASEBOARD_FAB2_LIB.BASEBOARD_FAB2(SCH_1):PAGE200
 R9P10    1      A RES_0402-10.0K,1%,1/16W,CHIP,GA   I192 @BASEBOARD_FAB2_LIB.BASEBOARD_FAB2(SCH_1):PAGE200
  U9P2    2    VDD TPS3700_SM-IC,H69492-001   I200 @BASEBOARD_FAB2_LIB.BASEBOARD_FAB2(SCH_1):PAGE200
 C9P11    1      A CAP_A_0402V-0.1UF,16V,10%,X7R,A   I201 @BASEBOARD_FAB2_LIB.BASEBOARD_FAB2(SCH_1):PAGE200
 R1D21    1      A RES_0402-4.75K,1%,1/16W,CHIP,GA   I204 @BASEBOARD_FAB2_LIB.BASEBOARD_FAB2(SCH_1):PAGE200
  R9P4    1      A RES_0402-2.7K,1%,1/16W,CHIP,G2A   I210 @BASEBOARD_FAB2_LIB.BASEBOARD_FAB2(SCH_1):PAGE200
  R9P5    1      A RES_0402-10.0K,1%,1/16W,CHIP,GA   I215 @BASEBOARD_FAB2_LIB.BASEBOARD_FAB2(SCH_1):PAGE200
  R4E4    1      A RES_0402-2.26K,1.0%,1/16W,CHIPA    I19 @BASEBOARD_FAB2_LIB.BASEBOARD_FAB2(SCH_1):PAGE201
 R4D31    1      A RES_0402-2.26K,1.0%,1/16W,EMPTA    I22 @BASEBOARD_FAB2_LIB.BASEBOARD_FAB2(SCH_1):PAGE201
 R4D58    1      A RES_0402-1.00K,1%,1/16W,CHIP,GA    I25 @BASEBOARD_FAB2_LIB.BASEBOARD_FAB2(SCH_1):PAGE201
  R4E5    1      A RES_0402-1.00K,1%,1/16W,CHIP,GA    I27 @BASEBOARD_FAB2_LIB.BASEBOARD_FAB2(SCH_1):PAGE201
 R4D26    1      A RES_0402-0.0,5%,1/16W,CHIP,G21A    I40 @BASEBOARD_FAB2_LIB.BASEBOARD_FAB2(SCH_1):PAGE201
 R6P32    1      A RES_0402-2.0K,1%,1/16W,EMPTY,GA   I102 @BASEBOARD_FAB2_LIB.BASEBOARD_FAB2(SCH_1):PAGE201
 R6P37    1      A RES_0402-2.0K,1%,1/16W,EMPTY,GA   I103 @BASEBOARD_FAB2_LIB.BASEBOARD_FAB2(SCH_1):PAGE201
  R4E3    1      A RES_0402-1.00K,1%,1/16W,CHIP,GA   I111 @BASEBOARD_FAB2_LIB.BASEBOARD_FAB2(SCH_1):PAGE201
 R4E20    1      A RES_0402-2.26K,1.0%,1/16W,EMPTA   I116 @BASEBOARD_FAB2_LIB.BASEBOARD_FAB2(SCH_1):PAGE201
  R1D6    1      A RES_0402-1.00K,1%,1/16W,CHIP,GA     I6 @BASEBOARD_FAB2_LIB.BASEBOARD_FAB2(SCH_1):PAGE206
  R1D7    1      A RES_0402-2.26K,1.0%,1/16W,CHIPA     I7 @BASEBOARD_FAB2_LIB.BASEBOARD_FAB2(SCH_1):PAGE206
 R1D53    1      A RES_0402-2.26K,1.0%,1/16W,EMPTA    I33 @BASEBOARD_FAB2_LIB.BASEBOARD_FAB2(SCH_1):PAGE206
 R1C18    1      A RES_0402-2.26K,1.0%,1/16W,EMPTA    I34 @BASEBOARD_FAB2_LIB.BASEBOARD_FAB2(SCH_1):PAGE206
 R1C28    1      A RES_0402-1.00K,1%,1/16W,CHIP,GA    I35 @BASEBOARD_FAB2_LIB.BASEBOARD_FAB2(SCH_1):PAGE206
  R1D8    1      A RES_0402-1.00K,1%,1/16W,CHIP,GA    I36 @BASEBOARD_FAB2_LIB.BASEBOARD_FAB2(SCH_1):PAGE206
 R1C14    1      A RES_0402-0.0,5%,1/16W,CHIP,G21A    I46 @BASEBOARD_FAB2_LIB.BASEBOARD_FAB2(SCH_1):PAGE206
 R3P22    1      A RES_0402-0.0,5%,1/16W,CHIP,G21A    I24 @BASEBOARD_FAB2_LIB.BASEBOARD_FAB2(SCH_1):PAGE211
 R3P25    1      A RES_0402-1.00K,1%,1/16W,CHIP,GA    I56 @BASEBOARD_FAB2_LIB.BASEBOARD_FAB2(SCH_1):PAGE211
 R3N23    1      A RES_0402-2.26K,1.0%,1/16W,EMPTA    I60 @BASEBOARD_FAB2_LIB.BASEBOARD_FAB2(SCH_1):PAGE211
 R3P18    1      A RES_0402-1.00K,1%,1/16W,CHIP,GA    I64 @BASEBOARD_FAB2_LIB.BASEBOARD_FAB2(SCH_1):PAGE211
 R3P21    1      A RES_0402-100.0K,1%,1/16W,EMPTYA    I88 @BASEBOARD_FAB2_LIB.BASEBOARD_FAB2(SCH_1):PAGE211
 R6P49    1      A RES_0402-2.26K,1.0%,1/16W,EMPTA    I14 @BASEBOARD_FAB2_LIB.BASEBOARD_FAB2(SCH_1):PAGE213
 R4D42    1      A RES_0402-1.00K,1%,1/16W,CHIP,GA    I15 @BASEBOARD_FAB2_LIB.BASEBOARD_FAB2(SCH_1):PAGE213
 R4D47    1      A RES_0402-0.0,5%,1/16W,CHIP,G21A    I25 @BASEBOARD_FAB2_LIB.BASEBOARD_FAB2(SCH_1):PAGE213
 R4D49    1      A RES_0402-1.00K,1%,1/16W,CHIP,GA    I63 @BASEBOARD_FAB2_LIB.BASEBOARD_FAB2(SCH_1):PAGE213
 R6P40    1      A RES_0402-100.0K,1%,1/16W,EMPTYA    I91 @BASEBOARD_FAB2_LIB.BASEBOARD_FAB2(SCH_1):PAGE213
 R7F36    1      A RES_0402-2.26K,1.0%,1/16W,EMPTA   I300 @BASEBOARD_FAB2_LIB.BASEBOARD_FAB2(SCH_1):PAGE215
 R7F22    1      A RES_0402-1.00K,1%,1/16W,CHIP,GA   I301 @BASEBOARD_FAB2_LIB.BASEBOARD_FAB2(SCH_1):PAGE215
 R7F27    1      A RES_0402-1.00K,1%,1/16W,CHIP,GA   I303 @BASEBOARD_FAB2_LIB.BASEBOARD_FAB2(SCH_1):PAGE215
 R3T13    1      A RES_0402-0.0,5%,1/16W,CHIP,G21A   I313 @BASEBOARD_FAB2_LIB.BASEBOARD_FAB2(SCH_1):PAGE215
 R7F20    1      A RES_0402-100.0K,1%,1/16W,EMPTYA   I315 @BASEBOARD_FAB2_LIB.BASEBOARD_FAB2(SCH_1):PAGE215
  R7A9    1      A RES_0402-2.26K,1.0%,1/16W,EMPTA    I14 @BASEBOARD_FAB2_LIB.BASEBOARD_FAB2(SCH_1):PAGE218
  R7B5    1      A RES_0402-1.00K,1%,1/16W,CHIP,GA    I16 @BASEBOARD_FAB2_LIB.BASEBOARD_FAB2(SCH_1):PAGE218
  R7B4    1      A RES_0402-1.00K,1%,1/16W,CHIP,GA    I17 @BASEBOARD_FAB2_LIB.BASEBOARD_FAB2(SCH_1):PAGE218
  R3M1    1      A RES_0402-0.0,5%,1/16W,CHIP,G21A    I34 @BASEBOARD_FAB2_LIB.BASEBOARD_FAB2(SCH_1):PAGE218
  R3M5    1      A RES_0402-100.0K,1%,1/16W,EMPTYA    I35 @BASEBOARD_FAB2_LIB.BASEBOARD_FAB2(SCH_1):PAGE218
  R1G6    1      A RES_0402-2.26K,1.0%,1/16W,EMPTA    I13 @BASEBOARD_FAB2_LIB.BASEBOARD_FAB2(SCH_1):PAGE223
 R1G16    1      A RES_0402-1.00K,1%,1/16W,CHIP,GA    I17 @BASEBOARD_FAB2_LIB.BASEBOARD_FAB2(SCH_1):PAGE223
 R9U10    1      A RES_0402-0.0,5%,1/16W,CHIP,G21A    I30 @BASEBOARD_FAB2_LIB.BASEBOARD_FAB2(SCH_1):PAGE223
 R1G11    1      A RES_0402-1.00K,1%,1/16W,CHIP,GA    I79 @BASEBOARD_FAB2_LIB.BASEBOARD_FAB2(SCH_1):PAGE223
  R9U8    1      A RES_0402-100.0K,1%,1/16W,EMPTYA    I85 @BASEBOARD_FAB2_LIB.BASEBOARD_FAB2(SCH_1):PAGE223
 R1B13    1      A RES_0402-2.26K,1.0%,1/16W,EMPTA    I13 @BASEBOARD_FAB2_LIB.BASEBOARD_FAB2(SCH_1):PAGE226
  R1B2    1      A RES_0402-1.00K,1%,1/16W,CHIP,GA    I17 @BASEBOARD_FAB2_LIB.BASEBOARD_FAB2(SCH_1):PAGE226
  R9M3    1      A RES_0402-0.0,5%,1/16W,CHIP,G21A    I30 @BASEBOARD_FAB2_LIB.BASEBOARD_FAB2(SCH_1):PAGE226
  R1B1    1      A RES_0402-1.00K,1%,1/16W,CHIP,GA    I79 @BASEBOARD_FAB2_LIB.BASEBOARD_FAB2(SCH_1):PAGE226
  R9M5    1      A RES_0402-100.0K,1%,1/16W,EMPTYA    I85 @BASEBOARD_FAB2_LIB.BASEBOARD_FAB2(SCH_1):PAGE226
 R7F19    1      A RES_0402-1.00K,1%,1/16W,CHIP,GA   I143 @BASEBOARD_FAB2_LIB.BASEBOARD_FAB2(SCH_1):PAGE231
 R7B17    1      A RES_0402-1.00K,1%,1/16W,CHIP,GA   I210 @BASEBOARD_FAB2_LIB.BASEBOARD_FAB2(SCH_1):PAGE232
 R4G14    1      A RES_0402-1.00K,1%,1/16W,CHIP,GA   I185 @BASEBOARD_FAB2_LIB.BASEBOARD_FAB2(SCH_1):PAGE233
 R4B10    1      A RES_0402-1.00K,1%,1/16W,CHIP,GA   I143 @BASEBOARD_FAB2_LIB.BASEBOARD_FAB2(SCH_1):PAGE234
 R2L24    1      A RES_0402-2.26K,1.0%,1/16W,EMPTA   I148 @BASEBOARD_FAB2_LIB.BASEBOARD_FAB2(SCH_1):PAGE235
  R8A6    1      A RES_0402-1.00K,1%,1/16W,CHIP,GA   I149 @BASEBOARD_FAB2_LIB.BASEBOARD_FAB2(SCH_1):PAGE235
 R2L14    1      A RES_0402-0.0,5%,1/16W,CHIP,G21A   I159 @BASEBOARD_FAB2_LIB.BASEBOARD_FAB2(SCH_1):PAGE235
  R8A5    1      A RES_0402-1.00K,1%,1/16W,CHIP,GA   I216 @BASEBOARD_FAB2_LIB.BASEBOARD_FAB2(SCH_1):PAGE235
  R8A7    1      A RES_0402-100.0K,1%,1/16W,EMPTYA   I222 @BASEBOARD_FAB2_LIB.BASEBOARD_FAB2(SCH_1):PAGE235
 R2L25    1      A RES_0402-100.0K,1%,1/16W,EMPTYA   I235 @BASEBOARD_FAB2_LIB.BASEBOARD_FAB2(SCH_1):PAGE235
 R2L26    1      A RES_0402-100.0K,1%,1/16W,EMPTYA   I236 @BASEBOARD_FAB2_LIB.BASEBOARD_FAB2(SCH_1):PAGE235
 R8A10    1      A RES_0402-5.11K,1%,1/16W,CHIP,GA     I3 @BASEBOARD_FAB2_LIB.BASEBOARD_FAB2(SCH_1):PAGE237
  C8A6    1      A CAP_0603-10UF,6.3V,20%,X6S,E15A    I29 @BASEBOARD_FAB2_LIB.BASEBOARD_FAB2(SCH_1):PAGE237
  C8A4    1      A CAP_0603LF-0.1UF,25V,10%,X7R,6A    I31 @BASEBOARD_FAB2_LIB.BASEBOARD_FAB2(SCH_1):PAGE237
 EU8A2   10    VDD RT9059_DFN-IC,H65765-001    I86 @BASEBOARD_FAB2_LIB.BASEBOARD_FAB2(SCH_1):PAGE237
 EU8A2    7 VIN<0> RT9059_DFN-IC,H65765-001    I86 @BASEBOARD_FAB2_LIB.BASEBOARD_FAB2(SCH_1):PAGE237
 EU8A2    8 VIN<1> RT9059_DFN-IC,H65765-001    I86 @BASEBOARD_FAB2_LIB.BASEBOARD_FAB2(SCH_1):PAGE237
 EU8A2    9 VIN<2> RT9059_DFN-IC,H65765-001    I86 @BASEBOARD_FAB2_LIB.BASEBOARD_FAB2(SCH_1):PAGE237
  C9F3    1      A CAP_0603-10UF,6.3V,20%,X6S,E15A     I7 @BASEBOARD_FAB2_LIB.BASEBOARD_FAB2(SCH_1):PAGE238
 R9F13    1      A RES_0402-10.0K,1%,1/16W,CHIP,GA    I21 @BASEBOARD_FAB2_LIB.BASEBOARD_FAB2(SCH_1):PAGE238
 C9E11    1      A CAP_0402-1.0UF,16V,10%,X6S,D97A    I39 @BASEBOARD_FAB2_LIB.BASEBOARD_FAB2(SCH_1):PAGE238
 EU9F1   10    VDD RT9059_DFN-IC,H65765-001    I40 @BASEBOARD_FAB2_LIB.BASEBOARD_FAB2(SCH_1):PAGE238
 EU9F1    7 VIN<0> RT9059_DFN-IC,H65765-001    I40 @BASEBOARD_FAB2_LIB.BASEBOARD_FAB2(SCH_1):PAGE238
 EU9F1    8 VIN<1> RT9059_DFN-IC,H65765-001    I40 @BASEBOARD_FAB2_LIB.BASEBOARD_FAB2(SCH_1):PAGE238
 EU9F1    9 VIN<2> RT9059_DFN-IC,H65765-001    I40 @BASEBOARD_FAB2_LIB.BASEBOARD_FAB2(SCH_1):PAGE238
 R9F12    1      A RES_0402-10.0K,1%,1/16W,CHIP,GA     I6 @BASEBOARD_FAB2_LIB.BASEBOARD_FAB2(SCH_1):PAGE239
  C1T7    1      A CAP_0603-10UF,6.3V,20%,X6S,E15A    I22 @BASEBOARD_FAB2_LIB.BASEBOARD_FAB2(SCH_1):PAGE239
 EU9F2   10    VDD RT9059_DFN-IC,H65765-001    I70 @BASEBOARD_FAB2_LIB.BASEBOARD_FAB2(SCH_1):PAGE239
 EU9F2    7 VIN<0> RT9059_DFN-IC,H65765-001    I70 @BASEBOARD_FAB2_LIB.BASEBOARD_FAB2(SCH_1):PAGE239
 EU9F2    8 VIN<1> RT9059_DFN-IC,H65765-001    I70 @BASEBOARD_FAB2_LIB.BASEBOARD_FAB2(SCH_1):PAGE239
 EU9F2    9 VIN<2> RT9059_DFN-IC,H65765-001    I70 @BASEBOARD_FAB2_LIB.BASEBOARD_FAB2(SCH_1):PAGE239
  C9F5    1      A CAP_A_0402V-0.1UF,16V,10%,X7R,A    I71 @BASEBOARD_FAB2_LIB.BASEBOARD_FAB2(SCH_1):PAGE239
  R8F5    1      A RES_0402-1.00K,1%,1/16W,CHIP,GA   I117 @BASEBOARD_FAB2_LIB.BASEBOARD_FAB2(SCH_1):PAGE240
 R8E25    1      A RES_0402-0.0,5%,1/16W,CHIP,G21A   I144 @BASEBOARD_FAB2_LIB.BASEBOARD_FAB2(SCH_1):PAGE240
  R2T4    1      A RES_0402-1.0K,0.1%,1/16W,CHIP,A   I152 @BASEBOARD_FAB2_LIB.BASEBOARD_FAB2(SCH_1):PAGE240
 C8F14    1      A CAPP_3018-470UF,6.3V,20%,POSCAA   I154 @BASEBOARD_FAB2_LIB.BASEBOARD_FAB2(SCH_1):PAGE240
  C8F8    1      A CAPP_3018-470UF,6.3V,20%,POSCAA   I155 @BASEBOARD_FAB2_LIB.BASEBOARD_FAB2(SCH_1):PAGE240
  C2T7    1      A CAP_0805-22UF,6.3V,20%,X6S,C95A   I158 @BASEBOARD_FAB2_LIB.BASEBOARD_FAB2(SCH_1):PAGE240
  C2T6    1      A CAP_0805-22UF,6.3V,20%,X6S,C95A   I160 @BASEBOARD_FAB2_LIB.BASEBOARD_FAB2(SCH_1):PAGE240
  L8F1    2    INB INDUCTOR_SM-1.00UH,IND,E98679-A   I173 @BASEBOARD_FAB2_LIB.BASEBOARD_FAB2(SCH_1):PAGE240
  C2T9    1      A CAP_0805-22UF,6.3V,20%,X6S,C95A   I174 @BASEBOARD_FAB2_LIB.BASEBOARD_FAB2(SCH_1):PAGE240
 R8E40    1      A RES_0402-100.0K,1%,1/16W,EMPTYA   I177 @BASEBOARD_FAB2_LIB.BASEBOARD_FAB2(SCH_1):PAGE240
 RN8F1    1      A RES_0402-4.75K,1%,1/16W,CHIP,GA     I5 @BASEBOARD_FAB2_LIB.BASEBOARD_FAB2(SCH_1):PAGE246
 RN8F2    1      A RES_0402-4.75K,1%,1/16W,CHIP,GA    I10 @BASEBOARD_FAB2_LIB.BASEBOARD_FAB2(SCH_1):PAGE246
 RN8F3    1      A RES_0402-4.75K,1%,1/16W,CHIP,GA    I11 @BASEBOARD_FAB2_LIB.BASEBOARD_FAB2(SCH_1):PAGE246
 RN8F4    1      A RES_0402-4.75K,1%,1/16W,EMPTY,A    I12 @BASEBOARD_FAB2_LIB.BASEBOARD_FAB2(SCH_1):PAGE246
 CN8F1    1      A CAP_0402-1.0UF,6.3V,10%,X6S,D9A    I15 @BASEBOARD_FAB2_LIB.BASEBOARD_FAB2(SCH_1):PAGE246
 CN8F2    1      A CAP_0402LF-0.01UF,25V,10%,X7R,A    I16 @BASEBOARD_FAB2_LIB.BASEBOARD_FAB2(SCH_1):PAGE246
 UN8F2    2    VCC W25Q256_XSOI-IC,H25002-001    I17 @BASEBOARD_FAB2_LIB.BASEBOARD_FAB2(SCH_1):PAGE246
  R6W1    1      A RES_0402-100.0K,1%,1/16W,CHIP,B   I229 @BASEBOARD_FAB2_LIB.BASEBOARD_FAB2(SCH_1):PAGE200
 R6W10    1      A RES_0402-4.75K,1%,1/16W,CHIP,GA     I1 @BASEBOARD_FAB2_LIB.BASEBOARD_FAB2(SCH_1):PAGE247
  R6W4    1      A RES_0402-4.75K,1%,1/16W,EMPTY,A     I5 @BASEBOARD_FAB2_LIB.BASEBOARD_FAB2(SCH_1):PAGE247
  R6W5    1      A RES_0402-4.75K,1%,1/16W,EMPTY,A    I10 @BASEBOARD_FAB2_LIB.BASEBOARD_FAB2(SCH_1):PAGE247
  R6W6    1      A RES_0402-4.75K,1%,1/16W,EMPTY,A    I11 @BASEBOARD_FAB2_LIB.BASEBOARD_FAB2(SCH_1):PAGE247
  C6W1    1      A CAP_0402LF-0.1UF,16V,10%,X7R,AA    I18 @BASEBOARD_FAB2_LIB.BASEBOARD_FAB2(SCH_1):PAGE247
 R6W16    1      A RES_0402-10.0K,1%,1/16W,CHIP,GA    I39 @BASEBOARD_FAB2_LIB.BASEBOARD_FAB2(SCH_1):PAGE168
 R6W15    1      A RES_0402-10.0K,1%,1/16W,CHIP,GA    I40 @BASEBOARD_FAB2_LIB.BASEBOARD_FAB2(SCH_1):PAGE168
  R3W7    1      A RES_0402-4.75K,1%,1/16W,CHIP,GA     I8 @BASEBOARD_FAB2_LIB.BASEBOARD_FAB2(SCH_1):PAGE249
  Q9W4    5    VCC LMV331IDCKRG4-GP_DISCRET-G-LMVA    I15 @BASEBOARD_FAB2_LIB.BASEBOARD_FAB2(SCH_1):PAGE249
  R3W3    1      A RES_0402-10.0K,1%,1/16W,CHIP,GA    I17 @BASEBOARD_FAB2_LIB.BASEBOARD_FAB2(SCH_1):PAGE249
  C8W2    1      A CAP_0402LF-0.1UF,16V,10%,X7R,AA    I21 @BASEBOARD_FAB2_LIB.BASEBOARD_FAB2(SCH_1):PAGE249
  R3W6    1      A RES_0402-4.75K,1%,1/16W,CHIP,GA    I27 @BASEBOARD_FAB2_LIB.BASEBOARD_FAB2(SCH_1):PAGE249
 R6W11    1      A RES_0402-4.75K,1%,1/16W,EMPTY,A    I67 @BASEBOARD_FAB2_LIB.BASEBOARD_FAB2(SCH_1):PAGE247
 R6W12    1      A RES_0402-4.75K,1%,1/16W,EMPTY,A    I68 @BASEBOARD_FAB2_LIB.BASEBOARD_FAB2(SCH_1):PAGE247
 C6W10    1      A CAP_0402LF-0.1UF,16V,10%,X7R,AA   I124 @BASEBOARD_FAB2_LIB.BASEBOARD_FAB2(SCH_1):PAGE176
EU25F2   10    VDD RT9059_DFN-IC,H65765-001    I73 @BASEBOARD_FAB2_LIB.BASEBOARD_FAB2(SCH_1):PAGE239
EU25F2    7 VIN<0> RT9059_DFN-IC,H65765-001    I73 @BASEBOARD_FAB2_LIB.BASEBOARD_FAB2(SCH_1):PAGE239
EU25F2    8 VIN<1> RT9059_DFN-IC,H65765-001    I73 @BASEBOARD_FAB2_LIB.BASEBOARD_FAB2(SCH_1):PAGE239
EU25F2    9 VIN<2> RT9059_DFN-IC,H65765-001    I73 @BASEBOARD_FAB2_LIB.BASEBOARD_FAB2(SCH_1):PAGE239
 R9W12    1      A RES_0402-10.0K,1%,1/16W,CHIP,GA    I79 @BASEBOARD_FAB2_LIB.BASEBOARD_FAB2(SCH_1):PAGE239
  C9W5    1      A CAP_A_0402V-0.1UF,16V,10%,X7R,A    I90 @BASEBOARD_FAB2_LIB.BASEBOARD_FAB2(SCH_1):PAGE239
  C1W7    1      A CAP_0603-10UF,6.3V,20%,X6S,E15A    I92 @BASEBOARD_FAB2_LIB.BASEBOARD_FAB2(SCH_1):PAGE239
  Y9F2    4    VDD OSC_C_SM4-24MHZ,OSC,D34520-021     I8 @BASEBOARD_FAB2_LIB.BASEBOARD_FAB2(SCH_1):PAGE145
 R9F61    1      A RES_0402-10.0K,1%,1/16W,CHIP,GA    I14 @BASEBOARD_FAB2_LIB.BASEBOARD_FAB2(SCH_1):PAGE145
 C9F23    1      A CAP_A_0402V-0.1UF,16V,10%,X7R,A    I15 @BASEBOARD_FAB2_LIB.BASEBOARD_FAB2(SCH_1):PAGE145
R25W95    1      A RES_0402-4.75K,1%,1/16W,CHIP,GA     I2 @BASEBOARD_FAB2_LIB.BASEBOARD_FAB2(SCH_1):PAGE151
R25W94    1      A RES_0402-4.75K,1%,1/16W,CHIP,GA     I9 @BASEBOARD_FAB2_LIB.BASEBOARD_FAB2(SCH_1):PAGE151
R25W96    1      A RES_0402-4.75K,1%,1/16W,CHIP,GA    I10 @BASEBOARD_FAB2_LIB.BASEBOARD_FAB2(SCH_1):PAGE151
R25W97    1      A RES_0402-4.75K,1%,1/16W,EMPTY,A    I11 @BASEBOARD_FAB2_LIB.BASEBOARD_FAB2(SCH_1):PAGE151
R25W98    1      A RES_0402-4.75K,1%,1/16W,CHIP,GA    I12 @BASEBOARD_FAB2_LIB.BASEBOARD_FAB2(SCH_1):PAGE151
R25W100    1      A RES_0402-4.75K,1%,1/16W,CHIP,GA    I13 @BASEBOARD_FAB2_LIB.BASEBOARD_FAB2(SCH_1):PAGE151
R25W99    1      A RES_0402-4.75K,1%,1/16W,EMPTY,A    I14 @BASEBOARD_FAB2_LIB.BASEBOARD_FAB2(SCH_1):PAGE151
R25W101    1      A RES_0402-4.75K,1%,1/16W,EMPTY,A    I27 @BASEBOARD_FAB2_LIB.BASEBOARD_FAB2(SCH_1):PAGE151
R25W102    1      A RES_0402-4.75K,1%,1/16W,CHIP,GA    I28 @BASEBOARD_FAB2_LIB.BASEBOARD_FAB2(SCH_1):PAGE151
R25W103    1      A RES_0402-4.75K,1%,1/16W,EMPTY,A    I29 @BASEBOARD_FAB2_LIB.BASEBOARD_FAB2(SCH_1):PAGE151
R25W104    1      A RES_0402-4.75K,1%,1/16W,EMPTY,A    I30 @BASEBOARD_FAB2_LIB.BASEBOARD_FAB2(SCH_1):PAGE151
R25W105    1      A RES_0402-4.75K,1%,1/16W,EMPTY,A    I31 @BASEBOARD_FAB2_LIB.BASEBOARD_FAB2(SCH_1):PAGE151
R25W106    1      A RES_0402-4.75K,1%,1/16W,EMPTY,A    I32 @BASEBOARD_FAB2_LIB.BASEBOARD_FAB2(SCH_1):PAGE151
R25W107    1      A RES_0402-4.75K,1%,1/16W,EMPTY,A    I33 @BASEBOARD_FAB2_LIB.BASEBOARD_FAB2(SCH_1):PAGE151
R25W108    1      A RES_0402-4.75K,1%,1/16W,CHIP,GA    I34 @BASEBOARD_FAB2_LIB.BASEBOARD_FAB2(SCH_1):PAGE151
R25W109    1      A RES_0402-4.75K,1%,1/16W,EMPTY,A    I35 @BASEBOARD_FAB2_LIB.BASEBOARD_FAB2(SCH_1):PAGE151
R25W110    1      A RES_0402-4.75K,1%,1/16W,CHIP,GA    I36 @BASEBOARD_FAB2_LIB.BASEBOARD_FAB2(SCH_1):PAGE151
R25W111    1      A RES_0402-4.75K,1%,1/16W,EMPTY,A    I43 @BASEBOARD_FAB2_LIB.BASEBOARD_FAB2(SCH_1):PAGE151
R25W112    1      A RES_0402-4.75K,1%,1/16W,EMPTY,A    I44 @BASEBOARD_FAB2_LIB.BASEBOARD_FAB2(SCH_1):PAGE151
R25W113    1      A RES_0402-4.75K,1%,1/16W,EMPTY,A    I45 @BASEBOARD_FAB2_LIB.BASEBOARD_FAB2(SCH_1):PAGE151
R25W114    1      A RES_0402-4.75K,1%,1/16W,EMPTY,A    I46 @BASEBOARD_FAB2_LIB.BASEBOARD_FAB2(SCH_1):PAGE151
R25W115    1      A RES_0402-4.75K,1%,1/16W,CHIP,GA    I47 @BASEBOARD_FAB2_LIB.BASEBOARD_FAB2(SCH_1):PAGE151
C25W60    1      A CAP_0402-1.0UF,6.3V,10%,X6S,D9A     I1 @BASEBOARD_FAB2_LIB.BASEBOARD_FAB2(SCH_1):PAGE150
R25W120    1      1 0R3J-0-U-GP_RCL_GP-0R3J-0-U-GPA     I7 @BASEBOARD_FAB2_LIB.BASEBOARD_FAB2(SCH_1):PAGE150
C25W50    1      1 SC4D7U10V3KX-GP_SMD-BCG-SC4D7UA    I21 @BASEBOARD_FAB2_LIB.BASEBOARD_FAB2(SCH_1):PAGE150
 FB2T6    1      1 HCB1608KF-800T30-GP_DISCRET-G9A    I26 @BASEBOARD_FAB2_LIB.BASEBOARD_FAB2(SCH_1):PAGE150
 FB2T1    1      1 HCB1608KF-800T30-GP_DISCRET-G9A    I32 @BASEBOARD_FAB2_LIB.BASEBOARD_FAB2(SCH_1):PAGE150
C25W49    1      1 SCD1U16V2KX-3GP_SMD-BCG-SCD1U1A    I36 @BASEBOARD_FAB2_LIB.BASEBOARD_FAB2(SCH_1):PAGE150
C25W48    1      A CAP_0402-1.0UF,6.3V,10%,X6S,D9A    I38 @BASEBOARD_FAB2_LIB.BASEBOARD_FAB2(SCH_1):PAGE150
R25W93    1      1 0R3J-0-U-GP_RCL_GP-0R3J-0-U-GPA    I57 @BASEBOARD_FAB2_LIB.BASEBOARD_FAB2(SCH_1):PAGE150
C25W62    1      1 SC4D7U10V3KX-GP_SMD-BCG-SC4D7UA    I65 @BASEBOARD_FAB2_LIB.BASEBOARD_FAB2(SCH_1):PAGE150
C25W61    1      1 SCD1U16V2KX-3GP_SMD-BCG-SCD1U1A    I67 @BASEBOARD_FAB2_LIB.BASEBOARD_FAB2(SCH_1):PAGE150
 FB2T3    1      1 HCB1608KF-800T30-GP_DISCRET-G9A    I76 @BASEBOARD_FAB2_LIB.BASEBOARD_FAB2(SCH_1):PAGE150
 FB2T4    1      1 HCB1608KF-800T30-GP_DISCRET-G9A    I84 @BASEBOARD_FAB2_LIB.BASEBOARD_FAB2(SCH_1):PAGE150
 FB2T5    1      1 HCB1608KF-800T30-GP_DISCRET-G9A    I89 @BASEBOARD_FAB2_LIB.BASEBOARD_FAB2(SCH_1):PAGE150
 R1U52    1      A RES_0402-1.5K,1%,1/16W,CHIP,G2A    I51 @BASEBOARD_FAB2_LIB.BASEBOARD_FAB2(SCH_1):PAGE146
R25W92    1      A RES_0402-10.0K,1%,1/16W,CHIP,GA     I3 @BASEBOARD_FAB2_LIB.BASEBOARD_FAB2(SCH_1):PAGE147
R25W91    1      A RES_0402-10.0K,1%,1/16W,CHIP,GA     I4 @BASEBOARD_FAB2_LIB.BASEBOARD_FAB2(SCH_1):PAGE147
R25W79    1      A RES_0402-10.0K,1%,1/16W,CHIP,GA    I42 @BASEBOARD_FAB2_LIB.BASEBOARD_FAB2(SCH_1):PAGE147
R25W80    1      A RES_0402-10.0K,1%,1/16W,CHIP,GA    I43 @BASEBOARD_FAB2_LIB.BASEBOARD_FAB2(SCH_1):PAGE147
R25W59    1      A RES_0402-0.0,5%,1/16W,CHIP,G21A    I16 @BASEBOARD_FAB2_LIB.BASEBOARD_FAB2(SCH_1):PAGE148
 R9E24    2      B RES_0402-221,1.0%,1/16W,CHIP,GA    I94 @BASEBOARD_FAB2_LIB.BASEBOARD_FAB2(SCH_1):PAGE149
 R9E21    1      A RES_0402-4.75K,1%,1/16W,CHIP,GA   I111 @BASEBOARD_FAB2_LIB.BASEBOARD_FAB2(SCH_1):PAGE149
 R8B25    1      A RES_0402-4.75K,1%,1/16W,CHIP,GA   I156 @BASEBOARD_FAB2_LIB.BASEBOARD_FAB2(SCH_1):PAGE149
  R3W5    1      1 82K5R2F-GP_SMD-RG-82K5R2F-GP,6A    I33 @BASEBOARD_FAB2_LIB.BASEBOARD_FAB2(SCH_1):PAGE249
  U6W2    8    VCC PCA9515ADGKR-1-GP_DISCRET-G5-PA    I77 @BASEBOARD_FAB2_LIB.BASEBOARD_FAB2(SCH_1):PAGE247
  C6W2    1      A CAP_0402LF-0.1UF,16V,10%,X7R,AA    I81 @BASEBOARD_FAB2_LIB.BASEBOARD_FAB2(SCH_1):PAGE247
  C6W3    1      A CAP_A_0402V-0.1UF,16V,10%,X7R,A    I85 @BASEBOARD_FAB2_LIB.BASEBOARD_FAB2(SCH_1):PAGE247
 R6W21    1      A RES_0402-1.00K,1%,1/16W,CHIP,GA    I90 @BASEBOARD_FAB2_LIB.BASEBOARD_FAB2(SCH_1):PAGE247
 U25W4  J17 LPVDD0 AST2520A1-GP-GP_ASIC2-GB1-AST2A    I28 @BASEBOARD_FAB2_LIB.BASEBOARD_FAB2(SCH_1):PAGE148
 U25W4  K17 LPVDD1 AST2520A1-GP-GP_ASIC2-GB1-AST2A    I28 @BASEBOARD_FAB2_LIB.BASEBOARD_FAB2(SCH_1):PAGE148
 U25W4  F10 R1VDD0 AST2520A1-GP-GP_ASIC2-GB1-AST2A    I28 @BASEBOARD_FAB2_LIB.BASEBOARD_FAB2(SCH_1):PAGE148
 U25W4  F11 R1VDD1 AST2520A1-GP-GP_ASIC2-GB1-AST2A    I28 @BASEBOARD_FAB2_LIB.BASEBOARD_FAB2(SCH_1):PAGE148
 U25W4   F7 R2VDD0 AST2520A1-GP-GP_ASIC2-GB1-AST2A    I28 @BASEBOARD_FAB2_LIB.BASEBOARD_FAB2(SCH_1):PAGE148
 U25W4   F8 R2VDD1 AST2520A1-GP-GP_ASIC2-GB1-AST2A    I28 @BASEBOARD_FAB2_LIB.BASEBOARD_FAB2(SCH_1):PAGE148
  U6W1   24    VCC PCA9555PWRG4-GP_DISCRET-G5-PCAA    I97 @BASEBOARD_FAB2_LIB.BASEBOARD_FAB2(SCH_1):PAGE247

P3V3_STBY_BMC_ADCVREFN @BASEBOARD_FAB2_LIB.BASEBOARD_FAB2(SCH_1):P3V3_STBY_BMC_ADCVREFN
 C25W8    1      A CAP_0402-0.1UF,16V,10%,EMPTY,AA    I38 @BASEBOARD_FAB2_LIB.BASEBOARD_FAB2(SCH_1):PAGE147
 C25W9    1      A CAP_0402-0.1UF,16V,10%,EMPTY,AA    I39 @BASEBOARD_FAB2_LIB.BASEBOARD_FAB2(SCH_1):PAGE147
 U25W4   H1 ADCVREFN AST2520A1-GP-GP_ASIC2-GB1-AST2A   I106 @BASEBOARD_FAB2_LIB.BASEBOARD_FAB2(SCH_1):PAGE147

P3V3_STBY_BMC_ADCVREFP @BASEBOARD_FAB2_LIB.BASEBOARD_FAB2(SCH_1):P3V3_STBY_BMC_ADCVREFP
 C25W9    2      B CAP_0402-0.1UF,16V,10%,EMPTY,AA    I39 @BASEBOARD_FAB2_LIB.BASEBOARD_FAB2(SCH_1):PAGE147
 C25W7    1      A CAP_0402-0.1UF,16V,10%,EMPTY,AA    I36 @BASEBOARD_FAB2_LIB.BASEBOARD_FAB2(SCH_1):PAGE147
 U25W4   H2 ADCVREFP AST2520A1-GP-GP_ASIC2-GB1-AST2A   I106 @BASEBOARD_FAB2_LIB.BASEBOARD_FAB2(SCH_1):PAGE147

P3V3_STBY_MNG @BASEBOARD_FAB2_LIB.BASEBOARD_FAB2(SCH_1):P3V3_STBY_MNG
 EU8F2   12 VDD32K ICS9FGP204_MLFP-IC,E95226-001    I34 @BASEBOARD_FAB2_LIB.BASEBOARD_FAB2(SCH_1):PAGE101
 EU8F2   23  VDD33 ICS9FGP204_MLFP-IC,E95226-001    I34 @BASEBOARD_FAB2_LIB.BASEBOARD_FAB2(SCH_1):PAGE101
 EU8F2    2  VDD96 ICS9FGP204_MLFP-IC,E95226-001    I34 @BASEBOARD_FAB2_LIB.BASEBOARD_FAB2(SCH_1):PAGE101
 EU8F2   15 VDDREF ICS9FGP204_MLFP-IC,E95226-001    I34 @BASEBOARD_FAB2_LIB.BASEBOARD_FAB2(SCH_1):PAGE101
 R2T23    1      A RES_0603-2.2,1.0%,1/10W,CHIP,GA    I94 @BASEBOARD_FAB2_LIB.BASEBOARD_FAB2(SCH_1):PAGE101
 R2T52    1      A RES_0603-2.2,1.0%,1/10W,CHIP,GA    I95 @BASEBOARD_FAB2_LIB.BASEBOARD_FAB2(SCH_1):PAGE101
 R2T21    1      A RES_0603-2.2,1.0%,1/10W,CHIP,GA   I105 @BASEBOARD_FAB2_LIB.BASEBOARD_FAB2(SCH_1):PAGE101
 C2T34    1      A CAP_A_0402V-0.1UF,16V,10%,X7R,A   I109 @BASEBOARD_FAB2_LIB.BASEBOARD_FAB2(SCH_1):PAGE101
 C2T30    1      A CAP_A_0402V-0.1UF,16V,10%,X7R,A   I110 @BASEBOARD_FAB2_LIB.BASEBOARD_FAB2(SCH_1):PAGE101
 C2T25    1      A CAP_A_0402V-0.1UF,16V,10%,X7R,A   I111 @BASEBOARD_FAB2_LIB.BASEBOARD_FAB2(SCH_1):PAGE101
 C2T17    1      A CAP_A_0402V-0.1UF,16V,10%,X7R,A   I112 @BASEBOARD_FAB2_LIB.BASEBOARD_FAB2(SCH_1):PAGE101
 C2T22    1      A CAP_0805-10UF,16V,10%,X6S,C953A   I113 @BASEBOARD_FAB2_LIB.BASEBOARD_FAB2(SCH_1):PAGE101
 FB2T2    2      B FERRITE_SMLF-600,FB,656554-043   I114 @BASEBOARD_FAB2_LIB.BASEBOARD_FAB2(SCH_1):PAGE101

P3V3_STBY_MNG_CPU @BASEBOARD_FAB2_LIB.BASEBOARD_FAB2(SCH_1):P3V3_STBY_MNG_CPU
 EU8F2    9 VDDCPU ICS9FGP204_MLFP-IC,E95226-001    I34 @BASEBOARD_FAB2_LIB.BASEBOARD_FAB2(SCH_1):PAGE101
 C2T18    1      A CAP_A_0402V-0.01UF,25V,10%,X7RA   I104 @BASEBOARD_FAB2_LIB.BASEBOARD_FAB2(SCH_1):PAGE101
 R2T21    2      B RES_0603-2.2,1.0%,1/10W,CHIP,GA   I105 @BASEBOARD_FAB2_LIB.BASEBOARD_FAB2(SCH_1):PAGE101
 C2T19    1      A CAP_A_0402V-1.0UF,6.3V,10%,X6SA   I106 @BASEBOARD_FAB2_LIB.BASEBOARD_FAB2(SCH_1):PAGE101

P3V3_STBY_MNG_RGMII @BASEBOARD_FAB2_LIB.BASEBOARD_FAB2(SCH_1):P3V3_STBY_MNG_RGMII
 EU8F2   34 VDD_RGMII ICS9FGP204_MLFP-IC,E95226-001    I34 @BASEBOARD_FAB2_LIB.BASEBOARD_FAB2(SCH_1):PAGE101
 C2T31    1      A CAP_A_0402V-1.0UF,6.3V,10%,X6SA    I89 @BASEBOARD_FAB2_LIB.BASEBOARD_FAB2(SCH_1):PAGE101
 C2T27    1      A CAP_A_0402V-0.01UF,25V,10%,X7RA    I90 @BASEBOARD_FAB2_LIB.BASEBOARD_FAB2(SCH_1):PAGE101
 R2T23    2      B RES_0603-2.2,1.0%,1/10W,CHIP,GA    I94 @BASEBOARD_FAB2_LIB.BASEBOARD_FAB2(SCH_1):PAGE101

P3V3_STBY_MNG_RMII @BASEBOARD_FAB2_LIB.BASEBOARD_FAB2(SCH_1):P3V3_STBY_MNG_RMII
 EU8F2   26 VDDRMII<0> ICS9FGP204_MLFP-IC,E95226-001    I34 @BASEBOARD_FAB2_LIB.BASEBOARD_FAB2(SCH_1):PAGE101
 EU8F2   31 VDDRMII<1> ICS9FGP204_MLFP-IC,E95226-001    I34 @BASEBOARD_FAB2_LIB.BASEBOARD_FAB2(SCH_1):PAGE101
 R2T52    2      B RES_0603-2.2,1.0%,1/10W,CHIP,GA    I95 @BASEBOARD_FAB2_LIB.BASEBOARD_FAB2(SCH_1):PAGE101
 C2T38    1      A CAP_A_0402V-1.0UF,6.3V,10%,X6SA    I97 @BASEBOARD_FAB2_LIB.BASEBOARD_FAB2(SCH_1):PAGE101
 C2T37    1      A CAP_A_0402V-0.01UF,25V,10%,X7RA    I99 @BASEBOARD_FAB2_LIB.BASEBOARD_FAB2(SCH_1):PAGE101

P3V3_STBY_P1V5_LAN_I210 @BASEBOARD_FAB2_LIB.BASEBOARD_FAB2(SCH_1):P3V3_STBY_P1V5_LAN_I210
 EU9E1   51 VDD3P3<1> SPRINGVILLE_SM1-IC,G47144-004    I72 @BASEBOARD_FAB2_LIB.BASEBOARD_FAB2(SCH_1):PAGE139
 R1T34    2      B RES_0603-0,5.0%,1/10W,CHIP,G22A   I239 @BASEBOARD_FAB2_LIB.BASEBOARD_FAB2(SCH_1):PAGE139
 R1T33    2      B RES_0603-0,5.0%,1/10W,EMPTY,G2A   I240 @BASEBOARD_FAB2_LIB.BASEBOARD_FAB2(SCH_1):PAGE139

P3V3_STBY_PLD_D @BASEBOARD_FAB2_LIB.BASEBOARD_FAB2(SCH_1):P3V3_STBY_PLD_D
  J7G2    1    IO1 CONN8_C77962004_PIP-CONN,C7796A    I47 @BASEBOARD_FAB2_LIB.BASEBOARD_FAB2(SCH_1):PAGE189
 CR3U1    1      C DIODE_SMLF-1N5819HW,IC,D55839-A    I49 @BASEBOARD_FAB2_LIB.BASEBOARD_FAB2(SCH_1):PAGE189

P3V3_SWITCH_G @BASEBOARD_FAB2_LIB.BASEBOARD_FAB2(SCH_1):P3V3_SWITCH_G
 EU2T1    7      G SLG55021_SM-IC,G56246-001     I1 @BASEBOARD_FAB2_LIB.BASEBOARD_FAB2(SCH_1):PAGE198
  Q8G1    4   GATE MOSFET_N_LCC3-BSZ019N03LS,NFETA    I85 @BASEBOARD_FAB2_LIB.BASEBOARD_FAB2(SCH_1):PAGE198

P3V3_USB2A_ALG @BASEBOARD_FAB2_LIB.BASEBOARD_FAB2(SCH_1):P3V3_USB2A_ALG
C25W71    1      A CAP_0402-1.0UF,6.3V,10%,X6S,D9A     I4 @BASEBOARD_FAB2_LIB.BASEBOARD_FAB2(SCH_1):PAGE150
C25W70    1      1 SC4D7U10V3KX-GP_SMD-BCG-SC4D7UA     I6 @BASEBOARD_FAB2_LIB.BASEBOARD_FAB2(SCH_1):PAGE150
R25W120    2      2 0R3J-0-U-GP_RCL_GP-0R3J-0-U-GPA     I7 @BASEBOARD_FAB2_LIB.BASEBOARD_FAB2(SCH_1):PAGE150
 U25W4   C7 USB2AV33 AST2520A1-GP-GP_ASIC2-GB1-AST2A    I28 @BASEBOARD_FAB2_LIB.BASEBOARD_FAB2(SCH_1):PAGE148

P3V_BAT_SOURCE @BASEBOARD_FAB2_LIB.BASEBOARD_FAB2(SCH_1):P3V_BAT_SOURCE
 R2U43    1      A RES_0402-1.00K,1%,1/16W,CHIP,GA    I46 @BASEBOARD_FAB2_LIB.BASEBOARD_FAB2(SCH_1):PAGE196
XBT8G1    1     P1 VERT_BATT_3PIN_PIP-3PVERT,C686A    I51 @BASEBOARD_FAB2_LIB.BASEBOARD_FAB2(SCH_1):PAGE196
XBT8G1    2     P2 VERT_BATT_3PIN_PIP-3PVERT,C686A    I51 @BASEBOARD_FAB2_LIB.BASEBOARD_FAB2(SCH_1):PAGE196

P3V_BAT_SOURCE_R @BASEBOARD_FAB2_LIB.BASEBOARD_FAB2(SCH_1):P3V_BAT_SOURCE_R
 R1U50    2      B RES_0402-200.0K,1%,1/16W,CHIP,A   I126 @BASEBOARD_FAB2_LIB.BASEBOARD_FAB2(SCH_1):PAGE169
  Q9G1    3 DRAIN<0> FET_N_DUAL_SMLF-NTJD4001N,FET,A   I157 @BASEBOARD_FAB2_LIB.BASEBOARD_FAB2(SCH_1):PAGE169

P5V @BASEBOARD_FAB2_LIB.BASEBOARD_FAB2(SCH_1):P5V
 R1U29    1      A RES_0402-5.11K,1%,1/16W,CHIP,GA   I141 @BASEBOARD_FAB2_LIB.BASEBOARD_FAB2(SCH_1):PAGE169
  F8B1    1   A<0> FUSE_SMLF-IC,C94311-006    I41 @BASEBOARD_FAB2_LIB.BASEBOARD_FAB2(SCH_1):PAGE172
  U1M3    5     IN TPS2061_SM-IC,H66405-001   I100 @BASEBOARD_FAB2_LIB.BASEBOARD_FAB2(SCH_1):PAGE176
 C1M38    1      A CAP_A_0402V-0.1UF,16V,10%,X7R,A   I108 @BASEBOARD_FAB2_LIB.BASEBOARD_FAB2(SCH_1):PAGE176
 R8D39    1      A RES_0402-49.9K,1%,1/16W,CHIP,GA   I114 @BASEBOARD_FAB2_LIB.BASEBOARD_FAB2(SCH_1):PAGE196
 EU8B1    6      S SLG55021_SM-IC,G56246-001    I13 @BASEBOARD_FAB2_LIB.BASEBOARD_FAB2(SCH_1):PAGE198
  C8B6    1      A CAP_0805-10UF,16V,10%,X6S,C953A    I40 @BASEBOARD_FAB2_LIB.BASEBOARD_FAB2(SCH_1):PAGE198
  C8B7    1      A CAP_A_0402V-0.1UF,16V,10%,X7R,A    I41 @BASEBOARD_FAB2_LIB.BASEBOARD_FAB2(SCH_1):PAGE198
  Q8B1    1    SRC MOSFET_N_LCC3-BSZ019N03LS,NFETA    I87 @BASEBOARD_FAB2_LIB.BASEBOARD_FAB2(SCH_1):PAGE198

P5V_HDD_SATA @BASEBOARD_FAB2_LIB.BASEBOARD_FAB2(SCH_1):P5V_HDD_SATA
  J8A4    1    IO1 CONN4_H73295001_PIP-EMPTY,H732A    I25 @BASEBOARD_FAB2_LIB.BASEBOARD_FAB2(SCH_1):PAGE172
  C9B1    1      A CAP_0805-10UF,16V,10%,X6S,C953A    I39 @BASEBOARD_FAB2_LIB.BASEBOARD_FAB2(SCH_1):PAGE172
  F8B1    2   B<0> FUSE_SMLF-IC,C94311-006    I41 @BASEBOARD_FAB2_LIB.BASEBOARD_FAB2(SCH_1):PAGE172
  J2L1    1    IO1 CONN4_H73295001_PIP-CONN,H7329A    I53 @BASEBOARD_FAB2_LIB.BASEBOARD_FAB2(SCH_1):PAGE172

P5V_STBY @BASEBOARD_FAB2_LIB.BASEBOARD_FAB2(SCH_1):P5V_STBY
  Q1L2    6 DRAIN<0> FET_N_DUAL_SMLF-NTJD4001N,FET,A   I188 @BASEBOARD_FAB2_LIB.BASEBOARD_FAB2(SCH_1):PAGE155
  R9A6    1      A RES_0402-20.0K,1%,1/16W,EMPTY,A   I191 @BASEBOARD_FAB2_LIB.BASEBOARD_FAB2(SCH_1):PAGE155
 CR1E1    1      C DIODE_SM-SDMK0340L,EMPTY,H7179A    I50 @BASEBOARD_FAB2_LIB.BASEBOARD_FAB2(SCH_1):PAGE161
 R1E12    1      A RES_0402-4.75K,1%,1/16W,CHIP,GA    I51 @BASEBOARD_FAB2_LIB.BASEBOARD_FAB2(SCH_1):PAGE161
 CR1B1    1      C DIODE_SM-SDMK0340L,EMPTY,H7179A    I64 @BASEBOARD_FAB2_LIB.BASEBOARD_FAB2(SCH_1):PAGE161
 R7F33    1      A RES_0402-4.75K,1%,1/16W,CHIP,GA    I65 @BASEBOARD_FAB2_LIB.BASEBOARD_FAB2(SCH_1):PAGE161
 R1U47    1      A RES_0402-5.11K,1%,1/16W,CHIP,GA   I115 @BASEBOARD_FAB2_LIB.BASEBOARD_FAB2(SCH_1):PAGE169
  R1L8    1      A RES_0402-470.0,5%,1/16W,CHIP,GA    I58 @BASEBOARD_FAB2_LIB.BASEBOARD_FAB2(SCH_1):PAGE175
  C1L4    1      A CAP_A_0402V-0.1UF,16V,10%,X7R,A    I64 @BASEBOARD_FAB2_LIB.BASEBOARD_FAB2(SCH_1):PAGE175
 R1L37    1      A RES_0402-301.0,1%,1/16W,CHIP,GA    I33 @BASEBOARD_FAB2_LIB.BASEBOARD_FAB2(SCH_1):PAGE177
  J9B3    3    IO3 SCONN120_A28699018_SM-SCONN,A2A   I336 @BASEBOARD_FAB2_LIB.BASEBOARD_FAB2(SCH_1):PAGE186
  J9B3    5    IO5 SCONN120_A28699018_SM-SCONN,A2A   I336 @BASEBOARD_FAB2_LIB.BASEBOARD_FAB2(SCH_1):PAGE186
  J9B3    7    IO7 SCONN120_A28699018_SM-SCONN,A2A   I336 @BASEBOARD_FAB2_LIB.BASEBOARD_FAB2(SCH_1):PAGE186
 C9B10    1      A CAP_A_0402V-0.1UF,16V,10%,X7R,A   I345 @BASEBOARD_FAB2_LIB.BASEBOARD_FAB2(SCH_1):PAGE186
  C9B9    1      A CAP_A_0402V-1.0UF,6.3V,10%,X6SA   I347 @BASEBOARD_FAB2_LIB.BASEBOARD_FAB2(SCH_1):PAGE186
  J4B2  A13  IOA13 SCONN120_H61426002_SM-CONN,H61A    I46 @BASEBOARD_FAB2_LIB.BASEBOARD_FAB2(SCH_1):PAGE193
  J4B2  B13  IOB13 SCONN120_H61426002_SM-CONN,H61A    I46 @BASEBOARD_FAB2_LIB.BASEBOARD_FAB2(SCH_1):PAGE193
  J4B2  C13  IOC13 SCONN120_H61426002_SM-CONN,H61A    I46 @BASEBOARD_FAB2_LIB.BASEBOARD_FAB2(SCH_1):PAGE193
  J6B1  A13  IOA13 SCONN120_H61426002_SM-CONN,H61A    I56 @BASEBOARD_FAB2_LIB.BASEBOARD_FAB2(SCH_1):PAGE194
  J6B1  B13  IOB13 SCONN120_H61426002_SM-CONN,H61A    I56 @BASEBOARD_FAB2_LIB.BASEBOARD_FAB2(SCH_1):PAGE194
  J6B1  C13  IOC13 SCONN120_H61426002_SM-CONN,H61A    I56 @BASEBOARD_FAB2_LIB.BASEBOARD_FAB2(SCH_1):PAGE194
 EU2T1    3 SHDN_N SLG55021_SM-IC,G56246-001     I1 @BASEBOARD_FAB2_LIB.BASEBOARD_FAB2(SCH_1):PAGE198
 EU2T1    1    VCC SLG55021_SM-IC,G56246-001     I1 @BASEBOARD_FAB2_LIB.BASEBOARD_FAB2(SCH_1):PAGE198
 EU8B1    5      D SLG55021_SM-IC,G56246-001    I13 @BASEBOARD_FAB2_LIB.BASEBOARD_FAB2(SCH_1):PAGE198
 EU8B1    3 SHDN_N SLG55021_SM-IC,G56246-001    I13 @BASEBOARD_FAB2_LIB.BASEBOARD_FAB2(SCH_1):PAGE198
 EU8B1    1    VCC SLG55021_SM-IC,G56246-001    I13 @BASEBOARD_FAB2_LIB.BASEBOARD_FAB2(SCH_1):PAGE198
 EU7E1    3 SHDN_N SLG55021_SM-IC,G56246-001    I19 @BASEBOARD_FAB2_LIB.BASEBOARD_FAB2(SCH_1):PAGE198
 EU7E1    1    VCC SLG55021_SM-IC,G56246-001    I19 @BASEBOARD_FAB2_LIB.BASEBOARD_FAB2(SCH_1):PAGE198
 C8F17    1      A CAP_A_0402V-0.1UF,16V,10%,X7R,A    I24 @BASEBOARD_FAB2_LIB.BASEBOARD_FAB2(SCH_1):PAGE198
  C8B8    1      A CAP_A_0402V-0.1UF,16V,10%,X7R,A    I26 @BASEBOARD_FAB2_LIB.BASEBOARD_FAB2(SCH_1):PAGE198
 C8E19    1      A CAP_A_0402V-0.1UF,16V,10%,X7R,A    I28 @BASEBOARD_FAB2_LIB.BASEBOARD_FAB2(SCH_1):PAGE198
  C8B5    1      A CAP_A_0402V-0.1UF,16V,10%,X7R,A    I37 @BASEBOARD_FAB2_LIB.BASEBOARD_FAB2(SCH_1):PAGE198
 C8B12    1      A CAP_0805-10UF,16V,10%,X6S,C953A    I38 @BASEBOARD_FAB2_LIB.BASEBOARD_FAB2(SCH_1):PAGE198
  C9M6    1      A CAP_A_0402V-0.1UF,16V,10%,X7R,A    I67 @BASEBOARD_FAB2_LIB.BASEBOARD_FAB2(SCH_1):PAGE198
 EU9M1    3 SHDN_N SLG55021_SM-IC,G56246-001    I69 @BASEBOARD_FAB2_LIB.BASEBOARD_FAB2(SCH_1):PAGE198
 EU9M1    1    VCC SLG55021_SM-IC,G56246-001    I69 @BASEBOARD_FAB2_LIB.BASEBOARD_FAB2(SCH_1):PAGE198
  Q8B1    5    DRN MOSFET_N_LCC3-BSZ019N03LS,NFETA    I87 @BASEBOARD_FAB2_LIB.BASEBOARD_FAB2(SCH_1):PAGE198
  C4E5    1      A CAP_0402-0.22UF,16V,10%,X7R,A3A    I18 @BASEBOARD_FAB2_LIB.BASEBOARD_FAB2(SCH_1):PAGE202
  C4E6    1      A CAP_A_0402V-1.0UF,6.3V,10%,X6SA    I19 @BASEBOARD_FAB2_LIB.BASEBOARD_FAB2(SCH_1):PAGE202
 C4E27    1      A CAP_0402-0.22UF,16V,10%,X7R,A3A    I24 @BASEBOARD_FAB2_LIB.BASEBOARD_FAB2(SCH_1):PAGE202
 C4E25    1      A CAP_A_0402V-1.0UF,6.3V,10%,X6SA    I25 @BASEBOARD_FAB2_LIB.BASEBOARD_FAB2(SCH_1):PAGE202
  R6R2    2      B RES_0402-1.0,1%,1/16W,CHIP,G21A    I33 @BASEBOARD_FAB2_LIB.BASEBOARD_FAB2(SCH_1):PAGE202
  R6R6    2      B RES_0402-1.0,1%,1/16W,CHIP,G21A    I39 @BASEBOARD_FAB2_LIB.BASEBOARD_FAB2(SCH_1):PAGE202
 EU4E1   35     EN IR354XX_SM-IR35411,IC,H73688-0A    I63 @BASEBOARD_FAB2_LIB.BASEBOARD_FAB2(SCH_1):PAGE202
 EU4E1    4   VDRV IR354XX_SM-IR35411,IC,H73688-0A    I63 @BASEBOARD_FAB2_LIB.BASEBOARD_FAB2(SCH_1):PAGE202
 EU4D6   35     EN IR354XX_SM-IR35411,IC,H73688-0A    I64 @BASEBOARD_FAB2_LIB.BASEBOARD_FAB2(SCH_1):PAGE202
 EU4D6    4   VDRV IR354XX_SM-IR35411,IC,H73688-0A    I64 @BASEBOARD_FAB2_LIB.BASEBOARD_FAB2(SCH_1):PAGE202
 R6P19    2      B RES_0402-1.0,1%,1/16W,CHIP,G21A    I38 @BASEBOARD_FAB2_LIB.BASEBOARD_FAB2(SCH_1):PAGE203
 C4D13    1      A CAP_0402-0.22UF,16V,10%,X7R,A3A    I40 @BASEBOARD_FAB2_LIB.BASEBOARD_FAB2(SCH_1):PAGE203
 C4D14    1      A CAP_A_0402V-1.0UF,6.3V,10%,X6SA    I41 @BASEBOARD_FAB2_LIB.BASEBOARD_FAB2(SCH_1):PAGE203
  C4D5    1      A CAP_0402-0.22UF,16V,10%,X7R,A3A    I48 @BASEBOARD_FAB2_LIB.BASEBOARD_FAB2(SCH_1):PAGE203
  C4D6    1      A CAP_A_0402V-1.0UF,6.3V,10%,X6SA    I49 @BASEBOARD_FAB2_LIB.BASEBOARD_FAB2(SCH_1):PAGE203
 R6P10    2      B RES_0402-1.0,1%,1/16W,CHIP,G21A    I50 @BASEBOARD_FAB2_LIB.BASEBOARD_FAB2(SCH_1):PAGE203
 EU4D3   35     EN IR354XX_SM-IR35411,IC,H73688-0A    I70 @BASEBOARD_FAB2_LIB.BASEBOARD_FAB2(SCH_1):PAGE203
 EU4D3    4   VDRV IR354XX_SM-IR35411,IC,H73688-0A    I70 @BASEBOARD_FAB2_LIB.BASEBOARD_FAB2(SCH_1):PAGE203
 EU4D1   35     EN IR354XX_SM-IR35411,IC,H73688-0A    I71 @BASEBOARD_FAB2_LIB.BASEBOARD_FAB2(SCH_1):PAGE203
 EU4D1    4   VDRV IR354XX_SM-IR35411,IC,H73688-0A    I71 @BASEBOARD_FAB2_LIB.BASEBOARD_FAB2(SCH_1):PAGE203
 C4D47    1      A CAP_0402-0.22UF,16V,10%,X7R,A3A    I18 @BASEBOARD_FAB2_LIB.BASEBOARD_FAB2(SCH_1):PAGE204
 C4C14    1      A CAP_A_0402V-1.0UF,6.3V,10%,X6SA    I19 @BASEBOARD_FAB2_LIB.BASEBOARD_FAB2(SCH_1):PAGE204
 R6P47    2      B RES_0402-1.0,1%,1/16W,CHIP,G21A    I33 @BASEBOARD_FAB2_LIB.BASEBOARD_FAB2(SCH_1):PAGE204
 EU4C2   35     EN IR354XX_SM-IR35411,IC,H73688-0A    I71 @BASEBOARD_FAB2_LIB.BASEBOARD_FAB2(SCH_1):PAGE204
 EU4C2    4   VDRV IR354XX_SM-IR35411,IC,H73688-0A    I71 @BASEBOARD_FAB2_LIB.BASEBOARD_FAB2(SCH_1):PAGE204
  C4C5    1      A CAP_0402-0.22UF,16V,10%,X7R,A3A    I16 @BASEBOARD_FAB2_LIB.BASEBOARD_FAB2(SCH_1):PAGE205
  C4C4    1      A CAP_A_0402V-1.0UF,6.3V,10%,X6SA    I18 @BASEBOARD_FAB2_LIB.BASEBOARD_FAB2(SCH_1):PAGE205
  R6N3    2      B RES_0402-1.0,1%,1/16W,CHIP,G21A    I19 @BASEBOARD_FAB2_LIB.BASEBOARD_FAB2(SCH_1):PAGE205
 EU4C1   35     EN IR354XX_SM-IR35412,IC,H73684-0A    I46 @BASEBOARD_FAB2_LIB.BASEBOARD_FAB2(SCH_1):PAGE205
 EU4C1    4   VDRV IR354XX_SM-IR35412,IC,H73684-0A    I46 @BASEBOARD_FAB2_LIB.BASEBOARD_FAB2(SCH_1):PAGE205
 EU1E2   35     EN IR354XX_SM-IR35411,IC,H73688-0A    I20 @BASEBOARD_FAB2_LIB.BASEBOARD_FAB2(SCH_1):PAGE207
 EU1E2    4   VDRV IR354XX_SM-IR35411,IC,H73688-0A    I20 @BASEBOARD_FAB2_LIB.BASEBOARD_FAB2(SCH_1):PAGE207
 EU1D4   35     EN IR354XX_SM-IR35411,IC,H73688-0A    I24 @BASEBOARD_FAB2_LIB.BASEBOARD_FAB2(SCH_1):PAGE207
 EU1D4    4   VDRV IR354XX_SM-IR35411,IC,H73688-0A    I24 @BASEBOARD_FAB2_LIB.BASEBOARD_FAB2(SCH_1):PAGE207
  R9R2    2      B RES_0402-1.0,1%,1/16W,CHIP,G21A    I26 @BASEBOARD_FAB2_LIB.BASEBOARD_FAB2(SCH_1):PAGE207
  C1E7    1      A CAP_0402-0.22UF,16V,10%,X7R,A3A    I28 @BASEBOARD_FAB2_LIB.BASEBOARD_FAB2(SCH_1):PAGE207
  C1E6    1      A CAP_A_0402V-1.0UF,6.3V,10%,X6SA    I29 @BASEBOARD_FAB2_LIB.BASEBOARD_FAB2(SCH_1):PAGE207
 C1E25    1      A CAP_0402-0.22UF,16V,10%,X7R,A3A    I36 @BASEBOARD_FAB2_LIB.BASEBOARD_FAB2(SCH_1):PAGE207
 C1E23    1      A CAP_A_0402V-1.0UF,6.3V,10%,X6SA    I37 @BASEBOARD_FAB2_LIB.BASEBOARD_FAB2(SCH_1):PAGE207
 R9R11    2      B RES_0402-1.0,1%,1/16W,CHIP,G21A    I39 @BASEBOARD_FAB2_LIB.BASEBOARD_FAB2(SCH_1):PAGE207
 EU1D3   35     EN IR354XX_SM-IR35411,IC,H73688-0A    I27 @BASEBOARD_FAB2_LIB.BASEBOARD_FAB2(SCH_1):PAGE208
 EU1D3    4   VDRV IR354XX_SM-IR35411,IC,H73688-0A    I27 @BASEBOARD_FAB2_LIB.BASEBOARD_FAB2(SCH_1):PAGE208
 R9P22    2      B RES_0402-1.0,1%,1/16W,CHIP,G21A    I36 @BASEBOARD_FAB2_LIB.BASEBOARD_FAB2(SCH_1):PAGE208
 C1D16    1      A CAP_0402-0.22UF,16V,10%,X7R,A3A    I38 @BASEBOARD_FAB2_LIB.BASEBOARD_FAB2(SCH_1):PAGE208
 C1D15    1      A CAP_A_0402V-1.0UF,6.3V,10%,X6SA    I39 @BASEBOARD_FAB2_LIB.BASEBOARD_FAB2(SCH_1):PAGE208
  C1D6    1      A CAP_0402-0.22UF,16V,10%,X7R,A3A    I46 @BASEBOARD_FAB2_LIB.BASEBOARD_FAB2(SCH_1):PAGE208
  C1D5    1      A CAP_A_0402V-1.0UF,6.3V,10%,X6SA    I47 @BASEBOARD_FAB2_LIB.BASEBOARD_FAB2(SCH_1):PAGE208
  R9P8    2      B RES_0402-1.0,1%,1/16W,CHIP,G21A    I49 @BASEBOARD_FAB2_LIB.BASEBOARD_FAB2(SCH_1):PAGE208
 EU1D1   35     EN IR354XX_SM-IR35411,IC,H73688-0A    I71 @BASEBOARD_FAB2_LIB.BASEBOARD_FAB2(SCH_1):PAGE208
 EU1D1    4   VDRV IR354XX_SM-IR35411,IC,H73688-0A    I71 @BASEBOARD_FAB2_LIB.BASEBOARD_FAB2(SCH_1):PAGE208
 C1C18    1      A CAP_A_0402V-1.0UF,6.3V,10%,X6SA    I21 @BASEBOARD_FAB2_LIB.BASEBOARD_FAB2(SCH_1):PAGE209
 C1D33    1      A CAP_0402-0.22UF,16V,10%,X7R,A3A    I22 @BASEBOARD_FAB2_LIB.BASEBOARD_FAB2(SCH_1):PAGE209
 R9P32    2      B RES_0402-1.0,1%,1/16W,CHIP,G21A    I24 @BASEBOARD_FAB2_LIB.BASEBOARD_FAB2(SCH_1):PAGE209
 EU1C3   35     EN IR354XX_SM-IR35411,IC,H73688-0A    I56 @BASEBOARD_FAB2_LIB.BASEBOARD_FAB2(SCH_1):PAGE209
 EU1C3    4   VDRV IR354XX_SM-IR35411,IC,H73688-0A    I56 @BASEBOARD_FAB2_LIB.BASEBOARD_FAB2(SCH_1):PAGE209
  R9N3    2      B RES_0402-1.0,1%,1/16W,CHIP,G21A    I20 @BASEBOARD_FAB2_LIB.BASEBOARD_FAB2(SCH_1):PAGE210
  C1C4    1      A CAP_0402-0.22UF,16V,10%,X7R,A3A    I22 @BASEBOARD_FAB2_LIB.BASEBOARD_FAB2(SCH_1):PAGE210
  C1C3    1      A CAP_A_0402V-1.0UF,6.3V,10%,X6SA    I23 @BASEBOARD_FAB2_LIB.BASEBOARD_FAB2(SCH_1):PAGE210
 EU1C1   35     EN IR354XX_SM-IR35412,IC,H73684-0A    I51 @BASEBOARD_FAB2_LIB.BASEBOARD_FAB2(SCH_1):PAGE210
 EU1C1    4   VDRV IR354XX_SM-IR35412,IC,H73684-0A    I51 @BASEBOARD_FAB2_LIB.BASEBOARD_FAB2(SCH_1):PAGE210
  R3N7    2      B RES_0402-1.0,1%,1/16W,CHIP,G21A    I32 @BASEBOARD_FAB2_LIB.BASEBOARD_FAB2(SCH_1):PAGE212
 C7C18    1      A CAP_0402-0.22UF,16V,10%,X7R,A3A    I33 @BASEBOARD_FAB2_LIB.BASEBOARD_FAB2(SCH_1):PAGE212
 C7C20    1      A CAP_A_0402V-1.0UF,6.3V,10%,X6SA    I34 @BASEBOARD_FAB2_LIB.BASEBOARD_FAB2(SCH_1):PAGE212
 EU7C1   35     EN IR354XX_SM-IR35412,IC,H73684-0A   I101 @BASEBOARD_FAB2_LIB.BASEBOARD_FAB2(SCH_1):PAGE212
 EU7C1    4   VDRV IR354XX_SM-IR35412,IC,H73684-0A   I101 @BASEBOARD_FAB2_LIB.BASEBOARD_FAB2(SCH_1):PAGE212
  R6R5    2      B RES_0402-1.0,1%,1/16W,CHIP,G21A    I71 @BASEBOARD_FAB2_LIB.BASEBOARD_FAB2(SCH_1):PAGE214
 C4E23    1      A CAP_0402-0.22UF,16V,10%,X7R,A3A    I73 @BASEBOARD_FAB2_LIB.BASEBOARD_FAB2(SCH_1):PAGE214
 C4E28    1      A CAP_A_0402V-1.0UF,6.3V,10%,X6SA    I74 @BASEBOARD_FAB2_LIB.BASEBOARD_FAB2(SCH_1):PAGE214
 EU4E2   35     EN IR354XX_SM-IR35412,IC,H73684-0A   I126 @BASEBOARD_FAB2_LIB.BASEBOARD_FAB2(SCH_1):PAGE214
 EU4E2    4   VDRV IR354XX_SM-IR35412,IC,H73684-0A   I126 @BASEBOARD_FAB2_LIB.BASEBOARD_FAB2(SCH_1):PAGE214
  R3U6    2      B RES_0402-1.0,1%,1/16W,CHIP,G21A    I52 @BASEBOARD_FAB2_LIB.BASEBOARD_FAB2(SCH_1):PAGE216
 C7G35    1      A CAP_A_0402V-1.0UF,6.3V,10%,X6SA    I53 @BASEBOARD_FAB2_LIB.BASEBOARD_FAB2(SCH_1):PAGE216
 C7G34    1      A CAP_0402-0.22UF,16V,10%,X7R,A3A    I54 @BASEBOARD_FAB2_LIB.BASEBOARD_FAB2(SCH_1):PAGE216
 C7G41    1      A CAP_0402-0.22UF,16V,10%,X7R,A3A    I72 @BASEBOARD_FAB2_LIB.BASEBOARD_FAB2(SCH_1):PAGE216
 C7G42    1      A CAP_A_0402V-1.0UF,6.3V,10%,X6SA    I73 @BASEBOARD_FAB2_LIB.BASEBOARD_FAB2(SCH_1):PAGE216
  R3U9    2      B RES_0402-1.0,1%,1/16W,CHIP,G21A    I76 @BASEBOARD_FAB2_LIB.BASEBOARD_FAB2(SCH_1):PAGE216
 EU7G2   35     EN IR354XX_SM-IR35411,IC,H73688-0A   I102 @BASEBOARD_FAB2_LIB.BASEBOARD_FAB2(SCH_1):PAGE216
 EU7G2    4   VDRV IR354XX_SM-IR35411,IC,H73688-0A   I102 @BASEBOARD_FAB2_LIB.BASEBOARD_FAB2(SCH_1):PAGE216
 EU7G3   35     EN IR354XX_SM-IR35411,IC,H73688-0A   I103 @BASEBOARD_FAB2_LIB.BASEBOARD_FAB2(SCH_1):PAGE216
 EU7G3    4   VDRV IR354XX_SM-IR35411,IC,H73688-0A   I103 @BASEBOARD_FAB2_LIB.BASEBOARD_FAB2(SCH_1):PAGE216
  R3L6    2      B RES_0402-1.0,1%,1/16W,CHIP,G21A    I52 @BASEBOARD_FAB2_LIB.BASEBOARD_FAB2(SCH_1):PAGE219
 C7A18    1      A CAP_A_0402V-1.0UF,6.3V,10%,X6SA    I53 @BASEBOARD_FAB2_LIB.BASEBOARD_FAB2(SCH_1):PAGE219
 C7A17    1      A CAP_0402-0.22UF,16V,10%,X7R,A3A    I54 @BASEBOARD_FAB2_LIB.BASEBOARD_FAB2(SCH_1):PAGE219
 C7A25    1      A CAP_0402-0.22UF,16V,10%,X7R,A3A    I72 @BASEBOARD_FAB2_LIB.BASEBOARD_FAB2(SCH_1):PAGE219
 C7A26    1      A CAP_A_0402V-1.0UF,6.3V,10%,X6SA    I73 @BASEBOARD_FAB2_LIB.BASEBOARD_FAB2(SCH_1):PAGE219
  R3L8    2      B RES_0402-1.0,1%,1/16W,CHIP,G21A    I76 @BASEBOARD_FAB2_LIB.BASEBOARD_FAB2(SCH_1):PAGE219
 EU7A1   35     EN IR354XX_SM-IR35411,IC,H73688-0A   I106 @BASEBOARD_FAB2_LIB.BASEBOARD_FAB2(SCH_1):PAGE219
 EU7A1    4   VDRV IR354XX_SM-IR35411,IC,H73688-0A   I106 @BASEBOARD_FAB2_LIB.BASEBOARD_FAB2(SCH_1):PAGE219
 EU7A4   35     EN IR354XX_SM-IR35411,IC,H73688-0A   I107 @BASEBOARD_FAB2_LIB.BASEBOARD_FAB2(SCH_1):PAGE219
 EU7A4    4   VDRV IR354XX_SM-IR35411,IC,H73688-0A   I107 @BASEBOARD_FAB2_LIB.BASEBOARD_FAB2(SCH_1):PAGE219
  R9U1    2      B RES_0402-1.0,1%,1/16W,CHIP,G21A    I52 @BASEBOARD_FAB2_LIB.BASEBOARD_FAB2(SCH_1):PAGE224
  C1G4    1      A CAP_A_0402V-1.0UF,6.3V,10%,X6SA    I53 @BASEBOARD_FAB2_LIB.BASEBOARD_FAB2(SCH_1):PAGE224
  C1G5    1      A CAP_0402-0.22UF,16V,10%,X7R,A3A    I54 @BASEBOARD_FAB2_LIB.BASEBOARD_FAB2(SCH_1):PAGE224
 C1G29    1      A CAP_0402-0.22UF,16V,10%,X7R,A3A    I72 @BASEBOARD_FAB2_LIB.BASEBOARD_FAB2(SCH_1):PAGE224
 C1F21    1      A CAP_A_0402V-1.0UF,6.3V,10%,X6SA    I73 @BASEBOARD_FAB2_LIB.BASEBOARD_FAB2(SCH_1):PAGE224
 R9U12    2      B RES_0402-1.0,1%,1/16W,CHIP,G21A    I76 @BASEBOARD_FAB2_LIB.BASEBOARD_FAB2(SCH_1):PAGE224
 EU1G1   35     EN IR354XX_SM-IR35411,IC,H73688-0A   I110 @BASEBOARD_FAB2_LIB.BASEBOARD_FAB2(SCH_1):PAGE224
 EU1G1    4   VDRV IR354XX_SM-IR35411,IC,H73688-0A   I110 @BASEBOARD_FAB2_LIB.BASEBOARD_FAB2(SCH_1):PAGE224
 EU1F1   35     EN IR354XX_SM-IR35411,IC,H73688-0A   I111 @BASEBOARD_FAB2_LIB.BASEBOARD_FAB2(SCH_1):PAGE224
 EU1F1    4   VDRV IR354XX_SM-IR35411,IC,H73688-0A   I111 @BASEBOARD_FAB2_LIB.BASEBOARD_FAB2(SCH_1):PAGE224
  R9L9    2      B RES_0402-1.0,1%,1/16W,CHIP,G21A    I52 @BASEBOARD_FAB2_LIB.BASEBOARD_FAB2(SCH_1):PAGE227
  C1A2    1      A CAP_A_0402V-1.0UF,6.3V,10%,X6SA    I53 @BASEBOARD_FAB2_LIB.BASEBOARD_FAB2(SCH_1):PAGE227
 C1B21    1      A CAP_0402-0.22UF,16V,10%,X7R,A3A    I54 @BASEBOARD_FAB2_LIB.BASEBOARD_FAB2(SCH_1):PAGE227
 C1A13    1      A CAP_0402-0.22UF,16V,10%,X7R,A3A    I72 @BASEBOARD_FAB2_LIB.BASEBOARD_FAB2(SCH_1):PAGE227
 C1A11    1      A CAP_A_0402V-1.0UF,6.3V,10%,X6SA    I73 @BASEBOARD_FAB2_LIB.BASEBOARD_FAB2(SCH_1):PAGE227
  R9L4    2      B RES_0402-1.0,1%,1/16W,CHIP,G21A    I76 @BASEBOARD_FAB2_LIB.BASEBOARD_FAB2(SCH_1):PAGE227
 EU1A2   35     EN IR354XX_SM-IR35411,IC,H73688-0A   I101 @BASEBOARD_FAB2_LIB.BASEBOARD_FAB2(SCH_1):PAGE227
 EU1A2    4   VDRV IR354XX_SM-IR35411,IC,H73688-0A   I101 @BASEBOARD_FAB2_LIB.BASEBOARD_FAB2(SCH_1):PAGE227
 EU1A1   35     EN IR354XX_SM-IR35411,IC,H73688-0A   I102 @BASEBOARD_FAB2_LIB.BASEBOARD_FAB2(SCH_1):PAGE227
 EU1A1    4   VDRV IR354XX_SM-IR35411,IC,H73688-0A   I102 @BASEBOARD_FAB2_LIB.BASEBOARD_FAB2(SCH_1):PAGE227
  R3L1    2      B RES_0402-1.0,1%,1/16W,CHIP,G21A    I14 @BASEBOARD_FAB2_LIB.BASEBOARD_FAB2(SCH_1):PAGE236
  C7A8    1      A CAP_0402-0.22UF,16V,10%,X7R,A3A    I16 @BASEBOARD_FAB2_LIB.BASEBOARD_FAB2(SCH_1):PAGE236
  C3L1    1      A CAP_A_0402V-1.0UF,6.3V,10%,X6SA    I17 @BASEBOARD_FAB2_LIB.BASEBOARD_FAB2(SCH_1):PAGE236
 C3L29    1      A CAP_A_0402V-1.0UF,6.3V,10%,X6SA    I38 @BASEBOARD_FAB2_LIB.BASEBOARD_FAB2(SCH_1):PAGE236
 C7A41    1      A CAP_0402-0.22UF,16V,10%,X7R,A3A    I39 @BASEBOARD_FAB2_LIB.BASEBOARD_FAB2(SCH_1):PAGE236
  R3L4    2      B RES_0402-1.0,1%,1/16W,CHIP,G21A    I41 @BASEBOARD_FAB2_LIB.BASEBOARD_FAB2(SCH_1):PAGE236
 EU7A3   35     EN IR354XX_SM-IR35412,IC,H73684-0A   I116 @BASEBOARD_FAB2_LIB.BASEBOARD_FAB2(SCH_1):PAGE236
 EU7A3    4   VDRV IR354XX_SM-IR35412,IC,H73684-0A   I116 @BASEBOARD_FAB2_LIB.BASEBOARD_FAB2(SCH_1):PAGE236
 EU7A2   35     EN IR354XX_SM-IR35412,IC,H73684-0A   I117 @BASEBOARD_FAB2_LIB.BASEBOARD_FAB2(SCH_1):PAGE236
 EU7A2    4   VDRV IR354XX_SM-IR35412,IC,H73684-0A   I117 @BASEBOARD_FAB2_LIB.BASEBOARD_FAB2(SCH_1):PAGE236
 C2R11    1      A CAP_0603-4.7UF,6.3V,10%,X6S,E1A   I109 @BASEBOARD_FAB2_LIB.BASEBOARD_FAB2(SCH_1):PAGE240
 EU8F1    5    VCC RT8240_QFN-IC,H66262-001   I125 @BASEBOARD_FAB2_LIB.BASEBOARD_FAB2(SCH_1):PAGE240
  C8E9    1      A CAP_0805-22UF,6.3V,20%,X6S,C95A     I2 @BASEBOARD_FAB2_LIB.BASEBOARD_FAB2(SCH_1):PAGE241
  C8E7    1      A CAP_0805-22UF,6.3V,20%,X6S,C95A     I3 @BASEBOARD_FAB2_LIB.BASEBOARD_FAB2(SCH_1):PAGE241
  C8E4    1      A CAPP_3018-470UF,6.3V,20%,POSCAA     I8 @BASEBOARD_FAB2_LIB.BASEBOARD_FAB2(SCH_1):PAGE241
 R8E18    1      A RES_0402-1.0K,0.1%,1/16W,CHIP,A     I9 @BASEBOARD_FAB2_LIB.BASEBOARD_FAB2(SCH_1):PAGE241
 R7E12    1      A RES_0402-1.00K,1%,1/16W,CHIP,GA    I11 @BASEBOARD_FAB2_LIB.BASEBOARD_FAB2(SCH_1):PAGE241
 R8E37    2      B RES_0402-0.0,5%,1/16W,CHIP,G21A    I78 @BASEBOARD_FAB2_LIB.BASEBOARD_FAB2(SCH_1):PAGE241
  L8E1    2    INB INDUCTOR_SM-2.2UH,IND,E98761-0A    I90 @BASEBOARD_FAB2_LIB.BASEBOARD_FAB2(SCH_1):PAGE241
 R6W13    1      A RES_0402-15.0K,1%,1/16W,CHIP,GA    I34 @BASEBOARD_FAB2_LIB.BASEBOARD_FAB2(SCH_1):PAGE168
  R9A5    1      A RES_0402-15.0K,1%,1/16W,CHIP,GA   I195 @BASEBOARD_FAB2_LIB.BASEBOARD_FAB2(SCH_1):PAGE155

P5V_STBY_DBG @BASEBOARD_FAB2_LIB.BASEBOARD_FAB2(SCH_1):P5V_STBY_DBG
  F1L1    1   A<0> FUSE_SMT-IC,H45581-001   I129 @BASEBOARD_FAB2_LIB.BASEBOARD_FAB2(SCH_1):PAGE155
  Q1L2    1 SOURCE<0> FET_N_DUAL_SMLF-NTJD4001N,FET,A   I188 @BASEBOARD_FAB2_LIB.BASEBOARD_FAB2(SCH_1):PAGE155

P5V_STBY_DGB_FS @BASEBOARD_FAB2_LIB.BASEBOARD_FAB2(SCH_1):P5V_STBY_DGB_FS
  C9A1    1      A CAP_A_0402V-0.1UF,16V,10%,X7R,A   I127 @BASEBOARD_FAB2_LIB.BASEBOARD_FAB2(SCH_1):PAGE155
  F1L1    2   B<0> FUSE_SMT-IC,H45581-001   I129 @BASEBOARD_FAB2_LIB.BASEBOARD_FAB2(SCH_1):PAGE155
  J9A2   14   IO14 CONN14_H54902001_PIP-CONN,H549A   I171 @BASEBOARD_FAB2_LIB.BASEBOARD_FAB2(SCH_1):PAGE155

P5V_SWITCH_G @BASEBOARD_FAB2_LIB.BASEBOARD_FAB2(SCH_1):P5V_SWITCH_G
 EU8B1    7      G SLG55021_SM-IC,G56246-001    I13 @BASEBOARD_FAB2_LIB.BASEBOARD_FAB2(SCH_1):PAGE198
  Q8B1    4   GATE MOSFET_N_LCC3-BSZ019N03LS,NFETA    I87 @BASEBOARD_FAB2_LIB.BASEBOARD_FAB2(SCH_1):PAGE198

P5V_USB @BASEBOARD_FAB2_LIB.BASEBOARD_FAB2(SCH_1):P5V_USB
  J9B1    1   VBUS CONN9_H51826001_PIP2-CONN,H518A    I69 @BASEBOARD_FAB2_LIB.BASEBOARD_FAB2(SCH_1):PAGE176
  U1M3    1    OUT TPS2061_SM-IC,H66405-001   I100 @BASEBOARD_FAB2_LIB.BASEBOARD_FAB2(SCH_1):PAGE176
  C9B8    1      A CAPP_7343HLF-330UF,10V,20%,POSA   I113 @BASEBOARD_FAB2_LIB.BASEBOARD_FAB2(SCH_1):PAGE176

PCA9555_A0 @BASEBOARD_FAB2_LIB.BASEBOARD_FAB2(SCH_1):PCA9555_A0
  R6W9    1      A RES_0402-4.75K,1%,1/16W,CHIP,GA     I9 @BASEBOARD_FAB2_LIB.BASEBOARD_FAB2(SCH_1):PAGE247
  R6W6    2      B RES_0402-4.75K,1%,1/16W,EMPTY,A    I11 @BASEBOARD_FAB2_LIB.BASEBOARD_FAB2(SCH_1):PAGE247
  U6W1   21     A0 PCA9555PWRG4-GP_DISCRET-G5-PCAA    I97 @BASEBOARD_FAB2_LIB.BASEBOARD_FAB2(SCH_1):PAGE247

PCA9555_A1 @BASEBOARD_FAB2_LIB.BASEBOARD_FAB2(SCH_1):PCA9555_A1
  R6W8    1      A RES_0402-4.75K,1%,1/16W,CHIP,GA     I8 @BASEBOARD_FAB2_LIB.BASEBOARD_FAB2(SCH_1):PAGE247
  R6W5    2      B RES_0402-4.75K,1%,1/16W,EMPTY,A    I10 @BASEBOARD_FAB2_LIB.BASEBOARD_FAB2(SCH_1):PAGE247
  U6W1    2     A1 PCA9555PWRG4-GP_DISCRET-G5-PCAA    I97 @BASEBOARD_FAB2_LIB.BASEBOARD_FAB2(SCH_1):PAGE247

PCA9555_A2 @BASEBOARD_FAB2_LIB.BASEBOARD_FAB2(SCH_1):PCA9555_A2
  R6W7    1      A RES_0402-4.75K,1%,1/16W,CHIP,GA     I3 @BASEBOARD_FAB2_LIB.BASEBOARD_FAB2(SCH_1):PAGE247
  R6W4    2      B RES_0402-4.75K,1%,1/16W,EMPTY,A     I5 @BASEBOARD_FAB2_LIB.BASEBOARD_FAB2(SCH_1):PAGE247
  U6W1    3     A2 PCA9555PWRG4-GP_DISCRET-G5-PCAA    I97 @BASEBOARD_FAB2_LIB.BASEBOARD_FAB2(SCH_1):PAGE247

PCA9555_INT_N @BASEBOARD_FAB2_LIB.BASEBOARD_FAB2(SCH_1):PCA9555_INT_N
 R6W10    2      B RES_0402-4.75K,1%,1/16W,CHIP,GA     I1 @BASEBOARD_FAB2_LIB.BASEBOARD_FAB2(SCH_1):PAGE247
  U6W1    1   INT# PCA9555PWRG4-GP_DISCRET-G5-PCAA    I97 @BASEBOARD_FAB2_LIB.BASEBOARD_FAB2(SCH_1):PAGE247

PD_ADCREXT @BASEBOARD_FAB2_LIB.BASEBOARD_FAB2(SCH_1):PD_ADCREXT
R25W57    2      B RES_0402-2.7K,1%,1/16W,CHIP,G2A    I40 @BASEBOARD_FAB2_LIB.BASEBOARD_FAB2(SCH_1):PAGE147
 U25W4   J1 ADCREXT AST2520A1-GP-GP_ASIC2-GB1-AST2A   I106 @BASEBOARD_FAB2_LIB.BASEBOARD_FAB2(SCH_1):PAGE147

PD_CKMNG_OE @BASEBOARD_FAB2_LIB.BASEBOARD_FAB2(SCH_1):PD_CKMNG_OE
 EU8F2    5  OE_96 ICS9FGP204_MLFP-IC,E95226-001    I34 @BASEBOARD_FAB2_LIB.BASEBOARD_FAB2(SCH_1):PAGE101
 EU8F2    6 OE_CPU ICS9FGP204_MLFP-IC,E95226-001    I34 @BASEBOARD_FAB2_LIB.BASEBOARD_FAB2(SCH_1):PAGE101
 R2T25    1      A RES_0402-1.00K,1%,1/16W,CHIP,GA    I48 @BASEBOARD_FAB2_LIB.BASEBOARD_FAB2(SCH_1):PAGE101

PD_CPU0_BIST_ENABLE @BASEBOARD_FAB2_LIB.BASEBOARD_FAB2(SCH_1):PD_CPU0_BIST_ENABLE
  U5D1 BA20 BIST_ENABLE SKX_EXT_B_BGA1-IC,TBD   I259 @BASEBOARD_FAB2_LIB.BASEBOARD_FAB2(SCH_1):PAGE21
  R4P1    2      B RES_0402-240,1.0%,1/16W,EMPTY,A     I4 @BASEBOARD_FAB2_LIB.BASEBOARD_FAB2(SCH_1):PAGE90

PD_CPU0_DMIMODE_OVERRIDE @BASEBOARD_FAB2_LIB.BASEBOARD_FAB2(SCH_1):PD_CPU0_DMIMODE_OVERRIDE
  U5D1 AW12 DMIMODE_OVERRIDE SKX_EXT_B_BGA1-IC,TBD   I204 @BASEBOARD_FAB2_LIB.BASEBOARD_FAB2(SCH_1):PAGE22
  R4P6    2      B RES_0402-240,1.0%,1/16W,EMPTY,A    I68 @BASEBOARD_FAB2_LIB.BASEBOARD_FAB2(SCH_1):PAGE90

PD_CPU0_KSFC_DIS @BASEBOARD_FAB2_LIB.BASEBOARD_FAB2(SCH_1):PD_CPU0_KSFC_DIS
  U5D1 AW14 TEST_15 SKX_EXT_B_BGA1-IC,TBD   I259 @BASEBOARD_FAB2_LIB.BASEBOARD_FAB2(SCH_1):PAGE21
  R4P7    2      B RES_0402-240,1.0%,1/16W,EMPTY,A    I72 @BASEBOARD_FAB2_LIB.BASEBOARD_FAB2(SCH_1):PAGE90

PD_CPU0_MCP01_DMON @BASEBOARD_FAB2_LIB.BASEBOARD_FAB2(SCH_1):PD_CPU0_MCP01_DMON
  U5D1 CN28 RSVD<75> SKX_EXT_B_BGA1-IC,TBD   I127 @BASEBOARD_FAB2_LIB.BASEBOARD_FAB2(SCH_1):PAGE39
  R4P5    2      B RES_0402-10.0K,1%,1/16W,CHIP,GA    I80 @BASEBOARD_FAB2_LIB.BASEBOARD_FAB2(SCH_1):PAGE97

PD_CPU0_RSVD_TEST_1 @BASEBOARD_FAB2_LIB.BASEBOARD_FAB2(SCH_1):PD_CPU0_RSVD_TEST_1
  R5R1    1      A RES_0402-49.9,1%,1/16W,CHIP,G2A   I188 @BASEBOARD_FAB2_LIB.BASEBOARD_FAB2(SCH_1):PAGE22
  U5D1 AF45 TEST_1 SKX_EXT_B_BGA1-IC,TBD   I204 @BASEBOARD_FAB2_LIB.BASEBOARD_FAB2(SCH_1):PAGE22

PD_CPU0_RSVD_TEST_2 @BASEBOARD_FAB2_LIB.BASEBOARD_FAB2(SCH_1):PD_CPU0_RSVD_TEST_2
  R5P4    1      A RES_0402-49.9,1%,1/16W,CHIP,G2A   I190 @BASEBOARD_FAB2_LIB.BASEBOARD_FAB2(SCH_1):PAGE22
  U5D1 AG46 TEST_2 SKX_EXT_B_BGA1-IC,TBD   I204 @BASEBOARD_FAB2_LIB.BASEBOARD_FAB2(SCH_1):PAGE22

PD_CPU0_TEST12 @BASEBOARD_FAB2_LIB.BASEBOARD_FAB2(SCH_1):PD_CPU0_TEST12
  U5D1 AY19 TEST_12 SKX_EXT_B_BGA1-IC,TBD   I259 @BASEBOARD_FAB2_LIB.BASEBOARD_FAB2(SCH_1):PAGE21
  R6D5    1      A RES_0402-49.9,1%,1/16W,CHIP,G2A    I81 @BASEBOARD_FAB2_LIB.BASEBOARD_FAB2(SCH_1):PAGE90

PD_CPU0_TEST13 @BASEBOARD_FAB2_LIB.BASEBOARD_FAB2(SCH_1):PD_CPU0_TEST13
  U5D1 DB51 TEST_13 SKX_EXT_B_BGA1-IC,TBD   I259 @BASEBOARD_FAB2_LIB.BASEBOARD_FAB2(SCH_1):PAGE21
  R5P3    1      A RES_0402-49.9,1%,1/16W,CHIP,G2A    I80 @BASEBOARD_FAB2_LIB.BASEBOARD_FAB2(SCH_1):PAGE90

PD_CPU0_TEST14 @BASEBOARD_FAB2_LIB.BASEBOARD_FAB2(SCH_1):PD_CPU0_TEST14
  U5D1 DC50 TEST_14 SKX_EXT_B_BGA1-IC,TBD   I259 @BASEBOARD_FAB2_LIB.BASEBOARD_FAB2(SCH_1):PAGE21
  R5P2    1      A RES_0402-49.9,1%,1/16W,CHIP,G2A    I79 @BASEBOARD_FAB2_LIB.BASEBOARD_FAB2(SCH_1):PAGE90

PD_CPU0_TXT_PLTEN @BASEBOARD_FAB2_LIB.BASEBOARD_FAB2(SCH_1):PD_CPU0_TXT_PLTEN
  U5D1 AV15 TXT_PLTEN SKX_EXT_B_BGA1-IC,TBD   I259 @BASEBOARD_FAB2_LIB.BASEBOARD_FAB2(SCH_1):PAGE21
  R6D6    2      B RES_0402-240,1.0%,1/16W,CHIP,GA     I3 @BASEBOARD_FAB2_LIB.BASEBOARD_FAB2(SCH_1):PAGE90

PD_CPU1_BIST_ENABLE @BASEBOARD_FAB2_LIB.BASEBOARD_FAB2(SCH_1):PD_CPU1_BIST_ENABLE
  U2D1 BA20 BIST_ENABLE SKX_EXT_B_BGA1-IC,TBD   I172 @BASEBOARD_FAB2_LIB.BASEBOARD_FAB2(SCH_1):PAGE55
 R3D13    2      B RES_0402-240,1.0%,1/16W,EMPTY,A    I12 @BASEBOARD_FAB2_LIB.BASEBOARD_FAB2(SCH_1):PAGE90

PD_CPU1_DMIMODE_OVERRIDE @BASEBOARD_FAB2_LIB.BASEBOARD_FAB2(SCH_1):PD_CPU1_DMIMODE_OVERRIDE
  U2D1 AW12 DMIMODE_OVERRIDE SKX_EXT_B_BGA1-IC,TBD   I169 @BASEBOARD_FAB2_LIB.BASEBOARD_FAB2(SCH_1):PAGE56
 R7P14    2      B RES_0402-240,1.0%,1/16W,CHIP,GA    I70 @BASEBOARD_FAB2_LIB.BASEBOARD_FAB2(SCH_1):PAGE90

PD_CPU1_KSFC_DIS @BASEBOARD_FAB2_LIB.BASEBOARD_FAB2(SCH_1):PD_CPU1_KSFC_DIS
  U2D1 AW14 TEST_15 SKX_EXT_B_BGA1-IC,TBD   I172 @BASEBOARD_FAB2_LIB.BASEBOARD_FAB2(SCH_1):PAGE55
 R7P15    2      B RES_0402-240,1.0%,1/16W,EMPTY,A    I74 @BASEBOARD_FAB2_LIB.BASEBOARD_FAB2(SCH_1):PAGE90

PD_CPU1_MCP01_DMON @BASEBOARD_FAB2_LIB.BASEBOARD_FAB2(SCH_1):PD_CPU1_MCP01_DMON
  U2D1 CN28 RSVD<75> SKX_EXT_B_BGA1-IC,TBD   I107 @BASEBOARD_FAB2_LIB.BASEBOARD_FAB2(SCH_1):PAGE73
 R7P13    2      B RES_0402-10.0K,1%,1/16W,CHIP,GA    I81 @BASEBOARD_FAB2_LIB.BASEBOARD_FAB2(SCH_1):PAGE97

PD_CPU1_RSVD_TEST_1 @BASEBOARD_FAB2_LIB.BASEBOARD_FAB2(SCH_1):PD_CPU1_RSVD_TEST_1
  U2D1 AF45 TEST_1 SKX_EXT_B_BGA1-IC,TBD   I169 @BASEBOARD_FAB2_LIB.BASEBOARD_FAB2(SCH_1):PAGE56
  R8R1    1      A RES_0402-49.9,1%,1/16W,CHIP,G2A   I174 @BASEBOARD_FAB2_LIB.BASEBOARD_FAB2(SCH_1):PAGE56

PD_CPU1_RSVD_TEST_2 @BASEBOARD_FAB2_LIB.BASEBOARD_FAB2(SCH_1):PD_CPU1_RSVD_TEST_2
  U2D1 AG46 TEST_2 SKX_EXT_B_BGA1-IC,TBD   I169 @BASEBOARD_FAB2_LIB.BASEBOARD_FAB2(SCH_1):PAGE56
  R8P3    1      A RES_0402-49.9,1%,1/16W,CHIP,G2A   I173 @BASEBOARD_FAB2_LIB.BASEBOARD_FAB2(SCH_1):PAGE56

PD_CPU1_TEST12 @BASEBOARD_FAB2_LIB.BASEBOARD_FAB2(SCH_1):PD_CPU1_TEST12
  U2D1 AY19 TEST_12 SKX_EXT_B_BGA1-IC,TBD   I172 @BASEBOARD_FAB2_LIB.BASEBOARD_FAB2(SCH_1):PAGE55
  R3D9    1      A RES_0402-49.9,1%,1/16W,CHIP,G2A    I88 @BASEBOARD_FAB2_LIB.BASEBOARD_FAB2(SCH_1):PAGE90

PD_CPU1_TEST13 @BASEBOARD_FAB2_LIB.BASEBOARD_FAB2(SCH_1):PD_CPU1_TEST13
  U2D1 DB51 TEST_13 SKX_EXT_B_BGA1-IC,TBD   I172 @BASEBOARD_FAB2_LIB.BASEBOARD_FAB2(SCH_1):PAGE55
  R8P2    1      A RES_0402-49.9,1%,1/16W,CHIP,G2A    I86 @BASEBOARD_FAB2_LIB.BASEBOARD_FAB2(SCH_1):PAGE90

PD_CPU1_TEST14 @BASEBOARD_FAB2_LIB.BASEBOARD_FAB2(SCH_1):PD_CPU1_TEST14
  U2D1 DC50 TEST_14 SKX_EXT_B_BGA1-IC,TBD   I172 @BASEBOARD_FAB2_LIB.BASEBOARD_FAB2(SCH_1):PAGE55
  R8P1    1      A RES_0402-49.9,1%,1/16W,CHIP,G2A    I85 @BASEBOARD_FAB2_LIB.BASEBOARD_FAB2(SCH_1):PAGE90

PD_CPU1_TXT_PLTEN @BASEBOARD_FAB2_LIB.BASEBOARD_FAB2(SCH_1):PD_CPU1_TXT_PLTEN
  U2D1 AV15 TXT_PLTEN SKX_EXT_B_BGA1-IC,TBD   I172 @BASEBOARD_FAB2_LIB.BASEBOARD_FAB2(SCH_1):PAGE55
 R3D12    2      B RES_0402-240,1.0%,1/16W,CHIP,GA    I11 @BASEBOARD_FAB2_LIB.BASEBOARD_FAB2(SCH_1):PAGE90

PD_DIR_2 @BASEBOARD_FAB2_LIB.BASEBOARD_FAB2(SCH_1):PD_DIR_2
  U9G1    1    DIR GTL2014_SM-IC,D66151-001     I1 @BASEBOARD_FAB2_LIB.BASEBOARD_FAB2(SCH_1):PAGE152
 R1U30    1      A RES_0402-1.00K,1%,1/16W,CHIP,GA     I2 @BASEBOARD_FAB2_LIB.BASEBOARD_FAB2(SCH_1):PAGE152

PD_FRU_WP @BASEBOARD_FAB2_LIB.BASEBOARD_FAB2(SCH_1):PD_FRU_WP
  U8D4    7     WP AT24C64_SOICLF-IC,C47049-001-GA    I49 @BASEBOARD_FAB2_LIB.BASEBOARD_FAB2(SCH_1):PAGE167
 R8D27    1      A RES_0402-1.00K,1%,1/16W,CHIP,GA    I50 @BASEBOARD_FAB2_LIB.BASEBOARD_FAB2(SCH_1):PAGE167

PD_GTL2014_1_VREF @BASEBOARD_FAB2_LIB.BASEBOARD_FAB2(SCH_1):PD_GTL2014_1_VREF
  U3P1    4   VREF GTL2014_SM-IC,D66151-001    I42 @BASEBOARD_FAB2_LIB.BASEBOARD_FAB2(SCH_1):PAGE96
 R3P32    2      B RES_0402-1.00K,1%,1/16W,CHIP,GA    I71 @BASEBOARD_FAB2_LIB.BASEBOARD_FAB2(SCH_1):PAGE96

PD_GTL2014_2_VREF @BASEBOARD_FAB2_LIB.BASEBOARD_FAB2(SCH_1):PD_GTL2014_2_VREF
  U4C2    4   VREF GTL2014_SM-IC,D66151-001    I46 @BASEBOARD_FAB2_LIB.BASEBOARD_FAB2(SCH_1):PAGE96
  R4C9    2      B RES_0402-1.00K,1%,1/16W,CHIP,GA    I69 @BASEBOARD_FAB2_LIB.BASEBOARD_FAB2(SCH_1):PAGE96

PD_GTL2104_4_DIR @BASEBOARD_FAB2_LIB.BASEBOARD_FAB2(SCH_1):PD_GTL2104_4_DIR
  U2T4    1    DIR GTL2014_SM-IC,D66151-001    I30 @BASEBOARD_FAB2_LIB.BASEBOARD_FAB2(SCH_1):PAGE93
 R2T50    1      A RES_0402-1.00K,1%,1/16W,CHIP,GA   I127 @BASEBOARD_FAB2_LIB.BASEBOARD_FAB2(SCH_1):PAGE93

PD_GTL2104_DIR_0 @BASEBOARD_FAB2_LIB.BASEBOARD_FAB2(SCH_1):PD_GTL2104_DIR_0
  U7D2    1    DIR GTL2014_SM-IC,D66151-001    I32 @BASEBOARD_FAB2_LIB.BASEBOARD_FAB2(SCH_1):PAGE92
 R7D26    1      A RES_0402-1.00K,1%,1/16W,CHIP,GA    I54 @BASEBOARD_FAB2_LIB.BASEBOARD_FAB2(SCH_1):PAGE92

PD_GTL2104_DIR_1 @BASEBOARD_FAB2_LIB.BASEBOARD_FAB2(SCH_1):PD_GTL2104_DIR_1
  U3P2    1    DIR GTL2014_SM-IC,D66151-001     I1 @BASEBOARD_FAB2_LIB.BASEBOARD_FAB2(SCH_1):PAGE92
  R3R1    1      A RES_0402-1.00K,1%,1/16W,CHIP,GA    I46 @BASEBOARD_FAB2_LIB.BASEBOARD_FAB2(SCH_1):PAGE92

PD_HSC_RETRY_N @BASEBOARD_FAB2_LIB.BASEBOARD_FAB2(SCH_1):PD_HSC_RETRY_N
 EU1D2   17 RETRY_N ADM1278_SM-IC,G99251-001    I10 @BASEBOARD_FAB2_LIB.BASEBOARD_FAB2(SCH_1):PAGE199
 R1D28    1      A RES_0402-100.0,1%,1/16W,EMPTY,A    I26 @BASEBOARD_FAB2_LIB.BASEBOARD_FAB2(SCH_1):PAGE199

PD_ID_EEPROM_WP @BASEBOARD_FAB2_LIB.BASEBOARD_FAB2(SCH_1):PD_ID_EEPROM_WP
  U6W3    7     WP AT24C64_SOICLF-IC,C47049-001-GA    I89 @BASEBOARD_FAB2_LIB.BASEBOARD_FAB2(SCH_1):PAGE247
 R6W23    1      A RES_0402-1.00K,1%,1/16W,CHIP,GA    I92 @BASEBOARD_FAB2_LIB.BASEBOARD_FAB2(SCH_1):PAGE247

PD_IE_DEBUG_MODE @BASEBOARD_FAB2_LIB.BASEBOARD_FAB2(SCH_1):PD_IE_DEBUG_MODE
 R1U64    1      A RES_0402-1.00K,1%,1/16W,CHIP,GA    I69 @BASEBOARD_FAB2_LIB.BASEBOARD_FAB2(SCH_1):PAGE137
  J9G1   11   IO11 CONN12_C73564003_PIP-CONN,C735A   I128 @BASEBOARD_FAB2_LIB.BASEBOARD_FAB2(SCH_1):PAGE137

PD_ME_RCVR_N @BASEBOARD_FAB2_LIB.BASEBOARD_FAB2(SCH_1):PD_ME_RCVR_N
 R7G28    1      A RES_0402-1.00K,1%,1/16W,CHIP,GA   I102 @BASEBOARD_FAB2_LIB.BASEBOARD_FAB2(SCH_1):PAGE136
  J7G3    5    IO5 CONN12_C73564003_PIP-CONN,C735A   I174 @BASEBOARD_FAB2_LIB.BASEBOARD_FAB2(SCH_1):PAGE136

PD_PASSWORD_CLEAR @BASEBOARD_FAB2_LIB.BASEBOARD_FAB2(SCH_1):PD_PASSWORD_CLEAR
 R7G29    1      A RES_0402-1.00K,1%,1/16W,CHIP,GA   I148 @BASEBOARD_FAB2_LIB.BASEBOARD_FAB2(SCH_1):PAGE136
  J7G3   11   IO11 CONN12_C73564003_PIP-CONN,C735A   I174 @BASEBOARD_FAB2_LIB.BASEBOARD_FAB2(SCH_1):PAGE136

PD_PEREXT @BASEBOARD_FAB2_LIB.BASEBOARD_FAB2(SCH_1):PD_PEREXT
R25W67    1      A RES_0402-10.0K,1%,1/16W,EMPTY,A    I46 @BASEBOARD_FAB2_LIB.BASEBOARD_FAB2(SCH_1):PAGE145
 U25W4  K20 PEREXT AST2520A1-GP-GP_ASIC2-GB1-AST2A   I117 @BASEBOARD_FAB2_LIB.BASEBOARD_FAB2(SCH_1):PAGE145

PD_PIROM_CPU0_ADDR0 @BASEBOARD_FAB2_LIB.BASEBOARD_FAB2(SCH_1):PD_PIROM_CPU0_ADDR0
  U5D1 CU58 PIROM_ADDR<0> SKX_EXT_B_BGA1-IC,TBD   I259 @BASEBOARD_FAB2_LIB.BASEBOARD_FAB2(SCH_1):PAGE21
 R6N14    2      B RES_0402-1.00K,1%,1/16W,CHIP,GA   I302 @BASEBOARD_FAB2_LIB.BASEBOARD_FAB2(SCH_1):PAGE156

PD_PIROM_CPU0_ADDR1 @BASEBOARD_FAB2_LIB.BASEBOARD_FAB2(SCH_1):PD_PIROM_CPU0_ADDR1
  U5D1 CV57 PIROM_ADDR<1> SKX_EXT_B_BGA1-IC,TBD   I259 @BASEBOARD_FAB2_LIB.BASEBOARD_FAB2(SCH_1):PAGE21
 R6N13    2      B RES_0402-1.00K,1%,1/16W,CHIP,GA   I303 @BASEBOARD_FAB2_LIB.BASEBOARD_FAB2(SCH_1):PAGE156

PD_PIROM_CPU0_ADDR2 @BASEBOARD_FAB2_LIB.BASEBOARD_FAB2(SCH_1):PD_PIROM_CPU0_ADDR2
  U5D1 CW56 PIROM_ADDR<2> SKX_EXT_B_BGA1-IC,TBD   I259 @BASEBOARD_FAB2_LIB.BASEBOARD_FAB2(SCH_1):PAGE21
 R6N15    2      B RES_0402-1.00K,1%,1/16W,CHIP,GA   I304 @BASEBOARD_FAB2_LIB.BASEBOARD_FAB2(SCH_1):PAGE156

PD_PIROM_CPU1_ADDR1 @BASEBOARD_FAB2_LIB.BASEBOARD_FAB2(SCH_1):PD_PIROM_CPU1_ADDR1
  U2D1 CV57 PIROM_ADDR<1> SKX_EXT_B_BGA1-IC,TBD   I172 @BASEBOARD_FAB2_LIB.BASEBOARD_FAB2(SCH_1):PAGE55
 R1C33    2      B RES_0402-1.00K,1%,1/16W,CHIP,GA   I313 @BASEBOARD_FAB2_LIB.BASEBOARD_FAB2(SCH_1):PAGE156

PD_PIROM_CPU1_ADDR2 @BASEBOARD_FAB2_LIB.BASEBOARD_FAB2(SCH_1):PD_PIROM_CPU1_ADDR2
  U2D1 CW56 PIROM_ADDR<2> SKX_EXT_B_BGA1-IC,TBD   I172 @BASEBOARD_FAB2_LIB.BASEBOARD_FAB2(SCH_1):PAGE55
 R1C32    2      B RES_0402-1.00K,1%,1/16W,CHIP,GA   I312 @BASEBOARD_FAB2_LIB.BASEBOARD_FAB2(SCH_1):PAGE156

PD_RST_RTCRST_N @BASEBOARD_FAB2_LIB.BASEBOARD_FAB2(SCH_1):PD_RST_RTCRST_N
 R1U63    1      A RES_0402-1.00K,1%,1/16W,CHIP,GA    I15 @BASEBOARD_FAB2_LIB.BASEBOARD_FAB2(SCH_1):PAGE137
  J9G1    6    IO6 CONN12_C73564003_PIP-CONN,C735A   I128 @BASEBOARD_FAB2_LIB.BASEBOARD_FAB2(SCH_1):PAGE137

PD_SATA0_CONTROLLER_TYPE_R @BASEBOARD_FAB2_LIB.BASEBOARD_FAB2(SCH_1):PD_SATA0_CONTROLLER_TYPE_R
  J8A1  1D2 SIDEBANDA_6 CONN72_G97614002_A_CP-CONN,G97A   I163 @BASEBOARD_FAB2_LIB.BASEBOARD_FAB2(SCH_1):PAGE173
 R2L18    1      A RES_0402-1.00K,1%,1/16W,CHIP,GA   I266 @BASEBOARD_FAB2_LIB.BASEBOARD_FAB2(SCH_1):PAGE173

PD_SATA1_CONTROLLER_TYPE_R @BASEBOARD_FAB2_LIB.BASEBOARD_FAB2(SCH_1):PD_SATA1_CONTROLLER_TYPE_R
  J8A1  2D2 SIDEBANDB_6 CONN72_G97614002_A_CP-CONN,G97A   I163 @BASEBOARD_FAB2_LIB.BASEBOARD_FAB2(SCH_1):PAGE173
 R2L22    1      A RES_0402-1.00K,1%,1/16W,CHIP,GA   I264 @BASEBOARD_FAB2_LIB.BASEBOARD_FAB2(SCH_1):PAGE173

PD_SATA2_CONTROLLER_TYPE @BASEBOARD_FAB2_LIB.BASEBOARD_FAB2(SCH_1):PD_SATA2_CONTROLLER_TYPE
  R1L3    1      A RES_0402-1.00K,1%,1/16W,CHIP,GA     I5 @BASEBOARD_FAB2_LIB.BASEBOARD_FAB2(SCH_1):PAGE174
  J8A2   D2 SIDEBAND6 CONN36_G97614001_CP-CONN,G9761A    I26 @BASEBOARD_FAB2_LIB.BASEBOARD_FAB2(SCH_1):PAGE174

PD_SPRV_RSET @BASEBOARD_FAB2_LIB.BASEBOARD_FAB2(SCH_1):PD_SPRV_RSET
 EU9E1   48   RSET SPRINGVILLE_SM1-IC,G47144-004    I72 @BASEBOARD_FAB2_LIB.BASEBOARD_FAB2(SCH_1):PAGE139
 R9E23    1      A RES_0402-4.99K,1%,1/16W,CHIP,GA   I174 @BASEBOARD_FAB2_LIB.BASEBOARD_FAB2(SCH_1):PAGE139

PD_SP_ENTEST @BASEBOARD_FAB2_LIB.BASEBOARD_FAB2(SCH_1):PD_SP_ENTEST
  R1U7    2      B RES_0402-10.0K,1%,1/16W,CHIP,GA    I78 @BASEBOARD_FAB2_LIB.BASEBOARD_FAB2(SCH_1):PAGE146
 U25W4   K3 ENTEST AST2520A1-GP-GP_ASIC2-GB1-AST2A   I105 @BASEBOARD_FAB2_LIB.BASEBOARD_FAB2(SCH_1):PAGE146

PD_TMP421_1_A0 @BASEBOARD_FAB2_LIB.BASEBOARD_FAB2(SCH_1):PD_TMP421_1_A0
  U9B4    4   A<0> TMP421_TSSOP-IC,G62962-001     I1 @BASEBOARD_FAB2_LIB.BASEBOARD_FAB2(SCH_1):PAGE167
  R9B8    1      A RES_0402-1.00K,1%,1/16W,CHIP,GA    I10 @BASEBOARD_FAB2_LIB.BASEBOARD_FAB2(SCH_1):PAGE167

PD_TMP421_2_A1 @BASEBOARD_FAB2_LIB.BASEBOARD_FAB2(SCH_1):PD_TMP421_2_A1
  U1E1    3   A<1> TMP421_TSSOP-IC,G62962-001    I30 @BASEBOARD_FAB2_LIB.BASEBOARD_FAB2(SCH_1):PAGE167
 R1E10    2      B RES_0402-1.00K,1%,1/16W,CHIP,GA    I38 @BASEBOARD_FAB2_LIB.BASEBOARD_FAB2(SCH_1):PAGE167

PECI_BMC @BASEBOARD_FAB2_LIB.BASEBOARD_FAB2(SCH_1):PECI_BMC
 R7C18    1      A RES_0402-0.0,5%,1/16W,EMPTY,G2A    I11 @BASEBOARD_FAB2_LIB.BASEBOARD_FAB2(SCH_1):PAGE166
 R7C17    2      B RES_0402-4.75K,1%,1/16W,CHIP,GA    I28 @BASEBOARD_FAB2_LIB.BASEBOARD_FAB2(SCH_1):PAGE166
 R9F33    1      A RES_0402-0.0,5%,1/16W,CHIP,G21A    I20 @BASEBOARD_FAB2_LIB.BASEBOARD_FAB2(SCH_1):PAGE145
 R9F20    1      A RES_0402-348,1%,1/16W,EMPTY,G2A    I22 @BASEBOARD_FAB2_LIB.BASEBOARD_FAB2(SCH_1):PAGE145

PECI_BMC_R @BASEBOARD_FAB2_LIB.BASEBOARD_FAB2(SCH_1):PECI_BMC_R
 R9F33    2      B RES_0402-0.0,5%,1/16W,CHIP,G21A    I20 @BASEBOARD_FAB2_LIB.BASEBOARD_FAB2(SCH_1):PAGE145
 U25W4 AB18   PECI AST2520A1-GP-GP_ASIC2-GB1-AST2A   I117 @BASEBOARD_FAB2_LIB.BASEBOARD_FAB2(SCH_1):PAGE145

PECI_CPU_G @BASEBOARD_FAB2_LIB.BASEBOARD_FAB2(SCH_1):PECI_CPU_G
  U5D1 AU12   PECI SKX_EXT_B_BGA1-IC,TBD   I259 @BASEBOARD_FAB2_LIB.BASEBOARD_FAB2(SCH_1):PAGE21
  U2D1 AU12   PECI SKX_EXT_B_BGA1-IC,TBD   I172 @BASEBOARD_FAB2_LIB.BASEBOARD_FAB2(SCH_1):PAGE55
 R7C18    2      B RES_0402-0.0,5%,1/16W,EMPTY,G2A    I11 @BASEBOARD_FAB2_LIB.BASEBOARD_FAB2(SCH_1):PAGE166
 R7C19    2      B RES_0402-0.0,5%,1/16W,CHIP,G21A    I15 @BASEBOARD_FAB2_LIB.BASEBOARD_FAB2(SCH_1):PAGE166
 R7D15    1      A RES_0402-348,1%,1/16W,CHIP,G21A    I32 @BASEBOARD_FAB2_LIB.BASEBOARD_FAB2(SCH_1):PAGE166

PECI_PCH @BASEBOARD_FAB2_LIB.BASEBOARD_FAB2(SCH_1):PECI_PCH
  U7C1   U9   PECI LBG_CORE_QAT_EXT_D_BGA1-IC,H91A    I73 @BASEBOARD_FAB2_LIB.BASEBOARD_FAB2(SCH_1):PAGE118
 R7C22    2      B RES_0402-4.75K,1%,1/16W,EMPTY,A    I14 @BASEBOARD_FAB2_LIB.BASEBOARD_FAB2(SCH_1):PAGE166
 R7C19    1      A RES_0402-0.0,5%,1/16W,CHIP,G21A    I15 @BASEBOARD_FAB2_LIB.BASEBOARD_FAB2(SCH_1):PAGE166

PE_PCH_SPRV_RX_C_DN @BASEBOARD_FAB2_LIB.BASEBOARD_FAB2(SCH_1):PE_PCH_SPRV_RX_C_DN
  U7C1 AM69 PCIE5_GBE_RXN LBG_CORE_QAT_EXT_D_BGA1-IC,H91A   I220 @BASEBOARD_FAB2_LIB.BASEBOARD_FAB2(SCH_1):PAGE116
  C9E5    2      B CAP_A_0402V-0.1UF,16V,10%,X7R,A    I87 @BASEBOARD_FAB2_LIB.BASEBOARD_FAB2(SCH_1):PAGE139

PE_PCH_SPRV_RX_C_DP @BASEBOARD_FAB2_LIB.BASEBOARD_FAB2(SCH_1):PE_PCH_SPRV_RX_C_DP
  U7C1 AM71 PCIE5_GBE_RXP LBG_CORE_QAT_EXT_D_BGA1-IC,H91A   I220 @BASEBOARD_FAB2_LIB.BASEBOARD_FAB2(SCH_1):PAGE116
  C9E4    2      B CAP_A_0402V-0.1UF,16V,10%,X7R,A    I88 @BASEBOARD_FAB2_LIB.BASEBOARD_FAB2(SCH_1):PAGE139

PE_PCH_SPRV_RX_DN @BASEBOARD_FAB2_LIB.BASEBOARD_FAB2(SCH_1):PE_PCH_SPRV_RX_DN
 EU9E1   20  PE_TN SPRINGVILLE_SM1-IC,G47144-004    I72 @BASEBOARD_FAB2_LIB.BASEBOARD_FAB2(SCH_1):PAGE139
  C9E5    1      A CAP_A_0402V-0.1UF,16V,10%,X7R,A    I87 @BASEBOARD_FAB2_LIB.BASEBOARD_FAB2(SCH_1):PAGE139

PE_PCH_SPRV_RX_DP @BASEBOARD_FAB2_LIB.BASEBOARD_FAB2(SCH_1):PE_PCH_SPRV_RX_DP
 EU9E1   21  PE_TP SPRINGVILLE_SM1-IC,G47144-004    I72 @BASEBOARD_FAB2_LIB.BASEBOARD_FAB2(SCH_1):PAGE139
  C9E4    1      A CAP_A_0402V-0.1UF,16V,10%,X7R,A    I88 @BASEBOARD_FAB2_LIB.BASEBOARD_FAB2(SCH_1):PAGE139

PE_PCH_SPRV_TX_C_DN @BASEBOARD_FAB2_LIB.BASEBOARD_FAB2(SCH_1):PE_PCH_SPRV_TX_C_DN
 EU9E1   23  PE_RN SPRINGVILLE_SM1-IC,G47144-004    I72 @BASEBOARD_FAB2_LIB.BASEBOARD_FAB2(SCH_1):PAGE139
 C2M24    2      B CAP_A_0402V-0.1UF,16V,10%,X7R,A    I90 @BASEBOARD_FAB2_LIB.BASEBOARD_FAB2(SCH_1):PAGE139

PE_PCH_SPRV_TX_C_DP @BASEBOARD_FAB2_LIB.BASEBOARD_FAB2(SCH_1):PE_PCH_SPRV_TX_C_DP
 EU9E1   24  PE_RP SPRINGVILLE_SM1-IC,G47144-004    I72 @BASEBOARD_FAB2_LIB.BASEBOARD_FAB2(SCH_1):PAGE139
 C2M23    2      B CAP_A_0402V-0.1UF,16V,10%,X7R,A    I89 @BASEBOARD_FAB2_LIB.BASEBOARD_FAB2(SCH_1):PAGE139

PE_PCH_SPRV_TX_DN @BASEBOARD_FAB2_LIB.BASEBOARD_FAB2(SCH_1):PE_PCH_SPRV_TX_DN
  U7C1 BH65 PCIE5_GBE_TXN LBG_CORE_QAT_EXT_D_BGA1-IC,H91A   I220 @BASEBOARD_FAB2_LIB.BASEBOARD_FAB2(SCH_1):PAGE116
 C2M24    1      A CAP_A_0402V-0.1UF,16V,10%,X7R,A    I90 @BASEBOARD_FAB2_LIB.BASEBOARD_FAB2(SCH_1):PAGE139

PE_PCH_SPRV_TX_DP @BASEBOARD_FAB2_LIB.BASEBOARD_FAB2(SCH_1):PE_PCH_SPRV_TX_DP
  U7C1 BJ63 PCIE5_GBE_TXP LBG_CORE_QAT_EXT_D_BGA1-IC,H91A   I220 @BASEBOARD_FAB2_LIB.BASEBOARD_FAB2(SCH_1):PAGE116
 C2M23    1      A CAP_A_0402V-0.1UF,16V,10%,X7R,A    I89 @BASEBOARD_FAB2_LIB.BASEBOARD_FAB2(SCH_1):PAGE139

PU_10GBE_LOM_PCI_DISABLE_N @BASEBOARD_FAB2_LIB.BASEBOARD_FAB2(SCH_1):PU_10GBE_LOM_PCI_DISABLE_N
  U7C1 BW22 GPP_I8_PCI_DIS_N LBG_CORE_QAT_EXT_D_BGA1-IC,H91A   I147 @BASEBOARD_FAB2_LIB.BASEBOARD_FAB2(SCH_1):PAGE120
  R2N9    2      B RES_0402-10.0K,1%,1/16W,CHIP,GA   I267 @BASEBOARD_FAB2_LIB.BASEBOARD_FAB2(SCH_1):PAGE133

PU_24M_OSC_OE @BASEBOARD_FAB2_LIB.BASEBOARD_FAB2(SCH_1):PU_24M_OSC_OE
  Y9F2    1 ENABLE_CONTROL OSC_C_SM4-24MHZ,OSC,D34520-021     I8 @BASEBOARD_FAB2_LIB.BASEBOARD_FAB2(SCH_1):PAGE145
 R9F61    2      B RES_0402-10.0K,1%,1/16W,CHIP,GA    I14 @BASEBOARD_FAB2_LIB.BASEBOARD_FAB2(SCH_1):PAGE145

PU_ADR_TIMER_HOLD_OFF_N @BASEBOARD_FAB2_LIB.BASEBOARD_FAB2(SCH_1):PU_ADR_TIMER_HOLD_OFF_N
  U7C1  BB3 GPP_H15_SML3ALERT_N_IE_N LBG_CORE_QAT_EXT_D_BGA1-IC,H91A   I147 @BASEBOARD_FAB2_LIB.BASEBOARD_FAB2(SCH_1):PAGE120
  R8D5    1      A RES_0402-1.00K,1%,1/16W,EMPTY,A    I50 @BASEBOARD_FAB2_LIB.BASEBOARD_FAB2(SCH_1):PAGE125
 R8D13    2      B RES_0402-10.0K,1%,1/16W,CHIP,GA    I52 @BASEBOARD_FAB2_LIB.BASEBOARD_FAB2(SCH_1):PAGE125

PU_AT24C64_A2 @BASEBOARD_FAB2_LIB.BASEBOARD_FAB2(SCH_1):PU_AT24C64_A2
  U8D4    3     A2 AT24C64_SOICLF-IC,C47049-001-GA    I49 @BASEBOARD_FAB2_LIB.BASEBOARD_FAB2(SCH_1):PAGE167
 R8D28    2      B RES_0402-1.00K,1%,1/16W,CHIP,GA    I70 @BASEBOARD_FAB2_LIB.BASEBOARD_FAB2(SCH_1):PAGE167

PU_BIOS_RECOVER_BOOT @BASEBOARD_FAB2_LIB.BASEBOARD_FAB2(SCH_1):PU_BIOS_RECOVER_BOOT
 R7G31    2      B RES_0402-1.00K,1%,1/16W,CHIP,GA   I139 @BASEBOARD_FAB2_LIB.BASEBOARD_FAB2(SCH_1):PAGE136
  J7G3   12   IO12 CONN12_C73564003_PIP-CONN,C735A   I174 @BASEBOARD_FAB2_LIB.BASEBOARD_FAB2(SCH_1):PAGE136

PU_BIOS_SPI_HOLD0_N @BASEBOARD_FAB2_LIB.BASEBOARD_FAB2(SCH_1):PU_BIOS_SPI_HOLD0_N
  R7F3    2      B RES_0402-33.2,1%,1/16W,CHIP,G2A   I109 @BASEBOARD_FAB2_LIB.BASEBOARD_FAB2(SCH_1):PAGE153
 R7F32    2      B RES_0402-10.0K,1%,1/16W,CHIP,GA   I140 @BASEBOARD_FAB2_LIB.BASEBOARD_FAB2(SCH_1):PAGE153
  U7F1    1 HOLD_N_IO<3> W25Q256_XSOI-IC,H25002-001   I146 @BASEBOARD_FAB2_LIB.BASEBOARD_FAB2(SCH_1):PAGE153

PU_BIOS_SPI_HOLD1_N @BASEBOARD_FAB2_LIB.BASEBOARD_FAB2(SCH_1):PU_BIOS_SPI_HOLD1_N
  R3T1    2      B RES_0402-33.2,1%,1/16W,CHIP,G2A   I157 @BASEBOARD_FAB2_LIB.BASEBOARD_FAB2(SCH_1):PAGE153
  U3T1    1 HOLD_N_IO<3> W25Q256_XSOI-IC,H25002-001   I165 @BASEBOARD_FAB2_LIB.BASEBOARD_FAB2(SCH_1):PAGE153
  R3T4    2      B RES_0402-10.0K,1%,1/16W,CHIP,GA   I174 @BASEBOARD_FAB2_LIB.BASEBOARD_FAB2(SCH_1):PAGE153

PU_BIOS_SPI_WP0_N @BASEBOARD_FAB2_LIB.BASEBOARD_FAB2(SCH_1):PU_BIOS_SPI_WP0_N
 R7F37    2      B RES_0402-33.2,1%,1/16W,CHIP,G2A   I108 @BASEBOARD_FAB2_LIB.BASEBOARD_FAB2(SCH_1):PAGE153
  U7F1    9 WP_N_IO<2> W25Q256_XSOI-IC,H25002-001   I146 @BASEBOARD_FAB2_LIB.BASEBOARD_FAB2(SCH_1):PAGE153
 R7F28    2      B RES_0402-10.0K,1%,1/16W,CHIP,GA   I168 @BASEBOARD_FAB2_LIB.BASEBOARD_FAB2(SCH_1):PAGE153
 R7F30    1      A RES_0402-10.0K,1%,1/16W,EMPTY,A   I170 @BASEBOARD_FAB2_LIB.BASEBOARD_FAB2(SCH_1):PAGE153

PU_BIOS_SPI_WP1_N @BASEBOARD_FAB2_LIB.BASEBOARD_FAB2(SCH_1):PU_BIOS_SPI_WP1_N
  R3U1    2      B RES_0402-33.2,1%,1/16W,CHIP,G2A   I156 @BASEBOARD_FAB2_LIB.BASEBOARD_FAB2(SCH_1):PAGE153
  U3T1    9 WP_N_IO<2> W25Q256_XSOI-IC,H25002-001   I165 @BASEBOARD_FAB2_LIB.BASEBOARD_FAB2(SCH_1):PAGE153
 R3T12    2      B RES_0402-10.0K,1%,1/16W,CHIP,GA   I178 @BASEBOARD_FAB2_LIB.BASEBOARD_FAB2(SCH_1):PAGE153
  R3T9    1      A RES_0402-10.0K,1%,1/16W,EMPTY,A   I179 @BASEBOARD_FAB2_LIB.BASEBOARD_FAB2(SCH_1):PAGE153

PU_BIOS_USB_RECOVERY @BASEBOARD_FAB2_LIB.BASEBOARD_FAB2(SCH_1):PU_BIOS_USB_RECOVERY
 R7G27    2      B RES_0402-1.00K,1%,1/16W,CHIP,GA   I155 @BASEBOARD_FAB2_LIB.BASEBOARD_FAB2(SCH_1):PAGE136
  J7G3    6    IO6 CONN12_C73564003_PIP-CONN,C735A   I174 @BASEBOARD_FAB2_LIB.BASEBOARD_FAB2(SCH_1):PAGE136

PU_CPU0_EAR_N @BASEBOARD_FAB2_LIB.BASEBOARD_FAB2(SCH_1):PU_CPU0_EAR_N
  U5D1 AJ14  EAR_N SKX_EXT_B_BGA1-IC,TBD   I259 @BASEBOARD_FAB2_LIB.BASEBOARD_FAB2(SCH_1):PAGE21
 R6D14    2      B RES_0402-240,1.0%,1/16W,EMPTY,A    I52 @BASEBOARD_FAB2_LIB.BASEBOARD_FAB2(SCH_1):PAGE90

PU_CPU0_FRMAGENT @BASEBOARD_FAB2_LIB.BASEBOARD_FAB2(SCH_1):PU_CPU0_FRMAGENT
  U5D1 AV17 FRMAGENT SKX_EXT_B_BGA1-IC,TBD   I259 @BASEBOARD_FAB2_LIB.BASEBOARD_FAB2(SCH_1):PAGE21
  R5D3    2      B RES_0402-240,1.0%,1/16W,CHIP,GA    I29 @BASEBOARD_FAB2_LIB.BASEBOARD_FAB2(SCH_1):PAGE90

PU_CPU0_LEGACY_SKT @BASEBOARD_FAB2_LIB.BASEBOARD_FAB2(SCH_1):PU_CPU0_LEGACY_SKT
  U5D1 AE20 LEGACY_SKT SKX_EXT_B_BGA1-IC,TBD   I259 @BASEBOARD_FAB2_LIB.BASEBOARD_FAB2(SCH_1):PAGE21
 R4P14    2      B RES_0402-240,1.0%,1/16W,CHIP,GA    I53 @BASEBOARD_FAB2_LIB.BASEBOARD_FAB2(SCH_1):PAGE90

PU_CPU0_SAFE_MODE_BOOT @BASEBOARD_FAB2_LIB.BASEBOARD_FAB2(SCH_1):PU_CPU0_SAFE_MODE_BOOT
  U5D1 AR18 SAFE_MODE_BOOT SKX_EXT_B_BGA1-IC,TBD   I259 @BASEBOARD_FAB2_LIB.BASEBOARD_FAB2(SCH_1):PAGE21
 R6D13    2      B RES_0402-240,1.0%,1/16W,EMPTY,A    I33 @BASEBOARD_FAB2_LIB.BASEBOARD_FAB2(SCH_1):PAGE90

PU_CPU0_SOCKET_ID_0 @BASEBOARD_FAB2_LIB.BASEBOARD_FAB2(SCH_1):PU_CPU0_SOCKET_ID_0
  U5D1 AU22 SOCKET_ID<0> SKX_EXT_B_BGA1-IC,TBD   I259 @BASEBOARD_FAB2_LIB.BASEBOARD_FAB2(SCH_1):PAGE21
 R6D15    2      B RES_0402-240,1.0%,1/16W,EMPTY,A    I48 @BASEBOARD_FAB2_LIB.BASEBOARD_FAB2(SCH_1):PAGE90

PU_CPU0_SOCKET_ID_1 @BASEBOARD_FAB2_LIB.BASEBOARD_FAB2(SCH_1):PU_CPU0_SOCKET_ID_1
  U5D1 AU16 SOCKET_ID<1> SKX_EXT_B_BGA1-IC,TBD   I259 @BASEBOARD_FAB2_LIB.BASEBOARD_FAB2(SCH_1):PAGE21
 R6D10    2      B RES_0402-240,1.0%,1/16W,EMPTY,A    I49 @BASEBOARD_FAB2_LIB.BASEBOARD_FAB2(SCH_1):PAGE90

PU_CPU0_TSC_SYNC @BASEBOARD_FAB2_LIB.BASEBOARD_FAB2(SCH_1):PU_CPU0_TSC_SYNC
  U5D1 AM11 TSC_SYNC SKX_EXT_B_BGA1-IC,TBD   I259 @BASEBOARD_FAB2_LIB.BASEBOARD_FAB2(SCH_1):PAGE21
 R4P21    2      B RES_0402-240,1.0%,1/16W,CHIP,GA    I72 @BASEBOARD_FAB2_LIB.BASEBOARD_FAB2(SCH_1):PAGE97

PU_CPU0_TXT_AGENT @BASEBOARD_FAB2_LIB.BASEBOARD_FAB2(SCH_1):PU_CPU0_TXT_AGENT
  U5D1 AW18 TXT_AGENT SKX_EXT_B_BGA1-IC,TBD   I259 @BASEBOARD_FAB2_LIB.BASEBOARD_FAB2(SCH_1):PAGE21
  R5D4    2      B RES_0402-240,1.0%,1/16W,EMPTY,A    I32 @BASEBOARD_FAB2_LIB.BASEBOARD_FAB2(SCH_1):PAGE90

PU_CPU1_EAR_N @BASEBOARD_FAB2_LIB.BASEBOARD_FAB2(SCH_1):PU_CPU1_EAR_N
  U2D1 AJ14  EAR_N SKX_EXT_B_BGA1-IC,TBD   I172 @BASEBOARD_FAB2_LIB.BASEBOARD_FAB2(SCH_1):PAGE55
 R3D25    2      B RES_0402-240,1.0%,1/16W,EMPTY,A    I66 @BASEBOARD_FAB2_LIB.BASEBOARD_FAB2(SCH_1):PAGE90

PU_CPU1_FRMAGENT @BASEBOARD_FAB2_LIB.BASEBOARD_FAB2(SCH_1):PU_CPU1_FRMAGENT
  U2D1 AV17 FRMAGENT SKX_EXT_B_BGA1-IC,TBD   I172 @BASEBOARD_FAB2_LIB.BASEBOARD_FAB2(SCH_1):PAGE55
 R3D22    2      B RES_0402-240,1.0%,1/16W,EMPTY,A    I17 @BASEBOARD_FAB2_LIB.BASEBOARD_FAB2(SCH_1):PAGE90

PU_CPU1_LEGACY_SKT @BASEBOARD_FAB2_LIB.BASEBOARD_FAB2(SCH_1):PU_CPU1_LEGACY_SKT
  U2D1 AE20 LEGACY_SKT SKX_EXT_B_BGA1-IC,TBD   I172 @BASEBOARD_FAB2_LIB.BASEBOARD_FAB2(SCH_1):PAGE55
 R7P22    2      B RES_0402-240,1.0%,1/16W,EMPTY,A    I76 @BASEBOARD_FAB2_LIB.BASEBOARD_FAB2(SCH_1):PAGE90

PU_CPU1_SAFE_MODE_BOOT @BASEBOARD_FAB2_LIB.BASEBOARD_FAB2(SCH_1):PU_CPU1_SAFE_MODE_BOOT
  U2D1 AR18 SAFE_MODE_BOOT SKX_EXT_B_BGA1-IC,TBD   I172 @BASEBOARD_FAB2_LIB.BASEBOARD_FAB2(SCH_1):PAGE55
 R3D26    2      B RES_0402-240,1.0%,1/16W,EMPTY,A    I28 @BASEBOARD_FAB2_LIB.BASEBOARD_FAB2(SCH_1):PAGE90

PU_CPU1_SOCKET_ID_0 @BASEBOARD_FAB2_LIB.BASEBOARD_FAB2(SCH_1):PU_CPU1_SOCKET_ID_0
  U2D1 AU22 SOCKET_ID<0> SKX_EXT_B_BGA1-IC,TBD   I172 @BASEBOARD_FAB2_LIB.BASEBOARD_FAB2(SCH_1):PAGE55
 R3D24    2      B RES_0402-240,1.0%,1/16W,CHIP,GA    I59 @BASEBOARD_FAB2_LIB.BASEBOARD_FAB2(SCH_1):PAGE90

PU_CPU1_SOCKET_ID_1 @BASEBOARD_FAB2_LIB.BASEBOARD_FAB2(SCH_1):PU_CPU1_SOCKET_ID_1
  U2D1 AU16 SOCKET_ID<1> SKX_EXT_B_BGA1-IC,TBD   I172 @BASEBOARD_FAB2_LIB.BASEBOARD_FAB2(SCH_1):PAGE55
 R3D17    2      B RES_0402-240,1.0%,1/16W,EMPTY,A    I60 @BASEBOARD_FAB2_LIB.BASEBOARD_FAB2(SCH_1):PAGE90

PU_CPU1_TSC_SYNC @BASEBOARD_FAB2_LIB.BASEBOARD_FAB2(SCH_1):PU_CPU1_TSC_SYNC
  U2D1 AM11 TSC_SYNC SKX_EXT_B_BGA1-IC,TBD   I172 @BASEBOARD_FAB2_LIB.BASEBOARD_FAB2(SCH_1):PAGE55
 R4C10    2      B RES_0402-240,1.0%,1/16W,CHIP,GA    I76 @BASEBOARD_FAB2_LIB.BASEBOARD_FAB2(SCH_1):PAGE97

PU_CPU1_TXT_AGENT @BASEBOARD_FAB2_LIB.BASEBOARD_FAB2(SCH_1):PU_CPU1_TXT_AGENT
  U2D1 AW18 TXT_AGENT SKX_EXT_B_BGA1-IC,TBD   I172 @BASEBOARD_FAB2_LIB.BASEBOARD_FAB2(SCH_1):PAGE55
 R3D23    2      B RES_0402-240,1.0%,1/16W,EMPTY,A    I25 @BASEBOARD_FAB2_LIB.BASEBOARD_FAB2(SCH_1):PAGE90

PU_DATAIN1_SATA_0_R @BASEBOARD_FAB2_LIB.BASEBOARD_FAB2(SCH_1):PU_DATAIN1_SATA_0_R
  J8A1  1D1 SIDEBANDA_5 CONN72_G97614002_A_CP-CONN,G97A   I163 @BASEBOARD_FAB2_LIB.BASEBOARD_FAB2(SCH_1):PAGE173
 R2L21    2      B RES_0402-2.0K,1%,1/16W,CHIP,G2A   I263 @BASEBOARD_FAB2_LIB.BASEBOARD_FAB2(SCH_1):PAGE173

PU_DATAIN1_SATA_1_R @BASEBOARD_FAB2_LIB.BASEBOARD_FAB2(SCH_1):PU_DATAIN1_SATA_1_R
  J8A1  2D1 SIDEBANDB_5 CONN72_G97614002_A_CP-CONN,G97A   I163 @BASEBOARD_FAB2_LIB.BASEBOARD_FAB2(SCH_1):PAGE173
 R2L23    2      B RES_0402-2.0K,1%,1/16W,CHIP,G2A   I261 @BASEBOARD_FAB2_LIB.BASEBOARD_FAB2(SCH_1):PAGE173

PU_DATAIN1_SATA_2 @BASEBOARD_FAB2_LIB.BASEBOARD_FAB2(SCH_1):PU_DATAIN1_SATA_2
  R1L1    2      B RES_0402-2.0K,1%,1/16W,CHIP,G2A    I25 @BASEBOARD_FAB2_LIB.BASEBOARD_FAB2(SCH_1):PAGE174
  J8A2   D1 SIDEBAND5 CONN36_G97614001_CP-CONN,G9761A    I26 @BASEBOARD_FAB2_LIB.BASEBOARD_FAB2(SCH_1):PAGE174

PU_FAB2_MARKER_CPLD @BASEBOARD_FAB2_LIB.BASEBOARD_FAB2(SCH_1):PU_FAB2_MARKER_CPLD
  U8D7  K16   PR9B LCMXO2_A_256BGA-IC,H63395-001    I59 @BASEBOARD_FAB2_LIB.BASEBOARD_FAB2(SCH_1):PAGE191
 R7D42    2      B RES_0402-4.75K,1%,1/16W,CHIP,GA   I193 @BASEBOARD_FAB2_LIB.BASEBOARD_FAB2(SCH_1):PAGE191

PU_FM_RCIN_N @BASEBOARD_FAB2_LIB.BASEBOARD_FAB2(SCH_1):PU_FM_RCIN_N
  U7C1   N3 GPP_A0_RCIN_N_ESPI_ALERT1_N LBG_CORE_QAT_EXT_D_BGA1-IC,H91A   I115 @BASEBOARD_FAB2_LIB.BASEBOARD_FAB2(SCH_1):PAGE119
  R7D2    2      B RES_0402-1.00K,1%,1/16W,CHIP,GA   I332 @BASEBOARD_FAB2_LIB.BASEBOARD_FAB2(SCH_1):PAGE133

PU_GTL2014_1_DIR @BASEBOARD_FAB2_LIB.BASEBOARD_FAB2(SCH_1):PU_GTL2014_1_DIR
 R3P36    2      B RES_0402-1.00K,1%,1/16W,CHIP,GA    I36 @BASEBOARD_FAB2_LIB.BASEBOARD_FAB2(SCH_1):PAGE96
  U3P1    1    DIR GTL2014_SM-IC,D66151-001    I42 @BASEBOARD_FAB2_LIB.BASEBOARD_FAB2(SCH_1):PAGE96

PU_GTL2014_2_DIR @BASEBOARD_FAB2_LIB.BASEBOARD_FAB2(SCH_1):PU_GTL2014_2_DIR
  U4C2    1    DIR GTL2014_SM-IC,D66151-001    I46 @BASEBOARD_FAB2_LIB.BASEBOARD_FAB2(SCH_1):PAGE96
  R4C8    2      B RES_0402-1.00K,1%,1/16W,CHIP,GA    I55 @BASEBOARD_FAB2_LIB.BASEBOARD_FAB2(SCH_1):PAGE96

PU_ID_EEPROM_A2 @BASEBOARD_FAB2_LIB.BASEBOARD_FAB2(SCH_1):PU_ID_EEPROM_A2
  U6W3    3     A2 AT24C64_SOICLF-IC,C47049-001-GA    I89 @BASEBOARD_FAB2_LIB.BASEBOARD_FAB2(SCH_1):PAGE247
 R6W21    2      B RES_0402-1.00K,1%,1/16W,CHIP,GA    I90 @BASEBOARD_FAB2_LIB.BASEBOARD_FAB2(SCH_1):PAGE247

PU_IRQ_PCH_SCI_WHEA_N @BASEBOARD_FAB2_LIB.BASEBOARD_FAB2(SCH_1):PU_IRQ_PCH_SCI_WHEA_N
  U7C1   R1 GPP_A12_BMBUSY_N_SXEXITHLDOFF_N LBG_CORE_QAT_EXT_D_BGA1-IC,H91A   I115 @BASEBOARD_FAB2_LIB.BASEBOARD_FAB2(SCH_1):PAGE119
  R7D4    2      B RES_0402-10.0K,1%,1/16W,CHIP,GA   I245 @BASEBOARD_FAB2_LIB.BASEBOARD_FAB2(SCH_1):PAGE133

PU_IRQ_VRALERT_N @BASEBOARD_FAB2_LIB.BASEBOARD_FAB2(SCH_1):PU_IRQ_VRALERT_N
  U7C1 BN15 GPP_B2 LBG_CORE_QAT_EXT_D_BGA1-IC,H91A   I115 @BASEBOARD_FAB2_LIB.BASEBOARD_FAB2(SCH_1):PAGE119
 R2N16    2      B RES_0402-10.0K,1%,1/16W,CHIP,GA   I247 @BASEBOARD_FAB2_LIB.BASEBOARD_FAB2(SCH_1):PAGE133

PU_JTAG_SPRV_TCK @BASEBOARD_FAB2_LIB.BASEBOARD_FAB2(SCH_1):PU_JTAG_SPRV_TCK
 EU9E1   19 JTAG_CLK SPRINGVILLE_SM1-IC,G47144-004    I72 @BASEBOARD_FAB2_LIB.BASEBOARD_FAB2(SCH_1):PAGE139
  R9E2    2      B RES_0402-10.0K,1%,1/16W,CHIP,GA   I177 @BASEBOARD_FAB2_LIB.BASEBOARD_FAB2(SCH_1):PAGE139

PU_JTAG_SPRV_TDI @BASEBOARD_FAB2_LIB.BASEBOARD_FAB2(SCH_1):PU_JTAG_SPRV_TDI
 EU9E1   29 JTAG_TDI SPRINGVILLE_SM1-IC,G47144-004    I72 @BASEBOARD_FAB2_LIB.BASEBOARD_FAB2(SCH_1):PAGE139
  R9E1    2      B RES_0402-10.0K,1%,1/16W,CHIP,GA   I179 @BASEBOARD_FAB2_LIB.BASEBOARD_FAB2(SCH_1):PAGE139

PU_JTAG_SPRV_TDO @BASEBOARD_FAB2_LIB.BASEBOARD_FAB2(SCH_1):PU_JTAG_SPRV_TDO
 EU9E1    4 JTAG_TDO SPRINGVILLE_SM1-IC,G47144-004    I72 @BASEBOARD_FAB2_LIB.BASEBOARD_FAB2(SCH_1):PAGE139
 R9E22    1      A RES_0402-10.0K,1%,1/16W,CHIP,GA   I181 @BASEBOARD_FAB2_LIB.BASEBOARD_FAB2(SCH_1):PAGE139

PU_JTAG_SPRV_TMS @BASEBOARD_FAB2_LIB.BASEBOARD_FAB2(SCH_1):PU_JTAG_SPRV_TMS
 EU9E1   18 JTAG_TMS SPRINGVILLE_SM1-IC,G47144-004    I72 @BASEBOARD_FAB2_LIB.BASEBOARD_FAB2(SCH_1):PAGE139
  R9E3    2      B RES_0402-10.0K,1%,1/16W,CHIP,GA   I178 @BASEBOARD_FAB2_LIB.BASEBOARD_FAB2(SCH_1):PAGE139

PU_KEY_CONN_PIN2_R @BASEBOARD_FAB2_LIB.BASEBOARD_FAB2(SCH_1):PU_KEY_CONN_PIN2_R
 R9A16    1      A RES_0402-2.21K,1%,1/16W,CHIP,GA   I129 @BASEBOARD_FAB2_LIB.BASEBOARD_FAB2(SCH_1):PAGE135
  J9A1    2    IO2 CONN4_D42317002_PIP-CONN,D4231A   I131 @BASEBOARD_FAB2_LIB.BASEBOARD_FAB2(SCH_1):PAGE135

PU_LPC_CLKRUN_N @BASEBOARD_FAB2_LIB.BASEBOARD_FAB2(SCH_1):PU_LPC_CLKRUN_N
  U7C1  AB1 GPP_A8_CLKRUN_N LBG_CORE_QAT_EXT_D_BGA1-IC,H91A   I115 @BASEBOARD_FAB2_LIB.BASEBOARD_FAB2(SCH_1):PAGE119
  R7D8    2      B RES_0402-10.0K,1%,1/16W,CHIP,GA   I200 @BASEBOARD_FAB2_LIB.BASEBOARD_FAB2(SCH_1):PAGE133

PU_LPC_PME_N @BASEBOARD_FAB2_LIB.BASEBOARD_FAB2(SCH_1):PU_LPC_PME_N
  U7C1  AC2 GPP_A11_PME_N LBG_CORE_QAT_EXT_D_BGA1-IC,H91A   I115 @BASEBOARD_FAB2_LIB.BASEBOARD_FAB2(SCH_1):PAGE119
 R7D10    2      B RES_0402-10.0K,1%,1/16W,CHIP,GA   I202 @BASEBOARD_FAB2_LIB.BASEBOARD_FAB2(SCH_1):PAGE133

PU_M2_CLK_REQ_N @BASEBOARD_FAB2_LIB.BASEBOARD_FAB2(SCH_1):PU_M2_CLK_REQ_N
  J8F1   52 CLKREQ_N_NC SCONN75K_H17033002_SMT1-SCONN,A    I53 @BASEBOARD_FAB2_LIB.BASEBOARD_FAB2(SCH_1):PAGE185
 R8F36    2      B RES_0402-10.0K,1%,1/16W,CHIP,GA   I136 @BASEBOARD_FAB2_LIB.BASEBOARD_FAB2(SCH_1):PAGE185

PU_NV_HOLD_N @BASEBOARD_FAB2_LIB.BASEBOARD_FAB2(SCH_1):PU_NV_HOLD_N
  U9E1    7 RESET_N M25PE16_SM-IC,H77797-001     I1 @BASEBOARD_FAB2_LIB.BASEBOARD_FAB2(SCH_1):PAGE140
  R1R9    2      B RES_0402-3.32K,1%,1/16W,CHIP,GA    I10 @BASEBOARD_FAB2_LIB.BASEBOARD_FAB2(SCH_1):PAGE140

PU_NV_WP_N @BASEBOARD_FAB2_LIB.BASEBOARD_FAB2(SCH_1):PU_NV_WP_N
  U9E1    3    W_N M25PE16_SM-IC,H77797-001     I1 @BASEBOARD_FAB2_LIB.BASEBOARD_FAB2(SCH_1):PAGE140
  R1R3    2      B RES_0402-3.32K,1%,1/16W,CHIP,GA    I11 @BASEBOARD_FAB2_LIB.BASEBOARD_FAB2(SCH_1):PAGE140

PU_PCH_TLS_ENABLE_STRAP @BASEBOARD_FAB2_LIB.BASEBOARD_FAB2(SCH_1):PU_PCH_TLS_ENABLE_STRAP
  U7C1 BY27 GPP_C2_SMBALERT_N LBG_CORE_QAT_EXT_D_BGA1-IC,H91A   I115 @BASEBOARD_FAB2_LIB.BASEBOARD_FAB2(SCH_1):PAGE119
 R8C18    2      B RES_0402-1.00K,1%,1/16W,CHIP,GA    I40 @BASEBOARD_FAB2_LIB.BASEBOARD_FAB2(SCH_1):PAGE125
 R8C17    1      A RES_0402-1.00K,1%,1/16W,EMPTY,A    I41 @BASEBOARD_FAB2_LIB.BASEBOARD_FAB2(SCH_1):PAGE125

PU_PI7C9X1172_I2C_SPI_N @BASEBOARD_FAB2_LIB.BASEBOARD_FAB2(SCH_1):PU_PI7C9X1172_I2C_SPI_N
 EU9F3   32 I2C_SPI_N PI7C9X1172_QFN-IC,H66899-001     I1 @BASEBOARD_FAB2_LIB.BASEBOARD_FAB2(SCH_1):PAGE183
 R9F47    2      B RES_0402-4.75K,1%,1/16W,CHIP,GA     I4 @BASEBOARD_FAB2_LIB.BASEBOARD_FAB2(SCH_1):PAGE183

PU_PIROM_CPU1_ADDR0 @BASEBOARD_FAB2_LIB.BASEBOARD_FAB2(SCH_1):PU_PIROM_CPU1_ADDR0
  U2D1 CU58 PIROM_ADDR<0> SKX_EXT_B_BGA1-IC,TBD   I172 @BASEBOARD_FAB2_LIB.BASEBOARD_FAB2(SCH_1):PAGE55
 R1C34    2      B RES_0402-10.0K,1%,1/16W,CHIP,GA   I320 @BASEBOARD_FAB2_LIB.BASEBOARD_FAB2(SCH_1):PAGE156

PU_RST_PERST_BIT0 @BASEBOARD_FAB2_LIB.BASEBOARD_FAB2(SCH_1):PU_RST_PERST_BIT0
  U8D7   F4   PL3C LCMXO2_A_256BGA-IC,H63395-001   I179 @BASEBOARD_FAB2_LIB.BASEBOARD_FAB2(SCH_1):PAGE190
  R2R1    2      B RES_0402-10.0K,1%,1/16W,CHIP,GA    I34 @BASEBOARD_FAB2_LIB.BASEBOARD_FAB2(SCH_1):PAGE192

PU_RST_PERST_BIT1 @BASEBOARD_FAB2_LIB.BASEBOARD_FAB2(SCH_1):PU_RST_PERST_BIT1
  U8D7   B9  PT19A LCMXO2_A_256BGA-IC,H63395-001    I59 @BASEBOARD_FAB2_LIB.BASEBOARD_FAB2(SCH_1):PAGE191
  R7E6    2      B RES_0402-10.0K,1%,1/16W,CHIP,GA    I33 @BASEBOARD_FAB2_LIB.BASEBOARD_FAB2(SCH_1):PAGE192

PU_SPI0_RST @BASEBOARD_FAB2_LIB.BASEBOARD_FAB2(SCH_1):PU_SPI0_RST
  R7F6    2      B RES_0402-4.75K,1%,1/16W,EMPTY,A    I90 @BASEBOARD_FAB2_LIB.BASEBOARD_FAB2(SCH_1):PAGE153
  U7F1    3 RESET_N W25Q256_XSOI-IC,H25002-001   I146 @BASEBOARD_FAB2_LIB.BASEBOARD_FAB2(SCH_1):PAGE153

PU_SPI1_RST @BASEBOARD_FAB2_LIB.BASEBOARD_FAB2(SCH_1):PU_SPI1_RST
  R3T3    2      B RES_0402-4.75K,1%,1/16W,EMPTY,A   I150 @BASEBOARD_FAB2_LIB.BASEBOARD_FAB2(SCH_1):PAGE153
  U3T1    3 RESET_N W25Q256_XSOI-IC,H25002-001   I165 @BASEBOARD_FAB2_LIB.BASEBOARD_FAB2(SCH_1):PAGE153

PU_SPI_BMC_BT_HOLD_N @BASEBOARD_FAB2_LIB.BASEBOARD_FAB2(SCH_1):PU_SPI_BMC_BT_HOLD_N
 R8F14    2      B RES_0402-4.75K,1%,1/16W,CHIP,GA     I9 @BASEBOARD_FAB2_LIB.BASEBOARD_FAB2(SCH_1):PAGE162
  U8F2    1 HOLD_N_IO<3> W25Q128_SKT16-IC,H12709-001    I32 @BASEBOARD_FAB2_LIB.BASEBOARD_FAB2(SCH_1):PAGE162

PU_SPI_BMC_BT_WP_N @BASEBOARD_FAB2_LIB.BASEBOARD_FAB2(SCH_1):PU_SPI_BMC_BT_WP_N
 R8F34    2      B RES_0402-4.75K,1%,1/16W,CHIP,GA    I22 @BASEBOARD_FAB2_LIB.BASEBOARD_FAB2(SCH_1):PAGE162
 R8F35    1      A RES_0402-1.00K,1%,1/16W,EMPTY,A    I24 @BASEBOARD_FAB2_LIB.BASEBOARD_FAB2(SCH_1):PAGE162
  U8F2    9 WP_N_IO<2> W25Q128_SKT16-IC,H12709-001    I32 @BASEBOARD_FAB2_LIB.BASEBOARD_FAB2(SCH_1):PAGE162

PU_SPI_FLASH_RESET_2_N @BASEBOARD_FAB2_LIB.BASEBOARD_FAB2(SCH_1):PU_SPI_FLASH_RESET_2_N
 R8F16    2      B RES_0402-4.75K,1%,1/16W,EMPTY,A     I8 @BASEBOARD_FAB2_LIB.BASEBOARD_FAB2(SCH_1):PAGE162
  U8F2    3 RESET_N W25Q128_SKT16-IC,H12709-001    I32 @BASEBOARD_FAB2_LIB.BASEBOARD_FAB2(SCH_1):PAGE162

PU_SPRV_LAN_PWR_GOOD @BASEBOARD_FAB2_LIB.BASEBOARD_FAB2(SCH_1):PU_SPRV_LAN_PWR_GOOD
 EU9E1    1 LAN_PWR_GOOD SPRINGVILLE_SM1-IC,G47144-004    I72 @BASEBOARD_FAB2_LIB.BASEBOARD_FAB2(SCH_1):PAGE139
  R9F5    2      B RES_0402-3.32K,1%,1/16W,CHIP,GA   I173 @BASEBOARD_FAB2_LIB.BASEBOARD_FAB2(SCH_1):PAGE139

PU_THERMTRIP_FORCE_N @BASEBOARD_FAB2_LIB.BASEBOARD_FAB2(SCH_1):PU_THERMTRIP_FORCE_N
  U8D7  A12  PT22B LCMXO2_A_256BGA-IC,H63395-001    I59 @BASEBOARD_FAB2_LIB.BASEBOARD_FAB2(SCH_1):PAGE191
  R7E5    2      B RES_0402-10.0K,1%,1/16W,CHIP,GA    I38 @BASEBOARD_FAB2_LIB.BASEBOARD_FAB2(SCH_1):PAGE192

PU_TMP421_1_A1 @BASEBOARD_FAB2_LIB.BASEBOARD_FAB2(SCH_1):PU_TMP421_1_A1
  U9B4    3   A<1> TMP421_TSSOP-IC,G62962-001     I1 @BASEBOARD_FAB2_LIB.BASEBOARD_FAB2(SCH_1):PAGE167
  R9B6    2      B RES_0402-1.00K,1%,1/16W,CHIP,GA    I35 @BASEBOARD_FAB2_LIB.BASEBOARD_FAB2(SCH_1):PAGE167

PU_TMP421_2_A0 @BASEBOARD_FAB2_LIB.BASEBOARD_FAB2(SCH_1):PU_TMP421_2_A0
  U1E1    4   A<0> TMP421_TSSOP-IC,G62962-001    I30 @BASEBOARD_FAB2_LIB.BASEBOARD_FAB2(SCH_1):PAGE167
  R1E9    2      B RES_0402-1.00K,1%,1/16W,CHIP,GA    I34 @BASEBOARD_FAB2_LIB.BASEBOARD_FAB2(SCH_1):PAGE167

PU_TPM_SPI_BMC_HOLD_N @BASEBOARD_FAB2_LIB.BASEBOARD_FAB2(SCH_1):PU_TPM_SPI_BMC_HOLD_N
 RN8F3    2      B RES_0402-4.75K,1%,1/16W,CHIP,GA    I11 @BASEBOARD_FAB2_LIB.BASEBOARD_FAB2(SCH_1):PAGE246
 UN8F2    1 HOLD_N_IO<3> W25Q256_XSOI-IC,H25002-001    I17 @BASEBOARD_FAB2_LIB.BASEBOARD_FAB2(SCH_1):PAGE246

PU_TPM_SPI_BMC_WP_N @BASEBOARD_FAB2_LIB.BASEBOARD_FAB2(SCH_1):PU_TPM_SPI_BMC_WP_N
 RN8F6    1      A RES_0402-1.00K,1%,1/16W,EMPTY,A     I8 @BASEBOARD_FAB2_LIB.BASEBOARD_FAB2(SCH_1):PAGE246
 RN8F2    2      B RES_0402-4.75K,1%,1/16W,CHIP,GA    I10 @BASEBOARD_FAB2_LIB.BASEBOARD_FAB2(SCH_1):PAGE246
 UN8F2    9 WP_N_IO<2> W25Q256_XSOI-IC,H25002-001    I17 @BASEBOARD_FAB2_LIB.BASEBOARD_FAB2(SCH_1):PAGE246

PU_TPM_SPI_FLASH_RESET_2_N @BASEBOARD_FAB2_LIB.BASEBOARD_FAB2(SCH_1):PU_TPM_SPI_FLASH_RESET_2_N
 RN8F4    2      B RES_0402-4.75K,1%,1/16W,EMPTY,A    I12 @BASEBOARD_FAB2_LIB.BASEBOARD_FAB2(SCH_1):PAGE246
 UN8F2    3 RESET_N W25Q256_XSOI-IC,H25002-001    I17 @BASEBOARD_FAB2_LIB.BASEBOARD_FAB2(SCH_1):PAGE246

PU_TRI_STATE_EN @BASEBOARD_FAB2_LIB.BASEBOARD_FAB2(SCH_1):PU_TRI_STATE_EN
  U8E4    1     OE TTL1G126_A_SOT-74HC1G126,IC,A7B     I1 @BASEBOARD_FAB2_LIB.BASEBOARD_FAB2(SCH_1):PAGE142
 R8E23    1      A RES_0402-4.75K,1%,1/16W,CHIP,GA     I3 @BASEBOARD_FAB2_LIB.BASEBOARD_FAB2(SCH_1):PAGE142

PU_VR_PVCCIN_CPU0_FLT1_SMBALT_N @BASEBOARD_FAB2_LIB.BASEBOARD_FAB2(SCH_1):PU_VR_PVCCIN_CPU0_FLT1_SMBALT_N_IMON
 R4E20    2      B RES_0402-2.26K,1.0%,1/16W,EMPTA   I116 @BASEBOARD_FAB2_LIB.BASEBOARD_FAB2(SCH_1):PAGE201
 EU4D4   20    MP2 PXE1610B_QFN-IC,H79206-001   I155 @BASEBOARD_FAB2_LIB.BASEBOARD_FAB2(SCH_1):PAGE201

PU_VR_PVCCIN_CPU0_IMON @BASEBOARD_FAB2_LIB.BASEBOARD_FAB2(SCH_1):PU_VR_PVCCIN_CPU0_IMON
 R4D31    2      B RES_0402-2.26K,1.0%,1/16W,EMPTA    I22 @BASEBOARD_FAB2_LIB.BASEBOARD_FAB2(SCH_1):PAGE201
 EU4D4   39    MP3 PXE1610B_QFN-IC,H79206-001   I155 @BASEBOARD_FAB2_LIB.BASEBOARD_FAB2(SCH_1):PAGE201

PU_VR_PVCCIN_CPU1_FLT1_SMBALT_N @BASEBOARD_FAB2_LIB.BASEBOARD_FAB2(SCH_1):PU_VR_PVCCIN_CPU1_FLT1_SMBALT_N_IMON
 R1D53    2      B RES_0402-2.26K,1.0%,1/16W,EMPTA    I33 @BASEBOARD_FAB2_LIB.BASEBOARD_FAB2(SCH_1):PAGE206
 EU1C2   20    MP2 PXE1610B_QFN-IC,H79206-001   I130 @BASEBOARD_FAB2_LIB.BASEBOARD_FAB2(SCH_1):PAGE206

PU_VR_PVCCIN_CPU1_IMON @BASEBOARD_FAB2_LIB.BASEBOARD_FAB2(SCH_1):PU_VR_PVCCIN_CPU1_IMON
 R1C18    2      B RES_0402-2.26K,1.0%,1/16W,EMPTA    I34 @BASEBOARD_FAB2_LIB.BASEBOARD_FAB2(SCH_1):PAGE206
 EU1C2   39    MP3 PXE1610B_QFN-IC,H79206-001   I130 @BASEBOARD_FAB2_LIB.BASEBOARD_FAB2(SCH_1):PAGE206

PU_VR_PVCCIO_CPU0_FAULT1 @BASEBOARD_FAB2_LIB.BASEBOARD_FAB2(SCH_1):PU_VR_PVCCIO_CPU0_FAULT1
 R3N23    2      B RES_0402-2.26K,1.0%,1/16W,EMPTA    I60 @BASEBOARD_FAB2_LIB.BASEBOARD_FAB2(SCH_1):PAGE211
 EU3P1   32    MP4 PXE1110B_QFN-IC,H89187-001    I93 @BASEBOARD_FAB2_LIB.BASEBOARD_FAB2(SCH_1):PAGE211

PU_VR_PVCCIO_CPU1_FAULT1 @BASEBOARD_FAB2_LIB.BASEBOARD_FAB2(SCH_1):PU_VR_PVCCIO_CPU1_FAULT1
 R6P49    2      B RES_0402-2.26K,1.0%,1/16W,EMPTA    I14 @BASEBOARD_FAB2_LIB.BASEBOARD_FAB2(SCH_1):PAGE213
 EU4D5   32    MP4 PXE1110B_QFN-IC,H89187-001    I96 @BASEBOARD_FAB2_LIB.BASEBOARD_FAB2(SCH_1):PAGE213

PU_VR_PVDDQ_ABC_FAULT1 @BASEBOARD_FAB2_LIB.BASEBOARD_FAB2(SCH_1):PU_VR_PVDDQ_ABC_FAULT1
 R7F36    2      B RES_0402-2.26K,1.0%,1/16W,EMPTA   I300 @BASEBOARD_FAB2_LIB.BASEBOARD_FAB2(SCH_1):PAGE215
 EU7G1   13    MP0 PXM1310B_QFN-IC,H89186-001   I358 @BASEBOARD_FAB2_LIB.BASEBOARD_FAB2(SCH_1):PAGE215

PU_VR_PVDDQ_DEF_FAULT1 @BASEBOARD_FAB2_LIB.BASEBOARD_FAB2(SCH_1):PU_VR_PVDDQ_DEF_FAULT1
  R7A9    2      B RES_0402-2.26K,1.0%,1/16W,EMPTA    I14 @BASEBOARD_FAB2_LIB.BASEBOARD_FAB2(SCH_1):PAGE218
 EU7A5   13    MP0 PXM1310B_QFN-IC,H89186-001    I75 @BASEBOARD_FAB2_LIB.BASEBOARD_FAB2(SCH_1):PAGE218

PU_VR_PVDDQ_GHJ_FAULT1 @BASEBOARD_FAB2_LIB.BASEBOARD_FAB2(SCH_1):PU_VR_PVDDQ_GHJ_FAULT1
  R1G6    2      B RES_0402-2.26K,1.0%,1/16W,EMPTA    I13 @BASEBOARD_FAB2_LIB.BASEBOARD_FAB2(SCH_1):PAGE223
 EU1G2   13    MP0 PXM1310B_QFN-IC,H89186-001    I90 @BASEBOARD_FAB2_LIB.BASEBOARD_FAB2(SCH_1):PAGE223

PU_VR_PVDDQ_KLM_FAULT1 @BASEBOARD_FAB2_LIB.BASEBOARD_FAB2(SCH_1):PU_VR_PVDDQ_KLM_FAULT1
 R1B13    2      B RES_0402-2.26K,1.0%,1/16W,EMPTA    I13 @BASEBOARD_FAB2_LIB.BASEBOARD_FAB2(SCH_1):PAGE226
 EU1B1   13    MP0 PXM1310B_QFN-IC,H89186-001    I90 @BASEBOARD_FAB2_LIB.BASEBOARD_FAB2(SCH_1):PAGE226

PU_VR_PVNN_PCH_FAULT1 @BASEBOARD_FAB2_LIB.BASEBOARD_FAB2(SCH_1):PU_VR_PVNN_PCH_FAULT1
 R2L24    2      B RES_0402-2.26K,1.0%,1/16W,EMPTA   I148 @BASEBOARD_FAB2_LIB.BASEBOARD_FAB2(SCH_1):PAGE235
 EU8A1   32    MP4 PXE1110B_QFN-IC,H89187-001   I229 @BASEBOARD_FAB2_LIB.BASEBOARD_FAB2(SCH_1):PAGE235

PVCCIN_CPU0 @BASEBOARD_FAB2_LIB.BASEBOARD_FAB2(SCH_1):PVCCIN_CPU0
  R5P1    1      A RES_0603-100.0K,1%,1/10W,CHIP,A   I309 @BASEBOARD_FAB2_LIB.BASEBOARD_FAB2(SCH_1):PAGE37
  U5D1 BN78 VCCIN<130> SKX_EXT_B_BGA1-IC,TBD   I310 @BASEBOARD_FAB2_LIB.BASEBOARD_FAB2(SCH_1):PAGE37
  U5D1 BN76 VCCIN<131> SKX_EXT_B_BGA1-IC,TBD   I310 @BASEBOARD_FAB2_LIB.BASEBOARD_FAB2(SCH_1):PAGE37
  U5D1 BN74 VCCIN<132> SKX_EXT_B_BGA1-IC,TBD   I310 @BASEBOARD_FAB2_LIB.BASEBOARD_FAB2(SCH_1):PAGE37
  U5D1 BN72 VCCIN<133> SKX_EXT_B_BGA1-IC,TBD   I310 @BASEBOARD_FAB2_LIB.BASEBOARD_FAB2(SCH_1):PAGE37
  U5D1 BN70 VCCIN<134> SKX_EXT_B_BGA1-IC,TBD   I310 @BASEBOARD_FAB2_LIB.BASEBOARD_FAB2(SCH_1):PAGE37
  U5D1 BN68 VCCIN<135> SKX_EXT_B_BGA1-IC,TBD   I310 @BASEBOARD_FAB2_LIB.BASEBOARD_FAB2(SCH_1):PAGE37
  U5D1 BN66 VCCIN<136> SKX_EXT_B_BGA1-IC,TBD   I310 @BASEBOARD_FAB2_LIB.BASEBOARD_FAB2(SCH_1):PAGE37
  U5D1 BN64 VCCIN<137> SKX_EXT_B_BGA1-IC,TBD   I310 @BASEBOARD_FAB2_LIB.BASEBOARD_FAB2(SCH_1):PAGE37
  U5D1 BN62 VCCIN<138> SKX_EXT_B_BGA1-IC,TBD   I310 @BASEBOARD_FAB2_LIB.BASEBOARD_FAB2(SCH_1):PAGE37
  U5D1 BN60 VCCIN<139> SKX_EXT_B_BGA1-IC,TBD   I310 @BASEBOARD_FAB2_LIB.BASEBOARD_FAB2(SCH_1):PAGE37
  U5D1 BM83 VCCIN<140> SKX_EXT_B_BGA1-IC,TBD   I310 @BASEBOARD_FAB2_LIB.BASEBOARD_FAB2(SCH_1):PAGE37
  U5D1 BM81 VCCIN<141> SKX_EXT_B_BGA1-IC,TBD   I310 @BASEBOARD_FAB2_LIB.BASEBOARD_FAB2(SCH_1):PAGE37
  U5D1 BM79 VCCIN<142> SKX_EXT_B_BGA1-IC,TBD   I310 @BASEBOARD_FAB2_LIB.BASEBOARD_FAB2(SCH_1):PAGE37
  U5D1 BM77 VCCIN<143> SKX_EXT_B_BGA1-IC,TBD   I310 @BASEBOARD_FAB2_LIB.BASEBOARD_FAB2(SCH_1):PAGE37
  U5D1 BM75 VCCIN<144> SKX_EXT_B_BGA1-IC,TBD   I310 @BASEBOARD_FAB2_LIB.BASEBOARD_FAB2(SCH_1):PAGE37
  U5D1 BM73 VCCIN<145> SKX_EXT_B_BGA1-IC,TBD   I310 @BASEBOARD_FAB2_LIB.BASEBOARD_FAB2(SCH_1):PAGE37
  U5D1 BM71 VCCIN<146> SKX_EXT_B_BGA1-IC,TBD   I310 @BASEBOARD_FAB2_LIB.BASEBOARD_FAB2(SCH_1):PAGE37
  U5D1 BM69 VCCIN<147> SKX_EXT_B_BGA1-IC,TBD   I310 @BASEBOARD_FAB2_LIB.BASEBOARD_FAB2(SCH_1):PAGE37
  U5D1 BM67 VCCIN<148> SKX_EXT_B_BGA1-IC,TBD   I310 @BASEBOARD_FAB2_LIB.BASEBOARD_FAB2(SCH_1):PAGE37
  U5D1 BM65 VCCIN<149> SKX_EXT_B_BGA1-IC,TBD   I310 @BASEBOARD_FAB2_LIB.BASEBOARD_FAB2(SCH_1):PAGE37
  U5D1 BM63 VCCIN<150> SKX_EXT_B_BGA1-IC,TBD   I310 @BASEBOARD_FAB2_LIB.BASEBOARD_FAB2(SCH_1):PAGE37
  U5D1 BM61 VCCIN<151> SKX_EXT_B_BGA1-IC,TBD   I310 @BASEBOARD_FAB2_LIB.BASEBOARD_FAB2(SCH_1):PAGE37
  U5D1 BL84 VCCIN<152> SKX_EXT_B_BGA1-IC,TBD   I310 @BASEBOARD_FAB2_LIB.BASEBOARD_FAB2(SCH_1):PAGE37
  U5D1 BL62 VCCIN<153> SKX_EXT_B_BGA1-IC,TBD   I310 @BASEBOARD_FAB2_LIB.BASEBOARD_FAB2(SCH_1):PAGE37
  U5D1 BL60 VCCIN<154> SKX_EXT_B_BGA1-IC,TBD   I310 @BASEBOARD_FAB2_LIB.BASEBOARD_FAB2(SCH_1):PAGE37
  U5D1 BK83 VCCIN<155> SKX_EXT_B_BGA1-IC,TBD   I310 @BASEBOARD_FAB2_LIB.BASEBOARD_FAB2(SCH_1):PAGE37
  U5D1 BK81 VCCIN<156> SKX_EXT_B_BGA1-IC,TBD   I310 @BASEBOARD_FAB2_LIB.BASEBOARD_FAB2(SCH_1):PAGE37
  U5D1 BK79 VCCIN<157> SKX_EXT_B_BGA1-IC,TBD   I310 @BASEBOARD_FAB2_LIB.BASEBOARD_FAB2(SCH_1):PAGE37
  U5D1 BK77 VCCIN<158> SKX_EXT_B_BGA1-IC,TBD   I310 @BASEBOARD_FAB2_LIB.BASEBOARD_FAB2(SCH_1):PAGE37
  U5D1 BK75 VCCIN<159> SKX_EXT_B_BGA1-IC,TBD   I310 @BASEBOARD_FAB2_LIB.BASEBOARD_FAB2(SCH_1):PAGE37
  U5D1 BK73 VCCIN<160> SKX_EXT_B_BGA1-IC,TBD   I310 @BASEBOARD_FAB2_LIB.BASEBOARD_FAB2(SCH_1):PAGE37
  U5D1 BK71 VCCIN<161> SKX_EXT_B_BGA1-IC,TBD   I310 @BASEBOARD_FAB2_LIB.BASEBOARD_FAB2(SCH_1):PAGE37
  U5D1 BK69 VCCIN<162> SKX_EXT_B_BGA1-IC,TBD   I310 @BASEBOARD_FAB2_LIB.BASEBOARD_FAB2(SCH_1):PAGE37
  U5D1 BK67 VCCIN<163> SKX_EXT_B_BGA1-IC,TBD   I310 @BASEBOARD_FAB2_LIB.BASEBOARD_FAB2(SCH_1):PAGE37
  U5D1 BK65 VCCIN<164> SKX_EXT_B_BGA1-IC,TBD   I310 @BASEBOARD_FAB2_LIB.BASEBOARD_FAB2(SCH_1):PAGE37
  U5D1 BK63 VCCIN<165> SKX_EXT_B_BGA1-IC,TBD   I310 @BASEBOARD_FAB2_LIB.BASEBOARD_FAB2(SCH_1):PAGE37
  U5D1 BK61 VCCIN<166> SKX_EXT_B_BGA1-IC,TBD   I310 @BASEBOARD_FAB2_LIB.BASEBOARD_FAB2(SCH_1):PAGE37
  U5D1 BJ84 VCCIN<167> SKX_EXT_B_BGA1-IC,TBD   I310 @BASEBOARD_FAB2_LIB.BASEBOARD_FAB2(SCH_1):PAGE37
  U5D1 BJ82 VCCIN<168> SKX_EXT_B_BGA1-IC,TBD   I310 @BASEBOARD_FAB2_LIB.BASEBOARD_FAB2(SCH_1):PAGE37
  U5D1 BJ80 VCCIN<169> SKX_EXT_B_BGA1-IC,TBD   I310 @BASEBOARD_FAB2_LIB.BASEBOARD_FAB2(SCH_1):PAGE37
  U5D1 BJ78 VCCIN<170> SKX_EXT_B_BGA1-IC,TBD   I310 @BASEBOARD_FAB2_LIB.BASEBOARD_FAB2(SCH_1):PAGE37
  U5D1 BJ76 VCCIN<171> SKX_EXT_B_BGA1-IC,TBD   I310 @BASEBOARD_FAB2_LIB.BASEBOARD_FAB2(SCH_1):PAGE37
  U5D1 BJ74 VCCIN<172> SKX_EXT_B_BGA1-IC,TBD   I310 @BASEBOARD_FAB2_LIB.BASEBOARD_FAB2(SCH_1):PAGE37
  U5D1 BJ72 VCCIN<173> SKX_EXT_B_BGA1-IC,TBD   I310 @BASEBOARD_FAB2_LIB.BASEBOARD_FAB2(SCH_1):PAGE37
  U5D1 BJ70 VCCIN<174> SKX_EXT_B_BGA1-IC,TBD   I310 @BASEBOARD_FAB2_LIB.BASEBOARD_FAB2(SCH_1):PAGE37
  U5D1 BJ68 VCCIN<175> SKX_EXT_B_BGA1-IC,TBD   I310 @BASEBOARD_FAB2_LIB.BASEBOARD_FAB2(SCH_1):PAGE37
  U5D1 BJ66 VCCIN<176> SKX_EXT_B_BGA1-IC,TBD   I310 @BASEBOARD_FAB2_LIB.BASEBOARD_FAB2(SCH_1):PAGE37
  U5D1 BJ64 VCCIN<177> SKX_EXT_B_BGA1-IC,TBD   I310 @BASEBOARD_FAB2_LIB.BASEBOARD_FAB2(SCH_1):PAGE37
  U5D1 BJ62 VCCIN<178> SKX_EXT_B_BGA1-IC,TBD   I310 @BASEBOARD_FAB2_LIB.BASEBOARD_FAB2(SCH_1):PAGE37
  U5D1 BJ60 VCCIN<179> SKX_EXT_B_BGA1-IC,TBD   I310 @BASEBOARD_FAB2_LIB.BASEBOARD_FAB2(SCH_1):PAGE37
  U5D1 BH83 VCCIN<180> SKX_EXT_B_BGA1-IC,TBD   I310 @BASEBOARD_FAB2_LIB.BASEBOARD_FAB2(SCH_1):PAGE37
  U5D1 BH81 VCCIN<181> SKX_EXT_B_BGA1-IC,TBD   I310 @BASEBOARD_FAB2_LIB.BASEBOARD_FAB2(SCH_1):PAGE37
  U5D1 BH79 VCCIN<182> SKX_EXT_B_BGA1-IC,TBD   I310 @BASEBOARD_FAB2_LIB.BASEBOARD_FAB2(SCH_1):PAGE37
  U5D1 BH77 VCCIN<183> SKX_EXT_B_BGA1-IC,TBD   I310 @BASEBOARD_FAB2_LIB.BASEBOARD_FAB2(SCH_1):PAGE37
  U5D1 BH75 VCCIN<184> SKX_EXT_B_BGA1-IC,TBD   I310 @BASEBOARD_FAB2_LIB.BASEBOARD_FAB2(SCH_1):PAGE37
  U5D1 BH73 VCCIN<185> SKX_EXT_B_BGA1-IC,TBD   I310 @BASEBOARD_FAB2_LIB.BASEBOARD_FAB2(SCH_1):PAGE37
  U5D1 BH71 VCCIN<186> SKX_EXT_B_BGA1-IC,TBD   I310 @BASEBOARD_FAB2_LIB.BASEBOARD_FAB2(SCH_1):PAGE37
  U5D1 BH69 VCCIN<187> SKX_EXT_B_BGA1-IC,TBD   I310 @BASEBOARD_FAB2_LIB.BASEBOARD_FAB2(SCH_1):PAGE37
  U5D1 BH67 VCCIN<188> SKX_EXT_B_BGA1-IC,TBD   I310 @BASEBOARD_FAB2_LIB.BASEBOARD_FAB2(SCH_1):PAGE37
  U5D1 BH65 VCCIN<189> SKX_EXT_B_BGA1-IC,TBD   I310 @BASEBOARD_FAB2_LIB.BASEBOARD_FAB2(SCH_1):PAGE37
  U5D1 BH63 VCCIN<190> SKX_EXT_B_BGA1-IC,TBD   I310 @BASEBOARD_FAB2_LIB.BASEBOARD_FAB2(SCH_1):PAGE37
  U5D1 BH61 VCCIN<191> SKX_EXT_B_BGA1-IC,TBD   I310 @BASEBOARD_FAB2_LIB.BASEBOARD_FAB2(SCH_1):PAGE37
  U5D1 BG84 VCCIN<192> SKX_EXT_B_BGA1-IC,TBD   I310 @BASEBOARD_FAB2_LIB.BASEBOARD_FAB2(SCH_1):PAGE37
  U5D1 BG70 VCCIN<193> SKX_EXT_B_BGA1-IC,TBD   I310 @BASEBOARD_FAB2_LIB.BASEBOARD_FAB2(SCH_1):PAGE37
  U5D1 BG68 VCCIN<194> SKX_EXT_B_BGA1-IC,TBD   I310 @BASEBOARD_FAB2_LIB.BASEBOARD_FAB2(SCH_1):PAGE37
  U5D1 BG66 VCCIN<195> SKX_EXT_B_BGA1-IC,TBD   I310 @BASEBOARD_FAB2_LIB.BASEBOARD_FAB2(SCH_1):PAGE37
  U5D1 BG64 VCCIN<196> SKX_EXT_B_BGA1-IC,TBD   I310 @BASEBOARD_FAB2_LIB.BASEBOARD_FAB2(SCH_1):PAGE37
  U5D1 BG62 VCCIN<197> SKX_EXT_B_BGA1-IC,TBD   I310 @BASEBOARD_FAB2_LIB.BASEBOARD_FAB2(SCH_1):PAGE37
  U5D1 BG60 VCCIN<198> SKX_EXT_B_BGA1-IC,TBD   I310 @BASEBOARD_FAB2_LIB.BASEBOARD_FAB2(SCH_1):PAGE37
  U5D1 BF85 VCCIN<199> SKX_EXT_B_BGA1-IC,TBD   I310 @BASEBOARD_FAB2_LIB.BASEBOARD_FAB2(SCH_1):PAGE37
  U5D1 BF83 VCCIN<200> SKX_EXT_B_BGA1-IC,TBD   I310 @BASEBOARD_FAB2_LIB.BASEBOARD_FAB2(SCH_1):PAGE37
  U5D1 BF81 VCCIN<201> SKX_EXT_B_BGA1-IC,TBD   I310 @BASEBOARD_FAB2_LIB.BASEBOARD_FAB2(SCH_1):PAGE37
  U5D1 BF79 VCCIN<202> SKX_EXT_B_BGA1-IC,TBD   I310 @BASEBOARD_FAB2_LIB.BASEBOARD_FAB2(SCH_1):PAGE37
  U5D1 BF77 VCCIN<203> SKX_EXT_B_BGA1-IC,TBD   I310 @BASEBOARD_FAB2_LIB.BASEBOARD_FAB2(SCH_1):PAGE37
  U5D1 BF75 VCCIN<204> SKX_EXT_B_BGA1-IC,TBD   I310 @BASEBOARD_FAB2_LIB.BASEBOARD_FAB2(SCH_1):PAGE37
  U5D1 BF73 VCCIN<205> SKX_EXT_B_BGA1-IC,TBD   I310 @BASEBOARD_FAB2_LIB.BASEBOARD_FAB2(SCH_1):PAGE37
  U5D1 BF61 VCCIN<206> SKX_EXT_B_BGA1-IC,TBD   I310 @BASEBOARD_FAB2_LIB.BASEBOARD_FAB2(SCH_1):PAGE37
  U5D1 BE84 VCCIN<207> SKX_EXT_B_BGA1-IC,TBD   I310 @BASEBOARD_FAB2_LIB.BASEBOARD_FAB2(SCH_1):PAGE37
  U5D1 BE82 VCCIN<208> SKX_EXT_B_BGA1-IC,TBD   I310 @BASEBOARD_FAB2_LIB.BASEBOARD_FAB2(SCH_1):PAGE37
  U5D1 BE80 VCCIN<209> SKX_EXT_B_BGA1-IC,TBD   I310 @BASEBOARD_FAB2_LIB.BASEBOARD_FAB2(SCH_1):PAGE37
  U5D1 BE78 VCCIN<210> SKX_EXT_B_BGA1-IC,TBD   I310 @BASEBOARD_FAB2_LIB.BASEBOARD_FAB2(SCH_1):PAGE37
  U5D1 BE76 VCCIN<211> SKX_EXT_B_BGA1-IC,TBD   I310 @BASEBOARD_FAB2_LIB.BASEBOARD_FAB2(SCH_1):PAGE37
  U5D1 BE74 VCCIN<212> SKX_EXT_B_BGA1-IC,TBD   I310 @BASEBOARD_FAB2_LIB.BASEBOARD_FAB2(SCH_1):PAGE37
  U5D1 BE72 VCCIN<213> SKX_EXT_B_BGA1-IC,TBD   I310 @BASEBOARD_FAB2_LIB.BASEBOARD_FAB2(SCH_1):PAGE37
  U5D1 BE62 VCCIN<214> SKX_EXT_B_BGA1-IC,TBD   I310 @BASEBOARD_FAB2_LIB.BASEBOARD_FAB2(SCH_1):PAGE37
  U5D1 BE60 VCCIN<215> SKX_EXT_B_BGA1-IC,TBD   I310 @BASEBOARD_FAB2_LIB.BASEBOARD_FAB2(SCH_1):PAGE37
  U5D1 BD85 VCCIN<216> SKX_EXT_B_BGA1-IC,TBD   I310 @BASEBOARD_FAB2_LIB.BASEBOARD_FAB2(SCH_1):PAGE37
  U5D1 BD83 VCCIN<217> SKX_EXT_B_BGA1-IC,TBD   I310 @BASEBOARD_FAB2_LIB.BASEBOARD_FAB2(SCH_1):PAGE37
  U5D1 BD81 VCCIN<218> SKX_EXT_B_BGA1-IC,TBD   I310 @BASEBOARD_FAB2_LIB.BASEBOARD_FAB2(SCH_1):PAGE37
  U5D1 BD79 VCCIN<219> SKX_EXT_B_BGA1-IC,TBD   I310 @BASEBOARD_FAB2_LIB.BASEBOARD_FAB2(SCH_1):PAGE37
  U5D1 BD77 VCCIN<220> SKX_EXT_B_BGA1-IC,TBD   I310 @BASEBOARD_FAB2_LIB.BASEBOARD_FAB2(SCH_1):PAGE37
  U5D1 BD75 VCCIN<221> SKX_EXT_B_BGA1-IC,TBD   I310 @BASEBOARD_FAB2_LIB.BASEBOARD_FAB2(SCH_1):PAGE37
  U5D1 BD73 VCCIN<222> SKX_EXT_B_BGA1-IC,TBD   I310 @BASEBOARD_FAB2_LIB.BASEBOARD_FAB2(SCH_1):PAGE37
  U5D1 BD61 VCCIN<223> SKX_EXT_B_BGA1-IC,TBD   I310 @BASEBOARD_FAB2_LIB.BASEBOARD_FAB2(SCH_1):PAGE37
  U5D1 BC84 VCCIN<224> SKX_EXT_B_BGA1-IC,TBD   I310 @BASEBOARD_FAB2_LIB.BASEBOARD_FAB2(SCH_1):PAGE37
  U5D1 BC62 VCCIN<225> SKX_EXT_B_BGA1-IC,TBD   I310 @BASEBOARD_FAB2_LIB.BASEBOARD_FAB2(SCH_1):PAGE37
  U5D1 BC60 VCCIN<226> SKX_EXT_B_BGA1-IC,TBD   I310 @BASEBOARD_FAB2_LIB.BASEBOARD_FAB2(SCH_1):PAGE37
  U5D1 BB85 VCCIN<227> SKX_EXT_B_BGA1-IC,TBD   I310 @BASEBOARD_FAB2_LIB.BASEBOARD_FAB2(SCH_1):PAGE37
  U5D1 BB61 VCCIN<228> SKX_EXT_B_BGA1-IC,TBD   I310 @BASEBOARD_FAB2_LIB.BASEBOARD_FAB2(SCH_1):PAGE37
  U5D1 BA60 VCCIN<229> SKX_EXT_B_BGA1-IC,TBD   I310 @BASEBOARD_FAB2_LIB.BASEBOARD_FAB2(SCH_1):PAGE37
  U5D1 AY61 VCCIN<230> SKX_EXT_B_BGA1-IC,TBD   I310 @BASEBOARD_FAB2_LIB.BASEBOARD_FAB2(SCH_1):PAGE37
  U5D1 AW60 VCCIN<231> SKX_EXT_B_BGA1-IC,TBD   I310 @BASEBOARD_FAB2_LIB.BASEBOARD_FAB2(SCH_1):PAGE37
  U5D1 AV61 VCCIN<232> SKX_EXT_B_BGA1-IC,TBD   I310 @BASEBOARD_FAB2_LIB.BASEBOARD_FAB2(SCH_1):PAGE37
  U5D1 AV59 VCCIN<233> SKX_EXT_B_BGA1-IC,TBD   I310 @BASEBOARD_FAB2_LIB.BASEBOARD_FAB2(SCH_1):PAGE37
  U5D1 AU60 VCCIN<234> SKX_EXT_B_BGA1-IC,TBD   I310 @BASEBOARD_FAB2_LIB.BASEBOARD_FAB2(SCH_1):PAGE37
  U5D1 AU58 VCCIN<235> SKX_EXT_B_BGA1-IC,TBD   I310 @BASEBOARD_FAB2_LIB.BASEBOARD_FAB2(SCH_1):PAGE37
  U5D1 AT59 VCCIN<236> SKX_EXT_B_BGA1-IC,TBD   I310 @BASEBOARD_FAB2_LIB.BASEBOARD_FAB2(SCH_1):PAGE37
  U5D1 AT57 VCCIN<237> SKX_EXT_B_BGA1-IC,TBD   I310 @BASEBOARD_FAB2_LIB.BASEBOARD_FAB2(SCH_1):PAGE37
  U5D1 AR58 VCCIN<238> SKX_EXT_B_BGA1-IC,TBD   I310 @BASEBOARD_FAB2_LIB.BASEBOARD_FAB2(SCH_1):PAGE37
  U5D1 AR56 VCCIN<239> SKX_EXT_B_BGA1-IC,TBD   I310 @BASEBOARD_FAB2_LIB.BASEBOARD_FAB2(SCH_1):PAGE37
  U5D1 AP57 VCCIN<240> SKX_EXT_B_BGA1-IC,TBD   I310 @BASEBOARD_FAB2_LIB.BASEBOARD_FAB2(SCH_1):PAGE37
  U5D1 AP55 VCCIN<241> SKX_EXT_B_BGA1-IC,TBD   I310 @BASEBOARD_FAB2_LIB.BASEBOARD_FAB2(SCH_1):PAGE37
  U5D1 AN56 VCCIN<242> SKX_EXT_B_BGA1-IC,TBD   I310 @BASEBOARD_FAB2_LIB.BASEBOARD_FAB2(SCH_1):PAGE37
  U5D1 AN54 VCCIN<243> SKX_EXT_B_BGA1-IC,TBD   I310 @BASEBOARD_FAB2_LIB.BASEBOARD_FAB2(SCH_1):PAGE37
  U5D1 AN32 VCCIN<244> SKX_EXT_B_BGA1-IC,TBD   I310 @BASEBOARD_FAB2_LIB.BASEBOARD_FAB2(SCH_1):PAGE37
  U5D1 AM55 VCCIN<245> SKX_EXT_B_BGA1-IC,TBD   I310 @BASEBOARD_FAB2_LIB.BASEBOARD_FAB2(SCH_1):PAGE37
  U5D1 AM53 VCCIN<246> SKX_EXT_B_BGA1-IC,TBD   I310 @BASEBOARD_FAB2_LIB.BASEBOARD_FAB2(SCH_1):PAGE37
  U5D1 AM33 VCCIN<247> SKX_EXT_B_BGA1-IC,TBD   I310 @BASEBOARD_FAB2_LIB.BASEBOARD_FAB2(SCH_1):PAGE37
  U5D1 AL54 VCCIN<248> SKX_EXT_B_BGA1-IC,TBD   I310 @BASEBOARD_FAB2_LIB.BASEBOARD_FAB2(SCH_1):PAGE37
  U5D1 AL52 VCCIN<249> SKX_EXT_B_BGA1-IC,TBD   I310 @BASEBOARD_FAB2_LIB.BASEBOARD_FAB2(SCH_1):PAGE37
  U5D1 AL50 VCCIN<250> SKX_EXT_B_BGA1-IC,TBD   I310 @BASEBOARD_FAB2_LIB.BASEBOARD_FAB2(SCH_1):PAGE37
  U5D1 AL48 VCCIN<251> SKX_EXT_B_BGA1-IC,TBD   I310 @BASEBOARD_FAB2_LIB.BASEBOARD_FAB2(SCH_1):PAGE37
  U5D1 AL46 VCCIN<252> SKX_EXT_B_BGA1-IC,TBD   I310 @BASEBOARD_FAB2_LIB.BASEBOARD_FAB2(SCH_1):PAGE37
  U5D1 AL34 VCCIN<253> SKX_EXT_B_BGA1-IC,TBD   I310 @BASEBOARD_FAB2_LIB.BASEBOARD_FAB2(SCH_1):PAGE37
  U5D1 AK53 VCCIN<254> SKX_EXT_B_BGA1-IC,TBD   I310 @BASEBOARD_FAB2_LIB.BASEBOARD_FAB2(SCH_1):PAGE37
  U5D1 AK51 VCCIN<255> SKX_EXT_B_BGA1-IC,TBD   I310 @BASEBOARD_FAB2_LIB.BASEBOARD_FAB2(SCH_1):PAGE37
  U5D1 AK49 VCCIN<256> SKX_EXT_B_BGA1-IC,TBD   I310 @BASEBOARD_FAB2_LIB.BASEBOARD_FAB2(SCH_1):PAGE37
  U5D1 AK47 VCCIN<257> SKX_EXT_B_BGA1-IC,TBD   I310 @BASEBOARD_FAB2_LIB.BASEBOARD_FAB2(SCH_1):PAGE37
  U5D1 AK45 VCCIN<258> SKX_EXT_B_BGA1-IC,TBD   I310 @BASEBOARD_FAB2_LIB.BASEBOARD_FAB2(SCH_1):PAGE37
  U5D1 AK35 VCCIN<259> SKX_EXT_B_BGA1-IC,TBD   I310 @BASEBOARD_FAB2_LIB.BASEBOARD_FAB2(SCH_1):PAGE37
  U5D1 AJ36 VCCIN<260> SKX_EXT_B_BGA1-IC,TBD   I310 @BASEBOARD_FAB2_LIB.BASEBOARD_FAB2(SCH_1):PAGE37
  U5D1 AH41 VCCIN<261> SKX_EXT_B_BGA1-IC,TBD   I310 @BASEBOARD_FAB2_LIB.BASEBOARD_FAB2(SCH_1):PAGE37
  U5D1 AH39 VCCIN<262> SKX_EXT_B_BGA1-IC,TBD   I310 @BASEBOARD_FAB2_LIB.BASEBOARD_FAB2(SCH_1):PAGE37
  U5D1 AH37 VCCIN<263> SKX_EXT_B_BGA1-IC,TBD   I310 @BASEBOARD_FAB2_LIB.BASEBOARD_FAB2(SCH_1):PAGE37
  U5D1 AG42 VCCIN<264> SKX_EXT_B_BGA1-IC,TBD   I310 @BASEBOARD_FAB2_LIB.BASEBOARD_FAB2(SCH_1):PAGE37
  U5D1 AG40 VCCIN<265> SKX_EXT_B_BGA1-IC,TBD   I310 @BASEBOARD_FAB2_LIB.BASEBOARD_FAB2(SCH_1):PAGE37
  U5D1 AG38 VCCIN<266> SKX_EXT_B_BGA1-IC,TBD   I310 @BASEBOARD_FAB2_LIB.BASEBOARD_FAB2(SCH_1):PAGE37
  U5D1 AF43 VCCIN<267> SKX_EXT_B_BGA1-IC,TBD   I310 @BASEBOARD_FAB2_LIB.BASEBOARD_FAB2(SCH_1):PAGE37
  U5D1 CY49 VCCIN<0> SKX_EXT_B_BGA1-IC,TBD   I311 @BASEBOARD_FAB2_LIB.BASEBOARD_FAB2(SCH_1):PAGE37
  U5D1 CY47 VCCIN<1> SKX_EXT_B_BGA1-IC,TBD   I311 @BASEBOARD_FAB2_LIB.BASEBOARD_FAB2(SCH_1):PAGE37
  U5D1 CW50 VCCIN<2> SKX_EXT_B_BGA1-IC,TBD   I311 @BASEBOARD_FAB2_LIB.BASEBOARD_FAB2(SCH_1):PAGE37
  U5D1 CW48 VCCIN<3> SKX_EXT_B_BGA1-IC,TBD   I311 @BASEBOARD_FAB2_LIB.BASEBOARD_FAB2(SCH_1):PAGE37
  U5D1 CW46 VCCIN<4> SKX_EXT_B_BGA1-IC,TBD   I311 @BASEBOARD_FAB2_LIB.BASEBOARD_FAB2(SCH_1):PAGE37
  U5D1 CV51 VCCIN<5> SKX_EXT_B_BGA1-IC,TBD   I311 @BASEBOARD_FAB2_LIB.BASEBOARD_FAB2(SCH_1):PAGE37
  U5D1 CU54 VCCIN<6> SKX_EXT_B_BGA1-IC,TBD   I311 @BASEBOARD_FAB2_LIB.BASEBOARD_FAB2(SCH_1):PAGE37
  U5D1 CU52 VCCIN<7> SKX_EXT_B_BGA1-IC,TBD   I311 @BASEBOARD_FAB2_LIB.BASEBOARD_FAB2(SCH_1):PAGE37
  U5D1 CU42 VCCIN<8> SKX_EXT_B_BGA1-IC,TBD   I311 @BASEBOARD_FAB2_LIB.BASEBOARD_FAB2(SCH_1):PAGE37
  U5D1 CU40 VCCIN<9> SKX_EXT_B_BGA1-IC,TBD   I311 @BASEBOARD_FAB2_LIB.BASEBOARD_FAB2(SCH_1):PAGE37
  U5D1 CU38 VCCIN<10> SKX_EXT_B_BGA1-IC,TBD   I311 @BASEBOARD_FAB2_LIB.BASEBOARD_FAB2(SCH_1):PAGE37
  U5D1 CT55 VCCIN<11> SKX_EXT_B_BGA1-IC,TBD   I311 @BASEBOARD_FAB2_LIB.BASEBOARD_FAB2(SCH_1):PAGE37
  U5D1 CT53 VCCIN<12> SKX_EXT_B_BGA1-IC,TBD   I311 @BASEBOARD_FAB2_LIB.BASEBOARD_FAB2(SCH_1):PAGE37
  U5D1 CT41 VCCIN<13> SKX_EXT_B_BGA1-IC,TBD   I311 @BASEBOARD_FAB2_LIB.BASEBOARD_FAB2(SCH_1):PAGE37
  U5D1 CT39 VCCIN<14> SKX_EXT_B_BGA1-IC,TBD   I311 @BASEBOARD_FAB2_LIB.BASEBOARD_FAB2(SCH_1):PAGE37
  U5D1 CT37 VCCIN<15> SKX_EXT_B_BGA1-IC,TBD   I311 @BASEBOARD_FAB2_LIB.BASEBOARD_FAB2(SCH_1):PAGE37
  U5D1 CR56 VCCIN<16> SKX_EXT_B_BGA1-IC,TBD   I311 @BASEBOARD_FAB2_LIB.BASEBOARD_FAB2(SCH_1):PAGE37
  U5D1 CR54 VCCIN<17> SKX_EXT_B_BGA1-IC,TBD   I311 @BASEBOARD_FAB2_LIB.BASEBOARD_FAB2(SCH_1):PAGE37
  U5D1 CR34 VCCIN<18> SKX_EXT_B_BGA1-IC,TBD   I311 @BASEBOARD_FAB2_LIB.BASEBOARD_FAB2(SCH_1):PAGE37
  U5D1 CP57 VCCIN<19> SKX_EXT_B_BGA1-IC,TBD   I311 @BASEBOARD_FAB2_LIB.BASEBOARD_FAB2(SCH_1):PAGE37
  U5D1 CP55 VCCIN<20> SKX_EXT_B_BGA1-IC,TBD   I311 @BASEBOARD_FAB2_LIB.BASEBOARD_FAB2(SCH_1):PAGE37
  U5D1 CP33 VCCIN<21> SKX_EXT_B_BGA1-IC,TBD   I311 @BASEBOARD_FAB2_LIB.BASEBOARD_FAB2(SCH_1):PAGE37
  U5D1 CN58 VCCIN<22> SKX_EXT_B_BGA1-IC,TBD   I311 @BASEBOARD_FAB2_LIB.BASEBOARD_FAB2(SCH_1):PAGE37
  U5D1 CN56 VCCIN<23> SKX_EXT_B_BGA1-IC,TBD   I311 @BASEBOARD_FAB2_LIB.BASEBOARD_FAB2(SCH_1):PAGE37
  U5D1 CM59 VCCIN<24> SKX_EXT_B_BGA1-IC,TBD   I311 @BASEBOARD_FAB2_LIB.BASEBOARD_FAB2(SCH_1):PAGE37
  U5D1 CM57 VCCIN<25> SKX_EXT_B_BGA1-IC,TBD   I311 @BASEBOARD_FAB2_LIB.BASEBOARD_FAB2(SCH_1):PAGE37
  U5D1 CL60 VCCIN<26> SKX_EXT_B_BGA1-IC,TBD   I311 @BASEBOARD_FAB2_LIB.BASEBOARD_FAB2(SCH_1):PAGE37
  U5D1 CL58 VCCIN<27> SKX_EXT_B_BGA1-IC,TBD   I311 @BASEBOARD_FAB2_LIB.BASEBOARD_FAB2(SCH_1):PAGE37
  U5D1 CK61 VCCIN<28> SKX_EXT_B_BGA1-IC,TBD   I311 @BASEBOARD_FAB2_LIB.BASEBOARD_FAB2(SCH_1):PAGE37
  U5D1 CK59 VCCIN<29> SKX_EXT_B_BGA1-IC,TBD   I311 @BASEBOARD_FAB2_LIB.BASEBOARD_FAB2(SCH_1):PAGE37
  U5D1 CJ60 VCCIN<30> SKX_EXT_B_BGA1-IC,TBD   I311 @BASEBOARD_FAB2_LIB.BASEBOARD_FAB2(SCH_1):PAGE37
  U5D1 CH85 VCCIN<31> SKX_EXT_B_BGA1-IC,TBD   I311 @BASEBOARD_FAB2_LIB.BASEBOARD_FAB2(SCH_1):PAGE37
  U5D1 CH61 VCCIN<32> SKX_EXT_B_BGA1-IC,TBD   I311 @BASEBOARD_FAB2_LIB.BASEBOARD_FAB2(SCH_1):PAGE37
  U5D1 CG84 VCCIN<33> SKX_EXT_B_BGA1-IC,TBD   I311 @BASEBOARD_FAB2_LIB.BASEBOARD_FAB2(SCH_1):PAGE37
  U5D1 CG60 VCCIN<34> SKX_EXT_B_BGA1-IC,TBD   I311 @BASEBOARD_FAB2_LIB.BASEBOARD_FAB2(SCH_1):PAGE37
  U5D1 CF85 VCCIN<35> SKX_EXT_B_BGA1-IC,TBD   I311 @BASEBOARD_FAB2_LIB.BASEBOARD_FAB2(SCH_1):PAGE37
  U5D1 CF61 VCCIN<36> SKX_EXT_B_BGA1-IC,TBD   I311 @BASEBOARD_FAB2_LIB.BASEBOARD_FAB2(SCH_1):PAGE37
  U5D1 CE84 VCCIN<37> SKX_EXT_B_BGA1-IC,TBD   I311 @BASEBOARD_FAB2_LIB.BASEBOARD_FAB2(SCH_1):PAGE37
  U5D1 CE60 VCCIN<38> SKX_EXT_B_BGA1-IC,TBD   I311 @BASEBOARD_FAB2_LIB.BASEBOARD_FAB2(SCH_1):PAGE37
  U5D1 CD85 VCCIN<39> SKX_EXT_B_BGA1-IC,TBD   I311 @BASEBOARD_FAB2_LIB.BASEBOARD_FAB2(SCH_1):PAGE37
  U5D1 CD83 VCCIN<40> SKX_EXT_B_BGA1-IC,TBD   I311 @BASEBOARD_FAB2_LIB.BASEBOARD_FAB2(SCH_1):PAGE37
  U5D1 CD61 VCCIN<41> SKX_EXT_B_BGA1-IC,TBD   I311 @BASEBOARD_FAB2_LIB.BASEBOARD_FAB2(SCH_1):PAGE37
  U5D1 CC84 VCCIN<42> SKX_EXT_B_BGA1-IC,TBD   I311 @BASEBOARD_FAB2_LIB.BASEBOARD_FAB2(SCH_1):PAGE37
  U5D1 CC62 VCCIN<43> SKX_EXT_B_BGA1-IC,TBD   I311 @BASEBOARD_FAB2_LIB.BASEBOARD_FAB2(SCH_1):PAGE37
  U5D1 CC60 VCCIN<44> SKX_EXT_B_BGA1-IC,TBD   I311 @BASEBOARD_FAB2_LIB.BASEBOARD_FAB2(SCH_1):PAGE37
  U5D1 CB83 VCCIN<45> SKX_EXT_B_BGA1-IC,TBD   I311 @BASEBOARD_FAB2_LIB.BASEBOARD_FAB2(SCH_1):PAGE37
  U5D1 CB81 VCCIN<46> SKX_EXT_B_BGA1-IC,TBD   I311 @BASEBOARD_FAB2_LIB.BASEBOARD_FAB2(SCH_1):PAGE37
  U5D1 CB79 VCCIN<47> SKX_EXT_B_BGA1-IC,TBD   I311 @BASEBOARD_FAB2_LIB.BASEBOARD_FAB2(SCH_1):PAGE37
  U5D1 CB77 VCCIN<48> SKX_EXT_B_BGA1-IC,TBD   I311 @BASEBOARD_FAB2_LIB.BASEBOARD_FAB2(SCH_1):PAGE37
  U5D1 CB75 VCCIN<49> SKX_EXT_B_BGA1-IC,TBD   I311 @BASEBOARD_FAB2_LIB.BASEBOARD_FAB2(SCH_1):PAGE37
  U5D1 CB73 VCCIN<50> SKX_EXT_B_BGA1-IC,TBD   I311 @BASEBOARD_FAB2_LIB.BASEBOARD_FAB2(SCH_1):PAGE37
  U5D1 CB61 VCCIN<51> SKX_EXT_B_BGA1-IC,TBD   I311 @BASEBOARD_FAB2_LIB.BASEBOARD_FAB2(SCH_1):PAGE37
  U5D1 CA84 VCCIN<52> SKX_EXT_B_BGA1-IC,TBD   I311 @BASEBOARD_FAB2_LIB.BASEBOARD_FAB2(SCH_1):PAGE37
  U5D1 CA82 VCCIN<53> SKX_EXT_B_BGA1-IC,TBD   I311 @BASEBOARD_FAB2_LIB.BASEBOARD_FAB2(SCH_1):PAGE37
  U5D1 CA80 VCCIN<54> SKX_EXT_B_BGA1-IC,TBD   I311 @BASEBOARD_FAB2_LIB.BASEBOARD_FAB2(SCH_1):PAGE37
  U5D1 CA78 VCCIN<55> SKX_EXT_B_BGA1-IC,TBD   I311 @BASEBOARD_FAB2_LIB.BASEBOARD_FAB2(SCH_1):PAGE37
  U5D1 CA76 VCCIN<56> SKX_EXT_B_BGA1-IC,TBD   I311 @BASEBOARD_FAB2_LIB.BASEBOARD_FAB2(SCH_1):PAGE37
  U5D1 CA74 VCCIN<57> SKX_EXT_B_BGA1-IC,TBD   I311 @BASEBOARD_FAB2_LIB.BASEBOARD_FAB2(SCH_1):PAGE37
  U5D1 CA72 VCCIN<58> SKX_EXT_B_BGA1-IC,TBD   I311 @BASEBOARD_FAB2_LIB.BASEBOARD_FAB2(SCH_1):PAGE37
  U5D1 CA62 VCCIN<59> SKX_EXT_B_BGA1-IC,TBD   I311 @BASEBOARD_FAB2_LIB.BASEBOARD_FAB2(SCH_1):PAGE37
  U5D1 CA60 VCCIN<60> SKX_EXT_B_BGA1-IC,TBD   I311 @BASEBOARD_FAB2_LIB.BASEBOARD_FAB2(SCH_1):PAGE37
  U5D1 BY83 VCCIN<61> SKX_EXT_B_BGA1-IC,TBD   I311 @BASEBOARD_FAB2_LIB.BASEBOARD_FAB2(SCH_1):PAGE37
  U5D1 BY81 VCCIN<62> SKX_EXT_B_BGA1-IC,TBD   I311 @BASEBOARD_FAB2_LIB.BASEBOARD_FAB2(SCH_1):PAGE37
  U5D1 BY79 VCCIN<63> SKX_EXT_B_BGA1-IC,TBD   I311 @BASEBOARD_FAB2_LIB.BASEBOARD_FAB2(SCH_1):PAGE37
  U5D1 BY77 VCCIN<64> SKX_EXT_B_BGA1-IC,TBD   I311 @BASEBOARD_FAB2_LIB.BASEBOARD_FAB2(SCH_1):PAGE37
  U5D1 BY75 VCCIN<65> SKX_EXT_B_BGA1-IC,TBD   I311 @BASEBOARD_FAB2_LIB.BASEBOARD_FAB2(SCH_1):PAGE37
  U5D1 BY73 VCCIN<66> SKX_EXT_B_BGA1-IC,TBD   I311 @BASEBOARD_FAB2_LIB.BASEBOARD_FAB2(SCH_1):PAGE37
  U5D1 BY61 VCCIN<67> SKX_EXT_B_BGA1-IC,TBD   I311 @BASEBOARD_FAB2_LIB.BASEBOARD_FAB2(SCH_1):PAGE37
  U5D1 BW84 VCCIN<68> SKX_EXT_B_BGA1-IC,TBD   I311 @BASEBOARD_FAB2_LIB.BASEBOARD_FAB2(SCH_1):PAGE37
  U5D1 BW70 VCCIN<69> SKX_EXT_B_BGA1-IC,TBD   I311 @BASEBOARD_FAB2_LIB.BASEBOARD_FAB2(SCH_1):PAGE37
  U5D1 BW68 VCCIN<70> SKX_EXT_B_BGA1-IC,TBD   I311 @BASEBOARD_FAB2_LIB.BASEBOARD_FAB2(SCH_1):PAGE37
  U5D1 BW66 VCCIN<71> SKX_EXT_B_BGA1-IC,TBD   I311 @BASEBOARD_FAB2_LIB.BASEBOARD_FAB2(SCH_1):PAGE37
  U5D1 BW64 VCCIN<72> SKX_EXT_B_BGA1-IC,TBD   I311 @BASEBOARD_FAB2_LIB.BASEBOARD_FAB2(SCH_1):PAGE37
  U5D1 BW62 VCCIN<73> SKX_EXT_B_BGA1-IC,TBD   I311 @BASEBOARD_FAB2_LIB.BASEBOARD_FAB2(SCH_1):PAGE37
  U5D1 BW60 VCCIN<74> SKX_EXT_B_BGA1-IC,TBD   I311 @BASEBOARD_FAB2_LIB.BASEBOARD_FAB2(SCH_1):PAGE37
  U5D1 BV83 VCCIN<75> SKX_EXT_B_BGA1-IC,TBD   I311 @BASEBOARD_FAB2_LIB.BASEBOARD_FAB2(SCH_1):PAGE37
  U5D1 BV81 VCCIN<76> SKX_EXT_B_BGA1-IC,TBD   I311 @BASEBOARD_FAB2_LIB.BASEBOARD_FAB2(SCH_1):PAGE37
  U5D1 BV79 VCCIN<77> SKX_EXT_B_BGA1-IC,TBD   I311 @BASEBOARD_FAB2_LIB.BASEBOARD_FAB2(SCH_1):PAGE37
  U5D1 BV77 VCCIN<78> SKX_EXT_B_BGA1-IC,TBD   I311 @BASEBOARD_FAB2_LIB.BASEBOARD_FAB2(SCH_1):PAGE37
  U5D1 BV75 VCCIN<79> SKX_EXT_B_BGA1-IC,TBD   I311 @BASEBOARD_FAB2_LIB.BASEBOARD_FAB2(SCH_1):PAGE37
  U5D1 BV73 VCCIN<80> SKX_EXT_B_BGA1-IC,TBD   I311 @BASEBOARD_FAB2_LIB.BASEBOARD_FAB2(SCH_1):PAGE37
  U5D1 BV71 VCCIN<81> SKX_EXT_B_BGA1-IC,TBD   I311 @BASEBOARD_FAB2_LIB.BASEBOARD_FAB2(SCH_1):PAGE37
  U5D1 BV69 VCCIN<82> SKX_EXT_B_BGA1-IC,TBD   I311 @BASEBOARD_FAB2_LIB.BASEBOARD_FAB2(SCH_1):PAGE37
  U5D1 BV67 VCCIN<83> SKX_EXT_B_BGA1-IC,TBD   I311 @BASEBOARD_FAB2_LIB.BASEBOARD_FAB2(SCH_1):PAGE37
  U5D1 BV65 VCCIN<84> SKX_EXT_B_BGA1-IC,TBD   I311 @BASEBOARD_FAB2_LIB.BASEBOARD_FAB2(SCH_1):PAGE37
  U5D1 BV63 VCCIN<85> SKX_EXT_B_BGA1-IC,TBD   I311 @BASEBOARD_FAB2_LIB.BASEBOARD_FAB2(SCH_1):PAGE37
  U5D1 BV61 VCCIN<86> SKX_EXT_B_BGA1-IC,TBD   I311 @BASEBOARD_FAB2_LIB.BASEBOARD_FAB2(SCH_1):PAGE37
  U5D1 BU84 VCCIN<87> SKX_EXT_B_BGA1-IC,TBD   I311 @BASEBOARD_FAB2_LIB.BASEBOARD_FAB2(SCH_1):PAGE37
  U5D1 BU82 VCCIN<88> SKX_EXT_B_BGA1-IC,TBD   I311 @BASEBOARD_FAB2_LIB.BASEBOARD_FAB2(SCH_1):PAGE37
  U5D1 BU80 VCCIN<89> SKX_EXT_B_BGA1-IC,TBD   I311 @BASEBOARD_FAB2_LIB.BASEBOARD_FAB2(SCH_1):PAGE37
  U5D1 BU78 VCCIN<90> SKX_EXT_B_BGA1-IC,TBD   I311 @BASEBOARD_FAB2_LIB.BASEBOARD_FAB2(SCH_1):PAGE37
  U5D1 BU76 VCCIN<91> SKX_EXT_B_BGA1-IC,TBD   I311 @BASEBOARD_FAB2_LIB.BASEBOARD_FAB2(SCH_1):PAGE37
  U5D1 BU74 VCCIN<92> SKX_EXT_B_BGA1-IC,TBD   I311 @BASEBOARD_FAB2_LIB.BASEBOARD_FAB2(SCH_1):PAGE37
  U5D1 BU72 VCCIN<93> SKX_EXT_B_BGA1-IC,TBD   I311 @BASEBOARD_FAB2_LIB.BASEBOARD_FAB2(SCH_1):PAGE37
  U5D1 BU70 VCCIN<94> SKX_EXT_B_BGA1-IC,TBD   I311 @BASEBOARD_FAB2_LIB.BASEBOARD_FAB2(SCH_1):PAGE37
  U5D1 BU68 VCCIN<95> SKX_EXT_B_BGA1-IC,TBD   I311 @BASEBOARD_FAB2_LIB.BASEBOARD_FAB2(SCH_1):PAGE37
  U5D1 BU66 VCCIN<96> SKX_EXT_B_BGA1-IC,TBD   I311 @BASEBOARD_FAB2_LIB.BASEBOARD_FAB2(SCH_1):PAGE37
  U5D1 BU64 VCCIN<97> SKX_EXT_B_BGA1-IC,TBD   I311 @BASEBOARD_FAB2_LIB.BASEBOARD_FAB2(SCH_1):PAGE37
  U5D1 BU62 VCCIN<98> SKX_EXT_B_BGA1-IC,TBD   I311 @BASEBOARD_FAB2_LIB.BASEBOARD_FAB2(SCH_1):PAGE37
  U5D1 BU60 VCCIN<99> SKX_EXT_B_BGA1-IC,TBD   I311 @BASEBOARD_FAB2_LIB.BASEBOARD_FAB2(SCH_1):PAGE37
  U5D1 BT83 VCCIN<100> SKX_EXT_B_BGA1-IC,TBD   I311 @BASEBOARD_FAB2_LIB.BASEBOARD_FAB2(SCH_1):PAGE37
  U5D1 BT81 VCCIN<101> SKX_EXT_B_BGA1-IC,TBD   I311 @BASEBOARD_FAB2_LIB.BASEBOARD_FAB2(SCH_1):PAGE37
  U5D1 BT79 VCCIN<102> SKX_EXT_B_BGA1-IC,TBD   I311 @BASEBOARD_FAB2_LIB.BASEBOARD_FAB2(SCH_1):PAGE37
  U5D1 BT77 VCCIN<103> SKX_EXT_B_BGA1-IC,TBD   I311 @BASEBOARD_FAB2_LIB.BASEBOARD_FAB2(SCH_1):PAGE37
  U5D1 BT75 VCCIN<104> SKX_EXT_B_BGA1-IC,TBD   I311 @BASEBOARD_FAB2_LIB.BASEBOARD_FAB2(SCH_1):PAGE37
  U5D1 BT73 VCCIN<105> SKX_EXT_B_BGA1-IC,TBD   I311 @BASEBOARD_FAB2_LIB.BASEBOARD_FAB2(SCH_1):PAGE37
  U5D1 BT71 VCCIN<106> SKX_EXT_B_BGA1-IC,TBD   I311 @BASEBOARD_FAB2_LIB.BASEBOARD_FAB2(SCH_1):PAGE37
  U5D1 BT69 VCCIN<107> SKX_EXT_B_BGA1-IC,TBD   I311 @BASEBOARD_FAB2_LIB.BASEBOARD_FAB2(SCH_1):PAGE37
  U5D1 BT67 VCCIN<108> SKX_EXT_B_BGA1-IC,TBD   I311 @BASEBOARD_FAB2_LIB.BASEBOARD_FAB2(SCH_1):PAGE37
  U5D1 BT65 VCCIN<109> SKX_EXT_B_BGA1-IC,TBD   I311 @BASEBOARD_FAB2_LIB.BASEBOARD_FAB2(SCH_1):PAGE37
  U5D1 BT63 VCCIN<110> SKX_EXT_B_BGA1-IC,TBD   I311 @BASEBOARD_FAB2_LIB.BASEBOARD_FAB2(SCH_1):PAGE37
  U5D1 BT61 VCCIN<111> SKX_EXT_B_BGA1-IC,TBD   I311 @BASEBOARD_FAB2_LIB.BASEBOARD_FAB2(SCH_1):PAGE37
  U5D1 BR84 VCCIN<112> SKX_EXT_B_BGA1-IC,TBD   I311 @BASEBOARD_FAB2_LIB.BASEBOARD_FAB2(SCH_1):PAGE37
  U5D1 BR62 VCCIN<113> SKX_EXT_B_BGA1-IC,TBD   I311 @BASEBOARD_FAB2_LIB.BASEBOARD_FAB2(SCH_1):PAGE37
  U5D1 BR60 VCCIN<114> SKX_EXT_B_BGA1-IC,TBD   I311 @BASEBOARD_FAB2_LIB.BASEBOARD_FAB2(SCH_1):PAGE37
  U5D1 BP83 VCCIN<115> SKX_EXT_B_BGA1-IC,TBD   I311 @BASEBOARD_FAB2_LIB.BASEBOARD_FAB2(SCH_1):PAGE37
  U5D1 BP81 VCCIN<116> SKX_EXT_B_BGA1-IC,TBD   I311 @BASEBOARD_FAB2_LIB.BASEBOARD_FAB2(SCH_1):PAGE37
  U5D1 BP79 VCCIN<117> SKX_EXT_B_BGA1-IC,TBD   I311 @BASEBOARD_FAB2_LIB.BASEBOARD_FAB2(SCH_1):PAGE37
  U5D1 BP77 VCCIN<118> SKX_EXT_B_BGA1-IC,TBD   I311 @BASEBOARD_FAB2_LIB.BASEBOARD_FAB2(SCH_1):PAGE37
  U5D1 BP75 VCCIN<119> SKX_EXT_B_BGA1-IC,TBD   I311 @BASEBOARD_FAB2_LIB.BASEBOARD_FAB2(SCH_1):PAGE37
  U5D1 BP73 VCCIN<120> SKX_EXT_B_BGA1-IC,TBD   I311 @BASEBOARD_FAB2_LIB.BASEBOARD_FAB2(SCH_1):PAGE37
  U5D1 BP71 VCCIN<121> SKX_EXT_B_BGA1-IC,TBD   I311 @BASEBOARD_FAB2_LIB.BASEBOARD_FAB2(SCH_1):PAGE37
  U5D1 BP69 VCCIN<122> SKX_EXT_B_BGA1-IC,TBD   I311 @BASEBOARD_FAB2_LIB.BASEBOARD_FAB2(SCH_1):PAGE37
  U5D1 BP67 VCCIN<123> SKX_EXT_B_BGA1-IC,TBD   I311 @BASEBOARD_FAB2_LIB.BASEBOARD_FAB2(SCH_1):PAGE37
  U5D1 BP65 VCCIN<124> SKX_EXT_B_BGA1-IC,TBD   I311 @BASEBOARD_FAB2_LIB.BASEBOARD_FAB2(SCH_1):PAGE37
  U5D1 BP63 VCCIN<125> SKX_EXT_B_BGA1-IC,TBD   I311 @BASEBOARD_FAB2_LIB.BASEBOARD_FAB2(SCH_1):PAGE37
  U5D1 BP61 VCCIN<126> SKX_EXT_B_BGA1-IC,TBD   I311 @BASEBOARD_FAB2_LIB.BASEBOARD_FAB2(SCH_1):PAGE37
  U5D1 BN84 VCCIN<127> SKX_EXT_B_BGA1-IC,TBD   I311 @BASEBOARD_FAB2_LIB.BASEBOARD_FAB2(SCH_1):PAGE37
  U5D1 BN82 VCCIN<128> SKX_EXT_B_BGA1-IC,TBD   I311 @BASEBOARD_FAB2_LIB.BASEBOARD_FAB2(SCH_1):PAGE37
  U5D1 BN80 VCCIN<129> SKX_EXT_B_BGA1-IC,TBD   I311 @BASEBOARD_FAB2_LIB.BASEBOARD_FAB2(SCH_1):PAGE37
  C5P4    1      A CAP_0805-47UF,4V,20%,X6S,C9533A    I27 @BASEBOARD_FAB2_LIB.BASEBOARD_FAB2(SCH_1):PAGE42
 C5P23    1      A CAP_0805-47UF,4V,20%,X6S,C9533A    I28 @BASEBOARD_FAB2_LIB.BASEBOARD_FAB2(SCH_1):PAGE42
 C5P24    1      A CAP_0805-47UF,4V,20%,X6S,C9533A    I33 @BASEBOARD_FAB2_LIB.BASEBOARD_FAB2(SCH_1):PAGE42
 C5P25    1      A CAP_0805-47UF,4V,20%,X6S,C9533A    I37 @BASEBOARD_FAB2_LIB.BASEBOARD_FAB2(SCH_1):PAGE42
  C5P6    1      A CAP_0805-47UF,4V,20%,X6S,C9533A    I38 @BASEBOARD_FAB2_LIB.BASEBOARD_FAB2(SCH_1):PAGE42
 C5P41    1      A CAP_0805-47UF,4V,20%,X6S,C9533A    I40 @BASEBOARD_FAB2_LIB.BASEBOARD_FAB2(SCH_1):PAGE42
 C5P14    1      A CAP_0805-47UF,4V,20%,X6S,C9533A    I41 @BASEBOARD_FAB2_LIB.BASEBOARD_FAB2(SCH_1):PAGE42
  C5P5    1      A CAP_0805-47UF,4V,20%,X6S,C9533A    I42 @BASEBOARD_FAB2_LIB.BASEBOARD_FAB2(SCH_1):PAGE42
 C5P27    1      A CAP_0805-47UF,4V,20%,X6S,C9533A    I44 @BASEBOARD_FAB2_LIB.BASEBOARD_FAB2(SCH_1):PAGE42
 C5P33    1      A CAP_0805-47UF,4V,20%,X6S,C9533A    I50 @BASEBOARD_FAB2_LIB.BASEBOARD_FAB2(SCH_1):PAGE42
 C5P35    1      A CAP_0805-47UF,4V,20%,X6S,C9533A    I51 @BASEBOARD_FAB2_LIB.BASEBOARD_FAB2(SCH_1):PAGE42
 C5P32    1      A CAP_0805-47UF,4V,20%,X6S,C9533A    I53 @BASEBOARD_FAB2_LIB.BASEBOARD_FAB2(SCH_1):PAGE42
 C5P34    1      A CAP_0805-47UF,4V,20%,X6S,C9533A    I54 @BASEBOARD_FAB2_LIB.BASEBOARD_FAB2(SCH_1):PAGE42
 C5P22    1      A CAP_0805-47UF,4V,20%,X6S,C9533A    I55 @BASEBOARD_FAB2_LIB.BASEBOARD_FAB2(SCH_1):PAGE42
 C5P26    1      A CAP_0805-47UF,4V,20%,X6S,C9533A    I56 @BASEBOARD_FAB2_LIB.BASEBOARD_FAB2(SCH_1):PAGE42
 C5P40    1      A CAP_0805-47UF,4V,20%,X6S,C9533A    I57 @BASEBOARD_FAB2_LIB.BASEBOARD_FAB2(SCH_1):PAGE42
 C5P42    1      A CAP_0805-47UF,4V,20%,X6S,C9533A    I59 @BASEBOARD_FAB2_LIB.BASEBOARD_FAB2(SCH_1):PAGE42
 C5P43    1      A CAP_0805-47UF,4V,20%,X6S,C9533A    I60 @BASEBOARD_FAB2_LIB.BASEBOARD_FAB2(SCH_1):PAGE42
 C5P44    1      A CAP_0805-47UF,4V,20%,X6S,C9533A    I61 @BASEBOARD_FAB2_LIB.BASEBOARD_FAB2(SCH_1):PAGE42
 C5P37    1      A CAP_0805-47UF,4V,20%,X6S,C9533A    I63 @BASEBOARD_FAB2_LIB.BASEBOARD_FAB2(SCH_1):PAGE42
 C5P36    1      A CAP_0805-47UF,4V,20%,X6S,C9533A    I65 @BASEBOARD_FAB2_LIB.BASEBOARD_FAB2(SCH_1):PAGE42
 C5D28    1      A CAP_A_0603V-22.0UF,4V,20%,X6S,A   I100 @BASEBOARD_FAB2_LIB.BASEBOARD_FAB2(SCH_1):PAGE42
 C5D29    1      A CAP_A_0603V-22.0UF,4V,20%,X6S,A   I102 @BASEBOARD_FAB2_LIB.BASEBOARD_FAB2(SCH_1):PAGE42
 C5D32    1      A CAP_A_0603V-22.0UF,4V,20%,X6S,A   I103 @BASEBOARD_FAB2_LIB.BASEBOARD_FAB2(SCH_1):PAGE42
 C5D47    1      A CAP_A_0603V-22.0UF,4V,20%,X6S,A   I104 @BASEBOARD_FAB2_LIB.BASEBOARD_FAB2(SCH_1):PAGE42
 C5D31    1      A CAP_A_0603V-22.0UF,4V,20%,X6S,A   I106 @BASEBOARD_FAB2_LIB.BASEBOARD_FAB2(SCH_1):PAGE42
 C5D46    1      A CAP_A_0603V-22.0UF,4V,20%,X6S,A   I107 @BASEBOARD_FAB2_LIB.BASEBOARD_FAB2(SCH_1):PAGE42
 C5D27    1      A CAP_A_0603V-22.0UF,4V,20%,X6S,A   I109 @BASEBOARD_FAB2_LIB.BASEBOARD_FAB2(SCH_1):PAGE42
 C5D30    1      A CAP_A_0603V-22.0UF,4V,20%,X6S,A   I111 @BASEBOARD_FAB2_LIB.BASEBOARD_FAB2(SCH_1):PAGE42
 C5D60    1      A CAP_A_0603V-22.0UF,4V,20%,X6S,A   I112 @BASEBOARD_FAB2_LIB.BASEBOARD_FAB2(SCH_1):PAGE42
 C5D61    1      A CAP_A_0603V-22.0UF,4V,20%,X6S,A   I113 @BASEBOARD_FAB2_LIB.BASEBOARD_FAB2(SCH_1):PAGE42
 C5D41    1      A CAP_A_0603V-22.0UF,4V,20%,X6S,A   I114 @BASEBOARD_FAB2_LIB.BASEBOARD_FAB2(SCH_1):PAGE42
 C5D40    1      A CAP_A_0603V-22.0UF,4V,20%,X6S,A   I115 @BASEBOARD_FAB2_LIB.BASEBOARD_FAB2(SCH_1):PAGE42
 C5D14    1      A CAP_A_0603V-22.0UF,4V,20%,X6S,A   I117 @BASEBOARD_FAB2_LIB.BASEBOARD_FAB2(SCH_1):PAGE42
 C5D17    1      A CAP_A_0603V-22.0UF,4V,20%,X6S,A   I118 @BASEBOARD_FAB2_LIB.BASEBOARD_FAB2(SCH_1):PAGE42
 C5D58    1      A CAP_A_0603V-22.0UF,4V,20%,X6S,A   I120 @BASEBOARD_FAB2_LIB.BASEBOARD_FAB2(SCH_1):PAGE42
 C5D16    1      A CAP_A_0603V-22.0UF,4V,20%,X6S,A   I123 @BASEBOARD_FAB2_LIB.BASEBOARD_FAB2(SCH_1):PAGE42
  C5D5    1      A CAP_A_0603V-22.0UF,4V,20%,X6S,A   I125 @BASEBOARD_FAB2_LIB.BASEBOARD_FAB2(SCH_1):PAGE42
  C5D1    1      A CAP_A_0603V-22.0UF,4V,20%,X6S,A   I126 @BASEBOARD_FAB2_LIB.BASEBOARD_FAB2(SCH_1):PAGE42
  C5D4    1      A CAP_A_0603V-22.0UF,4V,20%,X6S,A   I127 @BASEBOARD_FAB2_LIB.BASEBOARD_FAB2(SCH_1):PAGE42
 C5D19    1      A CAP_A_0603V-22.0UF,4V,20%,X6S,A   I128 @BASEBOARD_FAB2_LIB.BASEBOARD_FAB2(SCH_1):PAGE42
 C5D59    1      A CAP_A_0603V-22.0UF,4V,20%,X6S,A   I129 @BASEBOARD_FAB2_LIB.BASEBOARD_FAB2(SCH_1):PAGE42
  C5D3    1      A CAP_A_0603V-22.0UF,4V,20%,X6S,A   I130 @BASEBOARD_FAB2_LIB.BASEBOARD_FAB2(SCH_1):PAGE42
 C5D43    1      A CAP_A_0603V-22.0UF,4V,20%,X6S,A   I131 @BASEBOARD_FAB2_LIB.BASEBOARD_FAB2(SCH_1):PAGE42
 C5D15    1      A CAP_A_0603V-22.0UF,4V,20%,X6S,A   I132 @BASEBOARD_FAB2_LIB.BASEBOARD_FAB2(SCH_1):PAGE42
 C5D18    1      A CAP_A_0603V-22.0UF,4V,20%,X6S,A   I134 @BASEBOARD_FAB2_LIB.BASEBOARD_FAB2(SCH_1):PAGE42
 C5D42    1      A CAP_A_0603V-22.0UF,4V,20%,X6S,A   I135 @BASEBOARD_FAB2_LIB.BASEBOARD_FAB2(SCH_1):PAGE42
  C5D2    1      A CAP_A_0603V-22.0UF,4V,20%,X6S,A   I136 @BASEBOARD_FAB2_LIB.BASEBOARD_FAB2(SCH_1):PAGE42
 C5D24    1      A CAP_A_0603V-22.0UF,4V,20%,X6S,A   I138 @BASEBOARD_FAB2_LIB.BASEBOARD_FAB2(SCH_1):PAGE42
 C5D39    1      A CAP_A_0603V-22.0UF,4V,20%,X6S,A   I140 @BASEBOARD_FAB2_LIB.BASEBOARD_FAB2(SCH_1):PAGE42
 C5D44    1      A CAP_A_0603V-22.0UF,4V,20%,X6S,A   I142 @BASEBOARD_FAB2_LIB.BASEBOARD_FAB2(SCH_1):PAGE42
 C5D26    1      A CAP_A_0603V-22.0UF,4V,20%,X6S,A   I154 @BASEBOARD_FAB2_LIB.BASEBOARD_FAB2(SCH_1):PAGE42
 C5D25    1      A CAP_A_0603V-22.0UF,4V,20%,X6S,A   I155 @BASEBOARD_FAB2_LIB.BASEBOARD_FAB2(SCH_1):PAGE42
 C5D45    1      A CAP_A_0603V-22.0UF,4V,20%,X6S,A   I156 @BASEBOARD_FAB2_LIB.BASEBOARD_FAB2(SCH_1):PAGE42
 C5P15    1      A CAP_0805-47UF,4V,20%,X6S,C9533A   I187 @BASEBOARD_FAB2_LIB.BASEBOARD_FAB2(SCH_1):PAGE42
 C5P16    1      A CAP_0805-47UF,4V,20%,X6S,C9533A   I188 @BASEBOARD_FAB2_LIB.BASEBOARD_FAB2(SCH_1):PAGE42
  C5P3    1      A CAP_0805-47UF,4V,20%,X6S,C9533A   I189 @BASEBOARD_FAB2_LIB.BASEBOARD_FAB2(SCH_1):PAGE42
 C5P17    1      A CAP_0805-47UF,4V,20%,X6S,C9533A   I190 @BASEBOARD_FAB2_LIB.BASEBOARD_FAB2(SCH_1):PAGE42
  L4E1    2    INB INDUCTOR_SM-0.12UH,IND,D92183-A     I5 @BASEBOARD_FAB2_LIB.BASEBOARD_FAB2(SCH_1):PAGE202
  C6R7    1      A CAP_A_0603V-22.0UF,4V,20%,X6S,A     I9 @BASEBOARD_FAB2_LIB.BASEBOARD_FAB2(SCH_1):PAGE202
 C4E11    1      A CAP_A_0603V-22.0UF,4V,20%,X6S,A    I27 @BASEBOARD_FAB2_LIB.BASEBOARD_FAB2(SCH_1):PAGE202
  L4D3    2    INB INDUCTOR_SM-0.12UH,IND,D92183-A    I29 @BASEBOARD_FAB2_LIB.BASEBOARD_FAB2(SCH_1):PAGE202
  C4E3    1      A CAP_A_0603V-22.0UF,4V,20%,X6S,A    I61 @BASEBOARD_FAB2_LIB.BASEBOARD_FAB2(SCH_1):PAGE202
 C6P16    1      A CAP_A_0603V-22.0UF,4V,20%,X6S,A    I62 @BASEBOARD_FAB2_LIB.BASEBOARD_FAB2(SCH_1):PAGE202
 EU4E1    1    VOS IR354XX_SM-IR35411,IC,H73688-0A    I63 @BASEBOARD_FAB2_LIB.BASEBOARD_FAB2(SCH_1):PAGE202
 EU4D6    1    VOS IR354XX_SM-IR35411,IC,H73688-0A    I64 @BASEBOARD_FAB2_LIB.BASEBOARD_FAB2(SCH_1):PAGE202
  L4D2    2    INB INDUCTOR_SM-0.12UH,IND,D92183-A    I15 @BASEBOARD_FAB2_LIB.BASEBOARD_FAB2(SCH_1):PAGE203
  C6R3    1      A CAPP_3018-470UF,2.5V,20%,ALUM,A    I16 @BASEBOARD_FAB2_LIB.BASEBOARD_FAB2(SCH_1):PAGE203
  C6R9    1      A CAPP_3018-470UF,2.5V,20%,ALUM,A    I18 @BASEBOARD_FAB2_LIB.BASEBOARD_FAB2(SCH_1):PAGE203
  L4D1    2    INB INDUCTOR_SM-0.12UH,IND,D92183-A    I24 @BASEBOARD_FAB2_LIB.BASEBOARD_FAB2(SCH_1):PAGE203
  C6P3    1      A CAP_A_0603V-22.0UF,4V,20%,X6S,A    I25 @BASEBOARD_FAB2_LIB.BASEBOARD_FAB2(SCH_1):PAGE203
 C6P23    1      A CAPP_3018-470UF,2.5V,20%,ALUM,A    I28 @BASEBOARD_FAB2_LIB.BASEBOARD_FAB2(SCH_1):PAGE203
 C6P14    1      A CAPP_3018-470UF,2.5V,20%,ALUM,A    I29 @BASEBOARD_FAB2_LIB.BASEBOARD_FAB2(SCH_1):PAGE203
 C6P18    1      A CAPP_3018-470UF,2.5V,20%,ALUM,A    I30 @BASEBOARD_FAB2_LIB.BASEBOARD_FAB2(SCH_1):PAGE203
  C6P8    1      A CAPP_3018-470UF,2.5V,20%,ALUM,A    I32 @BASEBOARD_FAB2_LIB.BASEBOARD_FAB2(SCH_1):PAGE203
  C6N9    1      A CAPP_3018-470UF,2.5V,20%,ALUM,A    I34 @BASEBOARD_FAB2_LIB.BASEBOARD_FAB2(SCH_1):PAGE203
 C6P21    1      A CAP_A_0603V-22.0UF,4V,20%,X6S,A    I66 @BASEBOARD_FAB2_LIB.BASEBOARD_FAB2(SCH_1):PAGE203
 R4E13    1      A RES_0603-100.0,1%,1/10W,CHIP,GA    I67 @BASEBOARD_FAB2_LIB.BASEBOARD_FAB2(SCH_1):PAGE203
 C4D34    1      A CAP_A_0603V-22.0UF,4V,20%,X6S,A    I68 @BASEBOARD_FAB2_LIB.BASEBOARD_FAB2(SCH_1):PAGE203
  C4D4    1      A CAP_A_0603V-22.0UF,4V,20%,X6S,A    I69 @BASEBOARD_FAB2_LIB.BASEBOARD_FAB2(SCH_1):PAGE203
 EU4D3    1    VOS IR354XX_SM-IR35411,IC,H73688-0A    I70 @BASEBOARD_FAB2_LIB.BASEBOARD_FAB2(SCH_1):PAGE203
 EU4D1    1    VOS IR354XX_SM-IR35411,IC,H73688-0A    I71 @BASEBOARD_FAB2_LIB.BASEBOARD_FAB2(SCH_1):PAGE203
  L4C3    2    INB INDUCTOR_SM-0.12UH,IND,D92183-A     I5 @BASEBOARD_FAB2_LIB.BASEBOARD_FAB2(SCH_1):PAGE204
 C4D12    1      A CAP_A_0603V-22.0UF,4V,20%,X6S,A     I9 @BASEBOARD_FAB2_LIB.BASEBOARD_FAB2(SCH_1):PAGE204
 R4E14    2      B RES_0402-100.0,1%,1/16W,CHIP,GA    I60 @BASEBOARD_FAB2_LIB.BASEBOARD_FAB2(SCH_1):PAGE204
  C6R2    1      A CAP_A_0603V-22.0UF,4V,20%,X6S,A    I70 @BASEBOARD_FAB2_LIB.BASEBOARD_FAB2(SCH_1):PAGE204
 EU4C2    1    VOS IR354XX_SM-IR35411,IC,H73688-0A    I71 @BASEBOARD_FAB2_LIB.BASEBOARD_FAB2(SCH_1):PAGE204

PVCCIN_CPU1 @BASEBOARD_FAB2_LIB.BASEBOARD_FAB2(SCH_1):PVCCIN_CPU1
 RT8P1    1      A RES_0603-100.0K,1%,1/10W,CHIP,A    I49 @BASEBOARD_FAB2_LIB.BASEBOARD_FAB2(SCH_1):PAGE71
  U2D1 BN78 VCCIN<130> SKX_EXT_B_BGA1-IC,TBD    I50 @BASEBOARD_FAB2_LIB.BASEBOARD_FAB2(SCH_1):PAGE71
  U2D1 BN76 VCCIN<131> SKX_EXT_B_BGA1-IC,TBD    I50 @BASEBOARD_FAB2_LIB.BASEBOARD_FAB2(SCH_1):PAGE71
  U2D1 BN74 VCCIN<132> SKX_EXT_B_BGA1-IC,TBD    I50 @BASEBOARD_FAB2_LIB.BASEBOARD_FAB2(SCH_1):PAGE71
  U2D1 BN72 VCCIN<133> SKX_EXT_B_BGA1-IC,TBD    I50 @BASEBOARD_FAB2_LIB.BASEBOARD_FAB2(SCH_1):PAGE71
  U2D1 BN70 VCCIN<134> SKX_EXT_B_BGA1-IC,TBD    I50 @BASEBOARD_FAB2_LIB.BASEBOARD_FAB2(SCH_1):PAGE71
  U2D1 BN68 VCCIN<135> SKX_EXT_B_BGA1-IC,TBD    I50 @BASEBOARD_FAB2_LIB.BASEBOARD_FAB2(SCH_1):PAGE71
  U2D1 BN66 VCCIN<136> SKX_EXT_B_BGA1-IC,TBD    I50 @BASEBOARD_FAB2_LIB.BASEBOARD_FAB2(SCH_1):PAGE71
  U2D1 BN64 VCCIN<137> SKX_EXT_B_BGA1-IC,TBD    I50 @BASEBOARD_FAB2_LIB.BASEBOARD_FAB2(SCH_1):PAGE71
  U2D1 BN62 VCCIN<138> SKX_EXT_B_BGA1-IC,TBD    I50 @BASEBOARD_FAB2_LIB.BASEBOARD_FAB2(SCH_1):PAGE71
  U2D1 BN60 VCCIN<139> SKX_EXT_B_BGA1-IC,TBD    I50 @BASEBOARD_FAB2_LIB.BASEBOARD_FAB2(SCH_1):PAGE71
  U2D1 BM83 VCCIN<140> SKX_EXT_B_BGA1-IC,TBD    I50 @BASEBOARD_FAB2_LIB.BASEBOARD_FAB2(SCH_1):PAGE71
  U2D1 BM81 VCCIN<141> SKX_EXT_B_BGA1-IC,TBD    I50 @BASEBOARD_FAB2_LIB.BASEBOARD_FAB2(SCH_1):PAGE71
  U2D1 BM79 VCCIN<142> SKX_EXT_B_BGA1-IC,TBD    I50 @BASEBOARD_FAB2_LIB.BASEBOARD_FAB2(SCH_1):PAGE71
  U2D1 BM77 VCCIN<143> SKX_EXT_B_BGA1-IC,TBD    I50 @BASEBOARD_FAB2_LIB.BASEBOARD_FAB2(SCH_1):PAGE71
  U2D1 BM75 VCCIN<144> SKX_EXT_B_BGA1-IC,TBD    I50 @BASEBOARD_FAB2_LIB.BASEBOARD_FAB2(SCH_1):PAGE71
  U2D1 BM73 VCCIN<145> SKX_EXT_B_BGA1-IC,TBD    I50 @BASEBOARD_FAB2_LIB.BASEBOARD_FAB2(SCH_1):PAGE71
  U2D1 BM71 VCCIN<146> SKX_EXT_B_BGA1-IC,TBD    I50 @BASEBOARD_FAB2_LIB.BASEBOARD_FAB2(SCH_1):PAGE71
  U2D1 BM69 VCCIN<147> SKX_EXT_B_BGA1-IC,TBD    I50 @BASEBOARD_FAB2_LIB.BASEBOARD_FAB2(SCH_1):PAGE71
  U2D1 BM67 VCCIN<148> SKX_EXT_B_BGA1-IC,TBD    I50 @BASEBOARD_FAB2_LIB.BASEBOARD_FAB2(SCH_1):PAGE71
  U2D1 BM65 VCCIN<149> SKX_EXT_B_BGA1-IC,TBD    I50 @BASEBOARD_FAB2_LIB.BASEBOARD_FAB2(SCH_1):PAGE71
  U2D1 BM63 VCCIN<150> SKX_EXT_B_BGA1-IC,TBD    I50 @BASEBOARD_FAB2_LIB.BASEBOARD_FAB2(SCH_1):PAGE71
  U2D1 BM61 VCCIN<151> SKX_EXT_B_BGA1-IC,TBD    I50 @BASEBOARD_FAB2_LIB.BASEBOARD_FAB2(SCH_1):PAGE71
  U2D1 BL84 VCCIN<152> SKX_EXT_B_BGA1-IC,TBD    I50 @BASEBOARD_FAB2_LIB.BASEBOARD_FAB2(SCH_1):PAGE71
  U2D1 BL62 VCCIN<153> SKX_EXT_B_BGA1-IC,TBD    I50 @BASEBOARD_FAB2_LIB.BASEBOARD_FAB2(SCH_1):PAGE71
  U2D1 BL60 VCCIN<154> SKX_EXT_B_BGA1-IC,TBD    I50 @BASEBOARD_FAB2_LIB.BASEBOARD_FAB2(SCH_1):PAGE71
  U2D1 BK83 VCCIN<155> SKX_EXT_B_BGA1-IC,TBD    I50 @BASEBOARD_FAB2_LIB.BASEBOARD_FAB2(SCH_1):PAGE71
  U2D1 BK81 VCCIN<156> SKX_EXT_B_BGA1-IC,TBD    I50 @BASEBOARD_FAB2_LIB.BASEBOARD_FAB2(SCH_1):PAGE71
  U2D1 BK79 VCCIN<157> SKX_EXT_B_BGA1-IC,TBD    I50 @BASEBOARD_FAB2_LIB.BASEBOARD_FAB2(SCH_1):PAGE71
  U2D1 BK77 VCCIN<158> SKX_EXT_B_BGA1-IC,TBD    I50 @BASEBOARD_FAB2_LIB.BASEBOARD_FAB2(SCH_1):PAGE71
  U2D1 BK75 VCCIN<159> SKX_EXT_B_BGA1-IC,TBD    I50 @BASEBOARD_FAB2_LIB.BASEBOARD_FAB2(SCH_1):PAGE71
  U2D1 BK73 VCCIN<160> SKX_EXT_B_BGA1-IC,TBD    I50 @BASEBOARD_FAB2_LIB.BASEBOARD_FAB2(SCH_1):PAGE71
  U2D1 BK71 VCCIN<161> SKX_EXT_B_BGA1-IC,TBD    I50 @BASEBOARD_FAB2_LIB.BASEBOARD_FAB2(SCH_1):PAGE71
  U2D1 BK69 VCCIN<162> SKX_EXT_B_BGA1-IC,TBD    I50 @BASEBOARD_FAB2_LIB.BASEBOARD_FAB2(SCH_1):PAGE71
  U2D1 BK67 VCCIN<163> SKX_EXT_B_BGA1-IC,TBD    I50 @BASEBOARD_FAB2_LIB.BASEBOARD_FAB2(SCH_1):PAGE71
  U2D1 BK65 VCCIN<164> SKX_EXT_B_BGA1-IC,TBD    I50 @BASEBOARD_FAB2_LIB.BASEBOARD_FAB2(SCH_1):PAGE71
  U2D1 BK63 VCCIN<165> SKX_EXT_B_BGA1-IC,TBD    I50 @BASEBOARD_FAB2_LIB.BASEBOARD_FAB2(SCH_1):PAGE71
  U2D1 BK61 VCCIN<166> SKX_EXT_B_BGA1-IC,TBD    I50 @BASEBOARD_FAB2_LIB.BASEBOARD_FAB2(SCH_1):PAGE71
  U2D1 BJ84 VCCIN<167> SKX_EXT_B_BGA1-IC,TBD    I50 @BASEBOARD_FAB2_LIB.BASEBOARD_FAB2(SCH_1):PAGE71
  U2D1 BJ82 VCCIN<168> SKX_EXT_B_BGA1-IC,TBD    I50 @BASEBOARD_FAB2_LIB.BASEBOARD_FAB2(SCH_1):PAGE71
  U2D1 BJ80 VCCIN<169> SKX_EXT_B_BGA1-IC,TBD    I50 @BASEBOARD_FAB2_LIB.BASEBOARD_FAB2(SCH_1):PAGE71
  U2D1 BJ78 VCCIN<170> SKX_EXT_B_BGA1-IC,TBD    I50 @BASEBOARD_FAB2_LIB.BASEBOARD_FAB2(SCH_1):PAGE71
  U2D1 BJ76 VCCIN<171> SKX_EXT_B_BGA1-IC,TBD    I50 @BASEBOARD_FAB2_LIB.BASEBOARD_FAB2(SCH_1):PAGE71
  U2D1 BJ74 VCCIN<172> SKX_EXT_B_BGA1-IC,TBD    I50 @BASEBOARD_FAB2_LIB.BASEBOARD_FAB2(SCH_1):PAGE71
  U2D1 BJ72 VCCIN<173> SKX_EXT_B_BGA1-IC,TBD    I50 @BASEBOARD_FAB2_LIB.BASEBOARD_FAB2(SCH_1):PAGE71
  U2D1 BJ70 VCCIN<174> SKX_EXT_B_BGA1-IC,TBD    I50 @BASEBOARD_FAB2_LIB.BASEBOARD_FAB2(SCH_1):PAGE71
  U2D1 BJ68 VCCIN<175> SKX_EXT_B_BGA1-IC,TBD    I50 @BASEBOARD_FAB2_LIB.BASEBOARD_FAB2(SCH_1):PAGE71
  U2D1 BJ66 VCCIN<176> SKX_EXT_B_BGA1-IC,TBD    I50 @BASEBOARD_FAB2_LIB.BASEBOARD_FAB2(SCH_1):PAGE71
  U2D1 BJ64 VCCIN<177> SKX_EXT_B_BGA1-IC,TBD    I50 @BASEBOARD_FAB2_LIB.BASEBOARD_FAB2(SCH_1):PAGE71
  U2D1 BJ62 VCCIN<178> SKX_EXT_B_BGA1-IC,TBD    I50 @BASEBOARD_FAB2_LIB.BASEBOARD_FAB2(SCH_1):PAGE71
  U2D1 BJ60 VCCIN<179> SKX_EXT_B_BGA1-IC,TBD    I50 @BASEBOARD_FAB2_LIB.BASEBOARD_FAB2(SCH_1):PAGE71
  U2D1 BH83 VCCIN<180> SKX_EXT_B_BGA1-IC,TBD    I50 @BASEBOARD_FAB2_LIB.BASEBOARD_FAB2(SCH_1):PAGE71
  U2D1 BH81 VCCIN<181> SKX_EXT_B_BGA1-IC,TBD    I50 @BASEBOARD_FAB2_LIB.BASEBOARD_FAB2(SCH_1):PAGE71
  U2D1 BH79 VCCIN<182> SKX_EXT_B_BGA1-IC,TBD    I50 @BASEBOARD_FAB2_LIB.BASEBOARD_FAB2(SCH_1):PAGE71
  U2D1 BH77 VCCIN<183> SKX_EXT_B_BGA1-IC,TBD    I50 @BASEBOARD_FAB2_LIB.BASEBOARD_FAB2(SCH_1):PAGE71
  U2D1 BH75 VCCIN<184> SKX_EXT_B_BGA1-IC,TBD    I50 @BASEBOARD_FAB2_LIB.BASEBOARD_FAB2(SCH_1):PAGE71
  U2D1 BH73 VCCIN<185> SKX_EXT_B_BGA1-IC,TBD    I50 @BASEBOARD_FAB2_LIB.BASEBOARD_FAB2(SCH_1):PAGE71
  U2D1 BH71 VCCIN<186> SKX_EXT_B_BGA1-IC,TBD    I50 @BASEBOARD_FAB2_LIB.BASEBOARD_FAB2(SCH_1):PAGE71
  U2D1 BH69 VCCIN<187> SKX_EXT_B_BGA1-IC,TBD    I50 @BASEBOARD_FAB2_LIB.BASEBOARD_FAB2(SCH_1):PAGE71
  U2D1 BH67 VCCIN<188> SKX_EXT_B_BGA1-IC,TBD    I50 @BASEBOARD_FAB2_LIB.BASEBOARD_FAB2(SCH_1):PAGE71
  U2D1 BH65 VCCIN<189> SKX_EXT_B_BGA1-IC,TBD    I50 @BASEBOARD_FAB2_LIB.BASEBOARD_FAB2(SCH_1):PAGE71
  U2D1 BH63 VCCIN<190> SKX_EXT_B_BGA1-IC,TBD    I50 @BASEBOARD_FAB2_LIB.BASEBOARD_FAB2(SCH_1):PAGE71
  U2D1 BH61 VCCIN<191> SKX_EXT_B_BGA1-IC,TBD    I50 @BASEBOARD_FAB2_LIB.BASEBOARD_FAB2(SCH_1):PAGE71
  U2D1 BG84 VCCIN<192> SKX_EXT_B_BGA1-IC,TBD    I50 @BASEBOARD_FAB2_LIB.BASEBOARD_FAB2(SCH_1):PAGE71
  U2D1 BG70 VCCIN<193> SKX_EXT_B_BGA1-IC,TBD    I50 @BASEBOARD_FAB2_LIB.BASEBOARD_FAB2(SCH_1):PAGE71
  U2D1 BG68 VCCIN<194> SKX_EXT_B_BGA1-IC,TBD    I50 @BASEBOARD_FAB2_LIB.BASEBOARD_FAB2(SCH_1):PAGE71
  U2D1 BG66 VCCIN<195> SKX_EXT_B_BGA1-IC,TBD    I50 @BASEBOARD_FAB2_LIB.BASEBOARD_FAB2(SCH_1):PAGE71
  U2D1 BG64 VCCIN<196> SKX_EXT_B_BGA1-IC,TBD    I50 @BASEBOARD_FAB2_LIB.BASEBOARD_FAB2(SCH_1):PAGE71
  U2D1 BG62 VCCIN<197> SKX_EXT_B_BGA1-IC,TBD    I50 @BASEBOARD_FAB2_LIB.BASEBOARD_FAB2(SCH_1):PAGE71
  U2D1 BG60 VCCIN<198> SKX_EXT_B_BGA1-IC,TBD    I50 @BASEBOARD_FAB2_LIB.BASEBOARD_FAB2(SCH_1):PAGE71
  U2D1 BF85 VCCIN<199> SKX_EXT_B_BGA1-IC,TBD    I50 @BASEBOARD_FAB2_LIB.BASEBOARD_FAB2(SCH_1):PAGE71
  U2D1 BF83 VCCIN<200> SKX_EXT_B_BGA1-IC,TBD    I50 @BASEBOARD_FAB2_LIB.BASEBOARD_FAB2(SCH_1):PAGE71
  U2D1 BF81 VCCIN<201> SKX_EXT_B_BGA1-IC,TBD    I50 @BASEBOARD_FAB2_LIB.BASEBOARD_FAB2(SCH_1):PAGE71
  U2D1 BF79 VCCIN<202> SKX_EXT_B_BGA1-IC,TBD    I50 @BASEBOARD_FAB2_LIB.BASEBOARD_FAB2(SCH_1):PAGE71
  U2D1 BF77 VCCIN<203> SKX_EXT_B_BGA1-IC,TBD    I50 @BASEBOARD_FAB2_LIB.BASEBOARD_FAB2(SCH_1):PAGE71
  U2D1 BF75 VCCIN<204> SKX_EXT_B_BGA1-IC,TBD    I50 @BASEBOARD_FAB2_LIB.BASEBOARD_FAB2(SCH_1):PAGE71
  U2D1 BF73 VCCIN<205> SKX_EXT_B_BGA1-IC,TBD    I50 @BASEBOARD_FAB2_LIB.BASEBOARD_FAB2(SCH_1):PAGE71
  U2D1 BF61 VCCIN<206> SKX_EXT_B_BGA1-IC,TBD    I50 @BASEBOARD_FAB2_LIB.BASEBOARD_FAB2(SCH_1):PAGE71
  U2D1 BE84 VCCIN<207> SKX_EXT_B_BGA1-IC,TBD    I50 @BASEBOARD_FAB2_LIB.BASEBOARD_FAB2(SCH_1):PAGE71
  U2D1 BE82 VCCIN<208> SKX_EXT_B_BGA1-IC,TBD    I50 @BASEBOARD_FAB2_LIB.BASEBOARD_FAB2(SCH_1):PAGE71
  U2D1 BE80 VCCIN<209> SKX_EXT_B_BGA1-IC,TBD    I50 @BASEBOARD_FAB2_LIB.BASEBOARD_FAB2(SCH_1):PAGE71
  U2D1 BE78 VCCIN<210> SKX_EXT_B_BGA1-IC,TBD    I50 @BASEBOARD_FAB2_LIB.BASEBOARD_FAB2(SCH_1):PAGE71
  U2D1 BE76 VCCIN<211> SKX_EXT_B_BGA1-IC,TBD    I50 @BASEBOARD_FAB2_LIB.BASEBOARD_FAB2(SCH_1):PAGE71
  U2D1 BE74 VCCIN<212> SKX_EXT_B_BGA1-IC,TBD    I50 @BASEBOARD_FAB2_LIB.BASEBOARD_FAB2(SCH_1):PAGE71
  U2D1 BE72 VCCIN<213> SKX_EXT_B_BGA1-IC,TBD    I50 @BASEBOARD_FAB2_LIB.BASEBOARD_FAB2(SCH_1):PAGE71
  U2D1 BE62 VCCIN<214> SKX_EXT_B_BGA1-IC,TBD    I50 @BASEBOARD_FAB2_LIB.BASEBOARD_FAB2(SCH_1):PAGE71
  U2D1 BE60 VCCIN<215> SKX_EXT_B_BGA1-IC,TBD    I50 @BASEBOARD_FAB2_LIB.BASEBOARD_FAB2(SCH_1):PAGE71
  U2D1 BD85 VCCIN<216> SKX_EXT_B_BGA1-IC,TBD    I50 @BASEBOARD_FAB2_LIB.BASEBOARD_FAB2(SCH_1):PAGE71
  U2D1 BD83 VCCIN<217> SKX_EXT_B_BGA1-IC,TBD    I50 @BASEBOARD_FAB2_LIB.BASEBOARD_FAB2(SCH_1):PAGE71
  U2D1 BD81 VCCIN<218> SKX_EXT_B_BGA1-IC,TBD    I50 @BASEBOARD_FAB2_LIB.BASEBOARD_FAB2(SCH_1):PAGE71
  U2D1 BD79 VCCIN<219> SKX_EXT_B_BGA1-IC,TBD    I50 @BASEBOARD_FAB2_LIB.BASEBOARD_FAB2(SCH_1):PAGE71
  U2D1 BD77 VCCIN<220> SKX_EXT_B_BGA1-IC,TBD    I50 @BASEBOARD_FAB2_LIB.BASEBOARD_FAB2(SCH_1):PAGE71
  U2D1 BD75 VCCIN<221> SKX_EXT_B_BGA1-IC,TBD    I50 @BASEBOARD_FAB2_LIB.BASEBOARD_FAB2(SCH_1):PAGE71
  U2D1 BD73 VCCIN<222> SKX_EXT_B_BGA1-IC,TBD    I50 @BASEBOARD_FAB2_LIB.BASEBOARD_FAB2(SCH_1):PAGE71
  U2D1 BD61 VCCIN<223> SKX_EXT_B_BGA1-IC,TBD    I50 @BASEBOARD_FAB2_LIB.BASEBOARD_FAB2(SCH_1):PAGE71
  U2D1 BC84 VCCIN<224> SKX_EXT_B_BGA1-IC,TBD    I50 @BASEBOARD_FAB2_LIB.BASEBOARD_FAB2(SCH_1):PAGE71
  U2D1 BC62 VCCIN<225> SKX_EXT_B_BGA1-IC,TBD    I50 @BASEBOARD_FAB2_LIB.BASEBOARD_FAB2(SCH_1):PAGE71
  U2D1 BC60 VCCIN<226> SKX_EXT_B_BGA1-IC,TBD    I50 @BASEBOARD_FAB2_LIB.BASEBOARD_FAB2(SCH_1):PAGE71
  U2D1 BB85 VCCIN<227> SKX_EXT_B_BGA1-IC,TBD    I50 @BASEBOARD_FAB2_LIB.BASEBOARD_FAB2(SCH_1):PAGE71
  U2D1 BB61 VCCIN<228> SKX_EXT_B_BGA1-IC,TBD    I50 @BASEBOARD_FAB2_LIB.BASEBOARD_FAB2(SCH_1):PAGE71
  U2D1 BA60 VCCIN<229> SKX_EXT_B_BGA1-IC,TBD    I50 @BASEBOARD_FAB2_LIB.BASEBOARD_FAB2(SCH_1):PAGE71
  U2D1 AY61 VCCIN<230> SKX_EXT_B_BGA1-IC,TBD    I50 @BASEBOARD_FAB2_LIB.BASEBOARD_FAB2(SCH_1):PAGE71
  U2D1 AW60 VCCIN<231> SKX_EXT_B_BGA1-IC,TBD    I50 @BASEBOARD_FAB2_LIB.BASEBOARD_FAB2(SCH_1):PAGE71
  U2D1 AV61 VCCIN<232> SKX_EXT_B_BGA1-IC,TBD    I50 @BASEBOARD_FAB2_LIB.BASEBOARD_FAB2(SCH_1):PAGE71
  U2D1 AV59 VCCIN<233> SKX_EXT_B_BGA1-IC,TBD    I50 @BASEBOARD_FAB2_LIB.BASEBOARD_FAB2(SCH_1):PAGE71
  U2D1 AU60 VCCIN<234> SKX_EXT_B_BGA1-IC,TBD    I50 @BASEBOARD_FAB2_LIB.BASEBOARD_FAB2(SCH_1):PAGE71
  U2D1 AU58 VCCIN<235> SKX_EXT_B_BGA1-IC,TBD    I50 @BASEBOARD_FAB2_LIB.BASEBOARD_FAB2(SCH_1):PAGE71
  U2D1 AT59 VCCIN<236> SKX_EXT_B_BGA1-IC,TBD    I50 @BASEBOARD_FAB2_LIB.BASEBOARD_FAB2(SCH_1):PAGE71
  U2D1 AT57 VCCIN<237> SKX_EXT_B_BGA1-IC,TBD    I50 @BASEBOARD_FAB2_LIB.BASEBOARD_FAB2(SCH_1):PAGE71
  U2D1 AR58 VCCIN<238> SKX_EXT_B_BGA1-IC,TBD    I50 @BASEBOARD_FAB2_LIB.BASEBOARD_FAB2(SCH_1):PAGE71
  U2D1 AR56 VCCIN<239> SKX_EXT_B_BGA1-IC,TBD    I50 @BASEBOARD_FAB2_LIB.BASEBOARD_FAB2(SCH_1):PAGE71
  U2D1 AP57 VCCIN<240> SKX_EXT_B_BGA1-IC,TBD    I50 @BASEBOARD_FAB2_LIB.BASEBOARD_FAB2(SCH_1):PAGE71
  U2D1 AP55 VCCIN<241> SKX_EXT_B_BGA1-IC,TBD    I50 @BASEBOARD_FAB2_LIB.BASEBOARD_FAB2(SCH_1):PAGE71
  U2D1 AN56 VCCIN<242> SKX_EXT_B_BGA1-IC,TBD    I50 @BASEBOARD_FAB2_LIB.BASEBOARD_FAB2(SCH_1):PAGE71
  U2D1 AN54 VCCIN<243> SKX_EXT_B_BGA1-IC,TBD    I50 @BASEBOARD_FAB2_LIB.BASEBOARD_FAB2(SCH_1):PAGE71
  U2D1 AN32 VCCIN<244> SKX_EXT_B_BGA1-IC,TBD    I50 @BASEBOARD_FAB2_LIB.BASEBOARD_FAB2(SCH_1):PAGE71
  U2D1 AM55 VCCIN<245> SKX_EXT_B_BGA1-IC,TBD    I50 @BASEBOARD_FAB2_LIB.BASEBOARD_FAB2(SCH_1):PAGE71
  U2D1 AM53 VCCIN<246> SKX_EXT_B_BGA1-IC,TBD    I50 @BASEBOARD_FAB2_LIB.BASEBOARD_FAB2(SCH_1):PAGE71
  U2D1 AM33 VCCIN<247> SKX_EXT_B_BGA1-IC,TBD    I50 @BASEBOARD_FAB2_LIB.BASEBOARD_FAB2(SCH_1):PAGE71
  U2D1 AL54 VCCIN<248> SKX_EXT_B_BGA1-IC,TBD    I50 @BASEBOARD_FAB2_LIB.BASEBOARD_FAB2(SCH_1):PAGE71
  U2D1 AL52 VCCIN<249> SKX_EXT_B_BGA1-IC,TBD    I50 @BASEBOARD_FAB2_LIB.BASEBOARD_FAB2(SCH_1):PAGE71
  U2D1 AL50 VCCIN<250> SKX_EXT_B_BGA1-IC,TBD    I50 @BASEBOARD_FAB2_LIB.BASEBOARD_FAB2(SCH_1):PAGE71
  U2D1 AL48 VCCIN<251> SKX_EXT_B_BGA1-IC,TBD    I50 @BASEBOARD_FAB2_LIB.BASEBOARD_FAB2(SCH_1):PAGE71
  U2D1 AL46 VCCIN<252> SKX_EXT_B_BGA1-IC,TBD    I50 @BASEBOARD_FAB2_LIB.BASEBOARD_FAB2(SCH_1):PAGE71
  U2D1 AL34 VCCIN<253> SKX_EXT_B_BGA1-IC,TBD    I50 @BASEBOARD_FAB2_LIB.BASEBOARD_FAB2(SCH_1):PAGE71
  U2D1 AK53 VCCIN<254> SKX_EXT_B_BGA1-IC,TBD    I50 @BASEBOARD_FAB2_LIB.BASEBOARD_FAB2(SCH_1):PAGE71
  U2D1 AK51 VCCIN<255> SKX_EXT_B_BGA1-IC,TBD    I50 @BASEBOARD_FAB2_LIB.BASEBOARD_FAB2(SCH_1):PAGE71
  U2D1 AK49 VCCIN<256> SKX_EXT_B_BGA1-IC,TBD    I50 @BASEBOARD_FAB2_LIB.BASEBOARD_FAB2(SCH_1):PAGE71
  U2D1 AK47 VCCIN<257> SKX_EXT_B_BGA1-IC,TBD    I50 @BASEBOARD_FAB2_LIB.BASEBOARD_FAB2(SCH_1):PAGE71
  U2D1 AK45 VCCIN<258> SKX_EXT_B_BGA1-IC,TBD    I50 @BASEBOARD_FAB2_LIB.BASEBOARD_FAB2(SCH_1):PAGE71
  U2D1 AK35 VCCIN<259> SKX_EXT_B_BGA1-IC,TBD    I50 @BASEBOARD_FAB2_LIB.BASEBOARD_FAB2(SCH_1):PAGE71
  U2D1 AJ36 VCCIN<260> SKX_EXT_B_BGA1-IC,TBD    I50 @BASEBOARD_FAB2_LIB.BASEBOARD_FAB2(SCH_1):PAGE71
  U2D1 AH41 VCCIN<261> SKX_EXT_B_BGA1-IC,TBD    I50 @BASEBOARD_FAB2_LIB.BASEBOARD_FAB2(SCH_1):PAGE71
  U2D1 AH39 VCCIN<262> SKX_EXT_B_BGA1-IC,TBD    I50 @BASEBOARD_FAB2_LIB.BASEBOARD_FAB2(SCH_1):PAGE71
  U2D1 AH37 VCCIN<263> SKX_EXT_B_BGA1-IC,TBD    I50 @BASEBOARD_FAB2_LIB.BASEBOARD_FAB2(SCH_1):PAGE71
  U2D1 AG42 VCCIN<264> SKX_EXT_B_BGA1-IC,TBD    I50 @BASEBOARD_FAB2_LIB.BASEBOARD_FAB2(SCH_1):PAGE71
  U2D1 AG40 VCCIN<265> SKX_EXT_B_BGA1-IC,TBD    I50 @BASEBOARD_FAB2_LIB.BASEBOARD_FAB2(SCH_1):PAGE71
  U2D1 AG38 VCCIN<266> SKX_EXT_B_BGA1-IC,TBD    I50 @BASEBOARD_FAB2_LIB.BASEBOARD_FAB2(SCH_1):PAGE71
  U2D1 AF43 VCCIN<267> SKX_EXT_B_BGA1-IC,TBD    I50 @BASEBOARD_FAB2_LIB.BASEBOARD_FAB2(SCH_1):PAGE71
  U2D1 CY49 VCCIN<0> SKX_EXT_B_BGA1-IC,TBD    I51 @BASEBOARD_FAB2_LIB.BASEBOARD_FAB2(SCH_1):PAGE71
  U2D1 CY47 VCCIN<1> SKX_EXT_B_BGA1-IC,TBD    I51 @BASEBOARD_FAB2_LIB.BASEBOARD_FAB2(SCH_1):PAGE71
  U2D1 CW50 VCCIN<2> SKX_EXT_B_BGA1-IC,TBD    I51 @BASEBOARD_FAB2_LIB.BASEBOARD_FAB2(SCH_1):PAGE71
  U2D1 CW48 VCCIN<3> SKX_EXT_B_BGA1-IC,TBD    I51 @BASEBOARD_FAB2_LIB.BASEBOARD_FAB2(SCH_1):PAGE71
  U2D1 CW46 VCCIN<4> SKX_EXT_B_BGA1-IC,TBD    I51 @BASEBOARD_FAB2_LIB.BASEBOARD_FAB2(SCH_1):PAGE71
  U2D1 CV51 VCCIN<5> SKX_EXT_B_BGA1-IC,TBD    I51 @BASEBOARD_FAB2_LIB.BASEBOARD_FAB2(SCH_1):PAGE71
  U2D1 CU54 VCCIN<6> SKX_EXT_B_BGA1-IC,TBD    I51 @BASEBOARD_FAB2_LIB.BASEBOARD_FAB2(SCH_1):PAGE71
  U2D1 CU52 VCCIN<7> SKX_EXT_B_BGA1-IC,TBD    I51 @BASEBOARD_FAB2_LIB.BASEBOARD_FAB2(SCH_1):PAGE71
  U2D1 CU42 VCCIN<8> SKX_EXT_B_BGA1-IC,TBD    I51 @BASEBOARD_FAB2_LIB.BASEBOARD_FAB2(SCH_1):PAGE71
  U2D1 CU40 VCCIN<9> SKX_EXT_B_BGA1-IC,TBD    I51 @BASEBOARD_FAB2_LIB.BASEBOARD_FAB2(SCH_1):PAGE71
  U2D1 CU38 VCCIN<10> SKX_EXT_B_BGA1-IC,TBD    I51 @BASEBOARD_FAB2_LIB.BASEBOARD_FAB2(SCH_1):PAGE71
  U2D1 CT55 VCCIN<11> SKX_EXT_B_BGA1-IC,TBD    I51 @BASEBOARD_FAB2_LIB.BASEBOARD_FAB2(SCH_1):PAGE71
  U2D1 CT53 VCCIN<12> SKX_EXT_B_BGA1-IC,TBD    I51 @BASEBOARD_FAB2_LIB.BASEBOARD_FAB2(SCH_1):PAGE71
  U2D1 CT41 VCCIN<13> SKX_EXT_B_BGA1-IC,TBD    I51 @BASEBOARD_FAB2_LIB.BASEBOARD_FAB2(SCH_1):PAGE71
  U2D1 CT39 VCCIN<14> SKX_EXT_B_BGA1-IC,TBD    I51 @BASEBOARD_FAB2_LIB.BASEBOARD_FAB2(SCH_1):PAGE71
  U2D1 CT37 VCCIN<15> SKX_EXT_B_BGA1-IC,TBD    I51 @BASEBOARD_FAB2_LIB.BASEBOARD_FAB2(SCH_1):PAGE71
  U2D1 CR56 VCCIN<16> SKX_EXT_B_BGA1-IC,TBD    I51 @BASEBOARD_FAB2_LIB.BASEBOARD_FAB2(SCH_1):PAGE71
  U2D1 CR54 VCCIN<17> SKX_EXT_B_BGA1-IC,TBD    I51 @BASEBOARD_FAB2_LIB.BASEBOARD_FAB2(SCH_1):PAGE71
  U2D1 CR34 VCCIN<18> SKX_EXT_B_BGA1-IC,TBD    I51 @BASEBOARD_FAB2_LIB.BASEBOARD_FAB2(SCH_1):PAGE71
  U2D1 CP57 VCCIN<19> SKX_EXT_B_BGA1-IC,TBD    I51 @BASEBOARD_FAB2_LIB.BASEBOARD_FAB2(SCH_1):PAGE71
  U2D1 CP55 VCCIN<20> SKX_EXT_B_BGA1-IC,TBD    I51 @BASEBOARD_FAB2_LIB.BASEBOARD_FAB2(SCH_1):PAGE71
  U2D1 CP33 VCCIN<21> SKX_EXT_B_BGA1-IC,TBD    I51 @BASEBOARD_FAB2_LIB.BASEBOARD_FAB2(SCH_1):PAGE71
  U2D1 CN58 VCCIN<22> SKX_EXT_B_BGA1-IC,TBD    I51 @BASEBOARD_FAB2_LIB.BASEBOARD_FAB2(SCH_1):PAGE71
  U2D1 CN56 VCCIN<23> SKX_EXT_B_BGA1-IC,TBD    I51 @BASEBOARD_FAB2_LIB.BASEBOARD_FAB2(SCH_1):PAGE71
  U2D1 CM59 VCCIN<24> SKX_EXT_B_BGA1-IC,TBD    I51 @BASEBOARD_FAB2_LIB.BASEBOARD_FAB2(SCH_1):PAGE71
  U2D1 CM57 VCCIN<25> SKX_EXT_B_BGA1-IC,TBD    I51 @BASEBOARD_FAB2_LIB.BASEBOARD_FAB2(SCH_1):PAGE71
  U2D1 CL60 VCCIN<26> SKX_EXT_B_BGA1-IC,TBD    I51 @BASEBOARD_FAB2_LIB.BASEBOARD_FAB2(SCH_1):PAGE71
  U2D1 CL58 VCCIN<27> SKX_EXT_B_BGA1-IC,TBD    I51 @BASEBOARD_FAB2_LIB.BASEBOARD_FAB2(SCH_1):PAGE71
  U2D1 CK61 VCCIN<28> SKX_EXT_B_BGA1-IC,TBD    I51 @BASEBOARD_FAB2_LIB.BASEBOARD_FAB2(SCH_1):PAGE71
  U2D1 CK59 VCCIN<29> SKX_EXT_B_BGA1-IC,TBD    I51 @BASEBOARD_FAB2_LIB.BASEBOARD_FAB2(SCH_1):PAGE71
  U2D1 CJ60 VCCIN<30> SKX_EXT_B_BGA1-IC,TBD    I51 @BASEBOARD_FAB2_LIB.BASEBOARD_FAB2(SCH_1):PAGE71
  U2D1 CH85 VCCIN<31> SKX_EXT_B_BGA1-IC,TBD    I51 @BASEBOARD_FAB2_LIB.BASEBOARD_FAB2(SCH_1):PAGE71
  U2D1 CH61 VCCIN<32> SKX_EXT_B_BGA1-IC,TBD    I51 @BASEBOARD_FAB2_LIB.BASEBOARD_FAB2(SCH_1):PAGE71
  U2D1 CG84 VCCIN<33> SKX_EXT_B_BGA1-IC,TBD    I51 @BASEBOARD_FAB2_LIB.BASEBOARD_FAB2(SCH_1):PAGE71
  U2D1 CG60 VCCIN<34> SKX_EXT_B_BGA1-IC,TBD    I51 @BASEBOARD_FAB2_LIB.BASEBOARD_FAB2(SCH_1):PAGE71
  U2D1 CF85 VCCIN<35> SKX_EXT_B_BGA1-IC,TBD    I51 @BASEBOARD_FAB2_LIB.BASEBOARD_FAB2(SCH_1):PAGE71
  U2D1 CF61 VCCIN<36> SKX_EXT_B_BGA1-IC,TBD    I51 @BASEBOARD_FAB2_LIB.BASEBOARD_FAB2(SCH_1):PAGE71
  U2D1 CE84 VCCIN<37> SKX_EXT_B_BGA1-IC,TBD    I51 @BASEBOARD_FAB2_LIB.BASEBOARD_FAB2(SCH_1):PAGE71
  U2D1 CE60 VCCIN<38> SKX_EXT_B_BGA1-IC,TBD    I51 @BASEBOARD_FAB2_LIB.BASEBOARD_FAB2(SCH_1):PAGE71
  U2D1 CD85 VCCIN<39> SKX_EXT_B_BGA1-IC,TBD    I51 @BASEBOARD_FAB2_LIB.BASEBOARD_FAB2(SCH_1):PAGE71
  U2D1 CD83 VCCIN<40> SKX_EXT_B_BGA1-IC,TBD    I51 @BASEBOARD_FAB2_LIB.BASEBOARD_FAB2(SCH_1):PAGE71
  U2D1 CD61 VCCIN<41> SKX_EXT_B_BGA1-IC,TBD    I51 @BASEBOARD_FAB2_LIB.BASEBOARD_FAB2(SCH_1):PAGE71
  U2D1 CC84 VCCIN<42> SKX_EXT_B_BGA1-IC,TBD    I51 @BASEBOARD_FAB2_LIB.BASEBOARD_FAB2(SCH_1):PAGE71
  U2D1 CC62 VCCIN<43> SKX_EXT_B_BGA1-IC,TBD    I51 @BASEBOARD_FAB2_LIB.BASEBOARD_FAB2(SCH_1):PAGE71
  U2D1 CC60 VCCIN<44> SKX_EXT_B_BGA1-IC,TBD    I51 @BASEBOARD_FAB2_LIB.BASEBOARD_FAB2(SCH_1):PAGE71
  U2D1 CB83 VCCIN<45> SKX_EXT_B_BGA1-IC,TBD    I51 @BASEBOARD_FAB2_LIB.BASEBOARD_FAB2(SCH_1):PAGE71
  U2D1 CB81 VCCIN<46> SKX_EXT_B_BGA1-IC,TBD    I51 @BASEBOARD_FAB2_LIB.BASEBOARD_FAB2(SCH_1):PAGE71
  U2D1 CB79 VCCIN<47> SKX_EXT_B_BGA1-IC,TBD    I51 @BASEBOARD_FAB2_LIB.BASEBOARD_FAB2(SCH_1):PAGE71
  U2D1 CB77 VCCIN<48> SKX_EXT_B_BGA1-IC,TBD    I51 @BASEBOARD_FAB2_LIB.BASEBOARD_FAB2(SCH_1):PAGE71
  U2D1 CB75 VCCIN<49> SKX_EXT_B_BGA1-IC,TBD    I51 @BASEBOARD_FAB2_LIB.BASEBOARD_FAB2(SCH_1):PAGE71
  U2D1 CB73 VCCIN<50> SKX_EXT_B_BGA1-IC,TBD    I51 @BASEBOARD_FAB2_LIB.BASEBOARD_FAB2(SCH_1):PAGE71
  U2D1 CB61 VCCIN<51> SKX_EXT_B_BGA1-IC,TBD    I51 @BASEBOARD_FAB2_LIB.BASEBOARD_FAB2(SCH_1):PAGE71
  U2D1 CA84 VCCIN<52> SKX_EXT_B_BGA1-IC,TBD    I51 @BASEBOARD_FAB2_LIB.BASEBOARD_FAB2(SCH_1):PAGE71
  U2D1 CA82 VCCIN<53> SKX_EXT_B_BGA1-IC,TBD    I51 @BASEBOARD_FAB2_LIB.BASEBOARD_FAB2(SCH_1):PAGE71
  U2D1 CA80 VCCIN<54> SKX_EXT_B_BGA1-IC,TBD    I51 @BASEBOARD_FAB2_LIB.BASEBOARD_FAB2(SCH_1):PAGE71
  U2D1 CA78 VCCIN<55> SKX_EXT_B_BGA1-IC,TBD    I51 @BASEBOARD_FAB2_LIB.BASEBOARD_FAB2(SCH_1):PAGE71
  U2D1 CA76 VCCIN<56> SKX_EXT_B_BGA1-IC,TBD    I51 @BASEBOARD_FAB2_LIB.BASEBOARD_FAB2(SCH_1):PAGE71
  U2D1 CA74 VCCIN<57> SKX_EXT_B_BGA1-IC,TBD    I51 @BASEBOARD_FAB2_LIB.BASEBOARD_FAB2(SCH_1):PAGE71
  U2D1 CA72 VCCIN<58> SKX_EXT_B_BGA1-IC,TBD    I51 @BASEBOARD_FAB2_LIB.BASEBOARD_FAB2(SCH_1):PAGE71
  U2D1 CA62 VCCIN<59> SKX_EXT_B_BGA1-IC,TBD    I51 @BASEBOARD_FAB2_LIB.BASEBOARD_FAB2(SCH_1):PAGE71
  U2D1 CA60 VCCIN<60> SKX_EXT_B_BGA1-IC,TBD    I51 @BASEBOARD_FAB2_LIB.BASEBOARD_FAB2(SCH_1):PAGE71
  U2D1 BY83 VCCIN<61> SKX_EXT_B_BGA1-IC,TBD    I51 @BASEBOARD_FAB2_LIB.BASEBOARD_FAB2(SCH_1):PAGE71
  U2D1 BY81 VCCIN<62> SKX_EXT_B_BGA1-IC,TBD    I51 @BASEBOARD_FAB2_LIB.BASEBOARD_FAB2(SCH_1):PAGE71
  U2D1 BY79 VCCIN<63> SKX_EXT_B_BGA1-IC,TBD    I51 @BASEBOARD_FAB2_LIB.BASEBOARD_FAB2(SCH_1):PAGE71
  U2D1 BY77 VCCIN<64> SKX_EXT_B_BGA1-IC,TBD    I51 @BASEBOARD_FAB2_LIB.BASEBOARD_FAB2(SCH_1):PAGE71
  U2D1 BY75 VCCIN<65> SKX_EXT_B_BGA1-IC,TBD    I51 @BASEBOARD_FAB2_LIB.BASEBOARD_FAB2(SCH_1):PAGE71
  U2D1 BY73 VCCIN<66> SKX_EXT_B_BGA1-IC,TBD    I51 @BASEBOARD_FAB2_LIB.BASEBOARD_FAB2(SCH_1):PAGE71
  U2D1 BY61 VCCIN<67> SKX_EXT_B_BGA1-IC,TBD    I51 @BASEBOARD_FAB2_LIB.BASEBOARD_FAB2(SCH_1):PAGE71
  U2D1 BW84 VCCIN<68> SKX_EXT_B_BGA1-IC,TBD    I51 @BASEBOARD_FAB2_LIB.BASEBOARD_FAB2(SCH_1):PAGE71
  U2D1 BW70 VCCIN<69> SKX_EXT_B_BGA1-IC,TBD    I51 @BASEBOARD_FAB2_LIB.BASEBOARD_FAB2(SCH_1):PAGE71
  U2D1 BW68 VCCIN<70> SKX_EXT_B_BGA1-IC,TBD    I51 @BASEBOARD_FAB2_LIB.BASEBOARD_FAB2(SCH_1):PAGE71
  U2D1 BW66 VCCIN<71> SKX_EXT_B_BGA1-IC,TBD    I51 @BASEBOARD_FAB2_LIB.BASEBOARD_FAB2(SCH_1):PAGE71
  U2D1 BW64 VCCIN<72> SKX_EXT_B_BGA1-IC,TBD    I51 @BASEBOARD_FAB2_LIB.BASEBOARD_FAB2(SCH_1):PAGE71
  U2D1 BW62 VCCIN<73> SKX_EXT_B_BGA1-IC,TBD    I51 @BASEBOARD_FAB2_LIB.BASEBOARD_FAB2(SCH_1):PAGE71
  U2D1 BW60 VCCIN<74> SKX_EXT_B_BGA1-IC,TBD    I51 @BASEBOARD_FAB2_LIB.BASEBOARD_FAB2(SCH_1):PAGE71
  U2D1 BV83 VCCIN<75> SKX_EXT_B_BGA1-IC,TBD    I51 @BASEBOARD_FAB2_LIB.BASEBOARD_FAB2(SCH_1):PAGE71
  U2D1 BV81 VCCIN<76> SKX_EXT_B_BGA1-IC,TBD    I51 @BASEBOARD_FAB2_LIB.BASEBOARD_FAB2(SCH_1):PAGE71
  U2D1 BV79 VCCIN<77> SKX_EXT_B_BGA1-IC,TBD    I51 @BASEBOARD_FAB2_LIB.BASEBOARD_FAB2(SCH_1):PAGE71
  U2D1 BV77 VCCIN<78> SKX_EXT_B_BGA1-IC,TBD    I51 @BASEBOARD_FAB2_LIB.BASEBOARD_FAB2(SCH_1):PAGE71
  U2D1 BV75 VCCIN<79> SKX_EXT_B_BGA1-IC,TBD    I51 @BASEBOARD_FAB2_LIB.BASEBOARD_FAB2(SCH_1):PAGE71
  U2D1 BV73 VCCIN<80> SKX_EXT_B_BGA1-IC,TBD    I51 @BASEBOARD_FAB2_LIB.BASEBOARD_FAB2(SCH_1):PAGE71
  U2D1 BV71 VCCIN<81> SKX_EXT_B_BGA1-IC,TBD    I51 @BASEBOARD_FAB2_LIB.BASEBOARD_FAB2(SCH_1):PAGE71
  U2D1 BV69 VCCIN<82> SKX_EXT_B_BGA1-IC,TBD    I51 @BASEBOARD_FAB2_LIB.BASEBOARD_FAB2(SCH_1):PAGE71
  U2D1 BV67 VCCIN<83> SKX_EXT_B_BGA1-IC,TBD    I51 @BASEBOARD_FAB2_LIB.BASEBOARD_FAB2(SCH_1):PAGE71
  U2D1 BV65 VCCIN<84> SKX_EXT_B_BGA1-IC,TBD    I51 @BASEBOARD_FAB2_LIB.BASEBOARD_FAB2(SCH_1):PAGE71
  U2D1 BV63 VCCIN<85> SKX_EXT_B_BGA1-IC,TBD    I51 @BASEBOARD_FAB2_LIB.BASEBOARD_FAB2(SCH_1):PAGE71
  U2D1 BV61 VCCIN<86> SKX_EXT_B_BGA1-IC,TBD    I51 @BASEBOARD_FAB2_LIB.BASEBOARD_FAB2(SCH_1):PAGE71
  U2D1 BU84 VCCIN<87> SKX_EXT_B_BGA1-IC,TBD    I51 @BASEBOARD_FAB2_LIB.BASEBOARD_FAB2(SCH_1):PAGE71
  U2D1 BU82 VCCIN<88> SKX_EXT_B_BGA1-IC,TBD    I51 @BASEBOARD_FAB2_LIB.BASEBOARD_FAB2(SCH_1):PAGE71
  U2D1 BU80 VCCIN<89> SKX_EXT_B_BGA1-IC,TBD    I51 @BASEBOARD_FAB2_LIB.BASEBOARD_FAB2(SCH_1):PAGE71
  U2D1 BU78 VCCIN<90> SKX_EXT_B_BGA1-IC,TBD    I51 @BASEBOARD_FAB2_LIB.BASEBOARD_FAB2(SCH_1):PAGE71
  U2D1 BU76 VCCIN<91> SKX_EXT_B_BGA1-IC,TBD    I51 @BASEBOARD_FAB2_LIB.BASEBOARD_FAB2(SCH_1):PAGE71
  U2D1 BU74 VCCIN<92> SKX_EXT_B_BGA1-IC,TBD    I51 @BASEBOARD_FAB2_LIB.BASEBOARD_FAB2(SCH_1):PAGE71
  U2D1 BU72 VCCIN<93> SKX_EXT_B_BGA1-IC,TBD    I51 @BASEBOARD_FAB2_LIB.BASEBOARD_FAB2(SCH_1):PAGE71
  U2D1 BU70 VCCIN<94> SKX_EXT_B_BGA1-IC,TBD    I51 @BASEBOARD_FAB2_LIB.BASEBOARD_FAB2(SCH_1):PAGE71
  U2D1 BU68 VCCIN<95> SKX_EXT_B_BGA1-IC,TBD    I51 @BASEBOARD_FAB2_LIB.BASEBOARD_FAB2(SCH_1):PAGE71
  U2D1 BU66 VCCIN<96> SKX_EXT_B_BGA1-IC,TBD    I51 @BASEBOARD_FAB2_LIB.BASEBOARD_FAB2(SCH_1):PAGE71
  U2D1 BU64 VCCIN<97> SKX_EXT_B_BGA1-IC,TBD    I51 @BASEBOARD_FAB2_LIB.BASEBOARD_FAB2(SCH_1):PAGE71
  U2D1 BU62 VCCIN<98> SKX_EXT_B_BGA1-IC,TBD    I51 @BASEBOARD_FAB2_LIB.BASEBOARD_FAB2(SCH_1):PAGE71
  U2D1 BU60 VCCIN<99> SKX_EXT_B_BGA1-IC,TBD    I51 @BASEBOARD_FAB2_LIB.BASEBOARD_FAB2(SCH_1):PAGE71
  U2D1 BT83 VCCIN<100> SKX_EXT_B_BGA1-IC,TBD    I51 @BASEBOARD_FAB2_LIB.BASEBOARD_FAB2(SCH_1):PAGE71
  U2D1 BT81 VCCIN<101> SKX_EXT_B_BGA1-IC,TBD    I51 @BASEBOARD_FAB2_LIB.BASEBOARD_FAB2(SCH_1):PAGE71
  U2D1 BT79 VCCIN<102> SKX_EXT_B_BGA1-IC,TBD    I51 @BASEBOARD_FAB2_LIB.BASEBOARD_FAB2(SCH_1):PAGE71
  U2D1 BT77 VCCIN<103> SKX_EXT_B_BGA1-IC,TBD    I51 @BASEBOARD_FAB2_LIB.BASEBOARD_FAB2(SCH_1):PAGE71
  U2D1 BT75 VCCIN<104> SKX_EXT_B_BGA1-IC,TBD    I51 @BASEBOARD_FAB2_LIB.BASEBOARD_FAB2(SCH_1):PAGE71
  U2D1 BT73 VCCIN<105> SKX_EXT_B_BGA1-IC,TBD    I51 @BASEBOARD_FAB2_LIB.BASEBOARD_FAB2(SCH_1):PAGE71
  U2D1 BT71 VCCIN<106> SKX_EXT_B_BGA1-IC,TBD    I51 @BASEBOARD_FAB2_LIB.BASEBOARD_FAB2(SCH_1):PAGE71
  U2D1 BT69 VCCIN<107> SKX_EXT_B_BGA1-IC,TBD    I51 @BASEBOARD_FAB2_LIB.BASEBOARD_FAB2(SCH_1):PAGE71
  U2D1 BT67 VCCIN<108> SKX_EXT_B_BGA1-IC,TBD    I51 @BASEBOARD_FAB2_LIB.BASEBOARD_FAB2(SCH_1):PAGE71
  U2D1 BT65 VCCIN<109> SKX_EXT_B_BGA1-IC,TBD    I51 @BASEBOARD_FAB2_LIB.BASEBOARD_FAB2(SCH_1):PAGE71
  U2D1 BT63 VCCIN<110> SKX_EXT_B_BGA1-IC,TBD    I51 @BASEBOARD_FAB2_LIB.BASEBOARD_FAB2(SCH_1):PAGE71
  U2D1 BT61 VCCIN<111> SKX_EXT_B_BGA1-IC,TBD    I51 @BASEBOARD_FAB2_LIB.BASEBOARD_FAB2(SCH_1):PAGE71
  U2D1 BR84 VCCIN<112> SKX_EXT_B_BGA1-IC,TBD    I51 @BASEBOARD_FAB2_LIB.BASEBOARD_FAB2(SCH_1):PAGE71
  U2D1 BR62 VCCIN<113> SKX_EXT_B_BGA1-IC,TBD    I51 @BASEBOARD_FAB2_LIB.BASEBOARD_FAB2(SCH_1):PAGE71
  U2D1 BR60 VCCIN<114> SKX_EXT_B_BGA1-IC,TBD    I51 @BASEBOARD_FAB2_LIB.BASEBOARD_FAB2(SCH_1):PAGE71
  U2D1 BP83 VCCIN<115> SKX_EXT_B_BGA1-IC,TBD    I51 @BASEBOARD_FAB2_LIB.BASEBOARD_FAB2(SCH_1):PAGE71
  U2D1 BP81 VCCIN<116> SKX_EXT_B_BGA1-IC,TBD    I51 @BASEBOARD_FAB2_LIB.BASEBOARD_FAB2(SCH_1):PAGE71
  U2D1 BP79 VCCIN<117> SKX_EXT_B_BGA1-IC,TBD    I51 @BASEBOARD_FAB2_LIB.BASEBOARD_FAB2(SCH_1):PAGE71
  U2D1 BP77 VCCIN<118> SKX_EXT_B_BGA1-IC,TBD    I51 @BASEBOARD_FAB2_LIB.BASEBOARD_FAB2(SCH_1):PAGE71
  U2D1 BP75 VCCIN<119> SKX_EXT_B_BGA1-IC,TBD    I51 @BASEBOARD_FAB2_LIB.BASEBOARD_FAB2(SCH_1):PAGE71
  U2D1 BP73 VCCIN<120> SKX_EXT_B_BGA1-IC,TBD    I51 @BASEBOARD_FAB2_LIB.BASEBOARD_FAB2(SCH_1):PAGE71
  U2D1 BP71 VCCIN<121> SKX_EXT_B_BGA1-IC,TBD    I51 @BASEBOARD_FAB2_LIB.BASEBOARD_FAB2(SCH_1):PAGE71
  U2D1 BP69 VCCIN<122> SKX_EXT_B_BGA1-IC,TBD    I51 @BASEBOARD_FAB2_LIB.BASEBOARD_FAB2(SCH_1):PAGE71
  U2D1 BP67 VCCIN<123> SKX_EXT_B_BGA1-IC,TBD    I51 @BASEBOARD_FAB2_LIB.BASEBOARD_FAB2(SCH_1):PAGE71
  U2D1 BP65 VCCIN<124> SKX_EXT_B_BGA1-IC,TBD    I51 @BASEBOARD_FAB2_LIB.BASEBOARD_FAB2(SCH_1):PAGE71
  U2D1 BP63 VCCIN<125> SKX_EXT_B_BGA1-IC,TBD    I51 @BASEBOARD_FAB2_LIB.BASEBOARD_FAB2(SCH_1):PAGE71
  U2D1 BP61 VCCIN<126> SKX_EXT_B_BGA1-IC,TBD    I51 @BASEBOARD_FAB2_LIB.BASEBOARD_FAB2(SCH_1):PAGE71
  U2D1 BN84 VCCIN<127> SKX_EXT_B_BGA1-IC,TBD    I51 @BASEBOARD_FAB2_LIB.BASEBOARD_FAB2(SCH_1):PAGE71
  U2D1 BN82 VCCIN<128> SKX_EXT_B_BGA1-IC,TBD    I51 @BASEBOARD_FAB2_LIB.BASEBOARD_FAB2(SCH_1):PAGE71
  U2D1 BN80 VCCIN<129> SKX_EXT_B_BGA1-IC,TBD    I51 @BASEBOARD_FAB2_LIB.BASEBOARD_FAB2(SCH_1):PAGE71
 C2D12    1      A CAP_A_0603V-22.0UF,4V,20%,X6S,A    I59 @BASEBOARD_FAB2_LIB.BASEBOARD_FAB2(SCH_1):PAGE76
 C2D22    1      A CAP_A_0603V-22.0UF,4V,20%,X6S,A    I61 @BASEBOARD_FAB2_LIB.BASEBOARD_FAB2(SCH_1):PAGE76
 C2D31    1      A CAP_A_0603V-22.0UF,4V,20%,X6S,A    I63 @BASEBOARD_FAB2_LIB.BASEBOARD_FAB2(SCH_1):PAGE76
 C2D21    1      A CAP_A_0603V-22.0UF,4V,20%,X6S,A    I65 @BASEBOARD_FAB2_LIB.BASEBOARD_FAB2(SCH_1):PAGE76
 C2D27    1      A CAP_A_0603V-22.0UF,4V,20%,X6S,A    I66 @BASEBOARD_FAB2_LIB.BASEBOARD_FAB2(SCH_1):PAGE76
  C3D2    1      A CAP_A_0603V-22.0UF,4V,20%,X6S,A    I69 @BASEBOARD_FAB2_LIB.BASEBOARD_FAB2(SCH_1):PAGE76
 C2D36    1      A CAP_A_0603V-22.0UF,4V,20%,X6S,A    I70 @BASEBOARD_FAB2_LIB.BASEBOARD_FAB2(SCH_1):PAGE76
 C2D13    1      A CAP_A_0603V-22.0UF,4V,20%,X6S,A    I73 @BASEBOARD_FAB2_LIB.BASEBOARD_FAB2(SCH_1):PAGE76
 C2D19    1      A CAP_A_0603V-22.0UF,4V,20%,X6S,A    I75 @BASEBOARD_FAB2_LIB.BASEBOARD_FAB2(SCH_1):PAGE76
 C2D14    1      A CAP_A_0603V-22.0UF,4V,20%,X6S,A    I76 @BASEBOARD_FAB2_LIB.BASEBOARD_FAB2(SCH_1):PAGE76
 C2D20    1      A CAP_A_0603V-22.0UF,4V,20%,X6S,A    I79 @BASEBOARD_FAB2_LIB.BASEBOARD_FAB2(SCH_1):PAGE76
 C2D24    1      A CAP_A_0603V-22.0UF,4V,20%,X6S,A    I80 @BASEBOARD_FAB2_LIB.BASEBOARD_FAB2(SCH_1):PAGE76
 C2D25    1      A CAP_A_0603V-22.0UF,4V,20%,X6S,A    I82 @BASEBOARD_FAB2_LIB.BASEBOARD_FAB2(SCH_1):PAGE76
 C2D30    1      A CAP_A_0603V-22.0UF,4V,20%,X6S,A    I83 @BASEBOARD_FAB2_LIB.BASEBOARD_FAB2(SCH_1):PAGE76
 C2D33    1      A CAP_A_0603V-22.0UF,4V,20%,X6S,A    I85 @BASEBOARD_FAB2_LIB.BASEBOARD_FAB2(SCH_1):PAGE76
  C8P4    1      A CAP_0805-47UF,4V,20%,X6S,C9533A    I88 @BASEBOARD_FAB2_LIB.BASEBOARD_FAB2(SCH_1):PAGE76
 C8P20    1      A CAP_0805-47UF,4V,20%,X6S,C9533A    I89 @BASEBOARD_FAB2_LIB.BASEBOARD_FAB2(SCH_1):PAGE76
 C2D32    1      A CAP_A_0603V-22.0UF,4V,20%,X6S,A    I90 @BASEBOARD_FAB2_LIB.BASEBOARD_FAB2(SCH_1):PAGE76
 C8P18    1      A CAP_0805-47UF,4V,20%,X6S,C9533A    I92 @BASEBOARD_FAB2_LIB.BASEBOARD_FAB2(SCH_1):PAGE76
  C7P2    1      A CAP_0805-47UF,4V,20%,X6S,C9533A   I100 @BASEBOARD_FAB2_LIB.BASEBOARD_FAB2(SCH_1):PAGE76
  C8P3    1      A CAP_0805-47UF,4V,20%,X6S,C9533A   I101 @BASEBOARD_FAB2_LIB.BASEBOARD_FAB2(SCH_1):PAGE76
 C8P19    1      A CAP_0805-47UF,4V,20%,X6S,C9533A   I103 @BASEBOARD_FAB2_LIB.BASEBOARD_FAB2(SCH_1):PAGE76
  C7P1    1      A CAP_0805-47UF,4V,20%,X6S,C9533A   I105 @BASEBOARD_FAB2_LIB.BASEBOARD_FAB2(SCH_1):PAGE76
 C8P34    1      A CAP_0805-47UF,4V,20%,X6S,C9533A   I106 @BASEBOARD_FAB2_LIB.BASEBOARD_FAB2(SCH_1):PAGE76
 C8P12    1      A CAP_0805-47UF,4V,20%,X6S,C9533A   I107 @BASEBOARD_FAB2_LIB.BASEBOARD_FAB2(SCH_1):PAGE76
 C2D26    1      A CAP_A_0603V-22.0UF,4V,20%,X6S,A   I108 @BASEBOARD_FAB2_LIB.BASEBOARD_FAB2(SCH_1):PAGE76
  C3D1    1      A CAP_A_0603V-22.0UF,4V,20%,X6S,A   I111 @BASEBOARD_FAB2_LIB.BASEBOARD_FAB2(SCH_1):PAGE76
 C2D23    1      A CAP_A_0603V-22.0UF,4V,20%,X6S,A   I112 @BASEBOARD_FAB2_LIB.BASEBOARD_FAB2(SCH_1):PAGE76
 C2D17    1      A CAP_A_0603V-22.0UF,4V,20%,X6S,A   I114 @BASEBOARD_FAB2_LIB.BASEBOARD_FAB2(SCH_1):PAGE76
  C2D1    1      A CAP_A_0603V-22.0UF,4V,20%,X6S,A   I116 @BASEBOARD_FAB2_LIB.BASEBOARD_FAB2(SCH_1):PAGE76
 C8P26    1      A CAP_0805-47UF,4V,20%,X6S,C9533A   I118 @BASEBOARD_FAB2_LIB.BASEBOARD_FAB2(SCH_1):PAGE76
 C2D37    1      A CAP_A_0603V-22.0UF,4V,20%,X6S,A   I119 @BASEBOARD_FAB2_LIB.BASEBOARD_FAB2(SCH_1):PAGE76
 C2D34    1      A CAP_A_0603V-22.0UF,4V,20%,X6S,A   I122 @BASEBOARD_FAB2_LIB.BASEBOARD_FAB2(SCH_1):PAGE76
 C2D45    1      A CAP_A_0603V-22.0UF,4V,20%,X6S,A   I123 @BASEBOARD_FAB2_LIB.BASEBOARD_FAB2(SCH_1):PAGE76
 C2D16    1      A CAP_A_0603V-22.0UF,4V,20%,X6S,A   I124 @BASEBOARD_FAB2_LIB.BASEBOARD_FAB2(SCH_1):PAGE76
 C8P29    1      A CAP_0805-47UF,4V,20%,X6S,C9533A   I125 @BASEBOARD_FAB2_LIB.BASEBOARD_FAB2(SCH_1):PAGE76
 C8P10    1      A CAP_0805-47UF,4V,20%,X6S,C9533A   I127 @BASEBOARD_FAB2_LIB.BASEBOARD_FAB2(SCH_1):PAGE76
 C8P16    1      A CAP_0805-47UF,4V,20%,X6S,C9533A   I129 @BASEBOARD_FAB2_LIB.BASEBOARD_FAB2(SCH_1):PAGE76
 C8P33    1      A CAP_0805-47UF,4V,20%,X6S,C9533A   I131 @BASEBOARD_FAB2_LIB.BASEBOARD_FAB2(SCH_1):PAGE76
 C8P13    1      A CAP_0805-47UF,4V,20%,X6S,C9533A   I132 @BASEBOARD_FAB2_LIB.BASEBOARD_FAB2(SCH_1):PAGE76
 C8P17    1      A CAP_0805-47UF,4V,20%,X6S,C9533A   I133 @BASEBOARD_FAB2_LIB.BASEBOARD_FAB2(SCH_1):PAGE76
 C8P21    1      A CAP_0805-47UF,4V,20%,X6S,C9533A   I135 @BASEBOARD_FAB2_LIB.BASEBOARD_FAB2(SCH_1):PAGE76
 C8P25    1      A CAP_0805-47UF,4V,20%,X6S,C9533A   I136 @BASEBOARD_FAB2_LIB.BASEBOARD_FAB2(SCH_1):PAGE76
 C8P28    1      A CAP_0805-47UF,4V,20%,X6S,C9533A   I137 @BASEBOARD_FAB2_LIB.BASEBOARD_FAB2(SCH_1):PAGE76
 C8P11    1      A CAP_0805-47UF,4V,20%,X6S,C9533A   I139 @BASEBOARD_FAB2_LIB.BASEBOARD_FAB2(SCH_1):PAGE76
 C8P27    1      A CAP_0805-47UF,4V,20%,X6S,C9533A   I141 @BASEBOARD_FAB2_LIB.BASEBOARD_FAB2(SCH_1):PAGE76
 C2D15    1      A CAP_A_0603V-22.0UF,4V,20%,X6S,A   I159 @BASEBOARD_FAB2_LIB.BASEBOARD_FAB2(SCH_1):PAGE76
 C2D38    1      A CAP_A_0603V-22.0UF,4V,20%,X6S,A   I160 @BASEBOARD_FAB2_LIB.BASEBOARD_FAB2(SCH_1):PAGE76
 C2D35    1      A CAP_A_0603V-22.0UF,4V,20%,X6S,A   I161 @BASEBOARD_FAB2_LIB.BASEBOARD_FAB2(SCH_1):PAGE76
  C2D2    1      A CAP_A_0603V-22.0UF,4V,20%,X6S,A   I201 @BASEBOARD_FAB2_LIB.BASEBOARD_FAB2(SCH_1):PAGE76
  C2D3    1      A CAP_A_0603V-22.0UF,4V,20%,X6S,A   I202 @BASEBOARD_FAB2_LIB.BASEBOARD_FAB2(SCH_1):PAGE76
 C2D47    1      A CAP_A_0603V-22.0UF,4V,20%,X6S,A   I203 @BASEBOARD_FAB2_LIB.BASEBOARD_FAB2(SCH_1):PAGE76
 C2D46    1      A CAP_A_0603V-22.0UF,4V,20%,X6S,A   I204 @BASEBOARD_FAB2_LIB.BASEBOARD_FAB2(SCH_1):PAGE76
 C3D25    1      A CAP_A_0603V-22.0UF,4V,20%,X6S,A   I205 @BASEBOARD_FAB2_LIB.BASEBOARD_FAB2(SCH_1):PAGE76
 C7P19    1      A CAP_0805-47UF,4V,20%,X6S,C9533A   I215 @BASEBOARD_FAB2_LIB.BASEBOARD_FAB2(SCH_1):PAGE76
 C8P32    1      A CAP_0805-47UF,4V,20%,X6S,C9533A   I216 @BASEBOARD_FAB2_LIB.BASEBOARD_FAB2(SCH_1):PAGE76
 C8P24    1      A CAP_0805-47UF,4V,20%,X6S,C9533A   I217 @BASEBOARD_FAB2_LIB.BASEBOARD_FAB2(SCH_1):PAGE76
 C7P20    1      A CAP_0805-47UF,4V,20%,X6S,C9533A   I218 @BASEBOARD_FAB2_LIB.BASEBOARD_FAB2(SCH_1):PAGE76
  C9R8    1      A CAP_A_0603V-22.0UF,4V,20%,X6S,A     I8 @BASEBOARD_FAB2_LIB.BASEBOARD_FAB2(SCH_1):PAGE207
  L1E1    2    INB INDUCTOR_SM-0.12UH,IND,D92183-A    I10 @BASEBOARD_FAB2_LIB.BASEBOARD_FAB2(SCH_1):PAGE207
  L1D3    2    INB INDUCTOR_SM-0.12UH,IND,D92183-A    I16 @BASEBOARD_FAB2_LIB.BASEBOARD_FAB2(SCH_1):PAGE207
  C1E3    1      A CAP_A_0603V-22.0UF,4V,20%,X6S,A    I18 @BASEBOARD_FAB2_LIB.BASEBOARD_FAB2(SCH_1):PAGE207
 EU1E2    1    VOS IR354XX_SM-IR35411,IC,H73688-0A    I20 @BASEBOARD_FAB2_LIB.BASEBOARD_FAB2(SCH_1):PAGE207
 EU1D4    1    VOS IR354XX_SM-IR35411,IC,H73688-0A    I24 @BASEBOARD_FAB2_LIB.BASEBOARD_FAB2(SCH_1):PAGE207
  C1E9    1      A CAP_A_0603V-22.0UF,4V,20%,X6S,A    I58 @BASEBOARD_FAB2_LIB.BASEBOARD_FAB2(SCH_1):PAGE207
  C9P3    1      A CAP_A_0603V-22.0UF,4V,20%,X6S,A    I59 @BASEBOARD_FAB2_LIB.BASEBOARD_FAB2(SCH_1):PAGE207
  R1E3    1      A RES_0603-100.0,1%,1/10W,CHIP,GA     I7 @BASEBOARD_FAB2_LIB.BASEBOARD_FAB2(SCH_1):PAGE208
 C1D14    1      A CAP_A_0603V-22.0UF,4V,20%,X6S,A     I9 @BASEBOARD_FAB2_LIB.BASEBOARD_FAB2(SCH_1):PAGE208
  L1D2    2    INB INDUCTOR_SM-0.12UH,IND,D92183-A    I11 @BASEBOARD_FAB2_LIB.BASEBOARD_FAB2(SCH_1):PAGE208
  C9P8    1      A CAPP_3018-470UF,2.5V,20%,ALUM,A    I12 @BASEBOARD_FAB2_LIB.BASEBOARD_FAB2(SCH_1):PAGE208
  C9P5    1      A CAPP_3018-470UF,2.5V,20%,ALUM,A    I14 @BASEBOARD_FAB2_LIB.BASEBOARD_FAB2(SCH_1):PAGE208
  L1D1    2    INB INDUCTOR_SM-0.12UH,IND,D92183-A    I20 @BASEBOARD_FAB2_LIB.BASEBOARD_FAB2(SCH_1):PAGE208
  C1D3    1      A CAP_A_0603V-22.0UF,4V,20%,X6S,A    I22 @BASEBOARD_FAB2_LIB.BASEBOARD_FAB2(SCH_1):PAGE208
 C9N24    1      A CAPP_3018-470UF,2.5V,20%,ALUM,A    I24 @BASEBOARD_FAB2_LIB.BASEBOARD_FAB2(SCH_1):PAGE208
  C9R9    1      A CAPP_3018-470UF,2.5V,20%,ALUM,A    I25 @BASEBOARD_FAB2_LIB.BASEBOARD_FAB2(SCH_1):PAGE208
  C9R3    1      A CAPP_3018-470UF,2.5V,20%,ALUM,A    I26 @BASEBOARD_FAB2_LIB.BASEBOARD_FAB2(SCH_1):PAGE208
 EU1D3    1    VOS IR354XX_SM-IR35411,IC,H73688-0A    I27 @BASEBOARD_FAB2_LIB.BASEBOARD_FAB2(SCH_1):PAGE208
 C9P23    1      A CAPP_3018-470UF,2.5V,20%,ALUM,A    I28 @BASEBOARD_FAB2_LIB.BASEBOARD_FAB2(SCH_1):PAGE208
 C9P18    1      A CAPP_3018-470UF,2.5V,20%,ALUM,A    I30 @BASEBOARD_FAB2_LIB.BASEBOARD_FAB2(SCH_1):PAGE208
 C9P10    1      A CAP_A_0603V-22.0UF,4V,20%,X6S,A    I66 @BASEBOARD_FAB2_LIB.BASEBOARD_FAB2(SCH_1):PAGE208
  C9R2    1      A CAP_A_0603V-22.0UF,4V,20%,X6S,A    I67 @BASEBOARD_FAB2_LIB.BASEBOARD_FAB2(SCH_1):PAGE208
 EU1D1    1    VOS IR354XX_SM-IR35411,IC,H73688-0A    I71 @BASEBOARD_FAB2_LIB.BASEBOARD_FAB2(SCH_1):PAGE208
  R1E4    2      B RES_0402-100.0,1%,1/16W,CHIP,GA    I15 @BASEBOARD_FAB2_LIB.BASEBOARD_FAB2(SCH_1):PAGE209
  L1C2    2    INB INDUCTOR_SM-0.12UH,IND,D92183-A    I40 @BASEBOARD_FAB2_LIB.BASEBOARD_FAB2(SCH_1):PAGE209
 C1D24    1      A CAP_A_0603V-22.0UF,4V,20%,X6S,A    I42 @BASEBOARD_FAB2_LIB.BASEBOARD_FAB2(SCH_1):PAGE209
 C9P20    1      A CAP_A_0603V-22.0UF,4V,20%,X6S,A    I55 @BASEBOARD_FAB2_LIB.BASEBOARD_FAB2(SCH_1):PAGE209
 EU1C3    1    VOS IR354XX_SM-IR35411,IC,H73688-0A    I56 @BASEBOARD_FAB2_LIB.BASEBOARD_FAB2(SCH_1):PAGE209

PVCCIN_PVSA_CPU0_IINSEN @BASEBOARD_FAB2_LIB.BASEBOARD_FAB2(SCH_1):PVCCIN_PVSA_CPU0_IINSEN
 EU4D4   46 IINSEN PXE1610B_QFN-IC,H79206-001   I155 @BASEBOARD_FAB2_LIB.BASEBOARD_FAB2(SCH_1):PAGE201
  U4C1    6    OUT ADM4073_SM-EMPTY,G12194-001    I53 @BASEBOARD_FAB2_LIB.BASEBOARD_FAB2(SCH_1):PAGE204

PVCCIN_PVSA_CPU1_IINSEN @BASEBOARD_FAB2_LIB.BASEBOARD_FAB2(SCH_1):PVCCIN_PVSA_CPU1_IINSEN
 EU1C2   46 IINSEN PXE1610B_QFN-IC,H79206-001   I130 @BASEBOARD_FAB2_LIB.BASEBOARD_FAB2(SCH_1):PAGE206
  U1B3    6    OUT ADM4073_SM-EMPTY,G12194-001    I52 @BASEBOARD_FAB2_LIB.BASEBOARD_FAB2(SCH_1):PAGE209

PVCCIOMCP_CPU0 @BASEBOARD_FAB2_LIB.BASEBOARD_FAB2(SCH_1):PVCCIOMCP_CPU0
  U5D1 BV15 CD_VCCP<0> SKX_EXT_B_BGA1-IC,TBD    I34 @BASEBOARD_FAB2_LIB.BASEBOARD_FAB2(SCH_1):PAGE38
  U5D1 BV13 CD_VCCP<1> SKX_EXT_B_BGA1-IC,TBD    I34 @BASEBOARD_FAB2_LIB.BASEBOARD_FAB2(SCH_1):PAGE38
  U5D1 BV11 CD_VCCP<2> SKX_EXT_B_BGA1-IC,TBD    I34 @BASEBOARD_FAB2_LIB.BASEBOARD_FAB2(SCH_1):PAGE38
  U5D1 BU14 CD_VCCP<3> SKX_EXT_B_BGA1-IC,TBD    I34 @BASEBOARD_FAB2_LIB.BASEBOARD_FAB2(SCH_1):PAGE38
  U5D1 BU12 CD_VCCP<4> SKX_EXT_B_BGA1-IC,TBD    I34 @BASEBOARD_FAB2_LIB.BASEBOARD_FAB2(SCH_1):PAGE38
  U5D1 BT15 CD_VCCP<5> SKX_EXT_B_BGA1-IC,TBD    I34 @BASEBOARD_FAB2_LIB.BASEBOARD_FAB2(SCH_1):PAGE38
  U5D1 BT13 CD_VCCP<6> SKX_EXT_B_BGA1-IC,TBD    I34 @BASEBOARD_FAB2_LIB.BASEBOARD_FAB2(SCH_1):PAGE38
  U5D1 BT11 CD_VCCP<7> SKX_EXT_B_BGA1-IC,TBD    I34 @BASEBOARD_FAB2_LIB.BASEBOARD_FAB2(SCH_1):PAGE38
  U5D1 BR14 CD_VCCP<8> SKX_EXT_B_BGA1-IC,TBD    I34 @BASEBOARD_FAB2_LIB.BASEBOARD_FAB2(SCH_1):PAGE38
  U5D1 BR12 CD_VCCP<9> SKX_EXT_B_BGA1-IC,TBD    I34 @BASEBOARD_FAB2_LIB.BASEBOARD_FAB2(SCH_1):PAGE38
  U5D1 BP15 CD_VCCP<10> SKX_EXT_B_BGA1-IC,TBD    I34 @BASEBOARD_FAB2_LIB.BASEBOARD_FAB2(SCH_1):PAGE38
  U5D1 BP13 CD_VCCP<11> SKX_EXT_B_BGA1-IC,TBD    I34 @BASEBOARD_FAB2_LIB.BASEBOARD_FAB2(SCH_1):PAGE38
  U5D1 BP11 CD_VCCP<12> SKX_EXT_B_BGA1-IC,TBD    I34 @BASEBOARD_FAB2_LIB.BASEBOARD_FAB2(SCH_1):PAGE38
  U5D1 BN14 CD_VCCP<13> SKX_EXT_B_BGA1-IC,TBD    I34 @BASEBOARD_FAB2_LIB.BASEBOARD_FAB2(SCH_1):PAGE38
  U5D1 BN12 CD_VCCP<14> SKX_EXT_B_BGA1-IC,TBD    I34 @BASEBOARD_FAB2_LIB.BASEBOARD_FAB2(SCH_1):PAGE38
  U5D1 BM11 CD_VCCP<15> SKX_EXT_B_BGA1-IC,TBD    I34 @BASEBOARD_FAB2_LIB.BASEBOARD_FAB2(SCH_1):PAGE38
  J6B1  C17  IOC17 SCONN120_H61426002_SM-CONN,H61A    I56 @BASEBOARD_FAB2_LIB.BASEBOARD_FAB2(SCH_1):PAGE194
  J6B1  C18  IOC18 SCONN120_H61426002_SM-CONN,H61A    I56 @BASEBOARD_FAB2_LIB.BASEBOARD_FAB2(SCH_1):PAGE194
  J6B1  C19  IOC19 SCONN120_H61426002_SM-CONN,H61A    I56 @BASEBOARD_FAB2_LIB.BASEBOARD_FAB2(SCH_1):PAGE194
  J6B1  D15  IOD15 SCONN120_H61426002_SM-CONN,H61A    I56 @BASEBOARD_FAB2_LIB.BASEBOARD_FAB2(SCH_1):PAGE194
  J6B1  D16  IOD16 SCONN120_H61426002_SM-CONN,H61A    I56 @BASEBOARD_FAB2_LIB.BASEBOARD_FAB2(SCH_1):PAGE194
  J6B1  D17  IOD17 SCONN120_H61426002_SM-CONN,H61A    I56 @BASEBOARD_FAB2_LIB.BASEBOARD_FAB2(SCH_1):PAGE194
  J6B1  D18  IOD18 SCONN120_H61426002_SM-CONN,H61A    I56 @BASEBOARD_FAB2_LIB.BASEBOARD_FAB2(SCH_1):PAGE194
  J6B1  D19  IOD19 SCONN120_H61426002_SM-CONN,H61A    I56 @BASEBOARD_FAB2_LIB.BASEBOARD_FAB2(SCH_1):PAGE194
  J6B1  E15  IOE15 SCONN120_H61426002_SM-CONN,H61A    I56 @BASEBOARD_FAB2_LIB.BASEBOARD_FAB2(SCH_1):PAGE194
  J6B1  E16  IOE16 SCONN120_H61426002_SM-CONN,H61A    I56 @BASEBOARD_FAB2_LIB.BASEBOARD_FAB2(SCH_1):PAGE194
  J6B1  E17  IOE17 SCONN120_H61426002_SM-CONN,H61A    I56 @BASEBOARD_FAB2_LIB.BASEBOARD_FAB2(SCH_1):PAGE194
  J6B1  E18  IOE18 SCONN120_H61426002_SM-CONN,H61A    I56 @BASEBOARD_FAB2_LIB.BASEBOARD_FAB2(SCH_1):PAGE194
  J6B1  E19  IOE19 SCONN120_H61426002_SM-CONN,H61A    I56 @BASEBOARD_FAB2_LIB.BASEBOARD_FAB2(SCH_1):PAGE194
  J6B1  F15  IOF15 SCONN120_H61426002_SM-CONN,H61A    I56 @BASEBOARD_FAB2_LIB.BASEBOARD_FAB2(SCH_1):PAGE194
  J6B1  F16  IOF16 SCONN120_H61426002_SM-CONN,H61A    I56 @BASEBOARD_FAB2_LIB.BASEBOARD_FAB2(SCH_1):PAGE194
  J6B1  F17  IOF17 SCONN120_H61426002_SM-CONN,H61A    I56 @BASEBOARD_FAB2_LIB.BASEBOARD_FAB2(SCH_1):PAGE194
  J6B1  F18  IOF18 SCONN120_H61426002_SM-CONN,H61A    I56 @BASEBOARD_FAB2_LIB.BASEBOARD_FAB2(SCH_1):PAGE194
  J6B1  F19  IOF19 SCONN120_H61426002_SM-CONN,H61A    I56 @BASEBOARD_FAB2_LIB.BASEBOARD_FAB2(SCH_1):PAGE194
 C3N40    1      A CAP_A_0402V-1.0UF,6.3V,10%,X6SA    I86 @BASEBOARD_FAB2_LIB.BASEBOARD_FAB2(SCH_1):PAGE194
 C3M46    1      A CAP_A_0402V-1.0UF,6.3V,10%,X6SA    I99 @BASEBOARD_FAB2_LIB.BASEBOARD_FAB2(SCH_1):PAGE194
 C3N14    1      A CAPP_3018-470UF,2.5V,20%,ALUM,A   I101 @BASEBOARD_FAB2_LIB.BASEBOARD_FAB2(SCH_1):PAGE194

PVCCIOMCP_CPU1 @BASEBOARD_FAB2_LIB.BASEBOARD_FAB2(SCH_1):PVCCIOMCP_CPU1
  U2D1 BV15 CD_VCCP<0> SKX_EXT_B_BGA1-IC,TBD    I33 @BASEBOARD_FAB2_LIB.BASEBOARD_FAB2(SCH_1):PAGE72
  U2D1 BV13 CD_VCCP<1> SKX_EXT_B_BGA1-IC,TBD    I33 @BASEBOARD_FAB2_LIB.BASEBOARD_FAB2(SCH_1):PAGE72
  U2D1 BV11 CD_VCCP<2> SKX_EXT_B_BGA1-IC,TBD    I33 @BASEBOARD_FAB2_LIB.BASEBOARD_FAB2(SCH_1):PAGE72
  U2D1 BU14 CD_VCCP<3> SKX_EXT_B_BGA1-IC,TBD    I33 @BASEBOARD_FAB2_LIB.BASEBOARD_FAB2(SCH_1):PAGE72
  U2D1 BU12 CD_VCCP<4> SKX_EXT_B_BGA1-IC,TBD    I33 @BASEBOARD_FAB2_LIB.BASEBOARD_FAB2(SCH_1):PAGE72
  U2D1 BT15 CD_VCCP<5> SKX_EXT_B_BGA1-IC,TBD    I33 @BASEBOARD_FAB2_LIB.BASEBOARD_FAB2(SCH_1):PAGE72
  U2D1 BT13 CD_VCCP<6> SKX_EXT_B_BGA1-IC,TBD    I33 @BASEBOARD_FAB2_LIB.BASEBOARD_FAB2(SCH_1):PAGE72
  U2D1 BT11 CD_VCCP<7> SKX_EXT_B_BGA1-IC,TBD    I33 @BASEBOARD_FAB2_LIB.BASEBOARD_FAB2(SCH_1):PAGE72
  U2D1 BR14 CD_VCCP<8> SKX_EXT_B_BGA1-IC,TBD    I33 @BASEBOARD_FAB2_LIB.BASEBOARD_FAB2(SCH_1):PAGE72
  U2D1 BR12 CD_VCCP<9> SKX_EXT_B_BGA1-IC,TBD    I33 @BASEBOARD_FAB2_LIB.BASEBOARD_FAB2(SCH_1):PAGE72
  U2D1 BP15 CD_VCCP<10> SKX_EXT_B_BGA1-IC,TBD    I33 @BASEBOARD_FAB2_LIB.BASEBOARD_FAB2(SCH_1):PAGE72
  U2D1 BP13 CD_VCCP<11> SKX_EXT_B_BGA1-IC,TBD    I33 @BASEBOARD_FAB2_LIB.BASEBOARD_FAB2(SCH_1):PAGE72
  U2D1 BP11 CD_VCCP<12> SKX_EXT_B_BGA1-IC,TBD    I33 @BASEBOARD_FAB2_LIB.BASEBOARD_FAB2(SCH_1):PAGE72
  U2D1 BN14 CD_VCCP<13> SKX_EXT_B_BGA1-IC,TBD    I33 @BASEBOARD_FAB2_LIB.BASEBOARD_FAB2(SCH_1):PAGE72
  U2D1 BN12 CD_VCCP<14> SKX_EXT_B_BGA1-IC,TBD    I33 @BASEBOARD_FAB2_LIB.BASEBOARD_FAB2(SCH_1):PAGE72
  U2D1 BM11 CD_VCCP<15> SKX_EXT_B_BGA1-IC,TBD    I33 @BASEBOARD_FAB2_LIB.BASEBOARD_FAB2(SCH_1):PAGE72
  C4C1    1      A CAPP_3018-470UF,2.5V,20%,ALUM,A    I29 @BASEBOARD_FAB2_LIB.BASEBOARD_FAB2(SCH_1):PAGE193
  C3C2    1      A CAP_A_0402V-1.0UF,6.3V,10%,X6SA    I31 @BASEBOARD_FAB2_LIB.BASEBOARD_FAB2(SCH_1):PAGE193
  C3C1    1      A CAP_A_0402V-1.0UF,6.3V,10%,X6SA    I38 @BASEBOARD_FAB2_LIB.BASEBOARD_FAB2(SCH_1):PAGE193
  J4B2  C17  IOC17 SCONN120_H61426002_SM-CONN,H61A    I46 @BASEBOARD_FAB2_LIB.BASEBOARD_FAB2(SCH_1):PAGE193
  J4B2  C18  IOC18 SCONN120_H61426002_SM-CONN,H61A    I46 @BASEBOARD_FAB2_LIB.BASEBOARD_FAB2(SCH_1):PAGE193
  J4B2  C19  IOC19 SCONN120_H61426002_SM-CONN,H61A    I46 @BASEBOARD_FAB2_LIB.BASEBOARD_FAB2(SCH_1):PAGE193
  J4B2  D15  IOD15 SCONN120_H61426002_SM-CONN,H61A    I46 @BASEBOARD_FAB2_LIB.BASEBOARD_FAB2(SCH_1):PAGE193
  J4B2  D16  IOD16 SCONN120_H61426002_SM-CONN,H61A    I46 @BASEBOARD_FAB2_LIB.BASEBOARD_FAB2(SCH_1):PAGE193
  J4B2  D17  IOD17 SCONN120_H61426002_SM-CONN,H61A    I46 @BASEBOARD_FAB2_LIB.BASEBOARD_FAB2(SCH_1):PAGE193
  J4B2  D18  IOD18 SCONN120_H61426002_SM-CONN,H61A    I46 @BASEBOARD_FAB2_LIB.BASEBOARD_FAB2(SCH_1):PAGE193
  J4B2  D19  IOD19 SCONN120_H61426002_SM-CONN,H61A    I46 @BASEBOARD_FAB2_LIB.BASEBOARD_FAB2(SCH_1):PAGE193
  J4B2  E15  IOE15 SCONN120_H61426002_SM-CONN,H61A    I46 @BASEBOARD_FAB2_LIB.BASEBOARD_FAB2(SCH_1):PAGE193
  J4B2  E16  IOE16 SCONN120_H61426002_SM-CONN,H61A    I46 @BASEBOARD_FAB2_LIB.BASEBOARD_FAB2(SCH_1):PAGE193
  J4B2  E17  IOE17 SCONN120_H61426002_SM-CONN,H61A    I46 @BASEBOARD_FAB2_LIB.BASEBOARD_FAB2(SCH_1):PAGE193
  J4B2  E18  IOE18 SCONN120_H61426002_SM-CONN,H61A    I46 @BASEBOARD_FAB2_LIB.BASEBOARD_FAB2(SCH_1):PAGE193
  J4B2  E19  IOE19 SCONN120_H61426002_SM-CONN,H61A    I46 @BASEBOARD_FAB2_LIB.BASEBOARD_FAB2(SCH_1):PAGE193
  J4B2  F15  IOF15 SCONN120_H61426002_SM-CONN,H61A    I46 @BASEBOARD_FAB2_LIB.BASEBOARD_FAB2(SCH_1):PAGE193
  J4B2  F16  IOF16 SCONN120_H61426002_SM-CONN,H61A    I46 @BASEBOARD_FAB2_LIB.BASEBOARD_FAB2(SCH_1):PAGE193
  J4B2  F17  IOF17 SCONN120_H61426002_SM-CONN,H61A    I46 @BASEBOARD_FAB2_LIB.BASEBOARD_FAB2(SCH_1):PAGE193
  J4B2  F18  IOF18 SCONN120_H61426002_SM-CONN,H61A    I46 @BASEBOARD_FAB2_LIB.BASEBOARD_FAB2(SCH_1):PAGE193
  J4B2  F19  IOF19 SCONN120_H61426002_SM-CONN,H61A    I46 @BASEBOARD_FAB2_LIB.BASEBOARD_FAB2(SCH_1):PAGE193

PVCCIO_CPU0 @BASEBOARD_FAB2_LIB.BASEBOARD_FAB2(SCH_1):PVCCIO_CPU0
  R6B2    1      A RES_0402-100.0,1%,1/16W,CHIP,GA   I159 @BASEBOARD_FAB2_LIB.BASEBOARD_FAB2(SCH_1):PAGE21
  R6B1    1      A RES_0402-49.9,1%,1/16W,CHIP,G2A   I161 @BASEBOARD_FAB2_LIB.BASEBOARD_FAB2(SCH_1):PAGE21
  R6N2    2      B RES_0402-100.0,1%,1/16W,CHIP,GA   I163 @BASEBOARD_FAB2_LIB.BASEBOARD_FAB2(SCH_1):PAGE21
  R6N1    2      B RES_0402-49.9,1%,1/16W,CHIP,G2A   I164 @BASEBOARD_FAB2_LIB.BASEBOARD_FAB2(SCH_1):PAGE21
  R5D6    1      A RES_0402-10.0,1%,1/16W,EMPTY,GA   I312 @BASEBOARD_FAB2_LIB.BASEBOARD_FAB2(SCH_1):PAGE37
  U5D1 CM15 VCCIO<20> SKX_EXT_B_BGA1-IC,TBD    I34 @BASEBOARD_FAB2_LIB.BASEBOARD_FAB2(SCH_1):PAGE38
  U5D1 CL12 VCCIO<21> SKX_EXT_B_BGA1-IC,TBD    I34 @BASEBOARD_FAB2_LIB.BASEBOARD_FAB2(SCH_1):PAGE38
  U5D1  CK5 VCCIO<22> SKX_EXT_B_BGA1-IC,TBD    I34 @BASEBOARD_FAB2_LIB.BASEBOARD_FAB2(SCH_1):PAGE38
  U5D1  CV7 VCCIO<23> SKX_EXT_B_BGA1-IC,TBD    I34 @BASEBOARD_FAB2_LIB.BASEBOARD_FAB2(SCH_1):PAGE38
  U5D1  CH9 VCCIO<24> SKX_EXT_B_BGA1-IC,TBD    I34 @BASEBOARD_FAB2_LIB.BASEBOARD_FAB2(SCH_1):PAGE38
  U5D1   D7 VCCIO<25> SKX_EXT_B_BGA1-IC,TBD    I34 @BASEBOARD_FAB2_LIB.BASEBOARD_FAB2(SCH_1):PAGE38
  U5D1 CE18 VCCIO<26> SKX_EXT_B_BGA1-IC,TBD    I34 @BASEBOARD_FAB2_LIB.BASEBOARD_FAB2(SCH_1):PAGE38
  U5D1  CD9 VCCIO<27> SKX_EXT_B_BGA1-IC,TBD    I34 @BASEBOARD_FAB2_LIB.BASEBOARD_FAB2(SCH_1):PAGE38
  U5D1 CB17 VCCIO<28> SKX_EXT_B_BGA1-IC,TBD    I34 @BASEBOARD_FAB2_LIB.BASEBOARD_FAB2(SCH_1):PAGE38
  U5D1 CB13 VCCIO<29> SKX_EXT_B_BGA1-IC,TBD    I34 @BASEBOARD_FAB2_LIB.BASEBOARD_FAB2(SCH_1):PAGE38
  U5D1 BP25 VCCIO<30> SKX_EXT_B_BGA1-IC,TBD    I34 @BASEBOARD_FAB2_LIB.BASEBOARD_FAB2(SCH_1):PAGE38
  U5D1 BJ24 VCCIO<31> SKX_EXT_B_BGA1-IC,TBD    I34 @BASEBOARD_FAB2_LIB.BASEBOARD_FAB2(SCH_1):PAGE38
  U5D1 BF23 VCCIO<32> SKX_EXT_B_BGA1-IC,TBD    I34 @BASEBOARD_FAB2_LIB.BASEBOARD_FAB2(SCH_1):PAGE38
  U5D1 DA14 VCCIO<33> SKX_EXT_B_BGA1-IC,TBD    I34 @BASEBOARD_FAB2_LIB.BASEBOARD_FAB2(SCH_1):PAGE38
  U5D1  BB5 VCCIO<34> SKX_EXT_B_BGA1-IC,TBD    I34 @BASEBOARD_FAB2_LIB.BASEBOARD_FAB2(SCH_1):PAGE38
  U5D1 BA24 VCCIO<35> SKX_EXT_B_BGA1-IC,TBD    I34 @BASEBOARD_FAB2_LIB.BASEBOARD_FAB2(SCH_1):PAGE38
  U5D1 AY11 VCCIO<36> SKX_EXT_B_BGA1-IC,TBD    I34 @BASEBOARD_FAB2_LIB.BASEBOARD_FAB2(SCH_1):PAGE38
  U5D1  AW6 VCCIO<37> SKX_EXT_B_BGA1-IC,TBD    I34 @BASEBOARD_FAB2_LIB.BASEBOARD_FAB2(SCH_1):PAGE38
  U5D1 AT11 VCCIO<38> SKX_EXT_B_BGA1-IC,TBD    I34 @BASEBOARD_FAB2_LIB.BASEBOARD_FAB2(SCH_1):PAGE38
  U5D1  DD7 VCCIO<39> SKX_EXT_B_BGA1-IC,TBD    I34 @BASEBOARD_FAB2_LIB.BASEBOARD_FAB2(SCH_1):PAGE38
  U5D1 AN10 VCCIO<40> SKX_EXT_B_BGA1-IC,TBD    I34 @BASEBOARD_FAB2_LIB.BASEBOARD_FAB2(SCH_1):PAGE38
  U5D1 DF13 VCCIO<41> SKX_EXT_B_BGA1-IC,TBD    I34 @BASEBOARD_FAB2_LIB.BASEBOARD_FAB2(SCH_1):PAGE38
  U5D1  AH9 VCCIO<42> SKX_EXT_B_BGA1-IC,TBD    I34 @BASEBOARD_FAB2_LIB.BASEBOARD_FAB2(SCH_1):PAGE38
  U5D1  AC4 VCCIO<43> SKX_EXT_B_BGA1-IC,TBD    I34 @BASEBOARD_FAB2_LIB.BASEBOARD_FAB2(SCH_1):PAGE38
  U5D1 AC20 VCCIO<44> SKX_EXT_B_BGA1-IC,TBD    I34 @BASEBOARD_FAB2_LIB.BASEBOARD_FAB2(SCH_1):PAGE38
  U5D1 AA10 VCCIO<45> SKX_EXT_B_BGA1-IC,TBD    I34 @BASEBOARD_FAB2_LIB.BASEBOARD_FAB2(SCH_1):PAGE38
  U5D1   W6 VCCIO<46> SKX_EXT_B_BGA1-IC,TBD    I34 @BASEBOARD_FAB2_LIB.BASEBOARD_FAB2(SCH_1):PAGE38
  U5D1   W4 VCCIO<47> SKX_EXT_B_BGA1-IC,TBD    I34 @BASEBOARD_FAB2_LIB.BASEBOARD_FAB2(SCH_1):PAGE38
  U5D1 DF21 VCCIO<48> SKX_EXT_B_BGA1-IC,TBD    I34 @BASEBOARD_FAB2_LIB.BASEBOARD_FAB2(SCH_1):PAGE38
  U5D1  U14 VCCIO<49> SKX_EXT_B_BGA1-IC,TBD    I34 @BASEBOARD_FAB2_LIB.BASEBOARD_FAB2(SCH_1):PAGE38
  U5D1   T3 VCCIO<50> SKX_EXT_B_BGA1-IC,TBD    I34 @BASEBOARD_FAB2_LIB.BASEBOARD_FAB2(SCH_1):PAGE38
  U5D1   P5 VCCIO<51> SKX_EXT_B_BGA1-IC,TBD    I34 @BASEBOARD_FAB2_LIB.BASEBOARD_FAB2(SCH_1):PAGE38
  U5D1  M21 VCCIO<52> SKX_EXT_B_BGA1-IC,TBD    I34 @BASEBOARD_FAB2_LIB.BASEBOARD_FAB2(SCH_1):PAGE38
  U5D1  M11 VCCIO<53> SKX_EXT_B_BGA1-IC,TBD    I34 @BASEBOARD_FAB2_LIB.BASEBOARD_FAB2(SCH_1):PAGE38
  U5D1  DG8 VCCIO<54> SKX_EXT_B_BGA1-IC,TBD    I34 @BASEBOARD_FAB2_LIB.BASEBOARD_FAB2(SCH_1):PAGE38
  U5D1  DH7 VCCIO<55> SKX_EXT_B_BGA1-IC,TBD    I34 @BASEBOARD_FAB2_LIB.BASEBOARD_FAB2(SCH_1):PAGE38
  U5D1  L16 VCCIO<56> SKX_EXT_B_BGA1-IC,TBD    I34 @BASEBOARD_FAB2_LIB.BASEBOARD_FAB2(SCH_1):PAGE38
  U5D1  L14 VCCIO<57> SKX_EXT_B_BGA1-IC,TBD    I34 @BASEBOARD_FAB2_LIB.BASEBOARD_FAB2(SCH_1):PAGE38
  U5D1  J10 VCCIO<58> SKX_EXT_B_BGA1-IC,TBD    I34 @BASEBOARD_FAB2_LIB.BASEBOARD_FAB2(SCH_1):PAGE38
  U5D1  H13 VCCIO<59> SKX_EXT_B_BGA1-IC,TBD    I34 @BASEBOARD_FAB2_LIB.BASEBOARD_FAB2(SCH_1):PAGE38
  U5D1 DJ16 VCCIO<60> SKX_EXT_B_BGA1-IC,TBD    I34 @BASEBOARD_FAB2_LIB.BASEBOARD_FAB2(SCH_1):PAGE38
  U5D1 DM17 VCCIO<61> SKX_EXT_B_BGA1-IC,TBD    I34 @BASEBOARD_FAB2_LIB.BASEBOARD_FAB2(SCH_1):PAGE38
  U5D1  DN8 VCCIO<62> SKX_EXT_B_BGA1-IC,TBD    I34 @BASEBOARD_FAB2_LIB.BASEBOARD_FAB2(SCH_1):PAGE38
  U5D1 DP19 VCCIO<63> SKX_EXT_B_BGA1-IC,TBD    I34 @BASEBOARD_FAB2_LIB.BASEBOARD_FAB2(SCH_1):PAGE38
  U5D1 DR10 VCCIO<64> SKX_EXT_B_BGA1-IC,TBD    I34 @BASEBOARD_FAB2_LIB.BASEBOARD_FAB2(SCH_1):PAGE38
  U5D1  DR2 VCCIO<65> SKX_EXT_B_BGA1-IC,TBD    I34 @BASEBOARD_FAB2_LIB.BASEBOARD_FAB2(SCH_1):PAGE38
  U5D1 DU20 VCCIO<66> SKX_EXT_B_BGA1-IC,TBD    I34 @BASEBOARD_FAB2_LIB.BASEBOARD_FAB2(SCH_1):PAGE38
  U5D1 EA12 VCCIO<67> SKX_EXT_B_BGA1-IC,TBD    I34 @BASEBOARD_FAB2_LIB.BASEBOARD_FAB2(SCH_1):PAGE38
  U5D1 EB15 VCCIO<68> SKX_EXT_B_BGA1-IC,TBD    I34 @BASEBOARD_FAB2_LIB.BASEBOARD_FAB2(SCH_1):PAGE38
  U5D1   J2 VCCIO<69> SKX_EXT_B_BGA1-IC,TBD    I34 @BASEBOARD_FAB2_LIB.BASEBOARD_FAB2(SCH_1):PAGE38
  U5D1  K15 VCCIO<70> SKX_EXT_B_BGA1-IC,TBD    I34 @BASEBOARD_FAB2_LIB.BASEBOARD_FAB2(SCH_1):PAGE38
  U5D1   M7 VCCIO<71> SKX_EXT_B_BGA1-IC,TBD    I34 @BASEBOARD_FAB2_LIB.BASEBOARD_FAB2(SCH_1):PAGE38
  U5D1   M9 VCCIO<72> SKX_EXT_B_BGA1-IC,TBD    I34 @BASEBOARD_FAB2_LIB.BASEBOARD_FAB2(SCH_1):PAGE38
  U5D1  N18 VCCIO<73> SKX_EXT_B_BGA1-IC,TBD    I34 @BASEBOARD_FAB2_LIB.BASEBOARD_FAB2(SCH_1):PAGE38
  U5D1  W10 VCCIO<74> SKX_EXT_B_BGA1-IC,TBD    I34 @BASEBOARD_FAB2_LIB.BASEBOARD_FAB2(SCH_1):PAGE38
  U5D1 BC26 VCCIO<75> SKX_EXT_B_BGA1-IC,TBD    I34 @BASEBOARD_FAB2_LIB.BASEBOARD_FAB2(SCH_1):PAGE38
  U5D1 BB27 VCCIO<76> SKX_EXT_B_BGA1-IC,TBD    I34 @BASEBOARD_FAB2_LIB.BASEBOARD_FAB2(SCH_1):PAGE38
  U5D1 BA26 VCCIO<77> SKX_EXT_B_BGA1-IC,TBD    I34 @BASEBOARD_FAB2_LIB.BASEBOARD_FAB2(SCH_1):PAGE38
  U5D1 AY27 VCCIO<78> SKX_EXT_B_BGA1-IC,TBD    I34 @BASEBOARD_FAB2_LIB.BASEBOARD_FAB2(SCH_1):PAGE38
  U5D1 AW26 VCCIO<79> SKX_EXT_B_BGA1-IC,TBD    I34 @BASEBOARD_FAB2_LIB.BASEBOARD_FAB2(SCH_1):PAGE38
  U5D1 AV27 VCCIO<80> SKX_EXT_B_BGA1-IC,TBD    I34 @BASEBOARD_FAB2_LIB.BASEBOARD_FAB2(SCH_1):PAGE38
  U5D1 CF27 VCCIO<81> SKX_EXT_B_BGA1-IC,TBD    I34 @BASEBOARD_FAB2_LIB.BASEBOARD_FAB2(SCH_1):PAGE38
  U5D1 CD27 VCCIO<82> SKX_EXT_B_BGA1-IC,TBD    I34 @BASEBOARD_FAB2_LIB.BASEBOARD_FAB2(SCH_1):PAGE38
  U5D1 CC26 VCCIO<83> SKX_EXT_B_BGA1-IC,TBD    I34 @BASEBOARD_FAB2_LIB.BASEBOARD_FAB2(SCH_1):PAGE38
  U5D1 CJ28 VCCIO<84> SKX_EXT_B_BGA1-IC,TBD    I34 @BASEBOARD_FAB2_LIB.BASEBOARD_FAB2(SCH_1):PAGE38
  U5D1 CH27 VCCIO<85> SKX_EXT_B_BGA1-IC,TBD    I34 @BASEBOARD_FAB2_LIB.BASEBOARD_FAB2(SCH_1):PAGE38
  U5D1 BM27 VCCIO<86> SKX_EXT_B_BGA1-IC,TBD    I34 @BASEBOARD_FAB2_LIB.BASEBOARD_FAB2(SCH_1):PAGE38
  U5D1 BL26 VCCIO<87> SKX_EXT_B_BGA1-IC,TBD    I34 @BASEBOARD_FAB2_LIB.BASEBOARD_FAB2(SCH_1):PAGE38
  U5D1 BK27 VCCIO<88> SKX_EXT_B_BGA1-IC,TBD    I34 @BASEBOARD_FAB2_LIB.BASEBOARD_FAB2(SCH_1):PAGE38
  U5D1 BK25 VCCIO<89> SKX_EXT_B_BGA1-IC,TBD    I34 @BASEBOARD_FAB2_LIB.BASEBOARD_FAB2(SCH_1):PAGE38
  U5D1 BJ26 VCCIO<90> SKX_EXT_B_BGA1-IC,TBD    I34 @BASEBOARD_FAB2_LIB.BASEBOARD_FAB2(SCH_1):PAGE38
  U5D1 BH27 VCCIO<91> SKX_EXT_B_BGA1-IC,TBD    I34 @BASEBOARD_FAB2_LIB.BASEBOARD_FAB2(SCH_1):PAGE38
  U5D1 BH25 VCCIO<92> SKX_EXT_B_BGA1-IC,TBD    I34 @BASEBOARD_FAB2_LIB.BASEBOARD_FAB2(SCH_1):PAGE38
  U5D1 BG26 VCCIO<93> SKX_EXT_B_BGA1-IC,TBD    I34 @BASEBOARD_FAB2_LIB.BASEBOARD_FAB2(SCH_1):PAGE38
  U5D1 BF27 VCCIO<94> SKX_EXT_B_BGA1-IC,TBD    I34 @BASEBOARD_FAB2_LIB.BASEBOARD_FAB2(SCH_1):PAGE38
  U5D1 AE36 VCCIO<95> SKX_EXT_B_BGA1-IC,TBD    I34 @BASEBOARD_FAB2_LIB.BASEBOARD_FAB2(SCH_1):PAGE38
  U5D1 AD37 VCCIO<96> SKX_EXT_B_BGA1-IC,TBD    I34 @BASEBOARD_FAB2_LIB.BASEBOARD_FAB2(SCH_1):PAGE38
  U5D1 AC36 VCCIO<97> SKX_EXT_B_BGA1-IC,TBD    I34 @BASEBOARD_FAB2_LIB.BASEBOARD_FAB2(SCH_1):PAGE38
  U5D1 AF35 VCCIO<98> SKX_EXT_B_BGA1-IC,TBD    I34 @BASEBOARD_FAB2_LIB.BASEBOARD_FAB2(SCH_1):PAGE38
  U5D1 AD35 VCCIO<99> SKX_EXT_B_BGA1-IC,TBD    I34 @BASEBOARD_FAB2_LIB.BASEBOARD_FAB2(SCH_1):PAGE38
  U5D1 AE34 VCCIO<100> SKX_EXT_B_BGA1-IC,TBD    I34 @BASEBOARD_FAB2_LIB.BASEBOARD_FAB2(SCH_1):PAGE38
  U5D1 AG34 VCCIO<101> SKX_EXT_B_BGA1-IC,TBD    I34 @BASEBOARD_FAB2_LIB.BASEBOARD_FAB2(SCH_1):PAGE38
  U5D1 AM29 VCCIO<102> SKX_EXT_B_BGA1-IC,TBD    I34 @BASEBOARD_FAB2_LIB.BASEBOARD_FAB2(SCH_1):PAGE38
  U5D1 AL28 VCCIO<103> SKX_EXT_B_BGA1-IC,TBD    I34 @BASEBOARD_FAB2_LIB.BASEBOARD_FAB2(SCH_1):PAGE38
  U5D1 AR28 VCCIO<104> SKX_EXT_B_BGA1-IC,TBD    I34 @BASEBOARD_FAB2_LIB.BASEBOARD_FAB2(SCH_1):PAGE38
  U5D1 EE10 VCCIO<0> SKX_EXT_B_BGA1-IC,TBD   I127 @BASEBOARD_FAB2_LIB.BASEBOARD_FAB2(SCH_1):PAGE39
  U5D1 AE10 VCCIO<1> SKX_EXT_B_BGA1-IC,TBD   I127 @BASEBOARD_FAB2_LIB.BASEBOARD_FAB2(SCH_1):PAGE39
  U5D1  AF5 VCCIO<2> SKX_EXT_B_BGA1-IC,TBD   I127 @BASEBOARD_FAB2_LIB.BASEBOARD_FAB2(SCH_1):PAGE39
  U5D1 DV11 VCCIO<3> SKX_EXT_B_BGA1-IC,TBD   I127 @BASEBOARD_FAB2_LIB.BASEBOARD_FAB2(SCH_1):PAGE39
  U5D1  AM5 VCCIO<4> SKX_EXT_B_BGA1-IC,TBD   I127 @BASEBOARD_FAB2_LIB.BASEBOARD_FAB2(SCH_1):PAGE39
  U5D1  AT5 VCCIO<5> SKX_EXT_B_BGA1-IC,TBD   I127 @BASEBOARD_FAB2_LIB.BASEBOARD_FAB2(SCH_1):PAGE39
  U5D1  AT7 VCCIO<6> SKX_EXT_B_BGA1-IC,TBD   I127 @BASEBOARD_FAB2_LIB.BASEBOARD_FAB2(SCH_1):PAGE39
  U5D1 BE24 VCCIO<7> SKX_EXT_B_BGA1-IC,TBD   I127 @BASEBOARD_FAB2_LIB.BASEBOARD_FAB2(SCH_1):PAGE39
  U5D1 DK21 VCCIO<8> SKX_EXT_B_BGA1-IC,TBD   I127 @BASEBOARD_FAB2_LIB.BASEBOARD_FAB2(SCH_1):PAGE39
  U5D1  CF5 VCCIO<9> SKX_EXT_B_BGA1-IC,TBD   I127 @BASEBOARD_FAB2_LIB.BASEBOARD_FAB2(SCH_1):PAGE39
  U5D1 CG14 VCCIO<10> SKX_EXT_B_BGA1-IC,TBD   I127 @BASEBOARD_FAB2_LIB.BASEBOARD_FAB2(SCH_1):PAGE39
  U5D1 CL20 VCCIO<11> SKX_EXT_B_BGA1-IC,TBD   I127 @BASEBOARD_FAB2_LIB.BASEBOARD_FAB2(SCH_1):PAGE39
  U5D1 CP13 VCCIO<12> SKX_EXT_B_BGA1-IC,TBD   I127 @BASEBOARD_FAB2_LIB.BASEBOARD_FAB2(SCH_1):PAGE39
  U5D1 DE14 VCCIO<13> SKX_EXT_B_BGA1-IC,TBD   I127 @BASEBOARD_FAB2_LIB.BASEBOARD_FAB2(SCH_1):PAGE39
  U5D1 DC18 VCCIO<14> SKX_EXT_B_BGA1-IC,TBD   I127 @BASEBOARD_FAB2_LIB.BASEBOARD_FAB2(SCH_1):PAGE39
  U5D1 CY17 VCCIO<15> SKX_EXT_B_BGA1-IC,TBD   I127 @BASEBOARD_FAB2_LIB.BASEBOARD_FAB2(SCH_1):PAGE39
  U5D1 CU18 VCCIO<16> SKX_EXT_B_BGA1-IC,TBD   I127 @BASEBOARD_FAB2_LIB.BASEBOARD_FAB2(SCH_1):PAGE39
  U5D1 CV21 VCCIO<17> SKX_EXT_B_BGA1-IC,TBD   I127 @BASEBOARD_FAB2_LIB.BASEBOARD_FAB2(SCH_1):PAGE39
  U5D1 CU12 VCCIO<18> SKX_EXT_B_BGA1-IC,TBD   I127 @BASEBOARD_FAB2_LIB.BASEBOARD_FAB2(SCH_1):PAGE39
  U5D1  CN6 VCCIO<19> SKX_EXT_B_BGA1-IC,TBD   I127 @BASEBOARD_FAB2_LIB.BASEBOARD_FAB2(SCH_1):PAGE39
  C4P1    1      A CAP_0805-47UF,4V,20%,X6S,C9533A    I10 @BASEBOARD_FAB2_LIB.BASEBOARD_FAB2(SCH_1):PAGE42
  C4P9    1      A CAP_0805-47UF,4V,20%,X6S,C9533A    I12 @BASEBOARD_FAB2_LIB.BASEBOARD_FAB2(SCH_1):PAGE42
 C4P10    1      A CAP_0805-47UF,4V,20%,X6S,C9533A    I17 @BASEBOARD_FAB2_LIB.BASEBOARD_FAB2(SCH_1):PAGE42
  C6D7    1      A CAP_A_0603V-22.0UF,4V,20%,X6S,A    I72 @BASEBOARD_FAB2_LIB.BASEBOARD_FAB2(SCH_1):PAGE42
  C6D4    1      A CAP_A_0603V-22.0UF,4V,20%,X6S,A    I74 @BASEBOARD_FAB2_LIB.BASEBOARD_FAB2(SCH_1):PAGE42
  C6D3    1      A CAP_A_0603V-22.0UF,4V,20%,X6S,A    I80 @BASEBOARD_FAB2_LIB.BASEBOARD_FAB2(SCH_1):PAGE42
  C6D6    1      A CAP_A_0603V-22.0UF,4V,20%,X6S,A    I81 @BASEBOARD_FAB2_LIB.BASEBOARD_FAB2(SCH_1):PAGE42
  C6D9    1      A CAP_A_0603V-22.0UF,4V,20%,X6S,A   I145 @BASEBOARD_FAB2_LIB.BASEBOARD_FAB2(SCH_1):PAGE42
 C6D10    1      A CAP_A_0603V-22.0UF,4V,20%,X6S,A   I147 @BASEBOARD_FAB2_LIB.BASEBOARD_FAB2(SCH_1):PAGE42
  C4P6    1      A CAP_A_0603V-22.0UF,4V,20%,X6S,A   I164 @BASEBOARD_FAB2_LIB.BASEBOARD_FAB2(SCH_1):PAGE42
  C4P8    1      A CAP_A_0603V-22.0UF,4V,20%,X6S,A   I178 @BASEBOARD_FAB2_LIB.BASEBOARD_FAB2(SCH_1):PAGE42
  R5D3    1      A RES_0402-240,1.0%,1/16W,CHIP,GA    I29 @BASEBOARD_FAB2_LIB.BASEBOARD_FAB2(SCH_1):PAGE90
  R6D7    1      A RES_0402-240,1.0%,1/16W,EMPTY,A    I31 @BASEBOARD_FAB2_LIB.BASEBOARD_FAB2(SCH_1):PAGE90
  R5D4    1      A RES_0402-240,1.0%,1/16W,EMPTY,A    I32 @BASEBOARD_FAB2_LIB.BASEBOARD_FAB2(SCH_1):PAGE90
 R6D13    1      A RES_0402-240,1.0%,1/16W,EMPTY,A    I33 @BASEBOARD_FAB2_LIB.BASEBOARD_FAB2(SCH_1):PAGE90
 R6D15    1      A RES_0402-240,1.0%,1/16W,EMPTY,A    I48 @BASEBOARD_FAB2_LIB.BASEBOARD_FAB2(SCH_1):PAGE90
 R6D10    1      A RES_0402-240,1.0%,1/16W,EMPTY,A    I49 @BASEBOARD_FAB2_LIB.BASEBOARD_FAB2(SCH_1):PAGE90
 R6D14    1      A RES_0402-240,1.0%,1/16W,EMPTY,A    I52 @BASEBOARD_FAB2_LIB.BASEBOARD_FAB2(SCH_1):PAGE90
 R4P14    1      A RES_0402-240,1.0%,1/16W,CHIP,GA    I53 @BASEBOARD_FAB2_LIB.BASEBOARD_FAB2(SCH_1):PAGE90
  R7E2    1      A RES_0402-75,1.0%,1/16W,CHIP,G2A    I19 @BASEBOARD_FAB2_LIB.BASEBOARD_FAB2(SCH_1):PAGE92
 R3P45    1      A RES_0402-49.9,1%,1/16W,CHIP,G2A    I39 @BASEBOARD_FAB2_LIB.BASEBOARD_FAB2(SCH_1):PAGE92
 R7D33    1      A RES_0402-49.9,1%,1/16W,CHIP,G2A    I51 @BASEBOARD_FAB2_LIB.BASEBOARD_FAB2(SCH_1):PAGE92
  R6D9    1      A RES_0402-150.0,1%,1/16W,CHIP,GA    I64 @BASEBOARD_FAB2_LIB.BASEBOARD_FAB2(SCH_1):PAGE92
 R7P27    1      A RES_0402-150.0,1%,1/16W,CHIP,GA    I65 @BASEBOARD_FAB2_LIB.BASEBOARD_FAB2(SCH_1):PAGE92
 R2T37    1      A RES_0402-200.0,1%,1/16W,CHIP,GA    I94 @BASEBOARD_FAB2_LIB.BASEBOARD_FAB2(SCH_1):PAGE92
 R7P18    1      A RES_0402-150.0,1%,1/16W,CHIP,GA   I100 @BASEBOARD_FAB2_LIB.BASEBOARD_FAB2(SCH_1):PAGE92
  R4R2    1      A RES_0402-150.0,1%,1/16W,CHIP,GA   I101 @BASEBOARD_FAB2_LIB.BASEBOARD_FAB2(SCH_1):PAGE92
 R2T19    1      A RES_0402-200.0,1%,1/16W,CHIP,GA    I63 @BASEBOARD_FAB2_LIB.BASEBOARD_FAB2(SCH_1):PAGE93
  R4R3    1      A RES_0402-150.0,1%,1/16W,CHIP,GA    I79 @BASEBOARD_FAB2_LIB.BASEBOARD_FAB2(SCH_1):PAGE93
 R2T26    1      A RES_0402-200.0,1%,1/16W,CHIP,GA    I87 @BASEBOARD_FAB2_LIB.BASEBOARD_FAB2(SCH_1):PAGE93
 R2T36    1      A RES_0402-49.9,1%,1/16W,CHIP,G2A    I97 @BASEBOARD_FAB2_LIB.BASEBOARD_FAB2(SCH_1):PAGE93
 R2T72    1      A RES_0402-150.0,1%,1/16W,CHIP,GA   I143 @BASEBOARD_FAB2_LIB.BASEBOARD_FAB2(SCH_1):PAGE93
 R6D12    1      A RES_0402-49.9,1%,1/16W,CHIP,G2A     I2 @BASEBOARD_FAB2_LIB.BASEBOARD_FAB2(SCH_1):PAGE96
  R6D8    1      A RES_0402-49.9,1%,1/16W,CHIP,G2A     I3 @BASEBOARD_FAB2_LIB.BASEBOARD_FAB2(SCH_1):PAGE96
  R4R4    1      A RES_0402-150.0,1%,1/16W,CHIP,GA    I42 @BASEBOARD_FAB2_LIB.BASEBOARD_FAB2(SCH_1):PAGE97
 R7P20    1      A RES_0402-150.0,1%,1/16W,CHIP,GA    I44 @BASEBOARD_FAB2_LIB.BASEBOARD_FAB2(SCH_1):PAGE97
 R4P21    1      A RES_0402-240,1.0%,1/16W,CHIP,GA    I72 @BASEBOARD_FAB2_LIB.BASEBOARD_FAB2(SCH_1):PAGE97
  C6F2    1      A CAP_A_0402V-0.1UF,16V,10%,X7R,A     I2 @BASEBOARD_FAB2_LIB.BASEBOARD_FAB2(SCH_1):PAGE99
  U6F1    1   VCCA PCA9617_SSOP-IC,G81764-001-GNDA    I15 @BASEBOARD_FAB2_LIB.BASEBOARD_FAB2(SCH_1):PAGE99
  R4T6    1      A RES_0402-240,1.0%,1/16W,CHIP,GA    I17 @BASEBOARD_FAB2_LIB.BASEBOARD_FAB2(SCH_1):PAGE99
  R4T5    1      A RES_0402-240,1.0%,1/16W,CHIP,GA    I19 @BASEBOARD_FAB2_LIB.BASEBOARD_FAB2(SCH_1):PAGE99
  C7E1    1      A CAP_A_0402V-0.1UF,16V,10%,X7R,A    I23 @BASEBOARD_FAB2_LIB.BASEBOARD_FAB2(SCH_1):PAGE99
  U7E1    1   VCCA PCA9617_SSOP-IC,G81764-001-GNDA    I61 @BASEBOARD_FAB2_LIB.BASEBOARD_FAB2(SCH_1):PAGE99
 R3R13    1      A RES_0402-240,1.0%,1/16W,CHIP,GA    I65 @BASEBOARD_FAB2_LIB.BASEBOARD_FAB2(SCH_1):PAGE99
 R3P60    1      A RES_0402-240,1.0%,1/16W,CHIP,GA    I67 @BASEBOARD_FAB2_LIB.BASEBOARD_FAB2(SCH_1):PAGE99
  R9A4    2      B RES_0402-475.0,1%,1/16W,CHIP,GA    I55 @BASEBOARD_FAB2_LIB.BASEBOARD_FAB2(SCH_1):PAGE111
 R1L17    2      B RES_0402-150.0,1%,1/16W,CHIP,GA    I56 @BASEBOARD_FAB2_LIB.BASEBOARD_FAB2(SCH_1):PAGE111
 R6P46    1      A RES_0402-100.0,1%,1/16W,CHIP,GA    I49 @BASEBOARD_FAB2_LIB.BASEBOARD_FAB2(SCH_1):PAGE112
 R7P30    1      A RES_0402-100.0,1%,1/16W,CHIP,GA    I50 @BASEBOARD_FAB2_LIB.BASEBOARD_FAB2(SCH_1):PAGE112
  R1M3    1      A RES_0402-100.0,1%,1/16W,CHIP,GA    I51 @BASEBOARD_FAB2_LIB.BASEBOARD_FAB2(SCH_1):PAGE112
 R4P15    1      A RES_0402-100.0,1%,1/16W,CHIP,GA    I53 @BASEBOARD_FAB2_LIB.BASEBOARD_FAB2(SCH_1):PAGE112
  R1M4    1      A RES_0402-100.0,1%,1/16W,CHIP,GA    I54 @BASEBOARD_FAB2_LIB.BASEBOARD_FAB2(SCH_1):PAGE112
 R4P12    1      A RES_0402-100.0,1%,1/16W,CHIP,GA    I57 @BASEBOARD_FAB2_LIB.BASEBOARD_FAB2(SCH_1):PAGE112
 R4P23    1      A RES_0402-150.0,1%,1/16W,CHIP,GA    I58 @BASEBOARD_FAB2_LIB.BASEBOARD_FAB2(SCH_1):PAGE112
 R4P24    1      A RES_0402-150.0,1%,1/16W,CHIP,GA    I59 @BASEBOARD_FAB2_LIB.BASEBOARD_FAB2(SCH_1):PAGE112
 R1L15    1      A RES_0402-150.0,1%,1/16W,CHIP,GA    I60 @BASEBOARD_FAB2_LIB.BASEBOARD_FAB2(SCH_1):PAGE112
  R6T9    1      A RES_0402-100.0,1%,1/16W,CHIP,GA   I120 @BASEBOARD_FAB2_LIB.BASEBOARD_FAB2(SCH_1):PAGE112
  R6T8    1      A RES_0402-100.0,1%,1/16W,CHIP,GA   I121 @BASEBOARD_FAB2_LIB.BASEBOARD_FAB2(SCH_1):PAGE112
 R1U43    1      A RES_0402-49.9,1%,1/16W,CHIP,G2A    I25 @BASEBOARD_FAB2_LIB.BASEBOARD_FAB2(SCH_1):PAGE152
 R2U40    1      A RES_0402-150.0,1%,1/16W,CHIP,GA    I53 @BASEBOARD_FAB2_LIB.BASEBOARD_FAB2(SCH_1):PAGE152
 R2U41    1      A RES_0402-150.0,1%,1/16W,CHIP,GA    I54 @BASEBOARD_FAB2_LIB.BASEBOARD_FAB2(SCH_1):PAGE152
 R4P17    2      B RES_0402-150.0,1%,1/16W,CHIP,GA    I58 @BASEBOARD_FAB2_LIB.BASEBOARD_FAB2(SCH_1):PAGE152
 R4P20    2      B RES_0402-150.0,1%,1/16W,CHIP,GA    I59 @BASEBOARD_FAB2_LIB.BASEBOARD_FAB2(SCH_1):PAGE152
 R7C22    1      A RES_0402-4.75K,1%,1/16W,EMPTY,A    I14 @BASEBOARD_FAB2_LIB.BASEBOARD_FAB2(SCH_1):PAGE166
 R7C17    1      A RES_0402-4.75K,1%,1/16W,CHIP,GA    I28 @BASEBOARD_FAB2_LIB.BASEBOARD_FAB2(SCH_1):PAGE166
  J6B1   F1   IOF1 SCONN120_H61426002_SM-CONN,H61A    I56 @BASEBOARD_FAB2_LIB.BASEBOARD_FAB2(SCH_1):PAGE194
 R4E10    1      A RES_0402-100.0,1%,1/16W,CHIP,GA    I20 @BASEBOARD_FAB2_LIB.BASEBOARD_FAB2(SCH_1):PAGE201
  R4E9    1      A RES_0402-49.9,1%,1/16W,CHIP,G2A    I52 @BASEBOARD_FAB2_LIB.BASEBOARD_FAB2(SCH_1):PAGE201
 R6P16    1      A RES_0402-1.00K,1%,1/16W,CHIP,GA   I132 @BASEBOARD_FAB2_LIB.BASEBOARD_FAB2(SCH_1):PAGE201
 R3P13    1      A RES_0402-100.0,1%,1/16W,EMPTY,A    I17 @BASEBOARD_FAB2_LIB.BASEBOARD_FAB2(SCH_1):PAGE211
 R3P17    1      A RES_0402-49.9,1%,1/16W,EMPTY,GA    I28 @BASEBOARD_FAB2_LIB.BASEBOARD_FAB2(SCH_1):PAGE211
 C3N38    1      A CAPP_3018-470UF,2.5V,20%,ALUM,A    I16 @BASEBOARD_FAB2_LIB.BASEBOARD_FAB2(SCH_1):PAGE212
 C3N26    1      A CAPP_3018-470UF,2.5V,20%,ALUM,A    I17 @BASEBOARD_FAB2_LIB.BASEBOARD_FAB2(SCH_1):PAGE212
 C3N35    1      A CAPP_3018-470UF,2.5V,20%,ALUM,A    I18 @BASEBOARD_FAB2_LIB.BASEBOARD_FAB2(SCH_1):PAGE212
  C7C6    1      A CAP_A_0603V-22.0UF,4V,20%,X6S,A    I23 @BASEBOARD_FAB2_LIB.BASEBOARD_FAB2(SCH_1):PAGE212
  L7C2    2    INB INDUCTOR_SM-150NH,IND,D92183-0A    I25 @BASEBOARD_FAB2_LIB.BASEBOARD_FAB2(SCH_1):PAGE212
 R3N21    2      B RES_0402-100.0,1%,1/16W,CHIP,GA    I74 @BASEBOARD_FAB2_LIB.BASEBOARD_FAB2(SCH_1):PAGE212
 C7C10    1      A CAP_A_0603V-22.0UF,4V,20%,X6S,A    I77 @BASEBOARD_FAB2_LIB.BASEBOARD_FAB2(SCH_1):PAGE212
  R7C3    1      A RES_0402-51.1,1.0%,1/16W,CHIP,A    I78 @BASEBOARD_FAB2_LIB.BASEBOARD_FAB2(SCH_1):PAGE212
 EU7C1    1    VOS IR354XX_SM-IR35412,IC,H73684-0A   I101 @BASEBOARD_FAB2_LIB.BASEBOARD_FAB2(SCH_1):PAGE212
  R3U2    1      A RES_0402-100.0,1%,1/16W,CHIP,GA   I295 @BASEBOARD_FAB2_LIB.BASEBOARD_FAB2(SCH_1):PAGE215
 R3T11    1      A RES_0402-49.9,1%,1/16W,EMPTY,GA   I330 @BASEBOARD_FAB2_LIB.BASEBOARD_FAB2(SCH_1):PAGE215
 R3L11    1      A RES_0402-100.0,1%,1/16W,EMPTY,A     I7 @BASEBOARD_FAB2_LIB.BASEBOARD_FAB2(SCH_1):PAGE218
 R3L13    1      A RES_0402-49.9,1%,1/16W,CHIP,G2A    I47 @BASEBOARD_FAB2_LIB.BASEBOARD_FAB2(SCH_1):PAGE218
 C1T21    1      A CAP_A_0402V-1.0UF,6.3V,10%,X6SA    I20 @BASEBOARD_FAB2_LIB.BASEBOARD_FAB2(SCH_1):PAGE148
 U25W4 AA17 PECIVDD AST2520A1-GP-GP_ASIC2-GB1-AST2A    I28 @BASEBOARD_FAB2_LIB.BASEBOARD_FAB2(SCH_1):PAGE148

PVCCIO_CPU1 @BASEBOARD_FAB2_LIB.BASEBOARD_FAB2(SCH_1):PVCCIO_CPU1
  R9N1    1      A RES_0402-49.9,1%,1/16W,CHIP,G2A     I4 @BASEBOARD_FAB2_LIB.BASEBOARD_FAB2(SCH_1):PAGE55
  R9N2    1      A RES_0402-100.0,1%,1/16W,CHIP,GA     I7 @BASEBOARD_FAB2_LIB.BASEBOARD_FAB2(SCH_1):PAGE55
  R3B2    2      B RES_0402-49.9,1%,1/16W,CHIP,G2A    I19 @BASEBOARD_FAB2_LIB.BASEBOARD_FAB2(SCH_1):PAGE55
  R3B4    2      B RES_0402-100.0,1%,1/16W,CHIP,GA    I21 @BASEBOARD_FAB2_LIB.BASEBOARD_FAB2(SCH_1):PAGE55
 R3D32    1      A RES_0402-10.0,1%,1/16W,EMPTY,GA    I53 @BASEBOARD_FAB2_LIB.BASEBOARD_FAB2(SCH_1):PAGE71
  U2D1 CM15 VCCIO<20> SKX_EXT_B_BGA1-IC,TBD    I33 @BASEBOARD_FAB2_LIB.BASEBOARD_FAB2(SCH_1):PAGE72
  U2D1 CL12 VCCIO<21> SKX_EXT_B_BGA1-IC,TBD    I33 @BASEBOARD_FAB2_LIB.BASEBOARD_FAB2(SCH_1):PAGE72
  U2D1  CK5 VCCIO<22> SKX_EXT_B_BGA1-IC,TBD    I33 @BASEBOARD_FAB2_LIB.BASEBOARD_FAB2(SCH_1):PAGE72
  U2D1  CV7 VCCIO<23> SKX_EXT_B_BGA1-IC,TBD    I33 @BASEBOARD_FAB2_LIB.BASEBOARD_FAB2(SCH_1):PAGE72
  U2D1  CH9 VCCIO<24> SKX_EXT_B_BGA1-IC,TBD    I33 @BASEBOARD_FAB2_LIB.BASEBOARD_FAB2(SCH_1):PAGE72
  U2D1   D7 VCCIO<25> SKX_EXT_B_BGA1-IC,TBD    I33 @BASEBOARD_FAB2_LIB.BASEBOARD_FAB2(SCH_1):PAGE72
  U2D1 CE18 VCCIO<26> SKX_EXT_B_BGA1-IC,TBD    I33 @BASEBOARD_FAB2_LIB.BASEBOARD_FAB2(SCH_1):PAGE72
  U2D1  CD9 VCCIO<27> SKX_EXT_B_BGA1-IC,TBD    I33 @BASEBOARD_FAB2_LIB.BASEBOARD_FAB2(SCH_1):PAGE72
  U2D1 CB17 VCCIO<28> SKX_EXT_B_BGA1-IC,TBD    I33 @BASEBOARD_FAB2_LIB.BASEBOARD_FAB2(SCH_1):PAGE72
  U2D1 CB13 VCCIO<29> SKX_EXT_B_BGA1-IC,TBD    I33 @BASEBOARD_FAB2_LIB.BASEBOARD_FAB2(SCH_1):PAGE72
  U2D1 BP25 VCCIO<30> SKX_EXT_B_BGA1-IC,TBD    I33 @BASEBOARD_FAB2_LIB.BASEBOARD_FAB2(SCH_1):PAGE72
  U2D1 BJ24 VCCIO<31> SKX_EXT_B_BGA1-IC,TBD    I33 @BASEBOARD_FAB2_LIB.BASEBOARD_FAB2(SCH_1):PAGE72
  U2D1 BF23 VCCIO<32> SKX_EXT_B_BGA1-IC,TBD    I33 @BASEBOARD_FAB2_LIB.BASEBOARD_FAB2(SCH_1):PAGE72
  U2D1 DA14 VCCIO<33> SKX_EXT_B_BGA1-IC,TBD    I33 @BASEBOARD_FAB2_LIB.BASEBOARD_FAB2(SCH_1):PAGE72
  U2D1  BB5 VCCIO<34> SKX_EXT_B_BGA1-IC,TBD    I33 @BASEBOARD_FAB2_LIB.BASEBOARD_FAB2(SCH_1):PAGE72
  U2D1 BA24 VCCIO<35> SKX_EXT_B_BGA1-IC,TBD    I33 @BASEBOARD_FAB2_LIB.BASEBOARD_FAB2(SCH_1):PAGE72
  U2D1 AY11 VCCIO<36> SKX_EXT_B_BGA1-IC,TBD    I33 @BASEBOARD_FAB2_LIB.BASEBOARD_FAB2(SCH_1):PAGE72
  U2D1  AW6 VCCIO<37> SKX_EXT_B_BGA1-IC,TBD    I33 @BASEBOARD_FAB2_LIB.BASEBOARD_FAB2(SCH_1):PAGE72
  U2D1 AT11 VCCIO<38> SKX_EXT_B_BGA1-IC,TBD    I33 @BASEBOARD_FAB2_LIB.BASEBOARD_FAB2(SCH_1):PAGE72
  U2D1  DD7 VCCIO<39> SKX_EXT_B_BGA1-IC,TBD    I33 @BASEBOARD_FAB2_LIB.BASEBOARD_FAB2(SCH_1):PAGE72
  U2D1 AN10 VCCIO<40> SKX_EXT_B_BGA1-IC,TBD    I33 @BASEBOARD_FAB2_LIB.BASEBOARD_FAB2(SCH_1):PAGE72
  U2D1 DF13 VCCIO<41> SKX_EXT_B_BGA1-IC,TBD    I33 @BASEBOARD_FAB2_LIB.BASEBOARD_FAB2(SCH_1):PAGE72
  U2D1  AH9 VCCIO<42> SKX_EXT_B_BGA1-IC,TBD    I33 @BASEBOARD_FAB2_LIB.BASEBOARD_FAB2(SCH_1):PAGE72
  U2D1  AC4 VCCIO<43> SKX_EXT_B_BGA1-IC,TBD    I33 @BASEBOARD_FAB2_LIB.BASEBOARD_FAB2(SCH_1):PAGE72
  U2D1 AC20 VCCIO<44> SKX_EXT_B_BGA1-IC,TBD    I33 @BASEBOARD_FAB2_LIB.BASEBOARD_FAB2(SCH_1):PAGE72
  U2D1 AA10 VCCIO<45> SKX_EXT_B_BGA1-IC,TBD    I33 @BASEBOARD_FAB2_LIB.BASEBOARD_FAB2(SCH_1):PAGE72
  U2D1   W6 VCCIO<46> SKX_EXT_B_BGA1-IC,TBD    I33 @BASEBOARD_FAB2_LIB.BASEBOARD_FAB2(SCH_1):PAGE72
  U2D1   W4 VCCIO<47> SKX_EXT_B_BGA1-IC,TBD    I33 @BASEBOARD_FAB2_LIB.BASEBOARD_FAB2(SCH_1):PAGE72
  U2D1 DF21 VCCIO<48> SKX_EXT_B_BGA1-IC,TBD    I33 @BASEBOARD_FAB2_LIB.BASEBOARD_FAB2(SCH_1):PAGE72
  U2D1  U14 VCCIO<49> SKX_EXT_B_BGA1-IC,TBD    I33 @BASEBOARD_FAB2_LIB.BASEBOARD_FAB2(SCH_1):PAGE72
  U2D1   T3 VCCIO<50> SKX_EXT_B_BGA1-IC,TBD    I33 @BASEBOARD_FAB2_LIB.BASEBOARD_FAB2(SCH_1):PAGE72
  U2D1   P5 VCCIO<51> SKX_EXT_B_BGA1-IC,TBD    I33 @BASEBOARD_FAB2_LIB.BASEBOARD_FAB2(SCH_1):PAGE72
  U2D1  M21 VCCIO<52> SKX_EXT_B_BGA1-IC,TBD    I33 @BASEBOARD_FAB2_LIB.BASEBOARD_FAB2(SCH_1):PAGE72
  U2D1  M11 VCCIO<53> SKX_EXT_B_BGA1-IC,TBD    I33 @BASEBOARD_FAB2_LIB.BASEBOARD_FAB2(SCH_1):PAGE72
  U2D1  DG8 VCCIO<54> SKX_EXT_B_BGA1-IC,TBD    I33 @BASEBOARD_FAB2_LIB.BASEBOARD_FAB2(SCH_1):PAGE72
  U2D1  DH7 VCCIO<55> SKX_EXT_B_BGA1-IC,TBD    I33 @BASEBOARD_FAB2_LIB.BASEBOARD_FAB2(SCH_1):PAGE72
  U2D1  L16 VCCIO<56> SKX_EXT_B_BGA1-IC,TBD    I33 @BASEBOARD_FAB2_LIB.BASEBOARD_FAB2(SCH_1):PAGE72
  U2D1  L14 VCCIO<57> SKX_EXT_B_BGA1-IC,TBD    I33 @BASEBOARD_FAB2_LIB.BASEBOARD_FAB2(SCH_1):PAGE72
  U2D1  J10 VCCIO<58> SKX_EXT_B_BGA1-IC,TBD    I33 @BASEBOARD_FAB2_LIB.BASEBOARD_FAB2(SCH_1):PAGE72
  U2D1  H13 VCCIO<59> SKX_EXT_B_BGA1-IC,TBD    I33 @BASEBOARD_FAB2_LIB.BASEBOARD_FAB2(SCH_1):PAGE72
  U2D1 DJ16 VCCIO<60> SKX_EXT_B_BGA1-IC,TBD    I33 @BASEBOARD_FAB2_LIB.BASEBOARD_FAB2(SCH_1):PAGE72
  U2D1 DM17 VCCIO<61> SKX_EXT_B_BGA1-IC,TBD    I33 @BASEBOARD_FAB2_LIB.BASEBOARD_FAB2(SCH_1):PAGE72
  U2D1  DN8 VCCIO<62> SKX_EXT_B_BGA1-IC,TBD    I33 @BASEBOARD_FAB2_LIB.BASEBOARD_FAB2(SCH_1):PAGE72
  U2D1 DP19 VCCIO<63> SKX_EXT_B_BGA1-IC,TBD    I33 @BASEBOARD_FAB2_LIB.BASEBOARD_FAB2(SCH_1):PAGE72
  U2D1 DR10 VCCIO<64> SKX_EXT_B_BGA1-IC,TBD    I33 @BASEBOARD_FAB2_LIB.BASEBOARD_FAB2(SCH_1):PAGE72
  U2D1  DR2 VCCIO<65> SKX_EXT_B_BGA1-IC,TBD    I33 @BASEBOARD_FAB2_LIB.BASEBOARD_FAB2(SCH_1):PAGE72
  U2D1 DU20 VCCIO<66> SKX_EXT_B_BGA1-IC,TBD    I33 @BASEBOARD_FAB2_LIB.BASEBOARD_FAB2(SCH_1):PAGE72
  U2D1 EA12 VCCIO<67> SKX_EXT_B_BGA1-IC,TBD    I33 @BASEBOARD_FAB2_LIB.BASEBOARD_FAB2(SCH_1):PAGE72
  U2D1 EB15 VCCIO<68> SKX_EXT_B_BGA1-IC,TBD    I33 @BASEBOARD_FAB2_LIB.BASEBOARD_FAB2(SCH_1):PAGE72
  U2D1   J2 VCCIO<69> SKX_EXT_B_BGA1-IC,TBD    I33 @BASEBOARD_FAB2_LIB.BASEBOARD_FAB2(SCH_1):PAGE72
  U2D1  K15 VCCIO<70> SKX_EXT_B_BGA1-IC,TBD    I33 @BASEBOARD_FAB2_LIB.BASEBOARD_FAB2(SCH_1):PAGE72
  U2D1   M7 VCCIO<71> SKX_EXT_B_BGA1-IC,TBD    I33 @BASEBOARD_FAB2_LIB.BASEBOARD_FAB2(SCH_1):PAGE72
  U2D1   M9 VCCIO<72> SKX_EXT_B_BGA1-IC,TBD    I33 @BASEBOARD_FAB2_LIB.BASEBOARD_FAB2(SCH_1):PAGE72
  U2D1  N18 VCCIO<73> SKX_EXT_B_BGA1-IC,TBD    I33 @BASEBOARD_FAB2_LIB.BASEBOARD_FAB2(SCH_1):PAGE72
  U2D1  W10 VCCIO<74> SKX_EXT_B_BGA1-IC,TBD    I33 @BASEBOARD_FAB2_LIB.BASEBOARD_FAB2(SCH_1):PAGE72
  U2D1 BC26 VCCIO<75> SKX_EXT_B_BGA1-IC,TBD    I33 @BASEBOARD_FAB2_LIB.BASEBOARD_FAB2(SCH_1):PAGE72
  U2D1 BB27 VCCIO<76> SKX_EXT_B_BGA1-IC,TBD    I33 @BASEBOARD_FAB2_LIB.BASEBOARD_FAB2(SCH_1):PAGE72
  U2D1 BA26 VCCIO<77> SKX_EXT_B_BGA1-IC,TBD    I33 @BASEBOARD_FAB2_LIB.BASEBOARD_FAB2(SCH_1):PAGE72
  U2D1 AY27 VCCIO<78> SKX_EXT_B_BGA1-IC,TBD    I33 @BASEBOARD_FAB2_LIB.BASEBOARD_FAB2(SCH_1):PAGE72
  U2D1 AW26 VCCIO<79> SKX_EXT_B_BGA1-IC,TBD    I33 @BASEBOARD_FAB2_LIB.BASEBOARD_FAB2(SCH_1):PAGE72
  U2D1 AV27 VCCIO<80> SKX_EXT_B_BGA1-IC,TBD    I33 @BASEBOARD_FAB2_LIB.BASEBOARD_FAB2(SCH_1):PAGE72
  U2D1 CF27 VCCIO<81> SKX_EXT_B_BGA1-IC,TBD    I33 @BASEBOARD_FAB2_LIB.BASEBOARD_FAB2(SCH_1):PAGE72
  U2D1 CD27 VCCIO<82> SKX_EXT_B_BGA1-IC,TBD    I33 @BASEBOARD_FAB2_LIB.BASEBOARD_FAB2(SCH_1):PAGE72
  U2D1 CC26 VCCIO<83> SKX_EXT_B_BGA1-IC,TBD    I33 @BASEBOARD_FAB2_LIB.BASEBOARD_FAB2(SCH_1):PAGE72
  U2D1 CJ28 VCCIO<84> SKX_EXT_B_BGA1-IC,TBD    I33 @BASEBOARD_FAB2_LIB.BASEBOARD_FAB2(SCH_1):PAGE72
  U2D1 CH27 VCCIO<85> SKX_EXT_B_BGA1-IC,TBD    I33 @BASEBOARD_FAB2_LIB.BASEBOARD_FAB2(SCH_1):PAGE72
  U2D1 BM27 VCCIO<86> SKX_EXT_B_BGA1-IC,TBD    I33 @BASEBOARD_FAB2_LIB.BASEBOARD_FAB2(SCH_1):PAGE72
  U2D1 BL26 VCCIO<87> SKX_EXT_B_BGA1-IC,TBD    I33 @BASEBOARD_FAB2_LIB.BASEBOARD_FAB2(SCH_1):PAGE72
  U2D1 BK27 VCCIO<88> SKX_EXT_B_BGA1-IC,TBD    I33 @BASEBOARD_FAB2_LIB.BASEBOARD_FAB2(SCH_1):PAGE72
  U2D1 BK25 VCCIO<89> SKX_EXT_B_BGA1-IC,TBD    I33 @BASEBOARD_FAB2_LIB.BASEBOARD_FAB2(SCH_1):PAGE72
  U2D1 BJ26 VCCIO<90> SKX_EXT_B_BGA1-IC,TBD    I33 @BASEBOARD_FAB2_LIB.BASEBOARD_FAB2(SCH_1):PAGE72
  U2D1 BH27 VCCIO<91> SKX_EXT_B_BGA1-IC,TBD    I33 @BASEBOARD_FAB2_LIB.BASEBOARD_FAB2(SCH_1):PAGE72
  U2D1 BH25 VCCIO<92> SKX_EXT_B_BGA1-IC,TBD    I33 @BASEBOARD_FAB2_LIB.BASEBOARD_FAB2(SCH_1):PAGE72
  U2D1 BG26 VCCIO<93> SKX_EXT_B_BGA1-IC,TBD    I33 @BASEBOARD_FAB2_LIB.BASEBOARD_FAB2(SCH_1):PAGE72
  U2D1 BF27 VCCIO<94> SKX_EXT_B_BGA1-IC,TBD    I33 @BASEBOARD_FAB2_LIB.BASEBOARD_FAB2(SCH_1):PAGE72
  U2D1 AE36 VCCIO<95> SKX_EXT_B_BGA1-IC,TBD    I33 @BASEBOARD_FAB2_LIB.BASEBOARD_FAB2(SCH_1):PAGE72
  U2D1 AD37 VCCIO<96> SKX_EXT_B_BGA1-IC,TBD    I33 @BASEBOARD_FAB2_LIB.BASEBOARD_FAB2(SCH_1):PAGE72
  U2D1 AC36 VCCIO<97> SKX_EXT_B_BGA1-IC,TBD    I33 @BASEBOARD_FAB2_LIB.BASEBOARD_FAB2(SCH_1):PAGE72
  U2D1 AF35 VCCIO<98> SKX_EXT_B_BGA1-IC,TBD    I33 @BASEBOARD_FAB2_LIB.BASEBOARD_FAB2(SCH_1):PAGE72
  U2D1 AD35 VCCIO<99> SKX_EXT_B_BGA1-IC,TBD    I33 @BASEBOARD_FAB2_LIB.BASEBOARD_FAB2(SCH_1):PAGE72
  U2D1 AE34 VCCIO<100> SKX_EXT_B_BGA1-IC,TBD    I33 @BASEBOARD_FAB2_LIB.BASEBOARD_FAB2(SCH_1):PAGE72
  U2D1 AG34 VCCIO<101> SKX_EXT_B_BGA1-IC,TBD    I33 @BASEBOARD_FAB2_LIB.BASEBOARD_FAB2(SCH_1):PAGE72
  U2D1 AM29 VCCIO<102> SKX_EXT_B_BGA1-IC,TBD    I33 @BASEBOARD_FAB2_LIB.BASEBOARD_FAB2(SCH_1):PAGE72
  U2D1 AL28 VCCIO<103> SKX_EXT_B_BGA1-IC,TBD    I33 @BASEBOARD_FAB2_LIB.BASEBOARD_FAB2(SCH_1):PAGE72
  U2D1 AR28 VCCIO<104> SKX_EXT_B_BGA1-IC,TBD    I33 @BASEBOARD_FAB2_LIB.BASEBOARD_FAB2(SCH_1):PAGE72
  U2D1 EE10 VCCIO<0> SKX_EXT_B_BGA1-IC,TBD   I107 @BASEBOARD_FAB2_LIB.BASEBOARD_FAB2(SCH_1):PAGE73
  U2D1 AE10 VCCIO<1> SKX_EXT_B_BGA1-IC,TBD   I107 @BASEBOARD_FAB2_LIB.BASEBOARD_FAB2(SCH_1):PAGE73
  U2D1  AF5 VCCIO<2> SKX_EXT_B_BGA1-IC,TBD   I107 @BASEBOARD_FAB2_LIB.BASEBOARD_FAB2(SCH_1):PAGE73
  U2D1 DV11 VCCIO<3> SKX_EXT_B_BGA1-IC,TBD   I107 @BASEBOARD_FAB2_LIB.BASEBOARD_FAB2(SCH_1):PAGE73
  U2D1  AM5 VCCIO<4> SKX_EXT_B_BGA1-IC,TBD   I107 @BASEBOARD_FAB2_LIB.BASEBOARD_FAB2(SCH_1):PAGE73
  U2D1  AT5 VCCIO<5> SKX_EXT_B_BGA1-IC,TBD   I107 @BASEBOARD_FAB2_LIB.BASEBOARD_FAB2(SCH_1):PAGE73
  U2D1  AT7 VCCIO<6> SKX_EXT_B_BGA1-IC,TBD   I107 @BASEBOARD_FAB2_LIB.BASEBOARD_FAB2(SCH_1):PAGE73
  U2D1 BE24 VCCIO<7> SKX_EXT_B_BGA1-IC,TBD   I107 @BASEBOARD_FAB2_LIB.BASEBOARD_FAB2(SCH_1):PAGE73
  U2D1 DK21 VCCIO<8> SKX_EXT_B_BGA1-IC,TBD   I107 @BASEBOARD_FAB2_LIB.BASEBOARD_FAB2(SCH_1):PAGE73
  U2D1  CF5 VCCIO<9> SKX_EXT_B_BGA1-IC,TBD   I107 @BASEBOARD_FAB2_LIB.BASEBOARD_FAB2(SCH_1):PAGE73
  U2D1 CG14 VCCIO<10> SKX_EXT_B_BGA1-IC,TBD   I107 @BASEBOARD_FAB2_LIB.BASEBOARD_FAB2(SCH_1):PAGE73
  U2D1 CL20 VCCIO<11> SKX_EXT_B_BGA1-IC,TBD   I107 @BASEBOARD_FAB2_LIB.BASEBOARD_FAB2(SCH_1):PAGE73
  U2D1 CP13 VCCIO<12> SKX_EXT_B_BGA1-IC,TBD   I107 @BASEBOARD_FAB2_LIB.BASEBOARD_FAB2(SCH_1):PAGE73
  U2D1 DE14 VCCIO<13> SKX_EXT_B_BGA1-IC,TBD   I107 @BASEBOARD_FAB2_LIB.BASEBOARD_FAB2(SCH_1):PAGE73
  U2D1 DC18 VCCIO<14> SKX_EXT_B_BGA1-IC,TBD   I107 @BASEBOARD_FAB2_LIB.BASEBOARD_FAB2(SCH_1):PAGE73
  U2D1 CY17 VCCIO<15> SKX_EXT_B_BGA1-IC,TBD   I107 @BASEBOARD_FAB2_LIB.BASEBOARD_FAB2(SCH_1):PAGE73
  U2D1 CU18 VCCIO<16> SKX_EXT_B_BGA1-IC,TBD   I107 @BASEBOARD_FAB2_LIB.BASEBOARD_FAB2(SCH_1):PAGE73
  U2D1 CV21 VCCIO<17> SKX_EXT_B_BGA1-IC,TBD   I107 @BASEBOARD_FAB2_LIB.BASEBOARD_FAB2(SCH_1):PAGE73
  U2D1 CU12 VCCIO<18> SKX_EXT_B_BGA1-IC,TBD   I107 @BASEBOARD_FAB2_LIB.BASEBOARD_FAB2(SCH_1):PAGE73
  U2D1  CN6 VCCIO<19> SKX_EXT_B_BGA1-IC,TBD   I107 @BASEBOARD_FAB2_LIB.BASEBOARD_FAB2(SCH_1):PAGE73
  C3D9    1      A CAP_A_0603V-22.0UF,4V,20%,X6S,A    I15 @BASEBOARD_FAB2_LIB.BASEBOARD_FAB2(SCH_1):PAGE76
  C3D8    1      A CAP_A_0603V-22.0UF,4V,20%,X6S,A    I18 @BASEBOARD_FAB2_LIB.BASEBOARD_FAB2(SCH_1):PAGE76
 C7P17    1      A CAP_0805-47UF,4V,20%,X6S,C9533A    I29 @BASEBOARD_FAB2_LIB.BASEBOARD_FAB2(SCH_1):PAGE76
 C7P18    1      A CAP_0805-47UF,4V,20%,X6S,C9533A    I51 @BASEBOARD_FAB2_LIB.BASEBOARD_FAB2(SCH_1):PAGE76
  C7P3    1      A CAP_0805-47UF,4V,20%,X6S,C9533A    I52 @BASEBOARD_FAB2_LIB.BASEBOARD_FAB2(SCH_1):PAGE76
 C3D23    1      A CAP_A_0603V-22.0UF,4V,20%,X6S,A   I172 @BASEBOARD_FAB2_LIB.BASEBOARD_FAB2(SCH_1):PAGE76
 C3D15    1      A CAP_A_0603V-22.0UF,4V,20%,X6S,A   I174 @BASEBOARD_FAB2_LIB.BASEBOARD_FAB2(SCH_1):PAGE76
 C3D24    1      A CAP_A_0603V-22.0UF,4V,20%,X6S,A   I175 @BASEBOARD_FAB2_LIB.BASEBOARD_FAB2(SCH_1):PAGE76
 C3D16    1      A CAP_A_0603V-22.0UF,4V,20%,X6S,A   I176 @BASEBOARD_FAB2_LIB.BASEBOARD_FAB2(SCH_1):PAGE76
 C7P12    1      A CAP_A_0603V-22.0UF,4V,20%,X6S,A   I179 @BASEBOARD_FAB2_LIB.BASEBOARD_FAB2(SCH_1):PAGE76
 C7P16    1      A CAP_A_0603V-22.0UF,4V,20%,X6S,A   I206 @BASEBOARD_FAB2_LIB.BASEBOARD_FAB2(SCH_1):PAGE76
 R3D22    1      A RES_0402-240,1.0%,1/16W,EMPTY,A    I17 @BASEBOARD_FAB2_LIB.BASEBOARD_FAB2(SCH_1):PAGE90
 R3D16    1      A RES_0402-240,1.0%,1/16W,EMPTY,A    I24 @BASEBOARD_FAB2_LIB.BASEBOARD_FAB2(SCH_1):PAGE90
 R3D23    1      A RES_0402-240,1.0%,1/16W,EMPTY,A    I25 @BASEBOARD_FAB2_LIB.BASEBOARD_FAB2(SCH_1):PAGE90
 R3D26    1      A RES_0402-240,1.0%,1/16W,EMPTY,A    I28 @BASEBOARD_FAB2_LIB.BASEBOARD_FAB2(SCH_1):PAGE90
 R3D24    1      A RES_0402-240,1.0%,1/16W,CHIP,GA    I59 @BASEBOARD_FAB2_LIB.BASEBOARD_FAB2(SCH_1):PAGE90
 R3D17    1      A RES_0402-240,1.0%,1/16W,EMPTY,A    I60 @BASEBOARD_FAB2_LIB.BASEBOARD_FAB2(SCH_1):PAGE90
 R3D25    1      A RES_0402-240,1.0%,1/16W,EMPTY,A    I66 @BASEBOARD_FAB2_LIB.BASEBOARD_FAB2(SCH_1):PAGE90
 R7P22    1      A RES_0402-240,1.0%,1/16W,EMPTY,A    I76 @BASEBOARD_FAB2_LIB.BASEBOARD_FAB2(SCH_1):PAGE90
 R3P41    1      A RES_0402-75,1.0%,1/16W,CHIP,G2A     I9 @BASEBOARD_FAB2_LIB.BASEBOARD_FAB2(SCH_1):PAGE92
 R7P28    1      A RES_0402-150.0,1%,1/16W,CHIP,GA   I106 @BASEBOARD_FAB2_LIB.BASEBOARD_FAB2(SCH_1):PAGE93
 R2T73    1      A RES_0402-150.0,1%,1/16W,CHIP,GA   I144 @BASEBOARD_FAB2_LIB.BASEBOARD_FAB2(SCH_1):PAGE93
 R3D20    1      A RES_0402-49.9,1%,1/16W,CHIP,G2A    I25 @BASEBOARD_FAB2_LIB.BASEBOARD_FAB2(SCH_1):PAGE96
 R3D15    1      A RES_0402-49.9,1%,1/16W,CHIP,G2A    I26 @BASEBOARD_FAB2_LIB.BASEBOARD_FAB2(SCH_1):PAGE96
 R4C10    1      A RES_0402-240,1.0%,1/16W,CHIP,GA    I76 @BASEBOARD_FAB2_LIB.BASEBOARD_FAB2(SCH_1):PAGE97
 C4G22    1      A CAP_A_0402V-0.1UF,16V,10%,X7R,A    I27 @BASEBOARD_FAB2_LIB.BASEBOARD_FAB2(SCH_1):PAGE99
  C3B4    1      A CAP_A_0402V-0.1UF,16V,10%,X7R,A    I47 @BASEBOARD_FAB2_LIB.BASEBOARD_FAB2(SCH_1):PAGE99
  U4G1    1   VCCA PCA9617_SSOP-IC,G81764-001-GNDA    I63 @BASEBOARD_FAB2_LIB.BASEBOARD_FAB2(SCH_1):PAGE99
  R6T1    1      A RES_0402-240,1.0%,1/16W,CHIP,GA    I70 @BASEBOARD_FAB2_LIB.BASEBOARD_FAB2(SCH_1):PAGE99
  R6T2    1      A RES_0402-240,1.0%,1/16W,CHIP,GA    I72 @BASEBOARD_FAB2_LIB.BASEBOARD_FAB2(SCH_1):PAGE99
  U3B1    1   VCCA PCA9617_SSOP-IC,G81764-001-GNDA    I75 @BASEBOARD_FAB2_LIB.BASEBOARD_FAB2(SCH_1):PAGE99
  R7M7    1      A RES_0402-240,1.0%,1/16W,CHIP,GA    I77 @BASEBOARD_FAB2_LIB.BASEBOARD_FAB2(SCH_1):PAGE99
  R7M2    1      A RES_0402-240,1.0%,1/16W,CHIP,GA    I79 @BASEBOARD_FAB2_LIB.BASEBOARD_FAB2(SCH_1):PAGE99
  R6T7    1      A RES_0402-150.0,1%,1/16W,CHIP,GA    I55 @BASEBOARD_FAB2_LIB.BASEBOARD_FAB2(SCH_1):PAGE112
  R6T6    1      A RES_0402-150.0,1%,1/16W,CHIP,GA    I56 @BASEBOARD_FAB2_LIB.BASEBOARD_FAB2(SCH_1):PAGE112
 R1U41    1      A RES_0402-150.0,1%,1/16W,CHIP,GA    I56 @BASEBOARD_FAB2_LIB.BASEBOARD_FAB2(SCH_1):PAGE152
 R1U35    1      A RES_0402-150.0,1%,1/16W,CHIP,GA    I57 @BASEBOARD_FAB2_LIB.BASEBOARD_FAB2(SCH_1):PAGE152
  R7P5    2      B RES_0402-150.0,1%,1/16W,CHIP,GA    I61 @BASEBOARD_FAB2_LIB.BASEBOARD_FAB2(SCH_1):PAGE152
 R7P21    2      B RES_0402-150.0,1%,1/16W,CHIP,GA    I62 @BASEBOARD_FAB2_LIB.BASEBOARD_FAB2(SCH_1):PAGE152
  U1B2    1   VCCA PCA9517_SM-IC,G77073-001-GND=GA     I1 @BASEBOARD_FAB2_LIB.BASEBOARD_FAB2(SCH_1):PAGE163
 R9M18    1      A RES_0402-240,1.0%,1/16W,CHIP,GA     I6 @BASEBOARD_FAB2_LIB.BASEBOARD_FAB2(SCH_1):PAGE163
 R9M19    1      A RES_0402-240,1.0%,1/16W,CHIP,GA     I7 @BASEBOARD_FAB2_LIB.BASEBOARD_FAB2(SCH_1):PAGE163
  C9M8    1      A CAP_A_0402V-0.1UF,16V,10%,X7R,A    I10 @BASEBOARD_FAB2_LIB.BASEBOARD_FAB2(SCH_1):PAGE163
  J4B2   F1   IOF1 SCONN120_H61426002_SM-CONN,H61A    I46 @BASEBOARD_FAB2_LIB.BASEBOARD_FAB2(SCH_1):PAGE193
  R9P1    1      A RES_0402-100.0,1%,1/16W,CHIP,GA     I4 @BASEBOARD_FAB2_LIB.BASEBOARD_FAB2(SCH_1):PAGE206
  R9P2    1      A RES_0402-49.9,1%,1/16W,CHIP,G2A    I53 @BASEBOARD_FAB2_LIB.BASEBOARD_FAB2(SCH_1):PAGE206
 R9N14    1      A RES_0402-1.00K,1%,1/16W,CHIP,GA   I120 @BASEBOARD_FAB2_LIB.BASEBOARD_FAB2(SCH_1):PAGE206
 R6P35    1      A RES_0402-100.0,1%,1/16W,EMPTY,A    I27 @BASEBOARD_FAB2_LIB.BASEBOARD_FAB2(SCH_1):PAGE213
 R6P33    1      A RES_0402-110,1%,1/16W,EMPTY,G2A    I30 @BASEBOARD_FAB2_LIB.BASEBOARD_FAB2(SCH_1):PAGE213
  C4E7    1      A CAPP_3018-470UF,2.5V,20%,ALUM,A    I20 @BASEBOARD_FAB2_LIB.BASEBOARD_FAB2(SCH_1):PAGE214
 C6R12    1      A CAPP_3018-470UF,2.5V,20%,ALUM,A    I21 @BASEBOARD_FAB2_LIB.BASEBOARD_FAB2(SCH_1):PAGE214
  C6R5    1      A CAPP_3018-470UF,2.5V,20%,ALUM,A    I24 @BASEBOARD_FAB2_LIB.BASEBOARD_FAB2(SCH_1):PAGE214
  C7R1    1      A CAP_A_0603V-22.0UF,4V,20%,X6S,A    I65 @BASEBOARD_FAB2_LIB.BASEBOARD_FAB2(SCH_1):PAGE214
  L4E2    2    INB INDUCTOR_SM-150NH,IND,D92183-0A    I67 @BASEBOARD_FAB2_LIB.BASEBOARD_FAB2(SCH_1):PAGE214
  R3E1    2      B RES_0402-100.0,1%,1/16W,CHIP,GA   I105 @BASEBOARD_FAB2_LIB.BASEBOARD_FAB2(SCH_1):PAGE214
  C3E1    1      A CAP_A_0603V-22.0UF,4V,20%,X6S,A   I108 @BASEBOARD_FAB2_LIB.BASEBOARD_FAB2(SCH_1):PAGE214
  R7R1    1      A RES_0402-51.1,1.0%,1/16W,CHIP,A   I109 @BASEBOARD_FAB2_LIB.BASEBOARD_FAB2(SCH_1):PAGE214
 EU4E2    1    VOS IR354XX_SM-IR35412,IC,H73684-0A   I126 @BASEBOARD_FAB2_LIB.BASEBOARD_FAB2(SCH_1):PAGE214
  R9U3    1      A RES_0402-100.0,1%,1/16W,CHIP,GA     I8 @BASEBOARD_FAB2_LIB.BASEBOARD_FAB2(SCH_1):PAGE223
  R9U4    1      A RES_0402-49.9,1%,1/16W,EMPTY,GA    I50 @BASEBOARD_FAB2_LIB.BASEBOARD_FAB2(SCH_1):PAGE223
  R9M7    1      A RES_0402-100.0,1%,1/16W,EMPTY,A     I8 @BASEBOARD_FAB2_LIB.BASEBOARD_FAB2(SCH_1):PAGE226
  R9M6    1      A RES_0402-49.9,1%,1/16W,CHIP,G2A    I50 @BASEBOARD_FAB2_LIB.BASEBOARD_FAB2(SCH_1):PAGE226

PVCCMCP_CPU0 @BASEBOARD_FAB2_LIB.BASEBOARD_FAB2(SCH_1):PVCCMCP_CPU0
  U5D1 AP25 RSVD<196> SKX_EXT_B_BGA1-IC,TBD   I204 @BASEBOARD_FAB2_LIB.BASEBOARD_FAB2(SCH_1):PAGE22
  U5D1 AP23 RSVD<197> SKX_EXT_B_BGA1-IC,TBD   I204 @BASEBOARD_FAB2_LIB.BASEBOARD_FAB2(SCH_1):PAGE22
  U5D1 AN26 RSVD<200> SKX_EXT_B_BGA1-IC,TBD   I204 @BASEBOARD_FAB2_LIB.BASEBOARD_FAB2(SCH_1):PAGE22
  U5D1 AN24 RSVD<201> SKX_EXT_B_BGA1-IC,TBD   I204 @BASEBOARD_FAB2_LIB.BASEBOARD_FAB2(SCH_1):PAGE22
  U5D1 AN22 RSVD<202> SKX_EXT_B_BGA1-IC,TBD   I204 @BASEBOARD_FAB2_LIB.BASEBOARD_FAB2(SCH_1):PAGE22
  U5D1 AN18 RSVD<203> SKX_EXT_B_BGA1-IC,TBD   I204 @BASEBOARD_FAB2_LIB.BASEBOARD_FAB2(SCH_1):PAGE22
  U5D1 AM25 RSVD<207> SKX_EXT_B_BGA1-IC,TBD   I204 @BASEBOARD_FAB2_LIB.BASEBOARD_FAB2(SCH_1):PAGE22
  U5D1 AM21 RSVD<209> SKX_EXT_B_BGA1-IC,TBD   I204 @BASEBOARD_FAB2_LIB.BASEBOARD_FAB2(SCH_1):PAGE22
  U5D1 AT25 RSVD<187> SKX_EXT_B_BGA1-IC,TBD    I61 @BASEBOARD_FAB2_LIB.BASEBOARD_FAB2(SCH_1):PAGE29
  U5D1 AT23 RSVD<188> SKX_EXT_B_BGA1-IC,TBD    I61 @BASEBOARD_FAB2_LIB.BASEBOARD_FAB2(SCH_1):PAGE29
  U5D1 AR26 RSVD<191> SKX_EXT_B_BGA1-IC,TBD    I61 @BASEBOARD_FAB2_LIB.BASEBOARD_FAB2(SCH_1):PAGE29
  U5D1 AR22 RSVD<192> SKX_EXT_B_BGA1-IC,TBD    I61 @BASEBOARD_FAB2_LIB.BASEBOARD_FAB2(SCH_1):PAGE29
  U5D1 AR20 RSVD<193> SKX_EXT_B_BGA1-IC,TBD    I61 @BASEBOARD_FAB2_LIB.BASEBOARD_FAB2(SCH_1):PAGE29
  U5D1 CH23 RSVD<92> SKX_EXT_B_BGA1-IC,TBD    I15 @BASEBOARD_FAB2_LIB.BASEBOARD_FAB2(SCH_1):PAGE36
  U5D1 CH21 RSVD<93> SKX_EXT_B_BGA1-IC,TBD    I15 @BASEBOARD_FAB2_LIB.BASEBOARD_FAB2(SCH_1):PAGE36
  U5D1 CG26 RSVD<96> SKX_EXT_B_BGA1-IC,TBD    I15 @BASEBOARD_FAB2_LIB.BASEBOARD_FAB2(SCH_1):PAGE36
  U5D1 CG20 RSVD<98> SKX_EXT_B_BGA1-IC,TBD    I15 @BASEBOARD_FAB2_LIB.BASEBOARD_FAB2(SCH_1):PAGE36
  U5D1 CF23 RSVD<102> SKX_EXT_B_BGA1-IC,TBD    I15 @BASEBOARD_FAB2_LIB.BASEBOARD_FAB2(SCH_1):PAGE36
  U5D1 CF21 RSVD<103> SKX_EXT_B_BGA1-IC,TBD    I15 @BASEBOARD_FAB2_LIB.BASEBOARD_FAB2(SCH_1):PAGE36
  U5D1 CF19 RSVD<104> SKX_EXT_B_BGA1-IC,TBD    I15 @BASEBOARD_FAB2_LIB.BASEBOARD_FAB2(SCH_1):PAGE36
  U5D1 CE22 RSVD<107> SKX_EXT_B_BGA1-IC,TBD    I15 @BASEBOARD_FAB2_LIB.BASEBOARD_FAB2(SCH_1):PAGE36
  U5D1 CD21 RSVD<109> SKX_EXT_B_BGA1-IC,TBD    I15 @BASEBOARD_FAB2_LIB.BASEBOARD_FAB2(SCH_1):PAGE36
  U5D1 CD19 RSVD<110> SKX_EXT_B_BGA1-IC,TBD    I15 @BASEBOARD_FAB2_LIB.BASEBOARD_FAB2(SCH_1):PAGE36
  U5D1 CC20 RSVD<112> SKX_EXT_B_BGA1-IC,TBD    I15 @BASEBOARD_FAB2_LIB.BASEBOARD_FAB2(SCH_1):PAGE36
  U5D1 CB21 RSVD<115> SKX_EXT_B_BGA1-IC,TBD    I15 @BASEBOARD_FAB2_LIB.BASEBOARD_FAB2(SCH_1):PAGE36
  U5D1 CB19 RSVD<116> SKX_EXT_B_BGA1-IC,TBD    I15 @BASEBOARD_FAB2_LIB.BASEBOARD_FAB2(SCH_1):PAGE36
  U5D1 CA22 RSVD<118> SKX_EXT_B_BGA1-IC,TBD    I15 @BASEBOARD_FAB2_LIB.BASEBOARD_FAB2(SCH_1):PAGE36
  U5D1 BY19 RSVD<120> SKX_EXT_B_BGA1-IC,TBD    I15 @BASEBOARD_FAB2_LIB.BASEBOARD_FAB2(SCH_1):PAGE36
  U5D1 BW20 RSVD<122> SKX_EXT_B_BGA1-IC,TBD    I15 @BASEBOARD_FAB2_LIB.BASEBOARD_FAB2(SCH_1):PAGE36
  U5D1 BV21 RSVD<125> SKX_EXT_B_BGA1-IC,TBD    I15 @BASEBOARD_FAB2_LIB.BASEBOARD_FAB2(SCH_1):PAGE36
  U5D1 BV19 RSVD<126> SKX_EXT_B_BGA1-IC,TBD    I15 @BASEBOARD_FAB2_LIB.BASEBOARD_FAB2(SCH_1):PAGE36
  U5D1 BU22 RSVD<127> SKX_EXT_B_BGA1-IC,TBD    I15 @BASEBOARD_FAB2_LIB.BASEBOARD_FAB2(SCH_1):PAGE36
  U5D1 BU20 RSVD<128> SKX_EXT_B_BGA1-IC,TBD    I15 @BASEBOARD_FAB2_LIB.BASEBOARD_FAB2(SCH_1):PAGE36
  U5D1 BU18 RSVD<129> SKX_EXT_B_BGA1-IC,TBD    I15 @BASEBOARD_FAB2_LIB.BASEBOARD_FAB2(SCH_1):PAGE36
  U5D1 BR24 RSVD<130> SKX_EXT_B_BGA1-IC,TBD    I15 @BASEBOARD_FAB2_LIB.BASEBOARD_FAB2(SCH_1):PAGE36
  U5D1 BR22 RSVD<131> SKX_EXT_B_BGA1-IC,TBD    I15 @BASEBOARD_FAB2_LIB.BASEBOARD_FAB2(SCH_1):PAGE36
  U5D1 BP21 RSVD<132> SKX_EXT_B_BGA1-IC,TBD    I15 @BASEBOARD_FAB2_LIB.BASEBOARD_FAB2(SCH_1):PAGE36
  U5D1 BP17 RSVD<133> SKX_EXT_B_BGA1-IC,TBD    I15 @BASEBOARD_FAB2_LIB.BASEBOARD_FAB2(SCH_1):PAGE36
  U5D1 BN18 RSVD<134> SKX_EXT_B_BGA1-IC,TBD    I15 @BASEBOARD_FAB2_LIB.BASEBOARD_FAB2(SCH_1):PAGE36
  U5D1 BM19 RSVD<135> SKX_EXT_B_BGA1-IC,TBD    I15 @BASEBOARD_FAB2_LIB.BASEBOARD_FAB2(SCH_1):PAGE36
  U5D1 BM17 RSVD<136> SKX_EXT_B_BGA1-IC,TBD    I15 @BASEBOARD_FAB2_LIB.BASEBOARD_FAB2(SCH_1):PAGE36
  U5D1 BL20 RSVD<137> SKX_EXT_B_BGA1-IC,TBD    I15 @BASEBOARD_FAB2_LIB.BASEBOARD_FAB2(SCH_1):PAGE36
  U5D1 BL18 RSVD<138> SKX_EXT_B_BGA1-IC,TBD    I15 @BASEBOARD_FAB2_LIB.BASEBOARD_FAB2(SCH_1):PAGE36
  U5D1 BK17 RSVD<139> SKX_EXT_B_BGA1-IC,TBD    I15 @BASEBOARD_FAB2_LIB.BASEBOARD_FAB2(SCH_1):PAGE36
  U5D1 BJ20 RSVD<140> SKX_EXT_B_BGA1-IC,TBD    I15 @BASEBOARD_FAB2_LIB.BASEBOARD_FAB2(SCH_1):PAGE36
  U5D1 BJ18 RSVD<141> SKX_EXT_B_BGA1-IC,TBD    I15 @BASEBOARD_FAB2_LIB.BASEBOARD_FAB2(SCH_1):PAGE36
  U5D1 BJ16 RSVD<142> SKX_EXT_B_BGA1-IC,TBD    I15 @BASEBOARD_FAB2_LIB.BASEBOARD_FAB2(SCH_1):PAGE36
  U5D1 BH19 RSVD<143> SKX_EXT_B_BGA1-IC,TBD    I15 @BASEBOARD_FAB2_LIB.BASEBOARD_FAB2(SCH_1):PAGE36
  U5D1 CL24 RSVD<81> SKX_EXT_B_BGA1-IC,TBD    I16 @BASEBOARD_FAB2_LIB.BASEBOARD_FAB2(SCH_1):PAGE36
  U5D1 CK25 RSVD<83> SKX_EXT_B_BGA1-IC,TBD    I16 @BASEBOARD_FAB2_LIB.BASEBOARD_FAB2(SCH_1):PAGE36
  U5D1 CK23 RSVD<84> SKX_EXT_B_BGA1-IC,TBD    I16 @BASEBOARD_FAB2_LIB.BASEBOARD_FAB2(SCH_1):PAGE36
  U5D1 CJ26 RSVD<86> SKX_EXT_B_BGA1-IC,TBD    I16 @BASEBOARD_FAB2_LIB.BASEBOARD_FAB2(SCH_1):PAGE36
  U5D1 CJ24 RSVD<87> SKX_EXT_B_BGA1-IC,TBD    I16 @BASEBOARD_FAB2_LIB.BASEBOARD_FAB2(SCH_1):PAGE36
  U5D1 CJ22 RSVD<88> SKX_EXT_B_BGA1-IC,TBD    I16 @BASEBOARD_FAB2_LIB.BASEBOARD_FAB2(SCH_1):PAGE36
  U5D1 CJ20 RSVD<89> SKX_EXT_B_BGA1-IC,TBD    I16 @BASEBOARD_FAB2_LIB.BASEBOARD_FAB2(SCH_1):PAGE36
  U5D1 BL14 CD_VCC_CORE<0> SKX_EXT_B_BGA1-IC,TBD    I34 @BASEBOARD_FAB2_LIB.BASEBOARD_FAB2(SCH_1):PAGE38
  U5D1 BK15 CD_VCC_CORE<1> SKX_EXT_B_BGA1-IC,TBD    I34 @BASEBOARD_FAB2_LIB.BASEBOARD_FAB2(SCH_1):PAGE38
  U5D1 BK13 CD_VCC_CORE<2> SKX_EXT_B_BGA1-IC,TBD    I34 @BASEBOARD_FAB2_LIB.BASEBOARD_FAB2(SCH_1):PAGE38
  U5D1 BJ14 CD_VCC_CORE<3> SKX_EXT_B_BGA1-IC,TBD    I34 @BASEBOARD_FAB2_LIB.BASEBOARD_FAB2(SCH_1):PAGE38
  U5D1 BJ12 CD_VCC_CORE<4> SKX_EXT_B_BGA1-IC,TBD    I34 @BASEBOARD_FAB2_LIB.BASEBOARD_FAB2(SCH_1):PAGE38
  U5D1 BH13 CD_VCC_CORE<5> SKX_EXT_B_BGA1-IC,TBD    I34 @BASEBOARD_FAB2_LIB.BASEBOARD_FAB2(SCH_1):PAGE38
  U5D1 BG14 CD_VCC_CORE<6> SKX_EXT_B_BGA1-IC,TBD    I34 @BASEBOARD_FAB2_LIB.BASEBOARD_FAB2(SCH_1):PAGE38
  U5D1 BG12 CD_VCC_CORE<7> SKX_EXT_B_BGA1-IC,TBD    I34 @BASEBOARD_FAB2_LIB.BASEBOARD_FAB2(SCH_1):PAGE38
  U5D1 BF13 CD_VCC_CORE<8> SKX_EXT_B_BGA1-IC,TBD    I34 @BASEBOARD_FAB2_LIB.BASEBOARD_FAB2(SCH_1):PAGE38
  U5D1 BF11 CD_VCC_CORE<9> SKX_EXT_B_BGA1-IC,TBD    I34 @BASEBOARD_FAB2_LIB.BASEBOARD_FAB2(SCH_1):PAGE38
  U5D1 BE14 CD_VCC_CORE<10> SKX_EXT_B_BGA1-IC,TBD    I34 @BASEBOARD_FAB2_LIB.BASEBOARD_FAB2(SCH_1):PAGE38
  U5D1 BE12 CD_VCC_CORE<11> SKX_EXT_B_BGA1-IC,TBD    I34 @BASEBOARD_FAB2_LIB.BASEBOARD_FAB2(SCH_1):PAGE38
  U5D1 BD13 CD_VCC_CORE<12> SKX_EXT_B_BGA1-IC,TBD    I34 @BASEBOARD_FAB2_LIB.BASEBOARD_FAB2(SCH_1):PAGE38
  U5D1 DA24 RSVD<52> SKX_EXT_B_BGA1-IC,TBD   I127 @BASEBOARD_FAB2_LIB.BASEBOARD_FAB2(SCH_1):PAGE39
  U5D1 CY25 RSVD<58> SKX_EXT_B_BGA1-IC,TBD   I127 @BASEBOARD_FAB2_LIB.BASEBOARD_FAB2(SCH_1):PAGE39
  U5D1 CW24 RSVD<62> SKX_EXT_B_BGA1-IC,TBD   I127 @BASEBOARD_FAB2_LIB.BASEBOARD_FAB2(SCH_1):PAGE39
  U5D1 CV23 RSVD<65> SKX_EXT_B_BGA1-IC,TBD   I127 @BASEBOARD_FAB2_LIB.BASEBOARD_FAB2(SCH_1):PAGE39
  U5D1 CU24 RSVD<68> SKX_EXT_B_BGA1-IC,TBD   I127 @BASEBOARD_FAB2_LIB.BASEBOARD_FAB2(SCH_1):PAGE39
  U5D1 CT23 RSVD<71> SKX_EXT_B_BGA1-IC,TBD   I127 @BASEBOARD_FAB2_LIB.BASEBOARD_FAB2(SCH_1):PAGE39
  U5D1 CP23 RSVD<74> SKX_EXT_B_BGA1-IC,TBD   I127 @BASEBOARD_FAB2_LIB.BASEBOARD_FAB2(SCH_1):PAGE39
  U5D1 CN24 RSVD<76> SKX_EXT_B_BGA1-IC,TBD   I127 @BASEBOARD_FAB2_LIB.BASEBOARD_FAB2(SCH_1):PAGE39
  U5D1 CM25 RSVD<78> SKX_EXT_B_BGA1-IC,TBD   I127 @BASEBOARD_FAB2_LIB.BASEBOARD_FAB2(SCH_1):PAGE39
  U5D1 CM23 RSVD<79> SKX_EXT_B_BGA1-IC,TBD   I127 @BASEBOARD_FAB2_LIB.BASEBOARD_FAB2(SCH_1):PAGE39
  U5D1 CL26 RSVD<80> SKX_EXT_B_BGA1-IC,TBD   I127 @BASEBOARD_FAB2_LIB.BASEBOARD_FAB2(SCH_1):PAGE39
 C5P18    1      A CAP_0805-47UF,4V,20%,X6S,C9533A     I2 @BASEBOARD_FAB2_LIB.BASEBOARD_FAB2(SCH_1):PAGE42
 C5P28    1      A CAP_0805-47UF,4V,20%,X6S,C9533A     I3 @BASEBOARD_FAB2_LIB.BASEBOARD_FAB2(SCH_1):PAGE42
 C5P11    1      A CAP_0805-47UF,4V,20%,X6S,C9533A     I4 @BASEBOARD_FAB2_LIB.BASEBOARD_FAB2(SCH_1):PAGE42
 C5P10    1      A CAP_0805-47UF,4V,20%,X6S,C9533A     I6 @BASEBOARD_FAB2_LIB.BASEBOARD_FAB2(SCH_1):PAGE42
  C4P3    1      A CAP_0805-47UF,4V,20%,X6S,C9533A     I8 @BASEBOARD_FAB2_LIB.BASEBOARD_FAB2(SCH_1):PAGE42
  C4P7    1      A CAP_0805-47UF,4V,20%,X6S,C9533A     I9 @BASEBOARD_FAB2_LIB.BASEBOARD_FAB2(SCH_1):PAGE42
 C5P19    1      A CAP_0805-47UF,4V,20%,X6S,C9533A    I13 @BASEBOARD_FAB2_LIB.BASEBOARD_FAB2(SCH_1):PAGE42
  C4P4    1      A CAP_0805-47UF,4V,20%,X6S,C9533A    I14 @BASEBOARD_FAB2_LIB.BASEBOARD_FAB2(SCH_1):PAGE42
  C6D8    1      A CAP_A_0603V-22.0UF,4V,20%,X6S,A    I68 @BASEBOARD_FAB2_LIB.BASEBOARD_FAB2(SCH_1):PAGE42
 C5D38    1      A CAP_A_0603V-22.0UF,4V,20%,X6S,A    I69 @BASEBOARD_FAB2_LIB.BASEBOARD_FAB2(SCH_1):PAGE42
 C5D37    1      A CAP_A_0603V-22.0UF,4V,20%,X6S,A    I70 @BASEBOARD_FAB2_LIB.BASEBOARD_FAB2(SCH_1):PAGE42
  C6D5    1      A CAP_A_0603V-22.0UF,4V,20%,X6S,A    I75 @BASEBOARD_FAB2_LIB.BASEBOARD_FAB2(SCH_1):PAGE42
  C6D2    1      A CAP_A_0603V-22.0UF,4V,20%,X6S,A    I77 @BASEBOARD_FAB2_LIB.BASEBOARD_FAB2(SCH_1):PAGE42
 C5D51    1      A CAP_A_0603V-22.0UF,4V,20%,X6S,A    I83 @BASEBOARD_FAB2_LIB.BASEBOARD_FAB2(SCH_1):PAGE42
 C5D21    1      A CAP_A_0603V-22.0UF,4V,20%,X6S,A    I88 @BASEBOARD_FAB2_LIB.BASEBOARD_FAB2(SCH_1):PAGE42
 C5D50    1      A CAP_A_0603V-22.0UF,4V,20%,X6S,A    I89 @BASEBOARD_FAB2_LIB.BASEBOARD_FAB2(SCH_1):PAGE42
 C5D48    1      A CAP_A_0603V-22.0UF,4V,20%,X6S,A    I90 @BASEBOARD_FAB2_LIB.BASEBOARD_FAB2(SCH_1):PAGE42
 C5D23    1      A CAP_A_0603V-22.0UF,4V,20%,X6S,A    I98 @BASEBOARD_FAB2_LIB.BASEBOARD_FAB2(SCH_1):PAGE42
 C5P30    1      A CAP_0805-47UF,4V,20%,X6S,C9533A   I148 @BASEBOARD_FAB2_LIB.BASEBOARD_FAB2(SCH_1):PAGE42
 C5P29    1      A CAP_0805-47UF,4V,20%,X6S,C9533A   I149 @BASEBOARD_FAB2_LIB.BASEBOARD_FAB2(SCH_1):PAGE42
 C5D36    1      A CAP_A_0603V-22.0UF,4V,20%,X6S,A   I151 @BASEBOARD_FAB2_LIB.BASEBOARD_FAB2(SCH_1):PAGE42
 C5D49    1      A CAP_A_0603V-22.0UF,4V,20%,X6S,A   I152 @BASEBOARD_FAB2_LIB.BASEBOARD_FAB2(SCH_1):PAGE42
 C5D22    1      A CAP_A_0603V-22.0UF,4V,20%,X6S,A   I153 @BASEBOARD_FAB2_LIB.BASEBOARD_FAB2(SCH_1):PAGE42
 C5P31    1      A CAP_0805-47UF,4V,20%,X6S,C9533A   I162 @BASEBOARD_FAB2_LIB.BASEBOARD_FAB2(SCH_1):PAGE42
  C4P2    1      A CAP_0805-47UF,4V,20%,X6S,C9533A   I163 @BASEBOARD_FAB2_LIB.BASEBOARD_FAB2(SCH_1):PAGE42
  C4P5    1      A CAP_0805-47UF,4V,20%,X6S,C9533A   I172 @BASEBOARD_FAB2_LIB.BASEBOARD_FAB2(SCH_1):PAGE42
 C5D20    1      A CAP_A_0603V-22.0UF,4V,20%,X6S,A   I173 @BASEBOARD_FAB2_LIB.BASEBOARD_FAB2(SCH_1):PAGE42
 C5D33    1      A CAP_A_0603V-22.0UF,4V,20%,X6S,A   I174 @BASEBOARD_FAB2_LIB.BASEBOARD_FAB2(SCH_1):PAGE42
 C5D34    1      A CAP_A_0603V-22.0UF,4V,20%,X6S,A   I175 @BASEBOARD_FAB2_LIB.BASEBOARD_FAB2(SCH_1):PAGE42
 C5D35    1      A CAP_A_0603V-22.0UF,4V,20%,X6S,A   I176 @BASEBOARD_FAB2_LIB.BASEBOARD_FAB2(SCH_1):PAGE42
 C5D53    1      A CAP_A_0603V-22.0UF,4V,20%,X6S,A   I179 @BASEBOARD_FAB2_LIB.BASEBOARD_FAB2(SCH_1):PAGE42
 C5D52    1      A CAP_A_0603V-22.0UF,4V,20%,X6S,A   I180 @BASEBOARD_FAB2_LIB.BASEBOARD_FAB2(SCH_1):PAGE42
 C5P12    1      A CAP_0805-47UF,4V,20%,X6S,C9533A   I183 @BASEBOARD_FAB2_LIB.BASEBOARD_FAB2(SCH_1):PAGE42
 C5P21    1      A CAP_0805-47UF,4V,20%,X6S,C9533A   I184 @BASEBOARD_FAB2_LIB.BASEBOARD_FAB2(SCH_1):PAGE42
 C5P20    1      A CAP_0805-47UF,4V,20%,X6S,C9533A   I185 @BASEBOARD_FAB2_LIB.BASEBOARD_FAB2(SCH_1):PAGE42
 C5P13    1      A CAP_0805-47UF,4V,20%,X6S,C9533A   I186 @BASEBOARD_FAB2_LIB.BASEBOARD_FAB2(SCH_1):PAGE42
  C4R1    1      A CAPP_3018-470UF,2.5V,20%,ALUM,A    I29 @BASEBOARD_FAB2_LIB.BASEBOARD_FAB2(SCH_1):PAGE194
  C3R4    1      A CAPP_3018-470UF,2.5V,20%,ALUM,A    I31 @BASEBOARD_FAB2_LIB.BASEBOARD_FAB2(SCH_1):PAGE194
  J6E1   A1   IOA1 SCONN120_H61426002_SM-CONN,H61A    I55 @BASEBOARD_FAB2_LIB.BASEBOARD_FAB2(SCH_1):PAGE194
  J6E1   A2   IOA2 SCONN120_H61426002_SM-CONN,H61A    I55 @BASEBOARD_FAB2_LIB.BASEBOARD_FAB2(SCH_1):PAGE194
  J6E1   A3   IOA3 SCONN120_H61426002_SM-CONN,H61A    I55 @BASEBOARD_FAB2_LIB.BASEBOARD_FAB2(SCH_1):PAGE194
  J6E1   A5   IOA5 SCONN120_H61426002_SM-CONN,H61A    I55 @BASEBOARD_FAB2_LIB.BASEBOARD_FAB2(SCH_1):PAGE194
  J6E1   A6   IOA6 SCONN120_H61426002_SM-CONN,H61A    I55 @BASEBOARD_FAB2_LIB.BASEBOARD_FAB2(SCH_1):PAGE194
  J6E1   A7   IOA7 SCONN120_H61426002_SM-CONN,H61A    I55 @BASEBOARD_FAB2_LIB.BASEBOARD_FAB2(SCH_1):PAGE194
  J6E1   A8   IOA8 SCONN120_H61426002_SM-CONN,H61A    I55 @BASEBOARD_FAB2_LIB.BASEBOARD_FAB2(SCH_1):PAGE194
  J6E1   A9   IOA9 SCONN120_H61426002_SM-CONN,H61A    I55 @BASEBOARD_FAB2_LIB.BASEBOARD_FAB2(SCH_1):PAGE194
  J6E1  A10  IOA10 SCONN120_H61426002_SM-CONN,H61A    I55 @BASEBOARD_FAB2_LIB.BASEBOARD_FAB2(SCH_1):PAGE194
  J6E1  A11  IOA11 SCONN120_H61426002_SM-CONN,H61A    I55 @BASEBOARD_FAB2_LIB.BASEBOARD_FAB2(SCH_1):PAGE194
  J6E1  A12  IOA12 SCONN120_H61426002_SM-CONN,H61A    I55 @BASEBOARD_FAB2_LIB.BASEBOARD_FAB2(SCH_1):PAGE194
  J6E1  A13  IOA13 SCONN120_H61426002_SM-CONN,H61A    I55 @BASEBOARD_FAB2_LIB.BASEBOARD_FAB2(SCH_1):PAGE194
  J6E1  A14  IOA14 SCONN120_H61426002_SM-CONN,H61A    I55 @BASEBOARD_FAB2_LIB.BASEBOARD_FAB2(SCH_1):PAGE194
  J6E1  A15  IOA15 SCONN120_H61426002_SM-CONN,H61A    I55 @BASEBOARD_FAB2_LIB.BASEBOARD_FAB2(SCH_1):PAGE194
  J6E1  A16  IOA16 SCONN120_H61426002_SM-CONN,H61A    I55 @BASEBOARD_FAB2_LIB.BASEBOARD_FAB2(SCH_1):PAGE194
  J6E1  A17  IOA17 SCONN120_H61426002_SM-CONN,H61A    I55 @BASEBOARD_FAB2_LIB.BASEBOARD_FAB2(SCH_1):PAGE194
  J6E1  A18  IOA18 SCONN120_H61426002_SM-CONN,H61A    I55 @BASEBOARD_FAB2_LIB.BASEBOARD_FAB2(SCH_1):PAGE194
  J6E1   B1   IOB1 SCONN120_H61426002_SM-CONN,H61A    I55 @BASEBOARD_FAB2_LIB.BASEBOARD_FAB2(SCH_1):PAGE194
  J6E1   B2   IOB2 SCONN120_H61426002_SM-CONN,H61A    I55 @BASEBOARD_FAB2_LIB.BASEBOARD_FAB2(SCH_1):PAGE194
  J6E1   B3   IOB3 SCONN120_H61426002_SM-CONN,H61A    I55 @BASEBOARD_FAB2_LIB.BASEBOARD_FAB2(SCH_1):PAGE194
  J6E1   B5   IOB5 SCONN120_H61426002_SM-CONN,H61A    I55 @BASEBOARD_FAB2_LIB.BASEBOARD_FAB2(SCH_1):PAGE194
  J6E1   B6   IOB6 SCONN120_H61426002_SM-CONN,H61A    I55 @BASEBOARD_FAB2_LIB.BASEBOARD_FAB2(SCH_1):PAGE194
  J6E1   B7   IOB7 SCONN120_H61426002_SM-CONN,H61A    I55 @BASEBOARD_FAB2_LIB.BASEBOARD_FAB2(SCH_1):PAGE194
  J6E1   B8   IOB8 SCONN120_H61426002_SM-CONN,H61A    I55 @BASEBOARD_FAB2_LIB.BASEBOARD_FAB2(SCH_1):PAGE194
  J6E1   B9   IOB9 SCONN120_H61426002_SM-CONN,H61A    I55 @BASEBOARD_FAB2_LIB.BASEBOARD_FAB2(SCH_1):PAGE194
  J6E1  B10  IOB10 SCONN120_H61426002_SM-CONN,H61A    I55 @BASEBOARD_FAB2_LIB.BASEBOARD_FAB2(SCH_1):PAGE194
  J6E1  B11  IOB11 SCONN120_H61426002_SM-CONN,H61A    I55 @BASEBOARD_FAB2_LIB.BASEBOARD_FAB2(SCH_1):PAGE194
  J6E1  B12  IOB12 SCONN120_H61426002_SM-CONN,H61A    I55 @BASEBOARD_FAB2_LIB.BASEBOARD_FAB2(SCH_1):PAGE194
  J6E1  B13  IOB13 SCONN120_H61426002_SM-CONN,H61A    I55 @BASEBOARD_FAB2_LIB.BASEBOARD_FAB2(SCH_1):PAGE194
  J6E1  B14  IOB14 SCONN120_H61426002_SM-CONN,H61A    I55 @BASEBOARD_FAB2_LIB.BASEBOARD_FAB2(SCH_1):PAGE194
  J6E1  B15  IOB15 SCONN120_H61426002_SM-CONN,H61A    I55 @BASEBOARD_FAB2_LIB.BASEBOARD_FAB2(SCH_1):PAGE194
  J6E1  B16  IOB16 SCONN120_H61426002_SM-CONN,H61A    I55 @BASEBOARD_FAB2_LIB.BASEBOARD_FAB2(SCH_1):PAGE194
  J6E1  B17  IOB17 SCONN120_H61426002_SM-CONN,H61A    I55 @BASEBOARD_FAB2_LIB.BASEBOARD_FAB2(SCH_1):PAGE194
  J6E1  B18  IOB18 SCONN120_H61426002_SM-CONN,H61A    I55 @BASEBOARD_FAB2_LIB.BASEBOARD_FAB2(SCH_1):PAGE194
  J6E1   C1   IOC1 SCONN120_H61426002_SM-CONN,H61A    I55 @BASEBOARD_FAB2_LIB.BASEBOARD_FAB2(SCH_1):PAGE194
  J6E1   C2   IOC2 SCONN120_H61426002_SM-CONN,H61A    I55 @BASEBOARD_FAB2_LIB.BASEBOARD_FAB2(SCH_1):PAGE194
  J6E1   C3   IOC3 SCONN120_H61426002_SM-CONN,H61A    I55 @BASEBOARD_FAB2_LIB.BASEBOARD_FAB2(SCH_1):PAGE194
  J6E1   C4   IOC4 SCONN120_H61426002_SM-CONN,H61A    I55 @BASEBOARD_FAB2_LIB.BASEBOARD_FAB2(SCH_1):PAGE194
  J6E1   C5   IOC5 SCONN120_H61426002_SM-CONN,H61A    I55 @BASEBOARD_FAB2_LIB.BASEBOARD_FAB2(SCH_1):PAGE194
  J6E1   C6   IOC6 SCONN120_H61426002_SM-CONN,H61A    I55 @BASEBOARD_FAB2_LIB.BASEBOARD_FAB2(SCH_1):PAGE194
  J6E1   C7   IOC7 SCONN120_H61426002_SM-CONN,H61A    I55 @BASEBOARD_FAB2_LIB.BASEBOARD_FAB2(SCH_1):PAGE194
  J6E1   C8   IOC8 SCONN120_H61426002_SM-CONN,H61A    I55 @BASEBOARD_FAB2_LIB.BASEBOARD_FAB2(SCH_1):PAGE194
  J6E1   C9   IOC9 SCONN120_H61426002_SM-CONN,H61A    I55 @BASEBOARD_FAB2_LIB.BASEBOARD_FAB2(SCH_1):PAGE194
  J6E1  C10  IOC10 SCONN120_H61426002_SM-CONN,H61A    I55 @BASEBOARD_FAB2_LIB.BASEBOARD_FAB2(SCH_1):PAGE194
  J6E1  C11  IOC11 SCONN120_H61426002_SM-CONN,H61A    I55 @BASEBOARD_FAB2_LIB.BASEBOARD_FAB2(SCH_1):PAGE194
  J6E1  C12  IOC12 SCONN120_H61426002_SM-CONN,H61A    I55 @BASEBOARD_FAB2_LIB.BASEBOARD_FAB2(SCH_1):PAGE194
  J6E1  C13  IOC13 SCONN120_H61426002_SM-CONN,H61A    I55 @BASEBOARD_FAB2_LIB.BASEBOARD_FAB2(SCH_1):PAGE194
  J6E1  C14  IOC14 SCONN120_H61426002_SM-CONN,H61A    I55 @BASEBOARD_FAB2_LIB.BASEBOARD_FAB2(SCH_1):PAGE194
  J6E1  C15  IOC15 SCONN120_H61426002_SM-CONN,H61A    I55 @BASEBOARD_FAB2_LIB.BASEBOARD_FAB2(SCH_1):PAGE194
  J6E1  C16  IOC16 SCONN120_H61426002_SM-CONN,H61A    I55 @BASEBOARD_FAB2_LIB.BASEBOARD_FAB2(SCH_1):PAGE194
  J6E1  C17  IOC17 SCONN120_H61426002_SM-CONN,H61A    I55 @BASEBOARD_FAB2_LIB.BASEBOARD_FAB2(SCH_1):PAGE194
  J6E1  C18  IOC18 SCONN120_H61426002_SM-CONN,H61A    I55 @BASEBOARD_FAB2_LIB.BASEBOARD_FAB2(SCH_1):PAGE194

PVCCMCP_CPU1 @BASEBOARD_FAB2_LIB.BASEBOARD_FAB2(SCH_1):PVCCMCP_CPU1
  U2D1 AP25 RSVD<196> SKX_EXT_B_BGA1-IC,TBD   I169 @BASEBOARD_FAB2_LIB.BASEBOARD_FAB2(SCH_1):PAGE56
  U2D1 AP23 RSVD<197> SKX_EXT_B_BGA1-IC,TBD   I169 @BASEBOARD_FAB2_LIB.BASEBOARD_FAB2(SCH_1):PAGE56
  U2D1 AN26 RSVD<200> SKX_EXT_B_BGA1-IC,TBD   I169 @BASEBOARD_FAB2_LIB.BASEBOARD_FAB2(SCH_1):PAGE56
  U2D1 AN24 RSVD<201> SKX_EXT_B_BGA1-IC,TBD   I169 @BASEBOARD_FAB2_LIB.BASEBOARD_FAB2(SCH_1):PAGE56
  U2D1 AN22 RSVD<202> SKX_EXT_B_BGA1-IC,TBD   I169 @BASEBOARD_FAB2_LIB.BASEBOARD_FAB2(SCH_1):PAGE56
  U2D1 AN18 RSVD<203> SKX_EXT_B_BGA1-IC,TBD   I169 @BASEBOARD_FAB2_LIB.BASEBOARD_FAB2(SCH_1):PAGE56
  U2D1 AM25 RSVD<207> SKX_EXT_B_BGA1-IC,TBD   I169 @BASEBOARD_FAB2_LIB.BASEBOARD_FAB2(SCH_1):PAGE56
  U2D1 AM21 RSVD<209> SKX_EXT_B_BGA1-IC,TBD   I169 @BASEBOARD_FAB2_LIB.BASEBOARD_FAB2(SCH_1):PAGE56
  U2D1 AT25 RSVD<187> SKX_EXT_B_BGA1-IC,TBD    I23 @BASEBOARD_FAB2_LIB.BASEBOARD_FAB2(SCH_1):PAGE63
  U2D1 AT23 RSVD<188> SKX_EXT_B_BGA1-IC,TBD    I23 @BASEBOARD_FAB2_LIB.BASEBOARD_FAB2(SCH_1):PAGE63
  U2D1 AR26 RSVD<191> SKX_EXT_B_BGA1-IC,TBD    I23 @BASEBOARD_FAB2_LIB.BASEBOARD_FAB2(SCH_1):PAGE63
  U2D1 AR22 RSVD<192> SKX_EXT_B_BGA1-IC,TBD    I23 @BASEBOARD_FAB2_LIB.BASEBOARD_FAB2(SCH_1):PAGE63
  U2D1 AR20 RSVD<193> SKX_EXT_B_BGA1-IC,TBD    I23 @BASEBOARD_FAB2_LIB.BASEBOARD_FAB2(SCH_1):PAGE63
  U2D1 CH23 RSVD<92> SKX_EXT_B_BGA1-IC,TBD     I9 @BASEBOARD_FAB2_LIB.BASEBOARD_FAB2(SCH_1):PAGE70
  U2D1 CH21 RSVD<93> SKX_EXT_B_BGA1-IC,TBD     I9 @BASEBOARD_FAB2_LIB.BASEBOARD_FAB2(SCH_1):PAGE70
  U2D1 CG26 RSVD<96> SKX_EXT_B_BGA1-IC,TBD     I9 @BASEBOARD_FAB2_LIB.BASEBOARD_FAB2(SCH_1):PAGE70
  U2D1 CG20 RSVD<98> SKX_EXT_B_BGA1-IC,TBD     I9 @BASEBOARD_FAB2_LIB.BASEBOARD_FAB2(SCH_1):PAGE70
  U2D1 CF23 RSVD<102> SKX_EXT_B_BGA1-IC,TBD     I9 @BASEBOARD_FAB2_LIB.BASEBOARD_FAB2(SCH_1):PAGE70
  U2D1 CF21 RSVD<103> SKX_EXT_B_BGA1-IC,TBD     I9 @BASEBOARD_FAB2_LIB.BASEBOARD_FAB2(SCH_1):PAGE70
  U2D1 CF19 RSVD<104> SKX_EXT_B_BGA1-IC,TBD     I9 @BASEBOARD_FAB2_LIB.BASEBOARD_FAB2(SCH_1):PAGE70
  U2D1 CE22 RSVD<107> SKX_EXT_B_BGA1-IC,TBD     I9 @BASEBOARD_FAB2_LIB.BASEBOARD_FAB2(SCH_1):PAGE70
  U2D1 CD21 RSVD<109> SKX_EXT_B_BGA1-IC,TBD     I9 @BASEBOARD_FAB2_LIB.BASEBOARD_FAB2(SCH_1):PAGE70
  U2D1 CD19 RSVD<110> SKX_EXT_B_BGA1-IC,TBD     I9 @BASEBOARD_FAB2_LIB.BASEBOARD_FAB2(SCH_1):PAGE70
  U2D1 CC20 RSVD<112> SKX_EXT_B_BGA1-IC,TBD     I9 @BASEBOARD_FAB2_LIB.BASEBOARD_FAB2(SCH_1):PAGE70
  U2D1 CB21 RSVD<115> SKX_EXT_B_BGA1-IC,TBD     I9 @BASEBOARD_FAB2_LIB.BASEBOARD_FAB2(SCH_1):PAGE70
  U2D1 CB19 RSVD<116> SKX_EXT_B_BGA1-IC,TBD     I9 @BASEBOARD_FAB2_LIB.BASEBOARD_FAB2(SCH_1):PAGE70
  U2D1 CA22 RSVD<118> SKX_EXT_B_BGA1-IC,TBD     I9 @BASEBOARD_FAB2_LIB.BASEBOARD_FAB2(SCH_1):PAGE70
  U2D1 BY19 RSVD<120> SKX_EXT_B_BGA1-IC,TBD     I9 @BASEBOARD_FAB2_LIB.BASEBOARD_FAB2(SCH_1):PAGE70
  U2D1 BW20 RSVD<122> SKX_EXT_B_BGA1-IC,TBD     I9 @BASEBOARD_FAB2_LIB.BASEBOARD_FAB2(SCH_1):PAGE70
  U2D1 BV21 RSVD<125> SKX_EXT_B_BGA1-IC,TBD     I9 @BASEBOARD_FAB2_LIB.BASEBOARD_FAB2(SCH_1):PAGE70
  U2D1 BV19 RSVD<126> SKX_EXT_B_BGA1-IC,TBD     I9 @BASEBOARD_FAB2_LIB.BASEBOARD_FAB2(SCH_1):PAGE70
  U2D1 BU22 RSVD<127> SKX_EXT_B_BGA1-IC,TBD     I9 @BASEBOARD_FAB2_LIB.BASEBOARD_FAB2(SCH_1):PAGE70
  U2D1 BU20 RSVD<128> SKX_EXT_B_BGA1-IC,TBD     I9 @BASEBOARD_FAB2_LIB.BASEBOARD_FAB2(SCH_1):PAGE70
  U2D1 BU18 RSVD<129> SKX_EXT_B_BGA1-IC,TBD     I9 @BASEBOARD_FAB2_LIB.BASEBOARD_FAB2(SCH_1):PAGE70
  U2D1 BR24 RSVD<130> SKX_EXT_B_BGA1-IC,TBD     I9 @BASEBOARD_FAB2_LIB.BASEBOARD_FAB2(SCH_1):PAGE70
  U2D1 BR22 RSVD<131> SKX_EXT_B_BGA1-IC,TBD     I9 @BASEBOARD_FAB2_LIB.BASEBOARD_FAB2(SCH_1):PAGE70
  U2D1 BP21 RSVD<132> SKX_EXT_B_BGA1-IC,TBD     I9 @BASEBOARD_FAB2_LIB.BASEBOARD_FAB2(SCH_1):PAGE70
  U2D1 BP17 RSVD<133> SKX_EXT_B_BGA1-IC,TBD     I9 @BASEBOARD_FAB2_LIB.BASEBOARD_FAB2(SCH_1):PAGE70
  U2D1 BN18 RSVD<134> SKX_EXT_B_BGA1-IC,TBD     I9 @BASEBOARD_FAB2_LIB.BASEBOARD_FAB2(SCH_1):PAGE70
  U2D1 BM19 RSVD<135> SKX_EXT_B_BGA1-IC,TBD     I9 @BASEBOARD_FAB2_LIB.BASEBOARD_FAB2(SCH_1):PAGE70
  U2D1 BM17 RSVD<136> SKX_EXT_B_BGA1-IC,TBD     I9 @BASEBOARD_FAB2_LIB.BASEBOARD_FAB2(SCH_1):PAGE70
  U2D1 BL20 RSVD<137> SKX_EXT_B_BGA1-IC,TBD     I9 @BASEBOARD_FAB2_LIB.BASEBOARD_FAB2(SCH_1):PAGE70
  U2D1 BL18 RSVD<138> SKX_EXT_B_BGA1-IC,TBD     I9 @BASEBOARD_FAB2_LIB.BASEBOARD_FAB2(SCH_1):PAGE70
  U2D1 BK17 RSVD<139> SKX_EXT_B_BGA1-IC,TBD     I9 @BASEBOARD_FAB2_LIB.BASEBOARD_FAB2(SCH_1):PAGE70
  U2D1 BJ20 RSVD<140> SKX_EXT_B_BGA1-IC,TBD     I9 @BASEBOARD_FAB2_LIB.BASEBOARD_FAB2(SCH_1):PAGE70
  U2D1 BJ18 RSVD<141> SKX_EXT_B_BGA1-IC,TBD     I9 @BASEBOARD_FAB2_LIB.BASEBOARD_FAB2(SCH_1):PAGE70
  U2D1 BJ16 RSVD<142> SKX_EXT_B_BGA1-IC,TBD     I9 @BASEBOARD_FAB2_LIB.BASEBOARD_FAB2(SCH_1):PAGE70
  U2D1 BH19 RSVD<143> SKX_EXT_B_BGA1-IC,TBD     I9 @BASEBOARD_FAB2_LIB.BASEBOARD_FAB2(SCH_1):PAGE70
  U2D1 CL24 RSVD<81> SKX_EXT_B_BGA1-IC,TBD    I10 @BASEBOARD_FAB2_LIB.BASEBOARD_FAB2(SCH_1):PAGE70
  U2D1 CK25 RSVD<83> SKX_EXT_B_BGA1-IC,TBD    I10 @BASEBOARD_FAB2_LIB.BASEBOARD_FAB2(SCH_1):PAGE70
  U2D1 CK23 RSVD<84> SKX_EXT_B_BGA1-IC,TBD    I10 @BASEBOARD_FAB2_LIB.BASEBOARD_FAB2(SCH_1):PAGE70
  U2D1 CJ26 RSVD<86> SKX_EXT_B_BGA1-IC,TBD    I10 @BASEBOARD_FAB2_LIB.BASEBOARD_FAB2(SCH_1):PAGE70
  U2D1 CJ24 RSVD<87> SKX_EXT_B_BGA1-IC,TBD    I10 @BASEBOARD_FAB2_LIB.BASEBOARD_FAB2(SCH_1):PAGE70
  U2D1 CJ22 RSVD<88> SKX_EXT_B_BGA1-IC,TBD    I10 @BASEBOARD_FAB2_LIB.BASEBOARD_FAB2(SCH_1):PAGE70
  U2D1 CJ20 RSVD<89> SKX_EXT_B_BGA1-IC,TBD    I10 @BASEBOARD_FAB2_LIB.BASEBOARD_FAB2(SCH_1):PAGE70
  U2D1 BL14 CD_VCC_CORE<0> SKX_EXT_B_BGA1-IC,TBD    I33 @BASEBOARD_FAB2_LIB.BASEBOARD_FAB2(SCH_1):PAGE72
  U2D1 BK15 CD_VCC_CORE<1> SKX_EXT_B_BGA1-IC,TBD    I33 @BASEBOARD_FAB2_LIB.BASEBOARD_FAB2(SCH_1):PAGE72
  U2D1 BK13 CD_VCC_CORE<2> SKX_EXT_B_BGA1-IC,TBD    I33 @BASEBOARD_FAB2_LIB.BASEBOARD_FAB2(SCH_1):PAGE72
  U2D1 BJ14 CD_VCC_CORE<3> SKX_EXT_B_BGA1-IC,TBD    I33 @BASEBOARD_FAB2_LIB.BASEBOARD_FAB2(SCH_1):PAGE72
  U2D1 BJ12 CD_VCC_CORE<4> SKX_EXT_B_BGA1-IC,TBD    I33 @BASEBOARD_FAB2_LIB.BASEBOARD_FAB2(SCH_1):PAGE72
  U2D1 BH13 CD_VCC_CORE<5> SKX_EXT_B_BGA1-IC,TBD    I33 @BASEBOARD_FAB2_LIB.BASEBOARD_FAB2(SCH_1):PAGE72
  U2D1 BG14 CD_VCC_CORE<6> SKX_EXT_B_BGA1-IC,TBD    I33 @BASEBOARD_FAB2_LIB.BASEBOARD_FAB2(SCH_1):PAGE72
  U2D1 BG12 CD_VCC_CORE<7> SKX_EXT_B_BGA1-IC,TBD    I33 @BASEBOARD_FAB2_LIB.BASEBOARD_FAB2(SCH_1):PAGE72
  U2D1 BF13 CD_VCC_CORE<8> SKX_EXT_B_BGA1-IC,TBD    I33 @BASEBOARD_FAB2_LIB.BASEBOARD_FAB2(SCH_1):PAGE72
  U2D1 BF11 CD_VCC_CORE<9> SKX_EXT_B_BGA1-IC,TBD    I33 @BASEBOARD_FAB2_LIB.BASEBOARD_FAB2(SCH_1):PAGE72
  U2D1 BE14 CD_VCC_CORE<10> SKX_EXT_B_BGA1-IC,TBD    I33 @BASEBOARD_FAB2_LIB.BASEBOARD_FAB2(SCH_1):PAGE72
  U2D1 BE12 CD_VCC_CORE<11> SKX_EXT_B_BGA1-IC,TBD    I33 @BASEBOARD_FAB2_LIB.BASEBOARD_FAB2(SCH_1):PAGE72
  U2D1 BD13 CD_VCC_CORE<12> SKX_EXT_B_BGA1-IC,TBD    I33 @BASEBOARD_FAB2_LIB.BASEBOARD_FAB2(SCH_1):PAGE72
  U2D1 DA24 RSVD<52> SKX_EXT_B_BGA1-IC,TBD   I107 @BASEBOARD_FAB2_LIB.BASEBOARD_FAB2(SCH_1):PAGE73
  U2D1 CY25 RSVD<58> SKX_EXT_B_BGA1-IC,TBD   I107 @BASEBOARD_FAB2_LIB.BASEBOARD_FAB2(SCH_1):PAGE73
  U2D1 CW24 RSVD<62> SKX_EXT_B_BGA1-IC,TBD   I107 @BASEBOARD_FAB2_LIB.BASEBOARD_FAB2(SCH_1):PAGE73
  U2D1 CV23 RSVD<65> SKX_EXT_B_BGA1-IC,TBD   I107 @BASEBOARD_FAB2_LIB.BASEBOARD_FAB2(SCH_1):PAGE73
  U2D1 CU24 RSVD<68> SKX_EXT_B_BGA1-IC,TBD   I107 @BASEBOARD_FAB2_LIB.BASEBOARD_FAB2(SCH_1):PAGE73
  U2D1 CT23 RSVD<71> SKX_EXT_B_BGA1-IC,TBD   I107 @BASEBOARD_FAB2_LIB.BASEBOARD_FAB2(SCH_1):PAGE73
  U2D1 CP23 RSVD<74> SKX_EXT_B_BGA1-IC,TBD   I107 @BASEBOARD_FAB2_LIB.BASEBOARD_FAB2(SCH_1):PAGE73
  U2D1 CN24 RSVD<76> SKX_EXT_B_BGA1-IC,TBD   I107 @BASEBOARD_FAB2_LIB.BASEBOARD_FAB2(SCH_1):PAGE73
  U2D1 CM25 RSVD<78> SKX_EXT_B_BGA1-IC,TBD   I107 @BASEBOARD_FAB2_LIB.BASEBOARD_FAB2(SCH_1):PAGE73
  U2D1 CM23 RSVD<79> SKX_EXT_B_BGA1-IC,TBD   I107 @BASEBOARD_FAB2_LIB.BASEBOARD_FAB2(SCH_1):PAGE73
  U2D1 CL26 RSVD<80> SKX_EXT_B_BGA1-IC,TBD   I107 @BASEBOARD_FAB2_LIB.BASEBOARD_FAB2(SCH_1):PAGE73
 C3D21    1      A CAP_A_0603V-22.0UF,4V,20%,X6S,A     I1 @BASEBOARD_FAB2_LIB.BASEBOARD_FAB2(SCH_1):PAGE76
  C3D5    1      A CAP_A_0603V-22.0UF,4V,20%,X6S,A     I3 @BASEBOARD_FAB2_LIB.BASEBOARD_FAB2(SCH_1):PAGE76
 C3D12    1      A CAP_A_0603V-22.0UF,4V,20%,X6S,A     I4 @BASEBOARD_FAB2_LIB.BASEBOARD_FAB2(SCH_1):PAGE76
  C3D4    1      A CAP_A_0603V-22.0UF,4V,20%,X6S,A     I5 @BASEBOARD_FAB2_LIB.BASEBOARD_FAB2(SCH_1):PAGE76
 C3D11    1      A CAP_A_0603V-22.0UF,4V,20%,X6S,A     I7 @BASEBOARD_FAB2_LIB.BASEBOARD_FAB2(SCH_1):PAGE76
 C3D13    1      A CAP_A_0603V-22.0UF,4V,20%,X6S,A     I8 @BASEBOARD_FAB2_LIB.BASEBOARD_FAB2(SCH_1):PAGE76
 C2D40    1      A CAP_A_0603V-22.0UF,4V,20%,X6S,A    I10 @BASEBOARD_FAB2_LIB.BASEBOARD_FAB2(SCH_1):PAGE76
  C7P6    1      A CAP_0805-47UF,4V,20%,X6S,C9533A    I23 @BASEBOARD_FAB2_LIB.BASEBOARD_FAB2(SCH_1):PAGE76
 C7P13    1      A CAP_0805-47UF,4V,20%,X6S,C9533A    I25 @BASEBOARD_FAB2_LIB.BASEBOARD_FAB2(SCH_1):PAGE76
 C7P10    1      A CAP_0805-47UF,4V,20%,X6S,C9533A    I26 @BASEBOARD_FAB2_LIB.BASEBOARD_FAB2(SCH_1):PAGE76
  C7P7    1      A CAP_0805-47UF,4V,20%,X6S,C9533A    I27 @BASEBOARD_FAB2_LIB.BASEBOARD_FAB2(SCH_1):PAGE76
 C8P22    1      A CAP_0805-47UF,4V,20%,X6S,C9533A    I28 @BASEBOARD_FAB2_LIB.BASEBOARD_FAB2(SCH_1):PAGE76
 C7P15    1      A CAP_0805-47UF,4V,20%,X6S,C9533A    I45 @BASEBOARD_FAB2_LIB.BASEBOARD_FAB2(SCH_1):PAGE76
 C8P23    1      A CAP_0805-47UF,4V,20%,X6S,C9533A    I48 @BASEBOARD_FAB2_LIB.BASEBOARD_FAB2(SCH_1):PAGE76
 C7P14    1      A CAP_0805-47UF,4V,20%,X6S,C9533A    I49 @BASEBOARD_FAB2_LIB.BASEBOARD_FAB2(SCH_1):PAGE76
  C3D7    1      A CAP_A_0603V-22.0UF,4V,20%,X6S,A   I164 @BASEBOARD_FAB2_LIB.BASEBOARD_FAB2(SCH_1):PAGE76
 C2D39    1      A CAP_A_0603V-22.0UF,4V,20%,X6S,A   I165 @BASEBOARD_FAB2_LIB.BASEBOARD_FAB2(SCH_1):PAGE76
 C3D17    1      A CAP_A_0603V-22.0UF,4V,20%,X6S,A   I166 @BASEBOARD_FAB2_LIB.BASEBOARD_FAB2(SCH_1):PAGE76
 C3D18    1      A CAP_A_0603V-22.0UF,4V,20%,X6S,A   I169 @BASEBOARD_FAB2_LIB.BASEBOARD_FAB2(SCH_1):PAGE76
  C3D6    1      A CAP_A_0603V-22.0UF,4V,20%,X6S,A   I170 @BASEBOARD_FAB2_LIB.BASEBOARD_FAB2(SCH_1):PAGE76
 C3D14    1      A CAP_A_0603V-22.0UF,4V,20%,X6S,A   I171 @BASEBOARD_FAB2_LIB.BASEBOARD_FAB2(SCH_1):PAGE76
  C7P9    1      A CAP_0805-47UF,4V,20%,X6S,C9533A   I181 @BASEBOARD_FAB2_LIB.BASEBOARD_FAB2(SCH_1):PAGE76
  C7P5    1      A CAP_0805-47UF,4V,20%,X6S,C9533A   I182 @BASEBOARD_FAB2_LIB.BASEBOARD_FAB2(SCH_1):PAGE76
 C7P11    1      A CAP_0805-47UF,4V,20%,X6S,C9533A   I183 @BASEBOARD_FAB2_LIB.BASEBOARD_FAB2(SCH_1):PAGE76
  C7P8    1      A CAP_0805-47UF,4V,20%,X6S,C9533A   I184 @BASEBOARD_FAB2_LIB.BASEBOARD_FAB2(SCH_1):PAGE76
  C7P4    1      A CAP_0805-47UF,4V,20%,X6S,C9533A   I195 @BASEBOARD_FAB2_LIB.BASEBOARD_FAB2(SCH_1):PAGE76
 C3D10    1      A CAP_A_0603V-22.0UF,4V,20%,X6S,A   I196 @BASEBOARD_FAB2_LIB.BASEBOARD_FAB2(SCH_1):PAGE76
 C2D18    1      A CAP_A_0603V-22.0UF,4V,20%,X6S,A   I197 @BASEBOARD_FAB2_LIB.BASEBOARD_FAB2(SCH_1):PAGE76
 C2D28    1      A CAP_A_0603V-22.0UF,4V,20%,X6S,A   I198 @BASEBOARD_FAB2_LIB.BASEBOARD_FAB2(SCH_1):PAGE76
 C2D29    1      A CAP_A_0603V-22.0UF,4V,20%,X6S,A   I199 @BASEBOARD_FAB2_LIB.BASEBOARD_FAB2(SCH_1):PAGE76
 C3D20    1      A CAP_A_0603V-22.0UF,4V,20%,X6S,A   I207 @BASEBOARD_FAB2_LIB.BASEBOARD_FAB2(SCH_1):PAGE76
 C3D19    1      A CAP_A_0603V-22.0UF,4V,20%,X6S,A   I208 @BASEBOARD_FAB2_LIB.BASEBOARD_FAB2(SCH_1):PAGE76
 C8P14    1      A CAP_0805-47UF,4V,20%,X6S,C9533A   I211 @BASEBOARD_FAB2_LIB.BASEBOARD_FAB2(SCH_1):PAGE76
 C8P15    1      A CAP_0805-47UF,4V,20%,X6S,C9533A   I212 @BASEBOARD_FAB2_LIB.BASEBOARD_FAB2(SCH_1):PAGE76
  C8P8    1      A CAP_0805-47UF,4V,20%,X6S,C9533A   I213 @BASEBOARD_FAB2_LIB.BASEBOARD_FAB2(SCH_1):PAGE76
  C8P9    1      A CAP_0805-47UF,4V,20%,X6S,C9533A   I214 @BASEBOARD_FAB2_LIB.BASEBOARD_FAB2(SCH_1):PAGE76
  J4E1   A1   IOA1 SCONN120_H61426002_SM-CONN,H61A    I45 @BASEBOARD_FAB2_LIB.BASEBOARD_FAB2(SCH_1):PAGE193
  J4E1   A2   IOA2 SCONN120_H61426002_SM-CONN,H61A    I45 @BASEBOARD_FAB2_LIB.BASEBOARD_FAB2(SCH_1):PAGE193
  J4E1   A3   IOA3 SCONN120_H61426002_SM-CONN,H61A    I45 @BASEBOARD_FAB2_LIB.BASEBOARD_FAB2(SCH_1):PAGE193
  J4E1   A5   IOA5 SCONN120_H61426002_SM-CONN,H61A    I45 @BASEBOARD_FAB2_LIB.BASEBOARD_FAB2(SCH_1):PAGE193
  J4E1   A6   IOA6 SCONN120_H61426002_SM-CONN,H61A    I45 @BASEBOARD_FAB2_LIB.BASEBOARD_FAB2(SCH_1):PAGE193
  J4E1   A7   IOA7 SCONN120_H61426002_SM-CONN,H61A    I45 @BASEBOARD_FAB2_LIB.BASEBOARD_FAB2(SCH_1):PAGE193
  J4E1   A8   IOA8 SCONN120_H61426002_SM-CONN,H61A    I45 @BASEBOARD_FAB2_LIB.BASEBOARD_FAB2(SCH_1):PAGE193
  J4E1   A9   IOA9 SCONN120_H61426002_SM-CONN,H61A    I45 @BASEBOARD_FAB2_LIB.BASEBOARD_FAB2(SCH_1):PAGE193
  J4E1  A10  IOA10 SCONN120_H61426002_SM-CONN,H61A    I45 @BASEBOARD_FAB2_LIB.BASEBOARD_FAB2(SCH_1):PAGE193
  J4E1  A11  IOA11 SCONN120_H61426002_SM-CONN,H61A    I45 @BASEBOARD_FAB2_LIB.BASEBOARD_FAB2(SCH_1):PAGE193
  J4E1  A12  IOA12 SCONN120_H61426002_SM-CONN,H61A    I45 @BASEBOARD_FAB2_LIB.BASEBOARD_FAB2(SCH_1):PAGE193
  J4E1  A13  IOA13 SCONN120_H61426002_SM-CONN,H61A    I45 @BASEBOARD_FAB2_LIB.BASEBOARD_FAB2(SCH_1):PAGE193
  J4E1  A14  IOA14 SCONN120_H61426002_SM-CONN,H61A    I45 @BASEBOARD_FAB2_LIB.BASEBOARD_FAB2(SCH_1):PAGE193
  J4E1  A15  IOA15 SCONN120_H61426002_SM-CONN,H61A    I45 @BASEBOARD_FAB2_LIB.BASEBOARD_FAB2(SCH_1):PAGE193
  J4E1  A16  IOA16 SCONN120_H61426002_SM-CONN,H61A    I45 @BASEBOARD_FAB2_LIB.BASEBOARD_FAB2(SCH_1):PAGE193
  J4E1  A17  IOA17 SCONN120_H61426002_SM-CONN,H61A    I45 @BASEBOARD_FAB2_LIB.BASEBOARD_FAB2(SCH_1):PAGE193
  J4E1  A18  IOA18 SCONN120_H61426002_SM-CONN,H61A    I45 @BASEBOARD_FAB2_LIB.BASEBOARD_FAB2(SCH_1):PAGE193
  J4E1   B1   IOB1 SCONN120_H61426002_SM-CONN,H61A    I45 @BASEBOARD_FAB2_LIB.BASEBOARD_FAB2(SCH_1):PAGE193
  J4E1   B2   IOB2 SCONN120_H61426002_SM-CONN,H61A    I45 @BASEBOARD_FAB2_LIB.BASEBOARD_FAB2(SCH_1):PAGE193
  J4E1   B3   IOB3 SCONN120_H61426002_SM-CONN,H61A    I45 @BASEBOARD_FAB2_LIB.BASEBOARD_FAB2(SCH_1):PAGE193
  J4E1   B5   IOB5 SCONN120_H61426002_SM-CONN,H61A    I45 @BASEBOARD_FAB2_LIB.BASEBOARD_FAB2(SCH_1):PAGE193
  J4E1   B6   IOB6 SCONN120_H61426002_SM-CONN,H61A    I45 @BASEBOARD_FAB2_LIB.BASEBOARD_FAB2(SCH_1):PAGE193
  J4E1   B7   IOB7 SCONN120_H61426002_SM-CONN,H61A    I45 @BASEBOARD_FAB2_LIB.BASEBOARD_FAB2(SCH_1):PAGE193
  J4E1   B8   IOB8 SCONN120_H61426002_SM-CONN,H61A    I45 @BASEBOARD_FAB2_LIB.BASEBOARD_FAB2(SCH_1):PAGE193
  J4E1   B9   IOB9 SCONN120_H61426002_SM-CONN,H61A    I45 @BASEBOARD_FAB2_LIB.BASEBOARD_FAB2(SCH_1):PAGE193
  J4E1  B10  IOB10 SCONN120_H61426002_SM-CONN,H61A    I45 @BASEBOARD_FAB2_LIB.BASEBOARD_FAB2(SCH_1):PAGE193
  J4E1  B11  IOB11 SCONN120_H61426002_SM-CONN,H61A    I45 @BASEBOARD_FAB2_LIB.BASEBOARD_FAB2(SCH_1):PAGE193
  J4E1  B12  IOB12 SCONN120_H61426002_SM-CONN,H61A    I45 @BASEBOARD_FAB2_LIB.BASEBOARD_FAB2(SCH_1):PAGE193
  J4E1  B13  IOB13 SCONN120_H61426002_SM-CONN,H61A    I45 @BASEBOARD_FAB2_LIB.BASEBOARD_FAB2(SCH_1):PAGE193
  J4E1  B14  IOB14 SCONN120_H61426002_SM-CONN,H61A    I45 @BASEBOARD_FAB2_LIB.BASEBOARD_FAB2(SCH_1):PAGE193
  J4E1  B15  IOB15 SCONN120_H61426002_SM-CONN,H61A    I45 @BASEBOARD_FAB2_LIB.BASEBOARD_FAB2(SCH_1):PAGE193
  J4E1  B16  IOB16 SCONN120_H61426002_SM-CONN,H61A    I45 @BASEBOARD_FAB2_LIB.BASEBOARD_FAB2(SCH_1):PAGE193
  J4E1  B17  IOB17 SCONN120_H61426002_SM-CONN,H61A    I45 @BASEBOARD_FAB2_LIB.BASEBOARD_FAB2(SCH_1):PAGE193
  J4E1  B18  IOB18 SCONN120_H61426002_SM-CONN,H61A    I45 @BASEBOARD_FAB2_LIB.BASEBOARD_FAB2(SCH_1):PAGE193
  J4E1   C1   IOC1 SCONN120_H61426002_SM-CONN,H61A    I45 @BASEBOARD_FAB2_LIB.BASEBOARD_FAB2(SCH_1):PAGE193
  J4E1   C2   IOC2 SCONN120_H61426002_SM-CONN,H61A    I45 @BASEBOARD_FAB2_LIB.BASEBOARD_FAB2(SCH_1):PAGE193
  J4E1   C3   IOC3 SCONN120_H61426002_SM-CONN,H61A    I45 @BASEBOARD_FAB2_LIB.BASEBOARD_FAB2(SCH_1):PAGE193
  J4E1   C4   IOC4 SCONN120_H61426002_SM-CONN,H61A    I45 @BASEBOARD_FAB2_LIB.BASEBOARD_FAB2(SCH_1):PAGE193
  J4E1   C5   IOC5 SCONN120_H61426002_SM-CONN,H61A    I45 @BASEBOARD_FAB2_LIB.BASEBOARD_FAB2(SCH_1):PAGE193
  J4E1   C6   IOC6 SCONN120_H61426002_SM-CONN,H61A    I45 @BASEBOARD_FAB2_LIB.BASEBOARD_FAB2(SCH_1):PAGE193
  J4E1   C7   IOC7 SCONN120_H61426002_SM-CONN,H61A    I45 @BASEBOARD_FAB2_LIB.BASEBOARD_FAB2(SCH_1):PAGE193
  J4E1   C8   IOC8 SCONN120_H61426002_SM-CONN,H61A    I45 @BASEBOARD_FAB2_LIB.BASEBOARD_FAB2(SCH_1):PAGE193
  J4E1   C9   IOC9 SCONN120_H61426002_SM-CONN,H61A    I45 @BASEBOARD_FAB2_LIB.BASEBOARD_FAB2(SCH_1):PAGE193
  J4E1  C10  IOC10 SCONN120_H61426002_SM-CONN,H61A    I45 @BASEBOARD_FAB2_LIB.BASEBOARD_FAB2(SCH_1):PAGE193
  J4E1  C11  IOC11 SCONN120_H61426002_SM-CONN,H61A    I45 @BASEBOARD_FAB2_LIB.BASEBOARD_FAB2(SCH_1):PAGE193
  J4E1  C12  IOC12 SCONN120_H61426002_SM-CONN,H61A    I45 @BASEBOARD_FAB2_LIB.BASEBOARD_FAB2(SCH_1):PAGE193
  J4E1  C13  IOC13 SCONN120_H61426002_SM-CONN,H61A    I45 @BASEBOARD_FAB2_LIB.BASEBOARD_FAB2(SCH_1):PAGE193
  J4E1  C14  IOC14 SCONN120_H61426002_SM-CONN,H61A    I45 @BASEBOARD_FAB2_LIB.BASEBOARD_FAB2(SCH_1):PAGE193
  J4E1  C15  IOC15 SCONN120_H61426002_SM-CONN,H61A    I45 @BASEBOARD_FAB2_LIB.BASEBOARD_FAB2(SCH_1):PAGE193
  J4E1  C16  IOC16 SCONN120_H61426002_SM-CONN,H61A    I45 @BASEBOARD_FAB2_LIB.BASEBOARD_FAB2(SCH_1):PAGE193
  J4E1  C17  IOC17 SCONN120_H61426002_SM-CONN,H61A    I45 @BASEBOARD_FAB2_LIB.BASEBOARD_FAB2(SCH_1):PAGE193
  J4E1  C18  IOC18 SCONN120_H61426002_SM-CONN,H61A    I45 @BASEBOARD_FAB2_LIB.BASEBOARD_FAB2(SCH_1):PAGE193
 C4E24    1      A CAPP_3018-470UF,2.5V,20%,ALUM,A    I61 @BASEBOARD_FAB2_LIB.BASEBOARD_FAB2(SCH_1):PAGE193
 C6R16    1      A CAPP_3018-470UF,2.5V,20%,ALUM,A    I62 @BASEBOARD_FAB2_LIB.BASEBOARD_FAB2(SCH_1):PAGE193

PVDDQ_ABC @BASEBOARD_FAB2_LIB.BASEBOARD_FAB2(SCH_1):PVDDQ_ABC
  U5D1  B49 VCCD012<0> SKX_EXT_B_BGA1-IC,TBD    I33 @BASEBOARD_FAB2_LIB.BASEBOARD_FAB2(SCH_1):PAGE38
  U5D1  B53 VCCD012<1> SKX_EXT_B_BGA1-IC,TBD    I33 @BASEBOARD_FAB2_LIB.BASEBOARD_FAB2(SCH_1):PAGE38
  U5D1  B59 VCCD012<2> SKX_EXT_B_BGA1-IC,TBD    I33 @BASEBOARD_FAB2_LIB.BASEBOARD_FAB2(SCH_1):PAGE38
  U5D1  E46 VCCD012<3> SKX_EXT_B_BGA1-IC,TBD    I33 @BASEBOARD_FAB2_LIB.BASEBOARD_FAB2(SCH_1):PAGE38
  U5D1  E48 VCCD012<4> SKX_EXT_B_BGA1-IC,TBD    I33 @BASEBOARD_FAB2_LIB.BASEBOARD_FAB2(SCH_1):PAGE38
  U5D1  E50 VCCD012<5> SKX_EXT_B_BGA1-IC,TBD    I33 @BASEBOARD_FAB2_LIB.BASEBOARD_FAB2(SCH_1):PAGE38
  U5D1  E52 VCCD012<6> SKX_EXT_B_BGA1-IC,TBD    I33 @BASEBOARD_FAB2_LIB.BASEBOARD_FAB2(SCH_1):PAGE38
  U5D1  E54 VCCD012<7> SKX_EXT_B_BGA1-IC,TBD    I33 @BASEBOARD_FAB2_LIB.BASEBOARD_FAB2(SCH_1):PAGE38
  U5D1  E56 VCCD012<8> SKX_EXT_B_BGA1-IC,TBD    I33 @BASEBOARD_FAB2_LIB.BASEBOARD_FAB2(SCH_1):PAGE38
  U5D1  E58 VCCD012<9> SKX_EXT_B_BGA1-IC,TBD    I33 @BASEBOARD_FAB2_LIB.BASEBOARD_FAB2(SCH_1):PAGE38
  U5D1  E60 VCCD012<10> SKX_EXT_B_BGA1-IC,TBD    I33 @BASEBOARD_FAB2_LIB.BASEBOARD_FAB2(SCH_1):PAGE38
  U5D1  E62 VCCD012<11> SKX_EXT_B_BGA1-IC,TBD    I33 @BASEBOARD_FAB2_LIB.BASEBOARD_FAB2(SCH_1):PAGE38
  U5D1  E64 VCCD012<12> SKX_EXT_B_BGA1-IC,TBD    I33 @BASEBOARD_FAB2_LIB.BASEBOARD_FAB2(SCH_1):PAGE38
  U5D1  L46 VCCD012<13> SKX_EXT_B_BGA1-IC,TBD    I33 @BASEBOARD_FAB2_LIB.BASEBOARD_FAB2(SCH_1):PAGE38
  U5D1  L48 VCCD012<14> SKX_EXT_B_BGA1-IC,TBD    I33 @BASEBOARD_FAB2_LIB.BASEBOARD_FAB2(SCH_1):PAGE38
  U5D1  L50 VCCD012<15> SKX_EXT_B_BGA1-IC,TBD    I33 @BASEBOARD_FAB2_LIB.BASEBOARD_FAB2(SCH_1):PAGE38
  U5D1  L52 VCCD012<16> SKX_EXT_B_BGA1-IC,TBD    I33 @BASEBOARD_FAB2_LIB.BASEBOARD_FAB2(SCH_1):PAGE38
  U5D1  L54 VCCD012<17> SKX_EXT_B_BGA1-IC,TBD    I33 @BASEBOARD_FAB2_LIB.BASEBOARD_FAB2(SCH_1):PAGE38
  U5D1  L56 VCCD012<18> SKX_EXT_B_BGA1-IC,TBD    I33 @BASEBOARD_FAB2_LIB.BASEBOARD_FAB2(SCH_1):PAGE38
  U5D1  L58 VCCD012<19> SKX_EXT_B_BGA1-IC,TBD    I33 @BASEBOARD_FAB2_LIB.BASEBOARD_FAB2(SCH_1):PAGE38
  U5D1  L60 VCCD012<20> SKX_EXT_B_BGA1-IC,TBD    I33 @BASEBOARD_FAB2_LIB.BASEBOARD_FAB2(SCH_1):PAGE38
  U5D1  L62 VCCD012<21> SKX_EXT_B_BGA1-IC,TBD    I33 @BASEBOARD_FAB2_LIB.BASEBOARD_FAB2(SCH_1):PAGE38
  U5D1  N64 VCCD012<22> SKX_EXT_B_BGA1-IC,TBD    I33 @BASEBOARD_FAB2_LIB.BASEBOARD_FAB2(SCH_1):PAGE38
  U5D1  U46 VCCD012<23> SKX_EXT_B_BGA1-IC,TBD    I33 @BASEBOARD_FAB2_LIB.BASEBOARD_FAB2(SCH_1):PAGE38
  U5D1  U48 VCCD012<24> SKX_EXT_B_BGA1-IC,TBD    I33 @BASEBOARD_FAB2_LIB.BASEBOARD_FAB2(SCH_1):PAGE38
  U5D1  U50 VCCD012<25> SKX_EXT_B_BGA1-IC,TBD    I33 @BASEBOARD_FAB2_LIB.BASEBOARD_FAB2(SCH_1):PAGE38
  U5D1  U52 VCCD012<26> SKX_EXT_B_BGA1-IC,TBD    I33 @BASEBOARD_FAB2_LIB.BASEBOARD_FAB2(SCH_1):PAGE38
  U5D1  U54 VCCD012<27> SKX_EXT_B_BGA1-IC,TBD    I33 @BASEBOARD_FAB2_LIB.BASEBOARD_FAB2(SCH_1):PAGE38
  U5D1  U56 VCCD012<28> SKX_EXT_B_BGA1-IC,TBD    I33 @BASEBOARD_FAB2_LIB.BASEBOARD_FAB2(SCH_1):PAGE38
  U5D1  U58 VCCD012<29> SKX_EXT_B_BGA1-IC,TBD    I33 @BASEBOARD_FAB2_LIB.BASEBOARD_FAB2(SCH_1):PAGE38
  U5D1  U60 VCCD012<30> SKX_EXT_B_BGA1-IC,TBD    I33 @BASEBOARD_FAB2_LIB.BASEBOARD_FAB2(SCH_1):PAGE38
  U5D1  U62 VCCD012<31> SKX_EXT_B_BGA1-IC,TBD    I33 @BASEBOARD_FAB2_LIB.BASEBOARD_FAB2(SCH_1):PAGE38
  U5D1  W64 VCCD012<32> SKX_EXT_B_BGA1-IC,TBD    I33 @BASEBOARD_FAB2_LIB.BASEBOARD_FAB2(SCH_1):PAGE38
  U5D1  Y45 VCCD012<33> SKX_EXT_B_BGA1-IC,TBD    I33 @BASEBOARD_FAB2_LIB.BASEBOARD_FAB2(SCH_1):PAGE38
  U5D1  Y47 VCCD012<34> SKX_EXT_B_BGA1-IC,TBD    I33 @BASEBOARD_FAB2_LIB.BASEBOARD_FAB2(SCH_1):PAGE38
  U5D1  Y49 VCCD012<35> SKX_EXT_B_BGA1-IC,TBD    I33 @BASEBOARD_FAB2_LIB.BASEBOARD_FAB2(SCH_1):PAGE38
  U5D1  Y51 VCCD012<36> SKX_EXT_B_BGA1-IC,TBD    I33 @BASEBOARD_FAB2_LIB.BASEBOARD_FAB2(SCH_1):PAGE38
  U5D1  Y53 VCCD012<37> SKX_EXT_B_BGA1-IC,TBD    I33 @BASEBOARD_FAB2_LIB.BASEBOARD_FAB2(SCH_1):PAGE38
  U5D1  Y55 VCCD012<38> SKX_EXT_B_BGA1-IC,TBD    I33 @BASEBOARD_FAB2_LIB.BASEBOARD_FAB2(SCH_1):PAGE38
  U5D1  Y57 VCCD012<39> SKX_EXT_B_BGA1-IC,TBD    I33 @BASEBOARD_FAB2_LIB.BASEBOARD_FAB2(SCH_1):PAGE38
  U5D1  Y59 VCCD012<40> SKX_EXT_B_BGA1-IC,TBD    I33 @BASEBOARD_FAB2_LIB.BASEBOARD_FAB2(SCH_1):PAGE38
  U5D1  Y61 VCCD012<41> SKX_EXT_B_BGA1-IC,TBD    I33 @BASEBOARD_FAB2_LIB.BASEBOARD_FAB2(SCH_1):PAGE38
  U5D1  Y63 VCCD012<42> SKX_EXT_B_BGA1-IC,TBD    I33 @BASEBOARD_FAB2_LIB.BASEBOARD_FAB2(SCH_1):PAGE38
  U5D1 AD45 VCCD012<43> SKX_EXT_B_BGA1-IC,TBD    I33 @BASEBOARD_FAB2_LIB.BASEBOARD_FAB2(SCH_1):PAGE38
  U5D1 AF55 VCCD012<44> SKX_EXT_B_BGA1-IC,TBD    I33 @BASEBOARD_FAB2_LIB.BASEBOARD_FAB2(SCH_1):PAGE38
  U5D1 AF57 VCCD012<45> SKX_EXT_B_BGA1-IC,TBD    I33 @BASEBOARD_FAB2_LIB.BASEBOARD_FAB2(SCH_1):PAGE38
  U5D1 AF59 VCCD012<46> SKX_EXT_B_BGA1-IC,TBD    I33 @BASEBOARD_FAB2_LIB.BASEBOARD_FAB2(SCH_1):PAGE38
  U5D1 AF61 VCCD012<47> SKX_EXT_B_BGA1-IC,TBD    I33 @BASEBOARD_FAB2_LIB.BASEBOARD_FAB2(SCH_1):PAGE38
  U5D1 AF63 VCCD012<48> SKX_EXT_B_BGA1-IC,TBD    I33 @BASEBOARD_FAB2_LIB.BASEBOARD_FAB2(SCH_1):PAGE38
  U5D1  D45 VCCD012<49> SKX_EXT_B_BGA1-IC,TBD    I33 @BASEBOARD_FAB2_LIB.BASEBOARD_FAB2(SCH_1):PAGE38
  U5D1  C46 VCCD012<50> SKX_EXT_B_BGA1-IC,TBD    I33 @BASEBOARD_FAB2_LIB.BASEBOARD_FAB2(SCH_1):PAGE38
  U5D1  B47 VCCD012<51> SKX_EXT_B_BGA1-IC,TBD    I33 @BASEBOARD_FAB2_LIB.BASEBOARD_FAB2(SCH_1):PAGE38
  J4G1  236 VDD<0> SCONN288_H44441004_PIP-SCONN,HA   I260 @BASEBOARD_FAB2_LIB.BASEBOARD_FAB2(SCH_1):PAGE43
  J4G1  233 VDD<1> SCONN288_H44441004_PIP-SCONN,HA   I260 @BASEBOARD_FAB2_LIB.BASEBOARD_FAB2(SCH_1):PAGE43
  J4G1  231 VDD<2> SCONN288_H44441004_PIP-SCONN,HA   I260 @BASEBOARD_FAB2_LIB.BASEBOARD_FAB2(SCH_1):PAGE43
  J4G1  229 VDD<3> SCONN288_H44441004_PIP-SCONN,HA   I260 @BASEBOARD_FAB2_LIB.BASEBOARD_FAB2(SCH_1):PAGE43
  J4G1  226 VDD<4> SCONN288_H44441004_PIP-SCONN,HA   I260 @BASEBOARD_FAB2_LIB.BASEBOARD_FAB2(SCH_1):PAGE43
  J4G1  223 VDD<5> SCONN288_H44441004_PIP-SCONN,HA   I260 @BASEBOARD_FAB2_LIB.BASEBOARD_FAB2(SCH_1):PAGE43
  J4G1  220 VDD<6> SCONN288_H44441004_PIP-SCONN,HA   I260 @BASEBOARD_FAB2_LIB.BASEBOARD_FAB2(SCH_1):PAGE43
  J4G1  217 VDD<7> SCONN288_H44441004_PIP-SCONN,HA   I260 @BASEBOARD_FAB2_LIB.BASEBOARD_FAB2(SCH_1):PAGE43
  J4G1  215 VDD<8> SCONN288_H44441004_PIP-SCONN,HA   I260 @BASEBOARD_FAB2_LIB.BASEBOARD_FAB2(SCH_1):PAGE43
  J4G1  212 VDD<9> SCONN288_H44441004_PIP-SCONN,HA   I260 @BASEBOARD_FAB2_LIB.BASEBOARD_FAB2(SCH_1):PAGE43
  J4G1  209 VDD<10> SCONN288_H44441004_PIP-SCONN,HA   I260 @BASEBOARD_FAB2_LIB.BASEBOARD_FAB2(SCH_1):PAGE43
  J4G1  206 VDD<11> SCONN288_H44441004_PIP-SCONN,HA   I260 @BASEBOARD_FAB2_LIB.BASEBOARD_FAB2(SCH_1):PAGE43
  J4G1  204 VDD<12> SCONN288_H44441004_PIP-SCONN,HA   I260 @BASEBOARD_FAB2_LIB.BASEBOARD_FAB2(SCH_1):PAGE43
  J4G1   92 VDD<13> SCONN288_H44441004_PIP-SCONN,HA   I260 @BASEBOARD_FAB2_LIB.BASEBOARD_FAB2(SCH_1):PAGE43
  J4G1   90 VDD<14> SCONN288_H44441004_PIP-SCONN,HA   I260 @BASEBOARD_FAB2_LIB.BASEBOARD_FAB2(SCH_1):PAGE43
  J4G1   88 VDD<15> SCONN288_H44441004_PIP-SCONN,HA   I260 @BASEBOARD_FAB2_LIB.BASEBOARD_FAB2(SCH_1):PAGE43
  J4G1   85 VDD<16> SCONN288_H44441004_PIP-SCONN,HA   I260 @BASEBOARD_FAB2_LIB.BASEBOARD_FAB2(SCH_1):PAGE43
  J4G1   83 VDD<17> SCONN288_H44441004_PIP-SCONN,HA   I260 @BASEBOARD_FAB2_LIB.BASEBOARD_FAB2(SCH_1):PAGE43
  J4G1   80 VDD<18> SCONN288_H44441004_PIP-SCONN,HA   I260 @BASEBOARD_FAB2_LIB.BASEBOARD_FAB2(SCH_1):PAGE43
  J4G1   76 VDD<19> SCONN288_H44441004_PIP-SCONN,HA   I260 @BASEBOARD_FAB2_LIB.BASEBOARD_FAB2(SCH_1):PAGE43
  J4G1   73 VDD<20> SCONN288_H44441004_PIP-SCONN,HA   I260 @BASEBOARD_FAB2_LIB.BASEBOARD_FAB2(SCH_1):PAGE43
  J4G1   70 VDD<21> SCONN288_H44441004_PIP-SCONN,HA   I260 @BASEBOARD_FAB2_LIB.BASEBOARD_FAB2(SCH_1):PAGE43
  J4G1   67 VDD<22> SCONN288_H44441004_PIP-SCONN,HA   I260 @BASEBOARD_FAB2_LIB.BASEBOARD_FAB2(SCH_1):PAGE43
  J4G1   64 VDD<23> SCONN288_H44441004_PIP-SCONN,HA   I260 @BASEBOARD_FAB2_LIB.BASEBOARD_FAB2(SCH_1):PAGE43
  J4G1   61 VDD<24> SCONN288_H44441004_PIP-SCONN,HA   I260 @BASEBOARD_FAB2_LIB.BASEBOARD_FAB2(SCH_1):PAGE43
  J4G1   59 VDD<25> SCONN288_H44441004_PIP-SCONN,HA   I260 @BASEBOARD_FAB2_LIB.BASEBOARD_FAB2(SCH_1):PAGE43
  J6T1  236 VDD<0> SCONN288_H44441003_PIP-SCONN,HA    I75 @BASEBOARD_FAB2_LIB.BASEBOARD_FAB2(SCH_1):PAGE44
  J6T1  233 VDD<1> SCONN288_H44441003_PIP-SCONN,HA    I75 @BASEBOARD_FAB2_LIB.BASEBOARD_FAB2(SCH_1):PAGE44
  J6T1  231 VDD<2> SCONN288_H44441003_PIP-SCONN,HA    I75 @BASEBOARD_FAB2_LIB.BASEBOARD_FAB2(SCH_1):PAGE44
  J6T1  229 VDD<3> SCONN288_H44441003_PIP-SCONN,HA    I75 @BASEBOARD_FAB2_LIB.BASEBOARD_FAB2(SCH_1):PAGE44
  J6T1  226 VDD<4> SCONN288_H44441003_PIP-SCONN,HA    I75 @BASEBOARD_FAB2_LIB.BASEBOARD_FAB2(SCH_1):PAGE44
  J6T1  223 VDD<5> SCONN288_H44441003_PIP-SCONN,HA    I75 @BASEBOARD_FAB2_LIB.BASEBOARD_FAB2(SCH_1):PAGE44
  J6T1  220 VDD<6> SCONN288_H44441003_PIP-SCONN,HA    I75 @BASEBOARD_FAB2_LIB.BASEBOARD_FAB2(SCH_1):PAGE44
  J6T1  217 VDD<7> SCONN288_H44441003_PIP-SCONN,HA    I75 @BASEBOARD_FAB2_LIB.BASEBOARD_FAB2(SCH_1):PAGE44
  J6T1  215 VDD<8> SCONN288_H44441003_PIP-SCONN,HA    I75 @BASEBOARD_FAB2_LIB.BASEBOARD_FAB2(SCH_1):PAGE44
  J6T1  212 VDD<9> SCONN288_H44441003_PIP-SCONN,HA    I75 @BASEBOARD_FAB2_LIB.BASEBOARD_FAB2(SCH_1):PAGE44
  J6T1  209 VDD<10> SCONN288_H44441003_PIP-SCONN,HA    I75 @BASEBOARD_FAB2_LIB.BASEBOARD_FAB2(SCH_1):PAGE44
  J6T1  206 VDD<11> SCONN288_H44441003_PIP-SCONN,HA    I75 @BASEBOARD_FAB2_LIB.BASEBOARD_FAB2(SCH_1):PAGE44
  J6T1  204 VDD<12> SCONN288_H44441003_PIP-SCONN,HA    I75 @BASEBOARD_FAB2_LIB.BASEBOARD_FAB2(SCH_1):PAGE44
  J6T1   92 VDD<13> SCONN288_H44441003_PIP-SCONN,HA    I75 @BASEBOARD_FAB2_LIB.BASEBOARD_FAB2(SCH_1):PAGE44
  J6T1   90 VDD<14> SCONN288_H44441003_PIP-SCONN,HA    I75 @BASEBOARD_FAB2_LIB.BASEBOARD_FAB2(SCH_1):PAGE44
  J6T1   88 VDD<15> SCONN288_H44441003_PIP-SCONN,HA    I75 @BASEBOARD_FAB2_LIB.BASEBOARD_FAB2(SCH_1):PAGE44
  J6T1   85 VDD<16> SCONN288_H44441003_PIP-SCONN,HA    I75 @BASEBOARD_FAB2_LIB.BASEBOARD_FAB2(SCH_1):PAGE44
  J6T1   83 VDD<17> SCONN288_H44441003_PIP-SCONN,HA    I75 @BASEBOARD_FAB2_LIB.BASEBOARD_FAB2(SCH_1):PAGE44
  J6T1   80 VDD<18> SCONN288_H44441003_PIP-SCONN,HA    I75 @BASEBOARD_FAB2_LIB.BASEBOARD_FAB2(SCH_1):PAGE44
  J6T1   76 VDD<19> SCONN288_H44441003_PIP-SCONN,HA    I75 @BASEBOARD_FAB2_LIB.BASEBOARD_FAB2(SCH_1):PAGE44
  J6T1   73 VDD<20> SCONN288_H44441003_PIP-SCONN,HA    I75 @BASEBOARD_FAB2_LIB.BASEBOARD_FAB2(SCH_1):PAGE44
  J6T1   70 VDD<21> SCONN288_H44441003_PIP-SCONN,HA    I75 @BASEBOARD_FAB2_LIB.BASEBOARD_FAB2(SCH_1):PAGE44
  J6T1   67 VDD<22> SCONN288_H44441003_PIP-SCONN,HA    I75 @BASEBOARD_FAB2_LIB.BASEBOARD_FAB2(SCH_1):PAGE44
  J6T1   64 VDD<23> SCONN288_H44441003_PIP-SCONN,HA    I75 @BASEBOARD_FAB2_LIB.BASEBOARD_FAB2(SCH_1):PAGE44
  J6T1   61 VDD<24> SCONN288_H44441003_PIP-SCONN,HA    I75 @BASEBOARD_FAB2_LIB.BASEBOARD_FAB2(SCH_1):PAGE44
  J6T1   59 VDD<25> SCONN288_H44441003_PIP-SCONN,HA    I75 @BASEBOARD_FAB2_LIB.BASEBOARD_FAB2(SCH_1):PAGE44
  J4G2  236 VDD<0> SCONN288_H44441004_PIP-SCONN,HA   I169 @BASEBOARD_FAB2_LIB.BASEBOARD_FAB2(SCH_1):PAGE45
  J4G2  233 VDD<1> SCONN288_H44441004_PIP-SCONN,HA   I169 @BASEBOARD_FAB2_LIB.BASEBOARD_FAB2(SCH_1):PAGE45
  J4G2  231 VDD<2> SCONN288_H44441004_PIP-SCONN,HA   I169 @BASEBOARD_FAB2_LIB.BASEBOARD_FAB2(SCH_1):PAGE45
  J4G2  229 VDD<3> SCONN288_H44441004_PIP-SCONN,HA   I169 @BASEBOARD_FAB2_LIB.BASEBOARD_FAB2(SCH_1):PAGE45
  J4G2  226 VDD<4> SCONN288_H44441004_PIP-SCONN,HA   I169 @BASEBOARD_FAB2_LIB.BASEBOARD_FAB2(SCH_1):PAGE45
  J4G2  223 VDD<5> SCONN288_H44441004_PIP-SCONN,HA   I169 @BASEBOARD_FAB2_LIB.BASEBOARD_FAB2(SCH_1):PAGE45
  J4G2  220 VDD<6> SCONN288_H44441004_PIP-SCONN,HA   I169 @BASEBOARD_FAB2_LIB.BASEBOARD_FAB2(SCH_1):PAGE45
  J4G2  217 VDD<7> SCONN288_H44441004_PIP-SCONN,HA   I169 @BASEBOARD_FAB2_LIB.BASEBOARD_FAB2(SCH_1):PAGE45
  J4G2  215 VDD<8> SCONN288_H44441004_PIP-SCONN,HA   I169 @BASEBOARD_FAB2_LIB.BASEBOARD_FAB2(SCH_1):PAGE45
  J4G2  212 VDD<9> SCONN288_H44441004_PIP-SCONN,HA   I169 @BASEBOARD_FAB2_LIB.BASEBOARD_FAB2(SCH_1):PAGE45
  J4G2  209 VDD<10> SCONN288_H44441004_PIP-SCONN,HA   I169 @BASEBOARD_FAB2_LIB.BASEBOARD_FAB2(SCH_1):PAGE45
  J4G2  206 VDD<11> SCONN288_H44441004_PIP-SCONN,HA   I169 @BASEBOARD_FAB2_LIB.BASEBOARD_FAB2(SCH_1):PAGE45
  J4G2  204 VDD<12> SCONN288_H44441004_PIP-SCONN,HA   I169 @BASEBOARD_FAB2_LIB.BASEBOARD_FAB2(SCH_1):PAGE45
  J4G2   92 VDD<13> SCONN288_H44441004_PIP-SCONN,HA   I169 @BASEBOARD_FAB2_LIB.BASEBOARD_FAB2(SCH_1):PAGE45
  J4G2   90 VDD<14> SCONN288_H44441004_PIP-SCONN,HA   I169 @BASEBOARD_FAB2_LIB.BASEBOARD_FAB2(SCH_1):PAGE45
  J4G2   88 VDD<15> SCONN288_H44441004_PIP-SCONN,HA   I169 @BASEBOARD_FAB2_LIB.BASEBOARD_FAB2(SCH_1):PAGE45
  J4G2   85 VDD<16> SCONN288_H44441004_PIP-SCONN,HA   I169 @BASEBOARD_FAB2_LIB.BASEBOARD_FAB2(SCH_1):PAGE45
  J4G2   83 VDD<17> SCONN288_H44441004_PIP-SCONN,HA   I169 @BASEBOARD_FAB2_LIB.BASEBOARD_FAB2(SCH_1):PAGE45
  J4G2   80 VDD<18> SCONN288_H44441004_PIP-SCONN,HA   I169 @BASEBOARD_FAB2_LIB.BASEBOARD_FAB2(SCH_1):PAGE45
  J4G2   76 VDD<19> SCONN288_H44441004_PIP-SCONN,HA   I169 @BASEBOARD_FAB2_LIB.BASEBOARD_FAB2(SCH_1):PAGE45
  J4G2   73 VDD<20> SCONN288_H44441004_PIP-SCONN,HA   I169 @BASEBOARD_FAB2_LIB.BASEBOARD_FAB2(SCH_1):PAGE45
  J4G2   70 VDD<21> SCONN288_H44441004_PIP-SCONN,HA   I169 @BASEBOARD_FAB2_LIB.BASEBOARD_FAB2(SCH_1):PAGE45
  J4G2   67 VDD<22> SCONN288_H44441004_PIP-SCONN,HA   I169 @BASEBOARD_FAB2_LIB.BASEBOARD_FAB2(SCH_1):PAGE45
  J4G2   64 VDD<23> SCONN288_H44441004_PIP-SCONN,HA   I169 @BASEBOARD_FAB2_LIB.BASEBOARD_FAB2(SCH_1):PAGE45
  J4G2   61 VDD<24> SCONN288_H44441004_PIP-SCONN,HA   I169 @BASEBOARD_FAB2_LIB.BASEBOARD_FAB2(SCH_1):PAGE45
  J4G2   59 VDD<25> SCONN288_H44441004_PIP-SCONN,HA   I169 @BASEBOARD_FAB2_LIB.BASEBOARD_FAB2(SCH_1):PAGE45
  J6U1  236 VDD<0> SCONN288_H44441003_PIP-SCONN,HA    I67 @BASEBOARD_FAB2_LIB.BASEBOARD_FAB2(SCH_1):PAGE46
  J6U1  233 VDD<1> SCONN288_H44441003_PIP-SCONN,HA    I67 @BASEBOARD_FAB2_LIB.BASEBOARD_FAB2(SCH_1):PAGE46
  J6U1  231 VDD<2> SCONN288_H44441003_PIP-SCONN,HA    I67 @BASEBOARD_FAB2_LIB.BASEBOARD_FAB2(SCH_1):PAGE46
  J6U1  229 VDD<3> SCONN288_H44441003_PIP-SCONN,HA    I67 @BASEBOARD_FAB2_LIB.BASEBOARD_FAB2(SCH_1):PAGE46
  J6U1  226 VDD<4> SCONN288_H44441003_PIP-SCONN,HA    I67 @BASEBOARD_FAB2_LIB.BASEBOARD_FAB2(SCH_1):PAGE46
  J6U1  223 VDD<5> SCONN288_H44441003_PIP-SCONN,HA    I67 @BASEBOARD_FAB2_LIB.BASEBOARD_FAB2(SCH_1):PAGE46
  J6U1  220 VDD<6> SCONN288_H44441003_PIP-SCONN,HA    I67 @BASEBOARD_FAB2_LIB.BASEBOARD_FAB2(SCH_1):PAGE46
  J6U1  217 VDD<7> SCONN288_H44441003_PIP-SCONN,HA    I67 @BASEBOARD_FAB2_LIB.BASEBOARD_FAB2(SCH_1):PAGE46
  J6U1  215 VDD<8> SCONN288_H44441003_PIP-SCONN,HA    I67 @BASEBOARD_FAB2_LIB.BASEBOARD_FAB2(SCH_1):PAGE46
  J6U1  212 VDD<9> SCONN288_H44441003_PIP-SCONN,HA    I67 @BASEBOARD_FAB2_LIB.BASEBOARD_FAB2(SCH_1):PAGE46
  J6U1  209 VDD<10> SCONN288_H44441003_PIP-SCONN,HA    I67 @BASEBOARD_FAB2_LIB.BASEBOARD_FAB2(SCH_1):PAGE46
  J6U1  206 VDD<11> SCONN288_H44441003_PIP-SCONN,HA    I67 @BASEBOARD_FAB2_LIB.BASEBOARD_FAB2(SCH_1):PAGE46
  J6U1  204 VDD<12> SCONN288_H44441003_PIP-SCONN,HA    I67 @BASEBOARD_FAB2_LIB.BASEBOARD_FAB2(SCH_1):PAGE46
  J6U1   92 VDD<13> SCONN288_H44441003_PIP-SCONN,HA    I67 @BASEBOARD_FAB2_LIB.BASEBOARD_FAB2(SCH_1):PAGE46
  J6U1   90 VDD<14> SCONN288_H44441003_PIP-SCONN,HA    I67 @BASEBOARD_FAB2_LIB.BASEBOARD_FAB2(SCH_1):PAGE46
  J6U1   88 VDD<15> SCONN288_H44441003_PIP-SCONN,HA    I67 @BASEBOARD_FAB2_LIB.BASEBOARD_FAB2(SCH_1):PAGE46
  J6U1   85 VDD<16> SCONN288_H44441003_PIP-SCONN,HA    I67 @BASEBOARD_FAB2_LIB.BASEBOARD_FAB2(SCH_1):PAGE46
  J6U1   83 VDD<17> SCONN288_H44441003_PIP-SCONN,HA    I67 @BASEBOARD_FAB2_LIB.BASEBOARD_FAB2(SCH_1):PAGE46
  J6U1   80 VDD<18> SCONN288_H44441003_PIP-SCONN,HA    I67 @BASEBOARD_FAB2_LIB.BASEBOARD_FAB2(SCH_1):PAGE46
  J6U1   76 VDD<19> SCONN288_H44441003_PIP-SCONN,HA    I67 @BASEBOARD_FAB2_LIB.BASEBOARD_FAB2(SCH_1):PAGE46
  J6U1   73 VDD<20> SCONN288_H44441003_PIP-SCONN,HA    I67 @BASEBOARD_FAB2_LIB.BASEBOARD_FAB2(SCH_1):PAGE46
  J6U1   70 VDD<21> SCONN288_H44441003_PIP-SCONN,HA    I67 @BASEBOARD_FAB2_LIB.BASEBOARD_FAB2(SCH_1):PAGE46
  J6U1   67 VDD<22> SCONN288_H44441003_PIP-SCONN,HA    I67 @BASEBOARD_FAB2_LIB.BASEBOARD_FAB2(SCH_1):PAGE46
  J6U1   64 VDD<23> SCONN288_H44441003_PIP-SCONN,HA    I67 @BASEBOARD_FAB2_LIB.BASEBOARD_FAB2(SCH_1):PAGE46
  J6U1   61 VDD<24> SCONN288_H44441003_PIP-SCONN,HA    I67 @BASEBOARD_FAB2_LIB.BASEBOARD_FAB2(SCH_1):PAGE46
  J6U1   59 VDD<25> SCONN288_H44441003_PIP-SCONN,HA    I67 @BASEBOARD_FAB2_LIB.BASEBOARD_FAB2(SCH_1):PAGE46
  J4G3  236 VDD<0> SCONN288_H44441004_PIP-SCONN,HA   I179 @BASEBOARD_FAB2_LIB.BASEBOARD_FAB2(SCH_1):PAGE47
  J4G3  233 VDD<1> SCONN288_H44441004_PIP-SCONN,HA   I179 @BASEBOARD_FAB2_LIB.BASEBOARD_FAB2(SCH_1):PAGE47
  J4G3  231 VDD<2> SCONN288_H44441004_PIP-SCONN,HA   I179 @BASEBOARD_FAB2_LIB.BASEBOARD_FAB2(SCH_1):PAGE47
  J4G3  229 VDD<3> SCONN288_H44441004_PIP-SCONN,HA   I179 @BASEBOARD_FAB2_LIB.BASEBOARD_FAB2(SCH_1):PAGE47
  J4G3  226 VDD<4> SCONN288_H44441004_PIP-SCONN,HA   I179 @BASEBOARD_FAB2_LIB.BASEBOARD_FAB2(SCH_1):PAGE47
  J4G3  223 VDD<5> SCONN288_H44441004_PIP-SCONN,HA   I179 @BASEBOARD_FAB2_LIB.BASEBOARD_FAB2(SCH_1):PAGE47
  J4G3  220 VDD<6> SCONN288_H44441004_PIP-SCONN,HA   I179 @BASEBOARD_FAB2_LIB.BASEBOARD_FAB2(SCH_1):PAGE47
  J4G3  217 VDD<7> SCONN288_H44441004_PIP-SCONN,HA   I179 @BASEBOARD_FAB2_LIB.BASEBOARD_FAB2(SCH_1):PAGE47
  J4G3  215 VDD<8> SCONN288_H44441004_PIP-SCONN,HA   I179 @BASEBOARD_FAB2_LIB.BASEBOARD_FAB2(SCH_1):PAGE47
  J4G3  212 VDD<9> SCONN288_H44441004_PIP-SCONN,HA   I179 @BASEBOARD_FAB2_LIB.BASEBOARD_FAB2(SCH_1):PAGE47
  J4G3  209 VDD<10> SCONN288_H44441004_PIP-SCONN,HA   I179 @BASEBOARD_FAB2_LIB.BASEBOARD_FAB2(SCH_1):PAGE47
  J4G3  206 VDD<11> SCONN288_H44441004_PIP-SCONN,HA   I179 @BASEBOARD_FAB2_LIB.BASEBOARD_FAB2(SCH_1):PAGE47
  J4G3  204 VDD<12> SCONN288_H44441004_PIP-SCONN,HA   I179 @BASEBOARD_FAB2_LIB.BASEBOARD_FAB2(SCH_1):PAGE47
  J4G3   92 VDD<13> SCONN288_H44441004_PIP-SCONN,HA   I179 @BASEBOARD_FAB2_LIB.BASEBOARD_FAB2(SCH_1):PAGE47
  J4G3   90 VDD<14> SCONN288_H44441004_PIP-SCONN,HA   I179 @BASEBOARD_FAB2_LIB.BASEBOARD_FAB2(SCH_1):PAGE47
  J4G3   88 VDD<15> SCONN288_H44441004_PIP-SCONN,HA   I179 @BASEBOARD_FAB2_LIB.BASEBOARD_FAB2(SCH_1):PAGE47
  J4G3   85 VDD<16> SCONN288_H44441004_PIP-SCONN,HA   I179 @BASEBOARD_FAB2_LIB.BASEBOARD_FAB2(SCH_1):PAGE47
  J4G3   83 VDD<17> SCONN288_H44441004_PIP-SCONN,HA   I179 @BASEBOARD_FAB2_LIB.BASEBOARD_FAB2(SCH_1):PAGE47
  J4G3   80 VDD<18> SCONN288_H44441004_PIP-SCONN,HA   I179 @BASEBOARD_FAB2_LIB.BASEBOARD_FAB2(SCH_1):PAGE47
  J4G3   76 VDD<19> SCONN288_H44441004_PIP-SCONN,HA   I179 @BASEBOARD_FAB2_LIB.BASEBOARD_FAB2(SCH_1):PAGE47
  J4G3   73 VDD<20> SCONN288_H44441004_PIP-SCONN,HA   I179 @BASEBOARD_FAB2_LIB.BASEBOARD_FAB2(SCH_1):PAGE47
  J4G3   70 VDD<21> SCONN288_H44441004_PIP-SCONN,HA   I179 @BASEBOARD_FAB2_LIB.BASEBOARD_FAB2(SCH_1):PAGE47
  J4G3   67 VDD<22> SCONN288_H44441004_PIP-SCONN,HA   I179 @BASEBOARD_FAB2_LIB.BASEBOARD_FAB2(SCH_1):PAGE47
  J4G3   64 VDD<23> SCONN288_H44441004_PIP-SCONN,HA   I179 @BASEBOARD_FAB2_LIB.BASEBOARD_FAB2(SCH_1):PAGE47
  J4G3   61 VDD<24> SCONN288_H44441004_PIP-SCONN,HA   I179 @BASEBOARD_FAB2_LIB.BASEBOARD_FAB2(SCH_1):PAGE47
  J4G3   59 VDD<25> SCONN288_H44441004_PIP-SCONN,HA   I179 @BASEBOARD_FAB2_LIB.BASEBOARD_FAB2(SCH_1):PAGE47
  J6U2  236 VDD<0> SCONN288_H44441003_PIP-SCONN,HA   I171 @BASEBOARD_FAB2_LIB.BASEBOARD_FAB2(SCH_1):PAGE48
  J6U2  233 VDD<1> SCONN288_H44441003_PIP-SCONN,HA   I171 @BASEBOARD_FAB2_LIB.BASEBOARD_FAB2(SCH_1):PAGE48
  J6U2  231 VDD<2> SCONN288_H44441003_PIP-SCONN,HA   I171 @BASEBOARD_FAB2_LIB.BASEBOARD_FAB2(SCH_1):PAGE48
  J6U2  229 VDD<3> SCONN288_H44441003_PIP-SCONN,HA   I171 @BASEBOARD_FAB2_LIB.BASEBOARD_FAB2(SCH_1):PAGE48
  J6U2  226 VDD<4> SCONN288_H44441003_PIP-SCONN,HA   I171 @BASEBOARD_FAB2_LIB.BASEBOARD_FAB2(SCH_1):PAGE48
  J6U2  223 VDD<5> SCONN288_H44441003_PIP-SCONN,HA   I171 @BASEBOARD_FAB2_LIB.BASEBOARD_FAB2(SCH_1):PAGE48
  J6U2  220 VDD<6> SCONN288_H44441003_PIP-SCONN,HA   I171 @BASEBOARD_FAB2_LIB.BASEBOARD_FAB2(SCH_1):PAGE48
  J6U2  217 VDD<7> SCONN288_H44441003_PIP-SCONN,HA   I171 @BASEBOARD_FAB2_LIB.BASEBOARD_FAB2(SCH_1):PAGE48
  J6U2  215 VDD<8> SCONN288_H44441003_PIP-SCONN,HA   I171 @BASEBOARD_FAB2_LIB.BASEBOARD_FAB2(SCH_1):PAGE48
  J6U2  212 VDD<9> SCONN288_H44441003_PIP-SCONN,HA   I171 @BASEBOARD_FAB2_LIB.BASEBOARD_FAB2(SCH_1):PAGE48
  J6U2  209 VDD<10> SCONN288_H44441003_PIP-SCONN,HA   I171 @BASEBOARD_FAB2_LIB.BASEBOARD_FAB2(SCH_1):PAGE48
  J6U2  206 VDD<11> SCONN288_H44441003_PIP-SCONN,HA   I171 @BASEBOARD_FAB2_LIB.BASEBOARD_FAB2(SCH_1):PAGE48
  J6U2  204 VDD<12> SCONN288_H44441003_PIP-SCONN,HA   I171 @BASEBOARD_FAB2_LIB.BASEBOARD_FAB2(SCH_1):PAGE48
  J6U2   92 VDD<13> SCONN288_H44441003_PIP-SCONN,HA   I171 @BASEBOARD_FAB2_LIB.BASEBOARD_FAB2(SCH_1):PAGE48
  J6U2   90 VDD<14> SCONN288_H44441003_PIP-SCONN,HA   I171 @BASEBOARD_FAB2_LIB.BASEBOARD_FAB2(SCH_1):PAGE48
  J6U2   88 VDD<15> SCONN288_H44441003_PIP-SCONN,HA   I171 @BASEBOARD_FAB2_LIB.BASEBOARD_FAB2(SCH_1):PAGE48
  J6U2   85 VDD<16> SCONN288_H44441003_PIP-SCONN,HA   I171 @BASEBOARD_FAB2_LIB.BASEBOARD_FAB2(SCH_1):PAGE48
  J6U2   83 VDD<17> SCONN288_H44441003_PIP-SCONN,HA   I171 @BASEBOARD_FAB2_LIB.BASEBOARD_FAB2(SCH_1):PAGE48
  J6U2   80 VDD<18> SCONN288_H44441003_PIP-SCONN,HA   I171 @BASEBOARD_FAB2_LIB.BASEBOARD_FAB2(SCH_1):PAGE48
  J6U2   76 VDD<19> SCONN288_H44441003_PIP-SCONN,HA   I171 @BASEBOARD_FAB2_LIB.BASEBOARD_FAB2(SCH_1):PAGE48
  J6U2   73 VDD<20> SCONN288_H44441003_PIP-SCONN,HA   I171 @BASEBOARD_FAB2_LIB.BASEBOARD_FAB2(SCH_1):PAGE48
  J6U2   70 VDD<21> SCONN288_H44441003_PIP-SCONN,HA   I171 @BASEBOARD_FAB2_LIB.BASEBOARD_FAB2(SCH_1):PAGE48
  J6U2   67 VDD<22> SCONN288_H44441003_PIP-SCONN,HA   I171 @BASEBOARD_FAB2_LIB.BASEBOARD_FAB2(SCH_1):PAGE48
  J6U2   64 VDD<23> SCONN288_H44441003_PIP-SCONN,HA   I171 @BASEBOARD_FAB2_LIB.BASEBOARD_FAB2(SCH_1):PAGE48
  J6U2   61 VDD<24> SCONN288_H44441003_PIP-SCONN,HA   I171 @BASEBOARD_FAB2_LIB.BASEBOARD_FAB2(SCH_1):PAGE48
  J6U2   59 VDD<25> SCONN288_H44441003_PIP-SCONN,HA   I171 @BASEBOARD_FAB2_LIB.BASEBOARD_FAB2(SCH_1):PAGE48
 R3P38    1      A RES_0402-64.9,1.0%,1/16W,CHIP,A     I7 @BASEBOARD_FAB2_LIB.BASEBOARD_FAB2(SCH_1):PAGE96
  R4F4    1      A RES_0402-1.00K,1%,1/16W,CHIP,GA    I36 @BASEBOARD_FAB2_LIB.BASEBOARD_FAB2(SCH_1):PAGE98
  R4G2    1      A RES_0402-1.00K,1%,1/16W,CHIP,GA    I38 @BASEBOARD_FAB2_LIB.BASEBOARD_FAB2(SCH_1):PAGE98
 R4G21    1      A RES_0402-1.00K,1%,1/16W,CHIP,GA    I46 @BASEBOARD_FAB2_LIB.BASEBOARD_FAB2(SCH_1):PAGE98
  C6G3    1      A CAP_0805LF-22UF,4V,20%,X6S,C95A     I6 @BASEBOARD_FAB2_LIB.BASEBOARD_FAB2(SCH_1):PAGE216
  L7G2    2    INB INDUCTOR_SM-0.12UH,IND,D92183-A    I65 @BASEBOARD_FAB2_LIB.BASEBOARD_FAB2(SCH_1):PAGE216
 C7G27    1      A CAP_0805LF-22UF,4V,20%,X6S,C95A    I68 @BASEBOARD_FAB2_LIB.BASEBOARD_FAB2(SCH_1):PAGE216
 EU7G2    1    VOS IR354XX_SM-IR35411,IC,H73688-0A   I102 @BASEBOARD_FAB2_LIB.BASEBOARD_FAB2(SCH_1):PAGE216
 EU7G3    1    VOS IR354XX_SM-IR35411,IC,H73688-0A   I103 @BASEBOARD_FAB2_LIB.BASEBOARD_FAB2(SCH_1):PAGE216
  R3U4    1      A RES_0603-120.0,1%,1/10W,CHIP,GA    I58 @BASEBOARD_FAB2_LIB.BASEBOARD_FAB2(SCH_1):PAGE217
 C7G28    1      A CAPP_3018-470UF,2.5V,20%,ALUM,A    I75 @BASEBOARD_FAB2_LIB.BASEBOARD_FAB2(SCH_1):PAGE217
  C3U1    1      A CAPP_3018-470UF,2.5V,20%,ALUM,A    I76 @BASEBOARD_FAB2_LIB.BASEBOARD_FAB2(SCH_1):PAGE217
  C3U5    1      A CAPP_3018-470UF,2.5V,20%,ALUM,A    I77 @BASEBOARD_FAB2_LIB.BASEBOARD_FAB2(SCH_1):PAGE217
  C3U8    1      A CAPP_3018-470UF,2.5V,20%,ALUM,A    I78 @BASEBOARD_FAB2_LIB.BASEBOARD_FAB2(SCH_1):PAGE217
 C5U13    1      A CAP_0805-100UF,4V,20%,X5R,6024A    I82 @BASEBOARD_FAB2_LIB.BASEBOARD_FAB2(SCH_1):PAGE217
 C5U10    1      A CAP_0805-100UF,4V,20%,X5R,6024A    I83 @BASEBOARD_FAB2_LIB.BASEBOARD_FAB2(SCH_1):PAGE217
  C5U1    1      A CAP_0805-100UF,4V,20%,X5R,6024A    I88 @BASEBOARD_FAB2_LIB.BASEBOARD_FAB2(SCH_1):PAGE217
 C5U14    1      A CAP_0805-100UF,4V,20%,X5R,6024A    I89 @BASEBOARD_FAB2_LIB.BASEBOARD_FAB2(SCH_1):PAGE217
 C5U15    1      A CAP_0805-100UF,4V,20%,X5R,6024A    I90 @BASEBOARD_FAB2_LIB.BASEBOARD_FAB2(SCH_1):PAGE217
  C4T4    1      A CAP_0805-100UF,4V,20%,X5R,6024A    I91 @BASEBOARD_FAB2_LIB.BASEBOARD_FAB2(SCH_1):PAGE217
  C5G9    1      A CAP_0805-100UF,4V,20%,X5R,6024A    I92 @BASEBOARD_FAB2_LIB.BASEBOARD_FAB2(SCH_1):PAGE217
 C5G20    1      A CAP_0805-100UF,4V,20%,X5R,6024A   I110 @BASEBOARD_FAB2_LIB.BASEBOARD_FAB2(SCH_1):PAGE217
 C5P39    1      A CAP_0805LF-22UF,4V,20%,X6S,C95A   I184 @BASEBOARD_FAB2_LIB.BASEBOARD_FAB2(SCH_1):PAGE217
 C5D57    1      A CAP_0603LF-10UF,4V,20%,X6S,E15A   I186 @BASEBOARD_FAB2_LIB.BASEBOARD_FAB2(SCH_1):PAGE217
 C5D56    1      A CAP_0603LF-10UF,4V,20%,X6S,E15A   I188 @BASEBOARD_FAB2_LIB.BASEBOARD_FAB2(SCH_1):PAGE217
 C5D55    1      A CAP_0603LF-10UF,4V,20%,X6S,E15A   I189 @BASEBOARD_FAB2_LIB.BASEBOARD_FAB2(SCH_1):PAGE217
 C5D54    1      A CAP_0603LF-10UF,4V,20%,X6S,E15A   I190 @BASEBOARD_FAB2_LIB.BASEBOARD_FAB2(SCH_1):PAGE217
 C5P38    1      A CAP_0805LF-22UF,4V,20%,X6S,C95A   I193 @BASEBOARD_FAB2_LIB.BASEBOARD_FAB2(SCH_1):PAGE217
  C5F2    1      A CAP_A_0603V-47UF,4V,20%,X5R,60A   I205 @BASEBOARD_FAB2_LIB.BASEBOARD_FAB2(SCH_1):PAGE217
  C5F1    1      A CAP_A_0603V-47UF,4V,20%,X5R,60A   I206 @BASEBOARD_FAB2_LIB.BASEBOARD_FAB2(SCH_1):PAGE217
 C5G10    1      A CAP_A_0603V-47UF,4V,20%,X5R,60A   I207 @BASEBOARD_FAB2_LIB.BASEBOARD_FAB2(SCH_1):PAGE217
  C5T2    1      A CAP_A_0603V-47UF,4V,20%,X5R,60A   I208 @BASEBOARD_FAB2_LIB.BASEBOARD_FAB2(SCH_1):PAGE217
 C5U11    1      A CAP_A_0603V-47UF,4V,20%,X5R,60A   I209 @BASEBOARD_FAB2_LIB.BASEBOARD_FAB2(SCH_1):PAGE217
 C5T13    1      A CAP_A_0603V-47UF,4V,20%,X5R,60A   I210 @BASEBOARD_FAB2_LIB.BASEBOARD_FAB2(SCH_1):PAGE217
  C5T4    1      A CAP_A_0603V-47UF,4V,20%,X5R,60A   I211 @BASEBOARD_FAB2_LIB.BASEBOARD_FAB2(SCH_1):PAGE217
  C5T1    1      A CAP_A_0603V-47UF,4V,20%,X5R,60A   I212 @BASEBOARD_FAB2_LIB.BASEBOARD_FAB2(SCH_1):PAGE217
 C5G19    1      A CAP_A_0603V-47UF,4V,20%,X5R,60A   I213 @BASEBOARD_FAB2_LIB.BASEBOARD_FAB2(SCH_1):PAGE217
  C5T5    1      A CAP_A_0603V-22.0UF,4V,20%,X6S,A   I216 @BASEBOARD_FAB2_LIB.BASEBOARD_FAB2(SCH_1):PAGE217
  C5G3    1      A CAP_A_0603V-22.0UF,4V,20%,X6S,A   I217 @BASEBOARD_FAB2_LIB.BASEBOARD_FAB2(SCH_1):PAGE217
  C5T6    1      A CAP_A_0603V-22.0UF,4V,20%,X6S,A   I218 @BASEBOARD_FAB2_LIB.BASEBOARD_FAB2(SCH_1):PAGE217
  C5T7    1      A CAP_A_0603V-22.0UF,4V,20%,X6S,A   I219 @BASEBOARD_FAB2_LIB.BASEBOARD_FAB2(SCH_1):PAGE217
 C5G15    1      A CAP_A_0603V-22.0UF,4V,20%,X6S,A   I220 @BASEBOARD_FAB2_LIB.BASEBOARD_FAB2(SCH_1):PAGE217
 C5G16    1      A CAP_A_0603V-22.0UF,4V,20%,X6S,A   I221 @BASEBOARD_FAB2_LIB.BASEBOARD_FAB2(SCH_1):PAGE217
  C5T8    1      A CAP_A_0603V-22.0UF,4V,20%,X6S,A   I222 @BASEBOARD_FAB2_LIB.BASEBOARD_FAB2(SCH_1):PAGE217
 C5G14    1      A CAP_A_0603V-22.0UF,4V,20%,X6S,A   I223 @BASEBOARD_FAB2_LIB.BASEBOARD_FAB2(SCH_1):PAGE217
  C5T9    1      A CAP_A_0603V-22.0UF,4V,20%,X6S,A   I224 @BASEBOARD_FAB2_LIB.BASEBOARD_FAB2(SCH_1):PAGE217
 C5T10    1      A CAP_A_0603V-22.0UF,4V,20%,X6S,A   I225 @BASEBOARD_FAB2_LIB.BASEBOARD_FAB2(SCH_1):PAGE217
 C5G17    1      A CAP_A_0603V-22.0UF,4V,20%,X6S,A   I226 @BASEBOARD_FAB2_LIB.BASEBOARD_FAB2(SCH_1):PAGE217
 C5G18    1      A CAP_A_0603V-22.0UF,4V,20%,X6S,A   I227 @BASEBOARD_FAB2_LIB.BASEBOARD_FAB2(SCH_1):PAGE217
 C5T11    1      A CAP_A_0603V-22.0UF,4V,20%,X6S,A   I228 @BASEBOARD_FAB2_LIB.BASEBOARD_FAB2(SCH_1):PAGE217
 C5T12    1      A CAP_A_0603V-22.0UF,4V,20%,X6S,A   I229 @BASEBOARD_FAB2_LIB.BASEBOARD_FAB2(SCH_1):PAGE217
  C5G8    1      A CAP_A_0603V-22.0UF,4V,20%,X6S,A   I230 @BASEBOARD_FAB2_LIB.BASEBOARD_FAB2(SCH_1):PAGE217
  C5G1    1      A CAP_A_0603V-22.0UF,4V,20%,X6S,A   I231 @BASEBOARD_FAB2_LIB.BASEBOARD_FAB2(SCH_1):PAGE217
  C5U9    1      A CAP_A_0603V-22.0UF,4V,20%,X6S,A   I232 @BASEBOARD_FAB2_LIB.BASEBOARD_FAB2(SCH_1):PAGE217
  C5U8    1      A CAP_A_0603V-22.0UF,4V,20%,X6S,A   I233 @BASEBOARD_FAB2_LIB.BASEBOARD_FAB2(SCH_1):PAGE217
  C5G7    1      A CAP_A_0603V-22.0UF,4V,20%,X6S,A   I234 @BASEBOARD_FAB2_LIB.BASEBOARD_FAB2(SCH_1):PAGE217
  C5G5    1      A CAP_A_0603V-22.0UF,4V,20%,X6S,A   I235 @BASEBOARD_FAB2_LIB.BASEBOARD_FAB2(SCH_1):PAGE217
  C5U7    1      A CAP_A_0603V-22.0UF,4V,20%,X6S,A   I236 @BASEBOARD_FAB2_LIB.BASEBOARD_FAB2(SCH_1):PAGE217
  C5G6    1      A CAP_A_0603V-22.0UF,4V,20%,X6S,A   I237 @BASEBOARD_FAB2_LIB.BASEBOARD_FAB2(SCH_1):PAGE217
  C5U6    1      A CAP_A_0603V-22.0UF,4V,20%,X6S,A   I238 @BASEBOARD_FAB2_LIB.BASEBOARD_FAB2(SCH_1):PAGE217
  C5U5    1      A CAP_A_0603V-22.0UF,4V,20%,X6S,A   I239 @BASEBOARD_FAB2_LIB.BASEBOARD_FAB2(SCH_1):PAGE217
 C5G13    1      A CAP_A_0603V-22.0UF,4V,20%,X6S,A   I240 @BASEBOARD_FAB2_LIB.BASEBOARD_FAB2(SCH_1):PAGE217
  C5G4    1      A CAP_A_0603V-22.0UF,4V,20%,X6S,A   I241 @BASEBOARD_FAB2_LIB.BASEBOARD_FAB2(SCH_1):PAGE217
  C5U4    1      A CAP_A_0603V-22.0UF,4V,20%,X6S,A   I243 @BASEBOARD_FAB2_LIB.BASEBOARD_FAB2(SCH_1):PAGE217
  C5U3    1      A CAP_A_0603V-22.0UF,4V,20%,X6S,A   I244 @BASEBOARD_FAB2_LIB.BASEBOARD_FAB2(SCH_1):PAGE217
  C5G2    1      A CAP_A_0603V-22.0UF,4V,20%,X6S,A   I245 @BASEBOARD_FAB2_LIB.BASEBOARD_FAB2(SCH_1):PAGE217
 C5G12    1      A CAP_A_0603V-22.0UF,4V,20%,X6S,A   I246 @BASEBOARD_FAB2_LIB.BASEBOARD_FAB2(SCH_1):PAGE217
  C5U2    1      A CAP_A_0603V-22.0UF,4V,20%,X6S,A   I247 @BASEBOARD_FAB2_LIB.BASEBOARD_FAB2(SCH_1):PAGE217
 C5G11    1      A CAP_A_0603V-22.0UF,4V,20%,X6S,A   I250 @BASEBOARD_FAB2_LIB.BASEBOARD_FAB2(SCH_1):PAGE217
 SH4U2    2      B SHUNT_SH0201-EMPTY,N_A   I260 @BASEBOARD_FAB2_LIB.BASEBOARD_FAB2(SCH_1):PAGE217
 EU4G3   10    VIN MIC5166_DFN-IC,H55101-001     I1 @BASEBOARD_FAB2_LIB.BASEBOARD_FAB2(SCH_1):PAGE221
 C6U16    1      A CAP_0603LF-10UF,4V,20%,X6S,E15A    I22 @BASEBOARD_FAB2_LIB.BASEBOARD_FAB2(SCH_1):PAGE221
 C6U15    1      A CAP_0603LF-10UF,4V,20%,X6S,E15A    I26 @BASEBOARD_FAB2_LIB.BASEBOARD_FAB2(SCH_1):PAGE221
  R6U5    1      A RES_0402-0.0,5%,1/16W,CHIP,G21A    I32 @BASEBOARD_FAB2_LIB.BASEBOARD_FAB2(SCH_1):PAGE221
 C5G21    1      A CAP_0805-100UF,4V,20%,X5R,6024A    I11 @BASEBOARD_FAB2_LIB.BASEBOARD_FAB2(SCH_1):PAGE242
 C5G22    1      A CAP_0805-100UF,4V,20%,X5R,6024A    I15 @BASEBOARD_FAB2_LIB.BASEBOARD_FAB2(SCH_1):PAGE242
 C5G41    1      A CAP_A_0603V-22.0UF,4V,20%,X6S,A    I53 @BASEBOARD_FAB2_LIB.BASEBOARD_FAB2(SCH_1):PAGE242
 C5G42    1      A CAP_A_0603V-22.0UF,4V,20%,X6S,A    I54 @BASEBOARD_FAB2_LIB.BASEBOARD_FAB2(SCH_1):PAGE242
 C5G44    1      A CAP_A_0603V-22.0UF,4V,20%,X6S,A    I55 @BASEBOARD_FAB2_LIB.BASEBOARD_FAB2(SCH_1):PAGE242
 C5G43    1      A CAP_A_0603V-22.0UF,4V,20%,X6S,A    I56 @BASEBOARD_FAB2_LIB.BASEBOARD_FAB2(SCH_1):PAGE242
 C5G48    1      A CAP_A_0603V-22.0UF,4V,20%,X6S,A    I57 @BASEBOARD_FAB2_LIB.BASEBOARD_FAB2(SCH_1):PAGE242
 C5G47    1      A CAP_A_0603V-22.0UF,4V,20%,X6S,A    I58 @BASEBOARD_FAB2_LIB.BASEBOARD_FAB2(SCH_1):PAGE242
 C5G46    1      A CAP_A_0603V-22.0UF,4V,20%,X6S,A    I59 @BASEBOARD_FAB2_LIB.BASEBOARD_FAB2(SCH_1):PAGE242
 C5G45    1      A CAP_A_0603V-22.0UF,4V,20%,X6S,A    I60 @BASEBOARD_FAB2_LIB.BASEBOARD_FAB2(SCH_1):PAGE242
 C5G49    1      A CAP_A_0603V-22.0UF,4V,20%,X6S,A    I61 @BASEBOARD_FAB2_LIB.BASEBOARD_FAB2(SCH_1):PAGE242
 C5G54    1      A CAP_A_0603V-22.0UF,4V,20%,X6S,A    I62 @BASEBOARD_FAB2_LIB.BASEBOARD_FAB2(SCH_1):PAGE242
 C5G58    1      A CAP_A_0603V-22.0UF,4V,20%,X6S,A    I63 @BASEBOARD_FAB2_LIB.BASEBOARD_FAB2(SCH_1):PAGE242
 C5G57    1      A CAP_A_0603V-22.0UF,4V,20%,X6S,A    I64 @BASEBOARD_FAB2_LIB.BASEBOARD_FAB2(SCH_1):PAGE242
 C5G56    1      A CAP_A_0603V-22.0UF,4V,20%,X6S,A    I65 @BASEBOARD_FAB2_LIB.BASEBOARD_FAB2(SCH_1):PAGE242
 C5G55    1      A CAP_A_0603V-22.0UF,4V,20%,X6S,A    I66 @BASEBOARD_FAB2_LIB.BASEBOARD_FAB2(SCH_1):PAGE242
 C5G53    1      A CAP_A_0603V-22.0UF,4V,20%,X6S,A    I67 @BASEBOARD_FAB2_LIB.BASEBOARD_FAB2(SCH_1):PAGE242
 C5G52    1      A CAP_A_0603V-22.0UF,4V,20%,X6S,A    I68 @BASEBOARD_FAB2_LIB.BASEBOARD_FAB2(SCH_1):PAGE242
 C5G51    1      A CAP_A_0603V-22.0UF,4V,20%,X6S,A    I69 @BASEBOARD_FAB2_LIB.BASEBOARD_FAB2(SCH_1):PAGE242
 C5G50    1      A CAP_A_0603V-22.0UF,4V,20%,X6S,A    I70 @BASEBOARD_FAB2_LIB.BASEBOARD_FAB2(SCH_1):PAGE242
  L7G1    2    INB INDUCTOR_SM-0.12UH,IND,D92183-A   I125 @BASEBOARD_FAB2_LIB.BASEBOARD_FAB2(SCH_1):PAGE216

PVDDQ_DEF @BASEBOARD_FAB2_LIB.BASEBOARD_FAB2(SCH_1):PVDDQ_DEF
  U5D1 EF59 VCCD345<0> SKX_EXT_B_BGA1-IC,TBD    I33 @BASEBOARD_FAB2_LIB.BASEBOARD_FAB2(SCH_1):PAGE38
  U5D1 EF53 VCCD345<1> SKX_EXT_B_BGA1-IC,TBD    I33 @BASEBOARD_FAB2_LIB.BASEBOARD_FAB2(SCH_1):PAGE38
  U5D1 EF49 VCCD345<2> SKX_EXT_B_BGA1-IC,TBD    I33 @BASEBOARD_FAB2_LIB.BASEBOARD_FAB2(SCH_1):PAGE38
  U5D1 EC62 VCCD345<3> SKX_EXT_B_BGA1-IC,TBD    I33 @BASEBOARD_FAB2_LIB.BASEBOARD_FAB2(SCH_1):PAGE38
  U5D1 EC60 VCCD345<4> SKX_EXT_B_BGA1-IC,TBD    I33 @BASEBOARD_FAB2_LIB.BASEBOARD_FAB2(SCH_1):PAGE38
  U5D1 EC58 VCCD345<5> SKX_EXT_B_BGA1-IC,TBD    I33 @BASEBOARD_FAB2_LIB.BASEBOARD_FAB2(SCH_1):PAGE38
  U5D1 EC56 VCCD345<6> SKX_EXT_B_BGA1-IC,TBD    I33 @BASEBOARD_FAB2_LIB.BASEBOARD_FAB2(SCH_1):PAGE38
  U5D1 EC54 VCCD345<7> SKX_EXT_B_BGA1-IC,TBD    I33 @BASEBOARD_FAB2_LIB.BASEBOARD_FAB2(SCH_1):PAGE38
  U5D1 EC52 VCCD345<8> SKX_EXT_B_BGA1-IC,TBD    I33 @BASEBOARD_FAB2_LIB.BASEBOARD_FAB2(SCH_1):PAGE38
  U5D1 EC50 VCCD345<9> SKX_EXT_B_BGA1-IC,TBD    I33 @BASEBOARD_FAB2_LIB.BASEBOARD_FAB2(SCH_1):PAGE38
  U5D1 EC48 VCCD345<10> SKX_EXT_B_BGA1-IC,TBD    I33 @BASEBOARD_FAB2_LIB.BASEBOARD_FAB2(SCH_1):PAGE38
  U5D1 EC46 VCCD345<11> SKX_EXT_B_BGA1-IC,TBD    I33 @BASEBOARD_FAB2_LIB.BASEBOARD_FAB2(SCH_1):PAGE38
  U5D1 DU64 VCCD345<12> SKX_EXT_B_BGA1-IC,TBD    I33 @BASEBOARD_FAB2_LIB.BASEBOARD_FAB2(SCH_1):PAGE38
  U5D1 DU62 VCCD345<13> SKX_EXT_B_BGA1-IC,TBD    I33 @BASEBOARD_FAB2_LIB.BASEBOARD_FAB2(SCH_1):PAGE38
  U5D1 DU60 VCCD345<14> SKX_EXT_B_BGA1-IC,TBD    I33 @BASEBOARD_FAB2_LIB.BASEBOARD_FAB2(SCH_1):PAGE38
  U5D1 DU58 VCCD345<15> SKX_EXT_B_BGA1-IC,TBD    I33 @BASEBOARD_FAB2_LIB.BASEBOARD_FAB2(SCH_1):PAGE38
  U5D1 DU56 VCCD345<16> SKX_EXT_B_BGA1-IC,TBD    I33 @BASEBOARD_FAB2_LIB.BASEBOARD_FAB2(SCH_1):PAGE38
  U5D1 DU54 VCCD345<17> SKX_EXT_B_BGA1-IC,TBD    I33 @BASEBOARD_FAB2_LIB.BASEBOARD_FAB2(SCH_1):PAGE38
  U5D1 DU52 VCCD345<18> SKX_EXT_B_BGA1-IC,TBD    I33 @BASEBOARD_FAB2_LIB.BASEBOARD_FAB2(SCH_1):PAGE38
  U5D1 DU50 VCCD345<19> SKX_EXT_B_BGA1-IC,TBD    I33 @BASEBOARD_FAB2_LIB.BASEBOARD_FAB2(SCH_1):PAGE38
  U5D1 DU48 VCCD345<20> SKX_EXT_B_BGA1-IC,TBD    I33 @BASEBOARD_FAB2_LIB.BASEBOARD_FAB2(SCH_1):PAGE38
  U5D1 DU46 VCCD345<21> SKX_EXT_B_BGA1-IC,TBD    I33 @BASEBOARD_FAB2_LIB.BASEBOARD_FAB2(SCH_1):PAGE38
  U5D1 DL62 VCCD345<22> SKX_EXT_B_BGA1-IC,TBD    I33 @BASEBOARD_FAB2_LIB.BASEBOARD_FAB2(SCH_1):PAGE38
  U5D1 DL60 VCCD345<23> SKX_EXT_B_BGA1-IC,TBD    I33 @BASEBOARD_FAB2_LIB.BASEBOARD_FAB2(SCH_1):PAGE38
  U5D1 DL58 VCCD345<24> SKX_EXT_B_BGA1-IC,TBD    I33 @BASEBOARD_FAB2_LIB.BASEBOARD_FAB2(SCH_1):PAGE38
  U5D1 DL56 VCCD345<25> SKX_EXT_B_BGA1-IC,TBD    I33 @BASEBOARD_FAB2_LIB.BASEBOARD_FAB2(SCH_1):PAGE38
  U5D1 DL54 VCCD345<26> SKX_EXT_B_BGA1-IC,TBD    I33 @BASEBOARD_FAB2_LIB.BASEBOARD_FAB2(SCH_1):PAGE38
  U5D1 DL52 VCCD345<27> SKX_EXT_B_BGA1-IC,TBD    I33 @BASEBOARD_FAB2_LIB.BASEBOARD_FAB2(SCH_1):PAGE38
  U5D1 DL50 VCCD345<28> SKX_EXT_B_BGA1-IC,TBD    I33 @BASEBOARD_FAB2_LIB.BASEBOARD_FAB2(SCH_1):PAGE38
  U5D1 DL48 VCCD345<29> SKX_EXT_B_BGA1-IC,TBD    I33 @BASEBOARD_FAB2_LIB.BASEBOARD_FAB2(SCH_1):PAGE38
  U5D1 DL46 VCCD345<30> SKX_EXT_B_BGA1-IC,TBD    I33 @BASEBOARD_FAB2_LIB.BASEBOARD_FAB2(SCH_1):PAGE38
  U5D1 DJ64 VCCD345<31> SKX_EXT_B_BGA1-IC,TBD    I33 @BASEBOARD_FAB2_LIB.BASEBOARD_FAB2(SCH_1):PAGE38
  U5D1 DH63 VCCD345<32> SKX_EXT_B_BGA1-IC,TBD    I33 @BASEBOARD_FAB2_LIB.BASEBOARD_FAB2(SCH_1):PAGE38
  U5D1 DH61 VCCD345<33> SKX_EXT_B_BGA1-IC,TBD    I33 @BASEBOARD_FAB2_LIB.BASEBOARD_FAB2(SCH_1):PAGE38
  U5D1 DH59 VCCD345<34> SKX_EXT_B_BGA1-IC,TBD    I33 @BASEBOARD_FAB2_LIB.BASEBOARD_FAB2(SCH_1):PAGE38
  U5D1 DH57 VCCD345<35> SKX_EXT_B_BGA1-IC,TBD    I33 @BASEBOARD_FAB2_LIB.BASEBOARD_FAB2(SCH_1):PAGE38
  U5D1 DH55 VCCD345<36> SKX_EXT_B_BGA1-IC,TBD    I33 @BASEBOARD_FAB2_LIB.BASEBOARD_FAB2(SCH_1):PAGE38
  U5D1 DH53 VCCD345<37> SKX_EXT_B_BGA1-IC,TBD    I33 @BASEBOARD_FAB2_LIB.BASEBOARD_FAB2(SCH_1):PAGE38
  U5D1 DH51 VCCD345<38> SKX_EXT_B_BGA1-IC,TBD    I33 @BASEBOARD_FAB2_LIB.BASEBOARD_FAB2(SCH_1):PAGE38
  U5D1 DH49 VCCD345<39> SKX_EXT_B_BGA1-IC,TBD    I33 @BASEBOARD_FAB2_LIB.BASEBOARD_FAB2(SCH_1):PAGE38
  U5D1 DH47 VCCD345<40> SKX_EXT_B_BGA1-IC,TBD    I33 @BASEBOARD_FAB2_LIB.BASEBOARD_FAB2(SCH_1):PAGE38
  U5D1 DH45 VCCD345<41> SKX_EXT_B_BGA1-IC,TBD    I33 @BASEBOARD_FAB2_LIB.BASEBOARD_FAB2(SCH_1):PAGE38
  U5D1 DD45 VCCD345<42> SKX_EXT_B_BGA1-IC,TBD    I33 @BASEBOARD_FAB2_LIB.BASEBOARD_FAB2(SCH_1):PAGE38
  U5D1 DB63 VCCD345<43> SKX_EXT_B_BGA1-IC,TBD    I33 @BASEBOARD_FAB2_LIB.BASEBOARD_FAB2(SCH_1):PAGE38
  U5D1 DB61 VCCD345<44> SKX_EXT_B_BGA1-IC,TBD    I33 @BASEBOARD_FAB2_LIB.BASEBOARD_FAB2(SCH_1):PAGE38
  U5D1 DB59 VCCD345<45> SKX_EXT_B_BGA1-IC,TBD    I33 @BASEBOARD_FAB2_LIB.BASEBOARD_FAB2(SCH_1):PAGE38
  U5D1 DB57 VCCD345<46> SKX_EXT_B_BGA1-IC,TBD    I33 @BASEBOARD_FAB2_LIB.BASEBOARD_FAB2(SCH_1):PAGE38
  U5D1 DB55 VCCD345<47> SKX_EXT_B_BGA1-IC,TBD    I33 @BASEBOARD_FAB2_LIB.BASEBOARD_FAB2(SCH_1):PAGE38
  U5D1 DB53 VCCD345<48> SKX_EXT_B_BGA1-IC,TBD    I33 @BASEBOARD_FAB2_LIB.BASEBOARD_FAB2(SCH_1):PAGE38
  U5D1 EF45 VCCD345<49> SKX_EXT_B_BGA1-IC,TBD    I33 @BASEBOARD_FAB2_LIB.BASEBOARD_FAB2(SCH_1):PAGE38
  U5D1 EE44 VCCD345<50> SKX_EXT_B_BGA1-IC,TBD    I33 @BASEBOARD_FAB2_LIB.BASEBOARD_FAB2(SCH_1):PAGE38
  J4B1  236 VDD<0> SCONN288_H44441004_PIP-SCONN,HA   I169 @BASEBOARD_FAB2_LIB.BASEBOARD_FAB2(SCH_1):PAGE49
  J4B1  233 VDD<1> SCONN288_H44441004_PIP-SCONN,HA   I169 @BASEBOARD_FAB2_LIB.BASEBOARD_FAB2(SCH_1):PAGE49
  J4B1  231 VDD<2> SCONN288_H44441004_PIP-SCONN,HA   I169 @BASEBOARD_FAB2_LIB.BASEBOARD_FAB2(SCH_1):PAGE49
  J4B1  229 VDD<3> SCONN288_H44441004_PIP-SCONN,HA   I169 @BASEBOARD_FAB2_LIB.BASEBOARD_FAB2(SCH_1):PAGE49
  J4B1  226 VDD<4> SCONN288_H44441004_PIP-SCONN,HA   I169 @BASEBOARD_FAB2_LIB.BASEBOARD_FAB2(SCH_1):PAGE49
  J4B1  223 VDD<5> SCONN288_H44441004_PIP-SCONN,HA   I169 @BASEBOARD_FAB2_LIB.BASEBOARD_FAB2(SCH_1):PAGE49
  J4B1  220 VDD<6> SCONN288_H44441004_PIP-SCONN,HA   I169 @BASEBOARD_FAB2_LIB.BASEBOARD_FAB2(SCH_1):PAGE49
  J4B1  217 VDD<7> SCONN288_H44441004_PIP-SCONN,HA   I169 @BASEBOARD_FAB2_LIB.BASEBOARD_FAB2(SCH_1):PAGE49
  J4B1  215 VDD<8> SCONN288_H44441004_PIP-SCONN,HA   I169 @BASEBOARD_FAB2_LIB.BASEBOARD_FAB2(SCH_1):PAGE49
  J4B1  212 VDD<9> SCONN288_H44441004_PIP-SCONN,HA   I169 @BASEBOARD_FAB2_LIB.BASEBOARD_FAB2(SCH_1):PAGE49
  J4B1  209 VDD<10> SCONN288_H44441004_PIP-SCONN,HA   I169 @BASEBOARD_FAB2_LIB.BASEBOARD_FAB2(SCH_1):PAGE49
  J4B1  206 VDD<11> SCONN288_H44441004_PIP-SCONN,HA   I169 @BASEBOARD_FAB2_LIB.BASEBOARD_FAB2(SCH_1):PAGE49
  J4B1  204 VDD<12> SCONN288_H44441004_PIP-SCONN,HA   I169 @BASEBOARD_FAB2_LIB.BASEBOARD_FAB2(SCH_1):PAGE49
  J4B1   92 VDD<13> SCONN288_H44441004_PIP-SCONN,HA   I169 @BASEBOARD_FAB2_LIB.BASEBOARD_FAB2(SCH_1):PAGE49
  J4B1   90 VDD<14> SCONN288_H44441004_PIP-SCONN,HA   I169 @BASEBOARD_FAB2_LIB.BASEBOARD_FAB2(SCH_1):PAGE49
  J4B1   88 VDD<15> SCONN288_H44441004_PIP-SCONN,HA   I169 @BASEBOARD_FAB2_LIB.BASEBOARD_FAB2(SCH_1):PAGE49
  J4B1   85 VDD<16> SCONN288_H44441004_PIP-SCONN,HA   I169 @BASEBOARD_FAB2_LIB.BASEBOARD_FAB2(SCH_1):PAGE49
  J4B1   83 VDD<17> SCONN288_H44441004_PIP-SCONN,HA   I169 @BASEBOARD_FAB2_LIB.BASEBOARD_FAB2(SCH_1):PAGE49
  J4B1   80 VDD<18> SCONN288_H44441004_PIP-SCONN,HA   I169 @BASEBOARD_FAB2_LIB.BASEBOARD_FAB2(SCH_1):PAGE49
  J4B1   76 VDD<19> SCONN288_H44441004_PIP-SCONN,HA   I169 @BASEBOARD_FAB2_LIB.BASEBOARD_FAB2(SCH_1):PAGE49
  J4B1   73 VDD<20> SCONN288_H44441004_PIP-SCONN,HA   I169 @BASEBOARD_FAB2_LIB.BASEBOARD_FAB2(SCH_1):PAGE49
  J4B1   70 VDD<21> SCONN288_H44441004_PIP-SCONN,HA   I169 @BASEBOARD_FAB2_LIB.BASEBOARD_FAB2(SCH_1):PAGE49
  J4B1   67 VDD<22> SCONN288_H44441004_PIP-SCONN,HA   I169 @BASEBOARD_FAB2_LIB.BASEBOARD_FAB2(SCH_1):PAGE49
  J4B1   64 VDD<23> SCONN288_H44441004_PIP-SCONN,HA   I169 @BASEBOARD_FAB2_LIB.BASEBOARD_FAB2(SCH_1):PAGE49
  J4B1   61 VDD<24> SCONN288_H44441004_PIP-SCONN,HA   I169 @BASEBOARD_FAB2_LIB.BASEBOARD_FAB2(SCH_1):PAGE49
  J4B1   59 VDD<25> SCONN288_H44441004_PIP-SCONN,HA   I169 @BASEBOARD_FAB2_LIB.BASEBOARD_FAB2(SCH_1):PAGE49
  J6M1  236 VDD<0> SCONN288_H44441003_PIP-SCONN,HA    I50 @BASEBOARD_FAB2_LIB.BASEBOARD_FAB2(SCH_1):PAGE50
  J6M1  233 VDD<1> SCONN288_H44441003_PIP-SCONN,HA    I50 @BASEBOARD_FAB2_LIB.BASEBOARD_FAB2(SCH_1):PAGE50
  J6M1  231 VDD<2> SCONN288_H44441003_PIP-SCONN,HA    I50 @BASEBOARD_FAB2_LIB.BASEBOARD_FAB2(SCH_1):PAGE50
  J6M1  229 VDD<3> SCONN288_H44441003_PIP-SCONN,HA    I50 @BASEBOARD_FAB2_LIB.BASEBOARD_FAB2(SCH_1):PAGE50
  J6M1  226 VDD<4> SCONN288_H44441003_PIP-SCONN,HA    I50 @BASEBOARD_FAB2_LIB.BASEBOARD_FAB2(SCH_1):PAGE50
  J6M1  223 VDD<5> SCONN288_H44441003_PIP-SCONN,HA    I50 @BASEBOARD_FAB2_LIB.BASEBOARD_FAB2(SCH_1):PAGE50
  J6M1  220 VDD<6> SCONN288_H44441003_PIP-SCONN,HA    I50 @BASEBOARD_FAB2_LIB.BASEBOARD_FAB2(SCH_1):PAGE50
  J6M1  217 VDD<7> SCONN288_H44441003_PIP-SCONN,HA    I50 @BASEBOARD_FAB2_LIB.BASEBOARD_FAB2(SCH_1):PAGE50
  J6M1  215 VDD<8> SCONN288_H44441003_PIP-SCONN,HA    I50 @BASEBOARD_FAB2_LIB.BASEBOARD_FAB2(SCH_1):PAGE50
  J6M1  212 VDD<9> SCONN288_H44441003_PIP-SCONN,HA    I50 @BASEBOARD_FAB2_LIB.BASEBOARD_FAB2(SCH_1):PAGE50
  J6M1  209 VDD<10> SCONN288_H44441003_PIP-SCONN,HA    I50 @BASEBOARD_FAB2_LIB.BASEBOARD_FAB2(SCH_1):PAGE50
  J6M1  206 VDD<11> SCONN288_H44441003_PIP-SCONN,HA    I50 @BASEBOARD_FAB2_LIB.BASEBOARD_FAB2(SCH_1):PAGE50
  J6M1  204 VDD<12> SCONN288_H44441003_PIP-SCONN,HA    I50 @BASEBOARD_FAB2_LIB.BASEBOARD_FAB2(SCH_1):PAGE50
  J6M1   92 VDD<13> SCONN288_H44441003_PIP-SCONN,HA    I50 @BASEBOARD_FAB2_LIB.BASEBOARD_FAB2(SCH_1):PAGE50
  J6M1   90 VDD<14> SCONN288_H44441003_PIP-SCONN,HA    I50 @BASEBOARD_FAB2_LIB.BASEBOARD_FAB2(SCH_1):PAGE50
  J6M1   88 VDD<15> SCONN288_H44441003_PIP-SCONN,HA    I50 @BASEBOARD_FAB2_LIB.BASEBOARD_FAB2(SCH_1):PAGE50
  J6M1   85 VDD<16> SCONN288_H44441003_PIP-SCONN,HA    I50 @BASEBOARD_FAB2_LIB.BASEBOARD_FAB2(SCH_1):PAGE50
  J6M1   83 VDD<17> SCONN288_H44441003_PIP-SCONN,HA    I50 @BASEBOARD_FAB2_LIB.BASEBOARD_FAB2(SCH_1):PAGE50
  J6M1   80 VDD<18> SCONN288_H44441003_PIP-SCONN,HA    I50 @BASEBOARD_FAB2_LIB.BASEBOARD_FAB2(SCH_1):PAGE50
  J6M1   76 VDD<19> SCONN288_H44441003_PIP-SCONN,HA    I50 @BASEBOARD_FAB2_LIB.BASEBOARD_FAB2(SCH_1):PAGE50
  J6M1   73 VDD<20> SCONN288_H44441003_PIP-SCONN,HA    I50 @BASEBOARD_FAB2_LIB.BASEBOARD_FAB2(SCH_1):PAGE50
  J6M1   70 VDD<21> SCONN288_H44441003_PIP-SCONN,HA    I50 @BASEBOARD_FAB2_LIB.BASEBOARD_FAB2(SCH_1):PAGE50
  J6M1   67 VDD<22> SCONN288_H44441003_PIP-SCONN,HA    I50 @BASEBOARD_FAB2_LIB.BASEBOARD_FAB2(SCH_1):PAGE50
  J6M1   64 VDD<23> SCONN288_H44441003_PIP-SCONN,HA    I50 @BASEBOARD_FAB2_LIB.BASEBOARD_FAB2(SCH_1):PAGE50
  J6M1   61 VDD<24> SCONN288_H44441003_PIP-SCONN,HA    I50 @BASEBOARD_FAB2_LIB.BASEBOARD_FAB2(SCH_1):PAGE50
  J6M1   59 VDD<25> SCONN288_H44441003_PIP-SCONN,HA    I50 @BASEBOARD_FAB2_LIB.BASEBOARD_FAB2(SCH_1):PAGE50
  J4A2  236 VDD<0> SCONN288_H44441004_PIP-SCONN,HA   I167 @BASEBOARD_FAB2_LIB.BASEBOARD_FAB2(SCH_1):PAGE51
  J4A2  233 VDD<1> SCONN288_H44441004_PIP-SCONN,HA   I167 @BASEBOARD_FAB2_LIB.BASEBOARD_FAB2(SCH_1):PAGE51
  J4A2  231 VDD<2> SCONN288_H44441004_PIP-SCONN,HA   I167 @BASEBOARD_FAB2_LIB.BASEBOARD_FAB2(SCH_1):PAGE51
  J4A2  229 VDD<3> SCONN288_H44441004_PIP-SCONN,HA   I167 @BASEBOARD_FAB2_LIB.BASEBOARD_FAB2(SCH_1):PAGE51
  J4A2  226 VDD<4> SCONN288_H44441004_PIP-SCONN,HA   I167 @BASEBOARD_FAB2_LIB.BASEBOARD_FAB2(SCH_1):PAGE51
  J4A2  223 VDD<5> SCONN288_H44441004_PIP-SCONN,HA   I167 @BASEBOARD_FAB2_LIB.BASEBOARD_FAB2(SCH_1):PAGE51
  J4A2  220 VDD<6> SCONN288_H44441004_PIP-SCONN,HA   I167 @BASEBOARD_FAB2_LIB.BASEBOARD_FAB2(SCH_1):PAGE51
  J4A2  217 VDD<7> SCONN288_H44441004_PIP-SCONN,HA   I167 @BASEBOARD_FAB2_LIB.BASEBOARD_FAB2(SCH_1):PAGE51
  J4A2  215 VDD<8> SCONN288_H44441004_PIP-SCONN,HA   I167 @BASEBOARD_FAB2_LIB.BASEBOARD_FAB2(SCH_1):PAGE51
  J4A2  212 VDD<9> SCONN288_H44441004_PIP-SCONN,HA   I167 @BASEBOARD_FAB2_LIB.BASEBOARD_FAB2(SCH_1):PAGE51
  J4A2  209 VDD<10> SCONN288_H44441004_PIP-SCONN,HA   I167 @BASEBOARD_FAB2_LIB.BASEBOARD_FAB2(SCH_1):PAGE51
  J4A2  206 VDD<11> SCONN288_H44441004_PIP-SCONN,HA   I167 @BASEBOARD_FAB2_LIB.BASEBOARD_FAB2(SCH_1):PAGE51
  J4A2  204 VDD<12> SCONN288_H44441004_PIP-SCONN,HA   I167 @BASEBOARD_FAB2_LIB.BASEBOARD_FAB2(SCH_1):PAGE51
  J4A2   92 VDD<13> SCONN288_H44441004_PIP-SCONN,HA   I167 @BASEBOARD_FAB2_LIB.BASEBOARD_FAB2(SCH_1):PAGE51
  J4A2   90 VDD<14> SCONN288_H44441004_PIP-SCONN,HA   I167 @BASEBOARD_FAB2_LIB.BASEBOARD_FAB2(SCH_1):PAGE51
  J4A2   88 VDD<15> SCONN288_H44441004_PIP-SCONN,HA   I167 @BASEBOARD_FAB2_LIB.BASEBOARD_FAB2(SCH_1):PAGE51
  J4A2   85 VDD<16> SCONN288_H44441004_PIP-SCONN,HA   I167 @BASEBOARD_FAB2_LIB.BASEBOARD_FAB2(SCH_1):PAGE51
  J4A2   83 VDD<17> SCONN288_H44441004_PIP-SCONN,HA   I167 @BASEBOARD_FAB2_LIB.BASEBOARD_FAB2(SCH_1):PAGE51
  J4A2   80 VDD<18> SCONN288_H44441004_PIP-SCONN,HA   I167 @BASEBOARD_FAB2_LIB.BASEBOARD_FAB2(SCH_1):PAGE51
  J4A2   76 VDD<19> SCONN288_H44441004_PIP-SCONN,HA   I167 @BASEBOARD_FAB2_LIB.BASEBOARD_FAB2(SCH_1):PAGE51
  J4A2   73 VDD<20> SCONN288_H44441004_PIP-SCONN,HA   I167 @BASEBOARD_FAB2_LIB.BASEBOARD_FAB2(SCH_1):PAGE51
  J4A2   70 VDD<21> SCONN288_H44441004_PIP-SCONN,HA   I167 @BASEBOARD_FAB2_LIB.BASEBOARD_FAB2(SCH_1):PAGE51
  J4A2   67 VDD<22> SCONN288_H44441004_PIP-SCONN,HA   I167 @BASEBOARD_FAB2_LIB.BASEBOARD_FAB2(SCH_1):PAGE51
  J4A2   64 VDD<23> SCONN288_H44441004_PIP-SCONN,HA   I167 @BASEBOARD_FAB2_LIB.BASEBOARD_FAB2(SCH_1):PAGE51
  J4A2   61 VDD<24> SCONN288_H44441004_PIP-SCONN,HA   I167 @BASEBOARD_FAB2_LIB.BASEBOARD_FAB2(SCH_1):PAGE51
  J4A2   59 VDD<25> SCONN288_H44441004_PIP-SCONN,HA   I167 @BASEBOARD_FAB2_LIB.BASEBOARD_FAB2(SCH_1):PAGE51
  J6L2  236 VDD<0> SCONN288_H44441003_PIP-SCONN,HA    I55 @BASEBOARD_FAB2_LIB.BASEBOARD_FAB2(SCH_1):PAGE52
  J6L2  233 VDD<1> SCONN288_H44441003_PIP-SCONN,HA    I55 @BASEBOARD_FAB2_LIB.BASEBOARD_FAB2(SCH_1):PAGE52
  J6L2  231 VDD<2> SCONN288_H44441003_PIP-SCONN,HA    I55 @BASEBOARD_FAB2_LIB.BASEBOARD_FAB2(SCH_1):PAGE52
  J6L2  229 VDD<3> SCONN288_H44441003_PIP-SCONN,HA    I55 @BASEBOARD_FAB2_LIB.BASEBOARD_FAB2(SCH_1):PAGE52
  J6L2  226 VDD<4> SCONN288_H44441003_PIP-SCONN,HA    I55 @BASEBOARD_FAB2_LIB.BASEBOARD_FAB2(SCH_1):PAGE52
  J6L2  223 VDD<5> SCONN288_H44441003_PIP-SCONN,HA    I55 @BASEBOARD_FAB2_LIB.BASEBOARD_FAB2(SCH_1):PAGE52
  J6L2  220 VDD<6> SCONN288_H44441003_PIP-SCONN,HA    I55 @BASEBOARD_FAB2_LIB.BASEBOARD_FAB2(SCH_1):PAGE52
  J6L2  217 VDD<7> SCONN288_H44441003_PIP-SCONN,HA    I55 @BASEBOARD_FAB2_LIB.BASEBOARD_FAB2(SCH_1):PAGE52
  J6L2  215 VDD<8> SCONN288_H44441003_PIP-SCONN,HA    I55 @BASEBOARD_FAB2_LIB.BASEBOARD_FAB2(SCH_1):PAGE52
  J6L2  212 VDD<9> SCONN288_H44441003_PIP-SCONN,HA    I55 @BASEBOARD_FAB2_LIB.BASEBOARD_FAB2(SCH_1):PAGE52
  J6L2  209 VDD<10> SCONN288_H44441003_PIP-SCONN,HA    I55 @BASEBOARD_FAB2_LIB.BASEBOARD_FAB2(SCH_1):PAGE52
  J6L2  206 VDD<11> SCONN288_H44441003_PIP-SCONN,HA    I55 @BASEBOARD_FAB2_LIB.BASEBOARD_FAB2(SCH_1):PAGE52
  J6L2  204 VDD<12> SCONN288_H44441003_PIP-SCONN,HA    I55 @BASEBOARD_FAB2_LIB.BASEBOARD_FAB2(SCH_1):PAGE52
  J6L2   92 VDD<13> SCONN288_H44441003_PIP-SCONN,HA    I55 @BASEBOARD_FAB2_LIB.BASEBOARD_FAB2(SCH_1):PAGE52
  J6L2   90 VDD<14> SCONN288_H44441003_PIP-SCONN,HA    I55 @BASEBOARD_FAB2_LIB.BASEBOARD_FAB2(SCH_1):PAGE52
  J6L2   88 VDD<15> SCONN288_H44441003_PIP-SCONN,HA    I55 @BASEBOARD_FAB2_LIB.BASEBOARD_FAB2(SCH_1):PAGE52
  J6L2   85 VDD<16> SCONN288_H44441003_PIP-SCONN,HA    I55 @BASEBOARD_FAB2_LIB.BASEBOARD_FAB2(SCH_1):PAGE52
  J6L2   83 VDD<17> SCONN288_H44441003_PIP-SCONN,HA    I55 @BASEBOARD_FAB2_LIB.BASEBOARD_FAB2(SCH_1):PAGE52
  J6L2   80 VDD<18> SCONN288_H44441003_PIP-SCONN,HA    I55 @BASEBOARD_FAB2_LIB.BASEBOARD_FAB2(SCH_1):PAGE52
  J6L2   76 VDD<19> SCONN288_H44441003_PIP-SCONN,HA    I55 @BASEBOARD_FAB2_LIB.BASEBOARD_FAB2(SCH_1):PAGE52
  J6L2   73 VDD<20> SCONN288_H44441003_PIP-SCONN,HA    I55 @BASEBOARD_FAB2_LIB.BASEBOARD_FAB2(SCH_1):PAGE52
  J6L2   70 VDD<21> SCONN288_H44441003_PIP-SCONN,HA    I55 @BASEBOARD_FAB2_LIB.BASEBOARD_FAB2(SCH_1):PAGE52
  J6L2   67 VDD<22> SCONN288_H44441003_PIP-SCONN,HA    I55 @BASEBOARD_FAB2_LIB.BASEBOARD_FAB2(SCH_1):PAGE52
  J6L2   64 VDD<23> SCONN288_H44441003_PIP-SCONN,HA    I55 @BASEBOARD_FAB2_LIB.BASEBOARD_FAB2(SCH_1):PAGE52
  J6L2   61 VDD<24> SCONN288_H44441003_PIP-SCONN,HA    I55 @BASEBOARD_FAB2_LIB.BASEBOARD_FAB2(SCH_1):PAGE52
  J6L2   59 VDD<25> SCONN288_H44441003_PIP-SCONN,HA    I55 @BASEBOARD_FAB2_LIB.BASEBOARD_FAB2(SCH_1):PAGE52
  J4A1  236 VDD<0> SCONN288_H44441004_PIP-SCONN,HA   I171 @BASEBOARD_FAB2_LIB.BASEBOARD_FAB2(SCH_1):PAGE53
  J4A1  233 VDD<1> SCONN288_H44441004_PIP-SCONN,HA   I171 @BASEBOARD_FAB2_LIB.BASEBOARD_FAB2(SCH_1):PAGE53
  J4A1  231 VDD<2> SCONN288_H44441004_PIP-SCONN,HA   I171 @BASEBOARD_FAB2_LIB.BASEBOARD_FAB2(SCH_1):PAGE53
  J4A1  229 VDD<3> SCONN288_H44441004_PIP-SCONN,HA   I171 @BASEBOARD_FAB2_LIB.BASEBOARD_FAB2(SCH_1):PAGE53
  J4A1  226 VDD<4> SCONN288_H44441004_PIP-SCONN,HA   I171 @BASEBOARD_FAB2_LIB.BASEBOARD_FAB2(SCH_1):PAGE53
  J4A1  223 VDD<5> SCONN288_H44441004_PIP-SCONN,HA   I171 @BASEBOARD_FAB2_LIB.BASEBOARD_FAB2(SCH_1):PAGE53
  J4A1  220 VDD<6> SCONN288_H44441004_PIP-SCONN,HA   I171 @BASEBOARD_FAB2_LIB.BASEBOARD_FAB2(SCH_1):PAGE53
  J4A1  217 VDD<7> SCONN288_H44441004_PIP-SCONN,HA   I171 @BASEBOARD_FAB2_LIB.BASEBOARD_FAB2(SCH_1):PAGE53
  J4A1  215 VDD<8> SCONN288_H44441004_PIP-SCONN,HA   I171 @BASEBOARD_FAB2_LIB.BASEBOARD_FAB2(SCH_1):PAGE53
  J4A1  212 VDD<9> SCONN288_H44441004_PIP-SCONN,HA   I171 @BASEBOARD_FAB2_LIB.BASEBOARD_FAB2(SCH_1):PAGE53
  J4A1  209 VDD<10> SCONN288_H44441004_PIP-SCONN,HA   I171 @BASEBOARD_FAB2_LIB.BASEBOARD_FAB2(SCH_1):PAGE53
  J4A1  206 VDD<11> SCONN288_H44441004_PIP-SCONN,HA   I171 @BASEBOARD_FAB2_LIB.BASEBOARD_FAB2(SCH_1):PAGE53
  J4A1  204 VDD<12> SCONN288_H44441004_PIP-SCONN,HA   I171 @BASEBOARD_FAB2_LIB.BASEBOARD_FAB2(SCH_1):PAGE53
  J4A1   92 VDD<13> SCONN288_H44441004_PIP-SCONN,HA   I171 @BASEBOARD_FAB2_LIB.BASEBOARD_FAB2(SCH_1):PAGE53
  J4A1   90 VDD<14> SCONN288_H44441004_PIP-SCONN,HA   I171 @BASEBOARD_FAB2_LIB.BASEBOARD_FAB2(SCH_1):PAGE53
  J4A1   88 VDD<15> SCONN288_H44441004_PIP-SCONN,HA   I171 @BASEBOARD_FAB2_LIB.BASEBOARD_FAB2(SCH_1):PAGE53
  J4A1   85 VDD<16> SCONN288_H44441004_PIP-SCONN,HA   I171 @BASEBOARD_FAB2_LIB.BASEBOARD_FAB2(SCH_1):PAGE53
  J4A1   83 VDD<17> SCONN288_H44441004_PIP-SCONN,HA   I171 @BASEBOARD_FAB2_LIB.BASEBOARD_FAB2(SCH_1):PAGE53
  J4A1   80 VDD<18> SCONN288_H44441004_PIP-SCONN,HA   I171 @BASEBOARD_FAB2_LIB.BASEBOARD_FAB2(SCH_1):PAGE53
  J4A1   76 VDD<19> SCONN288_H44441004_PIP-SCONN,HA   I171 @BASEBOARD_FAB2_LIB.BASEBOARD_FAB2(SCH_1):PAGE53
  J4A1   73 VDD<20> SCONN288_H44441004_PIP-SCONN,HA   I171 @BASEBOARD_FAB2_LIB.BASEBOARD_FAB2(SCH_1):PAGE53
  J4A1   70 VDD<21> SCONN288_H44441004_PIP-SCONN,HA   I171 @BASEBOARD_FAB2_LIB.BASEBOARD_FAB2(SCH_1):PAGE53
  J4A1   67 VDD<22> SCONN288_H44441004_PIP-SCONN,HA   I171 @BASEBOARD_FAB2_LIB.BASEBOARD_FAB2(SCH_1):PAGE53
  J4A1   64 VDD<23> SCONN288_H44441004_PIP-SCONN,HA   I171 @BASEBOARD_FAB2_LIB.BASEBOARD_FAB2(SCH_1):PAGE53
  J4A1   61 VDD<24> SCONN288_H44441004_PIP-SCONN,HA   I171 @BASEBOARD_FAB2_LIB.BASEBOARD_FAB2(SCH_1):PAGE53
  J4A1   59 VDD<25> SCONN288_H44441004_PIP-SCONN,HA   I171 @BASEBOARD_FAB2_LIB.BASEBOARD_FAB2(SCH_1):PAGE53
  J6L1  236 VDD<0> SCONN288_H44441003_PIP-SCONN,HA   I170 @BASEBOARD_FAB2_LIB.BASEBOARD_FAB2(SCH_1):PAGE54
  J6L1  233 VDD<1> SCONN288_H44441003_PIP-SCONN,HA   I170 @BASEBOARD_FAB2_LIB.BASEBOARD_FAB2(SCH_1):PAGE54
  J6L1  231 VDD<2> SCONN288_H44441003_PIP-SCONN,HA   I170 @BASEBOARD_FAB2_LIB.BASEBOARD_FAB2(SCH_1):PAGE54
  J6L1  229 VDD<3> SCONN288_H44441003_PIP-SCONN,HA   I170 @BASEBOARD_FAB2_LIB.BASEBOARD_FAB2(SCH_1):PAGE54
  J6L1  226 VDD<4> SCONN288_H44441003_PIP-SCONN,HA   I170 @BASEBOARD_FAB2_LIB.BASEBOARD_FAB2(SCH_1):PAGE54
  J6L1  223 VDD<5> SCONN288_H44441003_PIP-SCONN,HA   I170 @BASEBOARD_FAB2_LIB.BASEBOARD_FAB2(SCH_1):PAGE54
  J6L1  220 VDD<6> SCONN288_H44441003_PIP-SCONN,HA   I170 @BASEBOARD_FAB2_LIB.BASEBOARD_FAB2(SCH_1):PAGE54
  J6L1  217 VDD<7> SCONN288_H44441003_PIP-SCONN,HA   I170 @BASEBOARD_FAB2_LIB.BASEBOARD_FAB2(SCH_1):PAGE54
  J6L1  215 VDD<8> SCONN288_H44441003_PIP-SCONN,HA   I170 @BASEBOARD_FAB2_LIB.BASEBOARD_FAB2(SCH_1):PAGE54
  J6L1  212 VDD<9> SCONN288_H44441003_PIP-SCONN,HA   I170 @BASEBOARD_FAB2_LIB.BASEBOARD_FAB2(SCH_1):PAGE54
  J6L1  209 VDD<10> SCONN288_H44441003_PIP-SCONN,HA   I170 @BASEBOARD_FAB2_LIB.BASEBOARD_FAB2(SCH_1):PAGE54
  J6L1  206 VDD<11> SCONN288_H44441003_PIP-SCONN,HA   I170 @BASEBOARD_FAB2_LIB.BASEBOARD_FAB2(SCH_1):PAGE54
  J6L1  204 VDD<12> SCONN288_H44441003_PIP-SCONN,HA   I170 @BASEBOARD_FAB2_LIB.BASEBOARD_FAB2(SCH_1):PAGE54
  J6L1   92 VDD<13> SCONN288_H44441003_PIP-SCONN,HA   I170 @BASEBOARD_FAB2_LIB.BASEBOARD_FAB2(SCH_1):PAGE54
  J6L1   90 VDD<14> SCONN288_H44441003_PIP-SCONN,HA   I170 @BASEBOARD_FAB2_LIB.BASEBOARD_FAB2(SCH_1):PAGE54
  J6L1   88 VDD<15> SCONN288_H44441003_PIP-SCONN,HA   I170 @BASEBOARD_FAB2_LIB.BASEBOARD_FAB2(SCH_1):PAGE54
  J6L1   85 VDD<16> SCONN288_H44441003_PIP-SCONN,HA   I170 @BASEBOARD_FAB2_LIB.BASEBOARD_FAB2(SCH_1):PAGE54
  J6L1   83 VDD<17> SCONN288_H44441003_PIP-SCONN,HA   I170 @BASEBOARD_FAB2_LIB.BASEBOARD_FAB2(SCH_1):PAGE54
  J6L1   80 VDD<18> SCONN288_H44441003_PIP-SCONN,HA   I170 @BASEBOARD_FAB2_LIB.BASEBOARD_FAB2(SCH_1):PAGE54
  J6L1   76 VDD<19> SCONN288_H44441003_PIP-SCONN,HA   I170 @BASEBOARD_FAB2_LIB.BASEBOARD_FAB2(SCH_1):PAGE54
  J6L1   73 VDD<20> SCONN288_H44441003_PIP-SCONN,HA   I170 @BASEBOARD_FAB2_LIB.BASEBOARD_FAB2(SCH_1):PAGE54
  J6L1   70 VDD<21> SCONN288_H44441003_PIP-SCONN,HA   I170 @BASEBOARD_FAB2_LIB.BASEBOARD_FAB2(SCH_1):PAGE54
  J6L1   67 VDD<22> SCONN288_H44441003_PIP-SCONN,HA   I170 @BASEBOARD_FAB2_LIB.BASEBOARD_FAB2(SCH_1):PAGE54
  J6L1   64 VDD<23> SCONN288_H44441003_PIP-SCONN,HA   I170 @BASEBOARD_FAB2_LIB.BASEBOARD_FAB2(SCH_1):PAGE54
  J6L1   61 VDD<24> SCONN288_H44441003_PIP-SCONN,HA   I170 @BASEBOARD_FAB2_LIB.BASEBOARD_FAB2(SCH_1):PAGE54
  J6L1   59 VDD<25> SCONN288_H44441003_PIP-SCONN,HA   I170 @BASEBOARD_FAB2_LIB.BASEBOARD_FAB2(SCH_1):PAGE54
 R3P29    1      A RES_0402-64.9,1.0%,1/16W,CHIP,A     I5 @BASEBOARD_FAB2_LIB.BASEBOARD_FAB2(SCH_1):PAGE96
  R6M1    1      A RES_0402-1.00K,1%,1/16W,CHIP,GA     I9 @BASEBOARD_FAB2_LIB.BASEBOARD_FAB2(SCH_1):PAGE98
 R6L13    1      A RES_0402-1.00K,1%,1/16W,CHIP,GA    I54 @BASEBOARD_FAB2_LIB.BASEBOARD_FAB2(SCH_1):PAGE98
  R6L2    1      A RES_0402-1.00K,1%,1/16W,CHIP,GA    I62 @BASEBOARD_FAB2_LIB.BASEBOARD_FAB2(SCH_1):PAGE98
  L7A1    2    INB INDUCTOR_SM-0.12UH,IND,D92183-A    I55 @BASEBOARD_FAB2_LIB.BASEBOARD_FAB2(SCH_1):PAGE219
  L7A3    2    INB INDUCTOR_SM-0.12UH,IND,D92183-A    I65 @BASEBOARD_FAB2_LIB.BASEBOARD_FAB2(SCH_1):PAGE219
  C6A4    1      A CAP_0805LF-22UF,4V,20%,X6S,C95A    I68 @BASEBOARD_FAB2_LIB.BASEBOARD_FAB2(SCH_1):PAGE219
  C6A1    1      A CAP_0805LF-22UF,4V,20%,X6S,C95A    I87 @BASEBOARD_FAB2_LIB.BASEBOARD_FAB2(SCH_1):PAGE219
 EU7A1    1    VOS IR354XX_SM-IR35411,IC,H73688-0A   I106 @BASEBOARD_FAB2_LIB.BASEBOARD_FAB2(SCH_1):PAGE219
 EU7A4    1    VOS IR354XX_SM-IR35411,IC,H73688-0A   I107 @BASEBOARD_FAB2_LIB.BASEBOARD_FAB2(SCH_1):PAGE219
  R4L4    1      A RES_0603-120.0,1%,1/10W,CHIP,GA    I58 @BASEBOARD_FAB2_LIB.BASEBOARD_FAB2(SCH_1):PAGE220
  C3L6    1      A CAPP_3018-470UF,2.5V,20%,ALUM,A    I75 @BASEBOARD_FAB2_LIB.BASEBOARD_FAB2(SCH_1):PAGE220
 C3L14    1      A CAPP_3018-470UF,2.5V,20%,ALUM,A    I76 @BASEBOARD_FAB2_LIB.BASEBOARD_FAB2(SCH_1):PAGE220
  C6A5    1      A CAPP_3018-470UF,2.5V,20%,ALUM,A    I77 @BASEBOARD_FAB2_LIB.BASEBOARD_FAB2(SCH_1):PAGE220
  C4L5    1      A CAPP_3018-470UF,2.5V,20%,ALUM,A    I78 @BASEBOARD_FAB2_LIB.BASEBOARD_FAB2(SCH_1):PAGE220
  C5M8    1      A CAP_0805-100UF,4V,20%,X5R,6024A    I82 @BASEBOARD_FAB2_LIB.BASEBOARD_FAB2(SCH_1):PAGE220
 C5L14    1      A CAP_0805-100UF,4V,20%,X5R,6024A    I83 @BASEBOARD_FAB2_LIB.BASEBOARD_FAB2(SCH_1):PAGE220
 C5M12    1      A CAP_0805-100UF,4V,20%,X5R,6024A    I88 @BASEBOARD_FAB2_LIB.BASEBOARD_FAB2(SCH_1):PAGE220
  C5L3    1      A CAP_0805-100UF,4V,20%,X5R,6024A    I89 @BASEBOARD_FAB2_LIB.BASEBOARD_FAB2(SCH_1):PAGE220
  C5L2    1      A CAP_0805-100UF,4V,20%,X5R,6024A    I90 @BASEBOARD_FAB2_LIB.BASEBOARD_FAB2(SCH_1):PAGE220
  C5L1    1      A CAP_0805-100UF,4V,20%,X5R,6024A    I91 @BASEBOARD_FAB2_LIB.BASEBOARD_FAB2(SCH_1):PAGE220
 C5A20    1      A CAP_0805-100UF,4V,20%,X5R,6024A    I92 @BASEBOARD_FAB2_LIB.BASEBOARD_FAB2(SCH_1):PAGE220
 C5A10    1      A CAP_0805-100UF,4V,20%,X5R,6024A   I110 @BASEBOARD_FAB2_LIB.BASEBOARD_FAB2(SCH_1):PAGE220
  C5P2    1      A CAP_0805LF-22UF,4V,20%,X6S,C95A   I177 @BASEBOARD_FAB2_LIB.BASEBOARD_FAB2(SCH_1):PAGE220
  C5P1    1      A CAP_0805LF-22UF,4V,20%,X6S,C95A   I179 @BASEBOARD_FAB2_LIB.BASEBOARD_FAB2(SCH_1):PAGE220
  C5D9    1      A CAP_0603LF-10UF,4V,20%,X6S,E15A   I180 @BASEBOARD_FAB2_LIB.BASEBOARD_FAB2(SCH_1):PAGE220
  C5D6    1      A CAP_0603LF-10UF,4V,20%,X6S,E15A   I182 @BASEBOARD_FAB2_LIB.BASEBOARD_FAB2(SCH_1):PAGE220
  C5D7    1      A CAP_0603LF-10UF,4V,20%,X6S,E15A   I183 @BASEBOARD_FAB2_LIB.BASEBOARD_FAB2(SCH_1):PAGE220
  C5D8    1      A CAP_0603LF-10UF,4V,20%,X6S,E15A   I184 @BASEBOARD_FAB2_LIB.BASEBOARD_FAB2(SCH_1):PAGE220
 C5L15    1      A CAP_A_0603V-47UF,4V,20%,X5R,60A   I192 @BASEBOARD_FAB2_LIB.BASEBOARD_FAB2(SCH_1):PAGE220
  C5A5    1      A CAP_A_0603V-47UF,4V,20%,X5R,60A   I193 @BASEBOARD_FAB2_LIB.BASEBOARD_FAB2(SCH_1):PAGE220
  C5B1    1      A CAP_A_0603V-47UF,4V,20%,X5R,60A   I194 @BASEBOARD_FAB2_LIB.BASEBOARD_FAB2(SCH_1):PAGE220
  C5M9    1      A CAP_A_0603V-47UF,4V,20%,X5R,60A   I195 @BASEBOARD_FAB2_LIB.BASEBOARD_FAB2(SCH_1):PAGE220
  C4M5    1      A CAP_A_0603V-47UF,4V,20%,X5R,60A   I196 @BASEBOARD_FAB2_LIB.BASEBOARD_FAB2(SCH_1):PAGE220
  C5B2    1      A CAP_A_0603V-47UF,4V,20%,X5R,60A   I197 @BASEBOARD_FAB2_LIB.BASEBOARD_FAB2(SCH_1):PAGE220
 C5M10    1      A CAP_A_0603V-47UF,4V,20%,X5R,60A   I198 @BASEBOARD_FAB2_LIB.BASEBOARD_FAB2(SCH_1):PAGE220
  C5M3    1      A CAP_A_0603V-47UF,4V,20%,X5R,60A   I199 @BASEBOARD_FAB2_LIB.BASEBOARD_FAB2(SCH_1):PAGE220
 C5M11    1      A CAP_A_0603V-47UF,4V,20%,X5R,60A   I200 @BASEBOARD_FAB2_LIB.BASEBOARD_FAB2(SCH_1):PAGE220
 C5A19    1      A CAP_A_0603V-22.0UF,4V,20%,X6S,A   I203 @BASEBOARD_FAB2_LIB.BASEBOARD_FAB2(SCH_1):PAGE220
 C5A18    1      A CAP_A_0603V-22.0UF,4V,20%,X6S,A   I204 @BASEBOARD_FAB2_LIB.BASEBOARD_FAB2(SCH_1):PAGE220
 C5A17    1      A CAP_A_0603V-22.0UF,4V,20%,X6S,A   I205 @BASEBOARD_FAB2_LIB.BASEBOARD_FAB2(SCH_1):PAGE220
  C5A4    1      A CAP_A_0603V-22.0UF,4V,20%,X6S,A   I206 @BASEBOARD_FAB2_LIB.BASEBOARD_FAB2(SCH_1):PAGE220
 C5A16    1      A CAP_A_0603V-22.0UF,4V,20%,X6S,A   I207 @BASEBOARD_FAB2_LIB.BASEBOARD_FAB2(SCH_1):PAGE220
  C5A9    1      A CAP_A_0603V-22.0UF,4V,20%,X6S,A   I208 @BASEBOARD_FAB2_LIB.BASEBOARD_FAB2(SCH_1):PAGE220
  C5A8    1      A CAP_A_0603V-22.0UF,4V,20%,X6S,A   I209 @BASEBOARD_FAB2_LIB.BASEBOARD_FAB2(SCH_1):PAGE220
  C5A3    1      A CAP_A_0603V-22.0UF,4V,20%,X6S,A   I210 @BASEBOARD_FAB2_LIB.BASEBOARD_FAB2(SCH_1):PAGE220
  C5A7    1      A CAP_A_0603V-22.0UF,4V,20%,X6S,A   I211 @BASEBOARD_FAB2_LIB.BASEBOARD_FAB2(SCH_1):PAGE220
  C5A6    1      A CAP_A_0603V-22.0UF,4V,20%,X6S,A   I212 @BASEBOARD_FAB2_LIB.BASEBOARD_FAB2(SCH_1):PAGE220
 C5A14    1      A CAP_A_0603V-22.0UF,4V,20%,X6S,A   I213 @BASEBOARD_FAB2_LIB.BASEBOARD_FAB2(SCH_1):PAGE220
  C5A2    1      A CAP_A_0603V-22.0UF,4V,20%,X6S,A   I214 @BASEBOARD_FAB2_LIB.BASEBOARD_FAB2(SCH_1):PAGE220
 C5A13    1      A CAP_A_0603V-22.0UF,4V,20%,X6S,A   I215 @BASEBOARD_FAB2_LIB.BASEBOARD_FAB2(SCH_1):PAGE220
 C5A12    1      A CAP_A_0603V-22.0UF,4V,20%,X6S,A   I216 @BASEBOARD_FAB2_LIB.BASEBOARD_FAB2(SCH_1):PAGE220
 C5A15    1      A CAP_A_0603V-22.0UF,4V,20%,X6S,A   I217 @BASEBOARD_FAB2_LIB.BASEBOARD_FAB2(SCH_1):PAGE220
  C5A1    1      A CAP_A_0603V-22.0UF,4V,20%,X6S,A   I219 @BASEBOARD_FAB2_LIB.BASEBOARD_FAB2(SCH_1):PAGE220
 C5A11    1      A CAP_A_0603V-22.0UF,4V,20%,X6S,A   I221 @BASEBOARD_FAB2_LIB.BASEBOARD_FAB2(SCH_1):PAGE220
  C4M2    1      A CAP_A_0603V-22.0UF,4V,20%,X6S,A   I222 @BASEBOARD_FAB2_LIB.BASEBOARD_FAB2(SCH_1):PAGE220
  C5M1    1      A CAP_A_0603V-22.0UF,4V,20%,X6S,A   I223 @BASEBOARD_FAB2_LIB.BASEBOARD_FAB2(SCH_1):PAGE220
  C5M2    1      A CAP_A_0603V-22.0UF,4V,20%,X6S,A   I224 @BASEBOARD_FAB2_LIB.BASEBOARD_FAB2(SCH_1):PAGE220
  C5M4    1      A CAP_A_0603V-22.0UF,4V,20%,X6S,A   I225 @BASEBOARD_FAB2_LIB.BASEBOARD_FAB2(SCH_1):PAGE220
  C5M5    1      A CAP_A_0603V-22.0UF,4V,20%,X6S,A   I226 @BASEBOARD_FAB2_LIB.BASEBOARD_FAB2(SCH_1):PAGE220
  C5M6    1      A CAP_A_0603V-22.0UF,4V,20%,X6S,A   I227 @BASEBOARD_FAB2_LIB.BASEBOARD_FAB2(SCH_1):PAGE220
  C5M7    1      A CAP_A_0603V-22.0UF,4V,20%,X6S,A   I228 @BASEBOARD_FAB2_LIB.BASEBOARD_FAB2(SCH_1):PAGE220
 C5L13    1      A CAP_A_0603V-22.0UF,4V,20%,X6S,A   I229 @BASEBOARD_FAB2_LIB.BASEBOARD_FAB2(SCH_1):PAGE220
 C5L12    1      A CAP_A_0603V-22.0UF,4V,20%,X6S,A   I230 @BASEBOARD_FAB2_LIB.BASEBOARD_FAB2(SCH_1):PAGE220
 C5L11    1      A CAP_A_0603V-22.0UF,4V,20%,X6S,A   I231 @BASEBOARD_FAB2_LIB.BASEBOARD_FAB2(SCH_1):PAGE220
 C5L10    1      A CAP_A_0603V-22.0UF,4V,20%,X6S,A   I232 @BASEBOARD_FAB2_LIB.BASEBOARD_FAB2(SCH_1):PAGE220
  C5L9    1      A CAP_A_0603V-22.0UF,4V,20%,X6S,A   I233 @BASEBOARD_FAB2_LIB.BASEBOARD_FAB2(SCH_1):PAGE220
  C5L8    1      A CAP_A_0603V-22.0UF,4V,20%,X6S,A   I234 @BASEBOARD_FAB2_LIB.BASEBOARD_FAB2(SCH_1):PAGE220
  C5L7    1      A CAP_A_0603V-22.0UF,4V,20%,X6S,A   I236 @BASEBOARD_FAB2_LIB.BASEBOARD_FAB2(SCH_1):PAGE220
  C5L6    1      A CAP_A_0603V-22.0UF,4V,20%,X6S,A   I237 @BASEBOARD_FAB2_LIB.BASEBOARD_FAB2(SCH_1):PAGE220
 SH4L2    2      B SHUNT_SH0201-EMPTY,N_A   I239 @BASEBOARD_FAB2_LIB.BASEBOARD_FAB2(SCH_1):PAGE220
  C6L3    1      A CAP_0603LF-10UF,4V,20%,X6S,E15A    I24 @BASEBOARD_FAB2_LIB.BASEBOARD_FAB2(SCH_1):PAGE222
  C6L4    1      A CAP_0603LF-10UF,4V,20%,X6S,E15A    I26 @BASEBOARD_FAB2_LIB.BASEBOARD_FAB2(SCH_1):PAGE222
 EU4A1   10    VIN MIC5166_DFN-IC,H55101-001    I31 @BASEBOARD_FAB2_LIB.BASEBOARD_FAB2(SCH_1):PAGE222
 R6L10    1      A RES_0402-0.0,5%,1/16W,CHIP,G21A    I34 @BASEBOARD_FAB2_LIB.BASEBOARD_FAB2(SCH_1):PAGE222
 C5G77    1      A CAP_0805-100UF,4V,20%,X5R,6024A    I37 @BASEBOARD_FAB2_LIB.BASEBOARD_FAB2(SCH_1):PAGE242
 C5G78    1      A CAP_0805-100UF,4V,20%,X5R,6024A    I41 @BASEBOARD_FAB2_LIB.BASEBOARD_FAB2(SCH_1):PAGE242
 C5G67    1      A CAP_A_0603V-22.0UF,4V,20%,X6S,A    I71 @BASEBOARD_FAB2_LIB.BASEBOARD_FAB2(SCH_1):PAGE242
 C5G66    1      A CAP_A_0603V-22.0UF,4V,20%,X6S,A    I72 @BASEBOARD_FAB2_LIB.BASEBOARD_FAB2(SCH_1):PAGE242
 C5G65    1      A CAP_A_0603V-22.0UF,4V,20%,X6S,A    I73 @BASEBOARD_FAB2_LIB.BASEBOARD_FAB2(SCH_1):PAGE242
 C5G64    1      A CAP_A_0603V-22.0UF,4V,20%,X6S,A    I74 @BASEBOARD_FAB2_LIB.BASEBOARD_FAB2(SCH_1):PAGE242
 C5G63    1      A CAP_A_0603V-22.0UF,4V,20%,X6S,A    I75 @BASEBOARD_FAB2_LIB.BASEBOARD_FAB2(SCH_1):PAGE242
 C5G62    1      A CAP_A_0603V-22.0UF,4V,20%,X6S,A    I76 @BASEBOARD_FAB2_LIB.BASEBOARD_FAB2(SCH_1):PAGE242
 C5G61    1      A CAP_A_0603V-22.0UF,4V,20%,X6S,A    I77 @BASEBOARD_FAB2_LIB.BASEBOARD_FAB2(SCH_1):PAGE242
 C5G60    1      A CAP_A_0603V-22.0UF,4V,20%,X6S,A    I78 @BASEBOARD_FAB2_LIB.BASEBOARD_FAB2(SCH_1):PAGE242
 C5G59    1      A CAP_A_0603V-22.0UF,4V,20%,X6S,A    I79 @BASEBOARD_FAB2_LIB.BASEBOARD_FAB2(SCH_1):PAGE242
 C5G76    1      A CAP_A_0603V-22.0UF,4V,20%,X6S,A    I80 @BASEBOARD_FAB2_LIB.BASEBOARD_FAB2(SCH_1):PAGE242
 C5G75    1      A CAP_A_0603V-22.0UF,4V,20%,X6S,A    I81 @BASEBOARD_FAB2_LIB.BASEBOARD_FAB2(SCH_1):PAGE242
 C5G74    1      A CAP_A_0603V-22.0UF,4V,20%,X6S,A    I82 @BASEBOARD_FAB2_LIB.BASEBOARD_FAB2(SCH_1):PAGE242
 C5G73    1      A CAP_A_0603V-22.0UF,4V,20%,X6S,A    I83 @BASEBOARD_FAB2_LIB.BASEBOARD_FAB2(SCH_1):PAGE242
 C5G72    1      A CAP_A_0603V-22.0UF,4V,20%,X6S,A    I84 @BASEBOARD_FAB2_LIB.BASEBOARD_FAB2(SCH_1):PAGE242
 C5G71    1      A CAP_A_0603V-22.0UF,4V,20%,X6S,A    I85 @BASEBOARD_FAB2_LIB.BASEBOARD_FAB2(SCH_1):PAGE242
 C5G70    1      A CAP_A_0603V-22.0UF,4V,20%,X6S,A    I86 @BASEBOARD_FAB2_LIB.BASEBOARD_FAB2(SCH_1):PAGE242
 C5G69    1      A CAP_A_0603V-22.0UF,4V,20%,X6S,A    I87 @BASEBOARD_FAB2_LIB.BASEBOARD_FAB2(SCH_1):PAGE242
 C5G68    1      A CAP_A_0603V-22.0UF,4V,20%,X6S,A    I88 @BASEBOARD_FAB2_LIB.BASEBOARD_FAB2(SCH_1):PAGE242

PVDDQ_GHJ @BASEBOARD_FAB2_LIB.BASEBOARD_FAB2(SCH_1):PVDDQ_GHJ
  U2D1  B49 VCCD012<0> SKX_EXT_B_BGA1-IC,TBD    I32 @BASEBOARD_FAB2_LIB.BASEBOARD_FAB2(SCH_1):PAGE72
  U2D1  B53 VCCD012<1> SKX_EXT_B_BGA1-IC,TBD    I32 @BASEBOARD_FAB2_LIB.BASEBOARD_FAB2(SCH_1):PAGE72
  U2D1  B59 VCCD012<2> SKX_EXT_B_BGA1-IC,TBD    I32 @BASEBOARD_FAB2_LIB.BASEBOARD_FAB2(SCH_1):PAGE72
  U2D1  E46 VCCD012<3> SKX_EXT_B_BGA1-IC,TBD    I32 @BASEBOARD_FAB2_LIB.BASEBOARD_FAB2(SCH_1):PAGE72
  U2D1  E48 VCCD012<4> SKX_EXT_B_BGA1-IC,TBD    I32 @BASEBOARD_FAB2_LIB.BASEBOARD_FAB2(SCH_1):PAGE72
  U2D1  E50 VCCD012<5> SKX_EXT_B_BGA1-IC,TBD    I32 @BASEBOARD_FAB2_LIB.BASEBOARD_FAB2(SCH_1):PAGE72
  U2D1  E52 VCCD012<6> SKX_EXT_B_BGA1-IC,TBD    I32 @BASEBOARD_FAB2_LIB.BASEBOARD_FAB2(SCH_1):PAGE72
  U2D1  E54 VCCD012<7> SKX_EXT_B_BGA1-IC,TBD    I32 @BASEBOARD_FAB2_LIB.BASEBOARD_FAB2(SCH_1):PAGE72
  U2D1  E56 VCCD012<8> SKX_EXT_B_BGA1-IC,TBD    I32 @BASEBOARD_FAB2_LIB.BASEBOARD_FAB2(SCH_1):PAGE72
  U2D1  E58 VCCD012<9> SKX_EXT_B_BGA1-IC,TBD    I32 @BASEBOARD_FAB2_LIB.BASEBOARD_FAB2(SCH_1):PAGE72
  U2D1  E60 VCCD012<10> SKX_EXT_B_BGA1-IC,TBD    I32 @BASEBOARD_FAB2_LIB.BASEBOARD_FAB2(SCH_1):PAGE72
  U2D1  E62 VCCD012<11> SKX_EXT_B_BGA1-IC,TBD    I32 @BASEBOARD_FAB2_LIB.BASEBOARD_FAB2(SCH_1):PAGE72
  U2D1  E64 VCCD012<12> SKX_EXT_B_BGA1-IC,TBD    I32 @BASEBOARD_FAB2_LIB.BASEBOARD_FAB2(SCH_1):PAGE72
  U2D1  L46 VCCD012<13> SKX_EXT_B_BGA1-IC,TBD    I32 @BASEBOARD_FAB2_LIB.BASEBOARD_FAB2(SCH_1):PAGE72
  U2D1  L48 VCCD012<14> SKX_EXT_B_BGA1-IC,TBD    I32 @BASEBOARD_FAB2_LIB.BASEBOARD_FAB2(SCH_1):PAGE72
  U2D1  L50 VCCD012<15> SKX_EXT_B_BGA1-IC,TBD    I32 @BASEBOARD_FAB2_LIB.BASEBOARD_FAB2(SCH_1):PAGE72
  U2D1  L52 VCCD012<16> SKX_EXT_B_BGA1-IC,TBD    I32 @BASEBOARD_FAB2_LIB.BASEBOARD_FAB2(SCH_1):PAGE72
  U2D1  L54 VCCD012<17> SKX_EXT_B_BGA1-IC,TBD    I32 @BASEBOARD_FAB2_LIB.BASEBOARD_FAB2(SCH_1):PAGE72
  U2D1  L56 VCCD012<18> SKX_EXT_B_BGA1-IC,TBD    I32 @BASEBOARD_FAB2_LIB.BASEBOARD_FAB2(SCH_1):PAGE72
  U2D1  L58 VCCD012<19> SKX_EXT_B_BGA1-IC,TBD    I32 @BASEBOARD_FAB2_LIB.BASEBOARD_FAB2(SCH_1):PAGE72
  U2D1  L60 VCCD012<20> SKX_EXT_B_BGA1-IC,TBD    I32 @BASEBOARD_FAB2_LIB.BASEBOARD_FAB2(SCH_1):PAGE72
  U2D1  L62 VCCD012<21> SKX_EXT_B_BGA1-IC,TBD    I32 @BASEBOARD_FAB2_LIB.BASEBOARD_FAB2(SCH_1):PAGE72
  U2D1  N64 VCCD012<22> SKX_EXT_B_BGA1-IC,TBD    I32 @BASEBOARD_FAB2_LIB.BASEBOARD_FAB2(SCH_1):PAGE72
  U2D1  U46 VCCD012<23> SKX_EXT_B_BGA1-IC,TBD    I32 @BASEBOARD_FAB2_LIB.BASEBOARD_FAB2(SCH_1):PAGE72
  U2D1  U48 VCCD012<24> SKX_EXT_B_BGA1-IC,TBD    I32 @BASEBOARD_FAB2_LIB.BASEBOARD_FAB2(SCH_1):PAGE72
  U2D1  U50 VCCD012<25> SKX_EXT_B_BGA1-IC,TBD    I32 @BASEBOARD_FAB2_LIB.BASEBOARD_FAB2(SCH_1):PAGE72
  U2D1  U52 VCCD012<26> SKX_EXT_B_BGA1-IC,TBD    I32 @BASEBOARD_FAB2_LIB.BASEBOARD_FAB2(SCH_1):PAGE72
  U2D1  U54 VCCD012<27> SKX_EXT_B_BGA1-IC,TBD    I32 @BASEBOARD_FAB2_LIB.BASEBOARD_FAB2(SCH_1):PAGE72
  U2D1  U56 VCCD012<28> SKX_EXT_B_BGA1-IC,TBD    I32 @BASEBOARD_FAB2_LIB.BASEBOARD_FAB2(SCH_1):PAGE72
  U2D1  U58 VCCD012<29> SKX_EXT_B_BGA1-IC,TBD    I32 @BASEBOARD_FAB2_LIB.BASEBOARD_FAB2(SCH_1):PAGE72
  U2D1  U60 VCCD012<30> SKX_EXT_B_BGA1-IC,TBD    I32 @BASEBOARD_FAB2_LIB.BASEBOARD_FAB2(SCH_1):PAGE72
  U2D1  U62 VCCD012<31> SKX_EXT_B_BGA1-IC,TBD    I32 @BASEBOARD_FAB2_LIB.BASEBOARD_FAB2(SCH_1):PAGE72
  U2D1  W64 VCCD012<32> SKX_EXT_B_BGA1-IC,TBD    I32 @BASEBOARD_FAB2_LIB.BASEBOARD_FAB2(SCH_1):PAGE72
  U2D1  Y45 VCCD012<33> SKX_EXT_B_BGA1-IC,TBD    I32 @BASEBOARD_FAB2_LIB.BASEBOARD_FAB2(SCH_1):PAGE72
  U2D1  Y47 VCCD012<34> SKX_EXT_B_BGA1-IC,TBD    I32 @BASEBOARD_FAB2_LIB.BASEBOARD_FAB2(SCH_1):PAGE72
  U2D1  Y49 VCCD012<35> SKX_EXT_B_BGA1-IC,TBD    I32 @BASEBOARD_FAB2_LIB.BASEBOARD_FAB2(SCH_1):PAGE72
  U2D1  Y51 VCCD012<36> SKX_EXT_B_BGA1-IC,TBD    I32 @BASEBOARD_FAB2_LIB.BASEBOARD_FAB2(SCH_1):PAGE72
  U2D1  Y53 VCCD012<37> SKX_EXT_B_BGA1-IC,TBD    I32 @BASEBOARD_FAB2_LIB.BASEBOARD_FAB2(SCH_1):PAGE72
  U2D1  Y55 VCCD012<38> SKX_EXT_B_BGA1-IC,TBD    I32 @BASEBOARD_FAB2_LIB.BASEBOARD_FAB2(SCH_1):PAGE72
  U2D1  Y57 VCCD012<39> SKX_EXT_B_BGA1-IC,TBD    I32 @BASEBOARD_FAB2_LIB.BASEBOARD_FAB2(SCH_1):PAGE72
  U2D1  Y59 VCCD012<40> SKX_EXT_B_BGA1-IC,TBD    I32 @BASEBOARD_FAB2_LIB.BASEBOARD_FAB2(SCH_1):PAGE72
  U2D1  Y61 VCCD012<41> SKX_EXT_B_BGA1-IC,TBD    I32 @BASEBOARD_FAB2_LIB.BASEBOARD_FAB2(SCH_1):PAGE72
  U2D1  Y63 VCCD012<42> SKX_EXT_B_BGA1-IC,TBD    I32 @BASEBOARD_FAB2_LIB.BASEBOARD_FAB2(SCH_1):PAGE72
  U2D1 AD45 VCCD012<43> SKX_EXT_B_BGA1-IC,TBD    I32 @BASEBOARD_FAB2_LIB.BASEBOARD_FAB2(SCH_1):PAGE72
  U2D1 AF55 VCCD012<44> SKX_EXT_B_BGA1-IC,TBD    I32 @BASEBOARD_FAB2_LIB.BASEBOARD_FAB2(SCH_1):PAGE72
  U2D1 AF57 VCCD012<45> SKX_EXT_B_BGA1-IC,TBD    I32 @BASEBOARD_FAB2_LIB.BASEBOARD_FAB2(SCH_1):PAGE72
  U2D1 AF59 VCCD012<46> SKX_EXT_B_BGA1-IC,TBD    I32 @BASEBOARD_FAB2_LIB.BASEBOARD_FAB2(SCH_1):PAGE72
  U2D1 AF61 VCCD012<47> SKX_EXT_B_BGA1-IC,TBD    I32 @BASEBOARD_FAB2_LIB.BASEBOARD_FAB2(SCH_1):PAGE72
  U2D1 AF63 VCCD012<48> SKX_EXT_B_BGA1-IC,TBD    I32 @BASEBOARD_FAB2_LIB.BASEBOARD_FAB2(SCH_1):PAGE72
  U2D1  D45 VCCD012<49> SKX_EXT_B_BGA1-IC,TBD    I32 @BASEBOARD_FAB2_LIB.BASEBOARD_FAB2(SCH_1):PAGE72
  U2D1  C46 VCCD012<50> SKX_EXT_B_BGA1-IC,TBD    I32 @BASEBOARD_FAB2_LIB.BASEBOARD_FAB2(SCH_1):PAGE72
  U2D1  B47 VCCD012<51> SKX_EXT_B_BGA1-IC,TBD    I32 @BASEBOARD_FAB2_LIB.BASEBOARD_FAB2(SCH_1):PAGE72
  J1G1  236 VDD<0> SCONN288_H44441004_PIP-SCONN,HA   I171 @BASEBOARD_FAB2_LIB.BASEBOARD_FAB2(SCH_1):PAGE77
  J1G1  233 VDD<1> SCONN288_H44441004_PIP-SCONN,HA   I171 @BASEBOARD_FAB2_LIB.BASEBOARD_FAB2(SCH_1):PAGE77
  J1G1  231 VDD<2> SCONN288_H44441004_PIP-SCONN,HA   I171 @BASEBOARD_FAB2_LIB.BASEBOARD_FAB2(SCH_1):PAGE77
  J1G1  229 VDD<3> SCONN288_H44441004_PIP-SCONN,HA   I171 @BASEBOARD_FAB2_LIB.BASEBOARD_FAB2(SCH_1):PAGE77
  J1G1  226 VDD<4> SCONN288_H44441004_PIP-SCONN,HA   I171 @BASEBOARD_FAB2_LIB.BASEBOARD_FAB2(SCH_1):PAGE77
  J1G1  223 VDD<5> SCONN288_H44441004_PIP-SCONN,HA   I171 @BASEBOARD_FAB2_LIB.BASEBOARD_FAB2(SCH_1):PAGE77
  J1G1  220 VDD<6> SCONN288_H44441004_PIP-SCONN,HA   I171 @BASEBOARD_FAB2_LIB.BASEBOARD_FAB2(SCH_1):PAGE77
  J1G1  217 VDD<7> SCONN288_H44441004_PIP-SCONN,HA   I171 @BASEBOARD_FAB2_LIB.BASEBOARD_FAB2(SCH_1):PAGE77
  J1G1  215 VDD<8> SCONN288_H44441004_PIP-SCONN,HA   I171 @BASEBOARD_FAB2_LIB.BASEBOARD_FAB2(SCH_1):PAGE77
  J1G1  212 VDD<9> SCONN288_H44441004_PIP-SCONN,HA   I171 @BASEBOARD_FAB2_LIB.BASEBOARD_FAB2(SCH_1):PAGE77
  J1G1  209 VDD<10> SCONN288_H44441004_PIP-SCONN,HA   I171 @BASEBOARD_FAB2_LIB.BASEBOARD_FAB2(SCH_1):PAGE77
  J1G1  206 VDD<11> SCONN288_H44441004_PIP-SCONN,HA   I171 @BASEBOARD_FAB2_LIB.BASEBOARD_FAB2(SCH_1):PAGE77
  J1G1  204 VDD<12> SCONN288_H44441004_PIP-SCONN,HA   I171 @BASEBOARD_FAB2_LIB.BASEBOARD_FAB2(SCH_1):PAGE77
  J1G1   92 VDD<13> SCONN288_H44441004_PIP-SCONN,HA   I171 @BASEBOARD_FAB2_LIB.BASEBOARD_FAB2(SCH_1):PAGE77
  J1G1   90 VDD<14> SCONN288_H44441004_PIP-SCONN,HA   I171 @BASEBOARD_FAB2_LIB.BASEBOARD_FAB2(SCH_1):PAGE77
  J1G1   88 VDD<15> SCONN288_H44441004_PIP-SCONN,HA   I171 @BASEBOARD_FAB2_LIB.BASEBOARD_FAB2(SCH_1):PAGE77
  J1G1   85 VDD<16> SCONN288_H44441004_PIP-SCONN,HA   I171 @BASEBOARD_FAB2_LIB.BASEBOARD_FAB2(SCH_1):PAGE77
  J1G1   83 VDD<17> SCONN288_H44441004_PIP-SCONN,HA   I171 @BASEBOARD_FAB2_LIB.BASEBOARD_FAB2(SCH_1):PAGE77
  J1G1   80 VDD<18> SCONN288_H44441004_PIP-SCONN,HA   I171 @BASEBOARD_FAB2_LIB.BASEBOARD_FAB2(SCH_1):PAGE77
  J1G1   76 VDD<19> SCONN288_H44441004_PIP-SCONN,HA   I171 @BASEBOARD_FAB2_LIB.BASEBOARD_FAB2(SCH_1):PAGE77
  J1G1   73 VDD<20> SCONN288_H44441004_PIP-SCONN,HA   I171 @BASEBOARD_FAB2_LIB.BASEBOARD_FAB2(SCH_1):PAGE77
  J1G1   70 VDD<21> SCONN288_H44441004_PIP-SCONN,HA   I171 @BASEBOARD_FAB2_LIB.BASEBOARD_FAB2(SCH_1):PAGE77
  J1G1   67 VDD<22> SCONN288_H44441004_PIP-SCONN,HA   I171 @BASEBOARD_FAB2_LIB.BASEBOARD_FAB2(SCH_1):PAGE77
  J1G1   64 VDD<23> SCONN288_H44441004_PIP-SCONN,HA   I171 @BASEBOARD_FAB2_LIB.BASEBOARD_FAB2(SCH_1):PAGE77
  J1G1   61 VDD<24> SCONN288_H44441004_PIP-SCONN,HA   I171 @BASEBOARD_FAB2_LIB.BASEBOARD_FAB2(SCH_1):PAGE77
  J1G1   59 VDD<25> SCONN288_H44441004_PIP-SCONN,HA   I171 @BASEBOARD_FAB2_LIB.BASEBOARD_FAB2(SCH_1):PAGE77
  J9T1  236 VDD<0> SCONN288_H44441003_PIP-SCONN,HA    I75 @BASEBOARD_FAB2_LIB.BASEBOARD_FAB2(SCH_1):PAGE78
  J9T1  233 VDD<1> SCONN288_H44441003_PIP-SCONN,HA    I75 @BASEBOARD_FAB2_LIB.BASEBOARD_FAB2(SCH_1):PAGE78
  J9T1  231 VDD<2> SCONN288_H44441003_PIP-SCONN,HA    I75 @BASEBOARD_FAB2_LIB.BASEBOARD_FAB2(SCH_1):PAGE78
  J9T1  229 VDD<3> SCONN288_H44441003_PIP-SCONN,HA    I75 @BASEBOARD_FAB2_LIB.BASEBOARD_FAB2(SCH_1):PAGE78
  J9T1  226 VDD<4> SCONN288_H44441003_PIP-SCONN,HA    I75 @BASEBOARD_FAB2_LIB.BASEBOARD_FAB2(SCH_1):PAGE78
  J9T1  223 VDD<5> SCONN288_H44441003_PIP-SCONN,HA    I75 @BASEBOARD_FAB2_LIB.BASEBOARD_FAB2(SCH_1):PAGE78
  J9T1  220 VDD<6> SCONN288_H44441003_PIP-SCONN,HA    I75 @BASEBOARD_FAB2_LIB.BASEBOARD_FAB2(SCH_1):PAGE78
  J9T1  217 VDD<7> SCONN288_H44441003_PIP-SCONN,HA    I75 @BASEBOARD_FAB2_LIB.BASEBOARD_FAB2(SCH_1):PAGE78
  J9T1  215 VDD<8> SCONN288_H44441003_PIP-SCONN,HA    I75 @BASEBOARD_FAB2_LIB.BASEBOARD_FAB2(SCH_1):PAGE78
  J9T1  212 VDD<9> SCONN288_H44441003_PIP-SCONN,HA    I75 @BASEBOARD_FAB2_LIB.BASEBOARD_FAB2(SCH_1):PAGE78
  J9T1  209 VDD<10> SCONN288_H44441003_PIP-SCONN,HA    I75 @BASEBOARD_FAB2_LIB.BASEBOARD_FAB2(SCH_1):PAGE78
  J9T1  206 VDD<11> SCONN288_H44441003_PIP-SCONN,HA    I75 @BASEBOARD_FAB2_LIB.BASEBOARD_FAB2(SCH_1):PAGE78
  J9T1  204 VDD<12> SCONN288_H44441003_PIP-SCONN,HA    I75 @BASEBOARD_FAB2_LIB.BASEBOARD_FAB2(SCH_1):PAGE78
  J9T1   92 VDD<13> SCONN288_H44441003_PIP-SCONN,HA    I75 @BASEBOARD_FAB2_LIB.BASEBOARD_FAB2(SCH_1):PAGE78
  J9T1   90 VDD<14> SCONN288_H44441003_PIP-SCONN,HA    I75 @BASEBOARD_FAB2_LIB.BASEBOARD_FAB2(SCH_1):PAGE78
  J9T1   88 VDD<15> SCONN288_H44441003_PIP-SCONN,HA    I75 @BASEBOARD_FAB2_LIB.BASEBOARD_FAB2(SCH_1):PAGE78
  J9T1   85 VDD<16> SCONN288_H44441003_PIP-SCONN,HA    I75 @BASEBOARD_FAB2_LIB.BASEBOARD_FAB2(SCH_1):PAGE78
  J9T1   83 VDD<17> SCONN288_H44441003_PIP-SCONN,HA    I75 @BASEBOARD_FAB2_LIB.BASEBOARD_FAB2(SCH_1):PAGE78
  J9T1   80 VDD<18> SCONN288_H44441003_PIP-SCONN,HA    I75 @BASEBOARD_FAB2_LIB.BASEBOARD_FAB2(SCH_1):PAGE78
  J9T1   76 VDD<19> SCONN288_H44441003_PIP-SCONN,HA    I75 @BASEBOARD_FAB2_LIB.BASEBOARD_FAB2(SCH_1):PAGE78
  J9T1   73 VDD<20> SCONN288_H44441003_PIP-SCONN,HA    I75 @BASEBOARD_FAB2_LIB.BASEBOARD_FAB2(SCH_1):PAGE78
  J9T1   70 VDD<21> SCONN288_H44441003_PIP-SCONN,HA    I75 @BASEBOARD_FAB2_LIB.BASEBOARD_FAB2(SCH_1):PAGE78
  J9T1   67 VDD<22> SCONN288_H44441003_PIP-SCONN,HA    I75 @BASEBOARD_FAB2_LIB.BASEBOARD_FAB2(SCH_1):PAGE78
  J9T1   64 VDD<23> SCONN288_H44441003_PIP-SCONN,HA    I75 @BASEBOARD_FAB2_LIB.BASEBOARD_FAB2(SCH_1):PAGE78
  J9T1   61 VDD<24> SCONN288_H44441003_PIP-SCONN,HA    I75 @BASEBOARD_FAB2_LIB.BASEBOARD_FAB2(SCH_1):PAGE78
  J9T1   59 VDD<25> SCONN288_H44441003_PIP-SCONN,HA    I75 @BASEBOARD_FAB2_LIB.BASEBOARD_FAB2(SCH_1):PAGE78
  J1G2  236 VDD<0> SCONN288_H44441004_PIP-SCONN,HA   I169 @BASEBOARD_FAB2_LIB.BASEBOARD_FAB2(SCH_1):PAGE79
  J1G2  233 VDD<1> SCONN288_H44441004_PIP-SCONN,HA   I169 @BASEBOARD_FAB2_LIB.BASEBOARD_FAB2(SCH_1):PAGE79
  J1G2  231 VDD<2> SCONN288_H44441004_PIP-SCONN,HA   I169 @BASEBOARD_FAB2_LIB.BASEBOARD_FAB2(SCH_1):PAGE79
  J1G2  229 VDD<3> SCONN288_H44441004_PIP-SCONN,HA   I169 @BASEBOARD_FAB2_LIB.BASEBOARD_FAB2(SCH_1):PAGE79
  J1G2  226 VDD<4> SCONN288_H44441004_PIP-SCONN,HA   I169 @BASEBOARD_FAB2_LIB.BASEBOARD_FAB2(SCH_1):PAGE79
  J1G2  223 VDD<5> SCONN288_H44441004_PIP-SCONN,HA   I169 @BASEBOARD_FAB2_LIB.BASEBOARD_FAB2(SCH_1):PAGE79
  J1G2  220 VDD<6> SCONN288_H44441004_PIP-SCONN,HA   I169 @BASEBOARD_FAB2_LIB.BASEBOARD_FAB2(SCH_1):PAGE79
  J1G2  217 VDD<7> SCONN288_H44441004_PIP-SCONN,HA   I169 @BASEBOARD_FAB2_LIB.BASEBOARD_FAB2(SCH_1):PAGE79
  J1G2  215 VDD<8> SCONN288_H44441004_PIP-SCONN,HA   I169 @BASEBOARD_FAB2_LIB.BASEBOARD_FAB2(SCH_1):PAGE79
  J1G2  212 VDD<9> SCONN288_H44441004_PIP-SCONN,HA   I169 @BASEBOARD_FAB2_LIB.BASEBOARD_FAB2(SCH_1):PAGE79
  J1G2  209 VDD<10> SCONN288_H44441004_PIP-SCONN,HA   I169 @BASEBOARD_FAB2_LIB.BASEBOARD_FAB2(SCH_1):PAGE79
  J1G2  206 VDD<11> SCONN288_H44441004_PIP-SCONN,HA   I169 @BASEBOARD_FAB2_LIB.BASEBOARD_FAB2(SCH_1):PAGE79
  J1G2  204 VDD<12> SCONN288_H44441004_PIP-SCONN,HA   I169 @BASEBOARD_FAB2_LIB.BASEBOARD_FAB2(SCH_1):PAGE79
  J1G2   92 VDD<13> SCONN288_H44441004_PIP-SCONN,HA   I169 @BASEBOARD_FAB2_LIB.BASEBOARD_FAB2(SCH_1):PAGE79
  J1G2   90 VDD<14> SCONN288_H44441004_PIP-SCONN,HA   I169 @BASEBOARD_FAB2_LIB.BASEBOARD_FAB2(SCH_1):PAGE79
  J1G2   88 VDD<15> SCONN288_H44441004_PIP-SCONN,HA   I169 @BASEBOARD_FAB2_LIB.BASEBOARD_FAB2(SCH_1):PAGE79
  J1G2   85 VDD<16> SCONN288_H44441004_PIP-SCONN,HA   I169 @BASEBOARD_FAB2_LIB.BASEBOARD_FAB2(SCH_1):PAGE79
  J1G2   83 VDD<17> SCONN288_H44441004_PIP-SCONN,HA   I169 @BASEBOARD_FAB2_LIB.BASEBOARD_FAB2(SCH_1):PAGE79
  J1G2   80 VDD<18> SCONN288_H44441004_PIP-SCONN,HA   I169 @BASEBOARD_FAB2_LIB.BASEBOARD_FAB2(SCH_1):PAGE79
  J1G2   76 VDD<19> SCONN288_H44441004_PIP-SCONN,HA   I169 @BASEBOARD_FAB2_LIB.BASEBOARD_FAB2(SCH_1):PAGE79
  J1G2   73 VDD<20> SCONN288_H44441004_PIP-SCONN,HA   I169 @BASEBOARD_FAB2_LIB.BASEBOARD_FAB2(SCH_1):PAGE79
  J1G2   70 VDD<21> SCONN288_H44441004_PIP-SCONN,HA   I169 @BASEBOARD_FAB2_LIB.BASEBOARD_FAB2(SCH_1):PAGE79
  J1G2   67 VDD<22> SCONN288_H44441004_PIP-SCONN,HA   I169 @BASEBOARD_FAB2_LIB.BASEBOARD_FAB2(SCH_1):PAGE79
  J1G2   64 VDD<23> SCONN288_H44441004_PIP-SCONN,HA   I169 @BASEBOARD_FAB2_LIB.BASEBOARD_FAB2(SCH_1):PAGE79
  J1G2   61 VDD<24> SCONN288_H44441004_PIP-SCONN,HA   I169 @BASEBOARD_FAB2_LIB.BASEBOARD_FAB2(SCH_1):PAGE79
  J1G2   59 VDD<25> SCONN288_H44441004_PIP-SCONN,HA   I169 @BASEBOARD_FAB2_LIB.BASEBOARD_FAB2(SCH_1):PAGE79
  J9U1  236 VDD<0> SCONN288_H44441003_PIP-SCONN,HA    I56 @BASEBOARD_FAB2_LIB.BASEBOARD_FAB2(SCH_1):PAGE80
  J9U1  233 VDD<1> SCONN288_H44441003_PIP-SCONN,HA    I56 @BASEBOARD_FAB2_LIB.BASEBOARD_FAB2(SCH_1):PAGE80
  J9U1  231 VDD<2> SCONN288_H44441003_PIP-SCONN,HA    I56 @BASEBOARD_FAB2_LIB.BASEBOARD_FAB2(SCH_1):PAGE80
  J9U1  229 VDD<3> SCONN288_H44441003_PIP-SCONN,HA    I56 @BASEBOARD_FAB2_LIB.BASEBOARD_FAB2(SCH_1):PAGE80
  J9U1  226 VDD<4> SCONN288_H44441003_PIP-SCONN,HA    I56 @BASEBOARD_FAB2_LIB.BASEBOARD_FAB2(SCH_1):PAGE80
  J9U1  223 VDD<5> SCONN288_H44441003_PIP-SCONN,HA    I56 @BASEBOARD_FAB2_LIB.BASEBOARD_FAB2(SCH_1):PAGE80
  J9U1  220 VDD<6> SCONN288_H44441003_PIP-SCONN,HA    I56 @BASEBOARD_FAB2_LIB.BASEBOARD_FAB2(SCH_1):PAGE80
  J9U1  217 VDD<7> SCONN288_H44441003_PIP-SCONN,HA    I56 @BASEBOARD_FAB2_LIB.BASEBOARD_FAB2(SCH_1):PAGE80
  J9U1  215 VDD<8> SCONN288_H44441003_PIP-SCONN,HA    I56 @BASEBOARD_FAB2_LIB.BASEBOARD_FAB2(SCH_1):PAGE80
  J9U1  212 VDD<9> SCONN288_H44441003_PIP-SCONN,HA    I56 @BASEBOARD_FAB2_LIB.BASEBOARD_FAB2(SCH_1):PAGE80
  J9U1  209 VDD<10> SCONN288_H44441003_PIP-SCONN,HA    I56 @BASEBOARD_FAB2_LIB.BASEBOARD_FAB2(SCH_1):PAGE80
  J9U1  206 VDD<11> SCONN288_H44441003_PIP-SCONN,HA    I56 @BASEBOARD_FAB2_LIB.BASEBOARD_FAB2(SCH_1):PAGE80
  J9U1  204 VDD<12> SCONN288_H44441003_PIP-SCONN,HA    I56 @BASEBOARD_FAB2_LIB.BASEBOARD_FAB2(SCH_1):PAGE80
  J9U1   92 VDD<13> SCONN288_H44441003_PIP-SCONN,HA    I56 @BASEBOARD_FAB2_LIB.BASEBOARD_FAB2(SCH_1):PAGE80
  J9U1   90 VDD<14> SCONN288_H44441003_PIP-SCONN,HA    I56 @BASEBOARD_FAB2_LIB.BASEBOARD_FAB2(SCH_1):PAGE80
  J9U1   88 VDD<15> SCONN288_H44441003_PIP-SCONN,HA    I56 @BASEBOARD_FAB2_LIB.BASEBOARD_FAB2(SCH_1):PAGE80
  J9U1   85 VDD<16> SCONN288_H44441003_PIP-SCONN,HA    I56 @BASEBOARD_FAB2_LIB.BASEBOARD_FAB2(SCH_1):PAGE80
  J9U1   83 VDD<17> SCONN288_H44441003_PIP-SCONN,HA    I56 @BASEBOARD_FAB2_LIB.BASEBOARD_FAB2(SCH_1):PAGE80
  J9U1   80 VDD<18> SCONN288_H44441003_PIP-SCONN,HA    I56 @BASEBOARD_FAB2_LIB.BASEBOARD_FAB2(SCH_1):PAGE80
  J9U1   76 VDD<19> SCONN288_H44441003_PIP-SCONN,HA    I56 @BASEBOARD_FAB2_LIB.BASEBOARD_FAB2(SCH_1):PAGE80
  J9U1   73 VDD<20> SCONN288_H44441003_PIP-SCONN,HA    I56 @BASEBOARD_FAB2_LIB.BASEBOARD_FAB2(SCH_1):PAGE80
  J9U1   70 VDD<21> SCONN288_H44441003_PIP-SCONN,HA    I56 @BASEBOARD_FAB2_LIB.BASEBOARD_FAB2(SCH_1):PAGE80
  J9U1   67 VDD<22> SCONN288_H44441003_PIP-SCONN,HA    I56 @BASEBOARD_FAB2_LIB.BASEBOARD_FAB2(SCH_1):PAGE80
  J9U1   64 VDD<23> SCONN288_H44441003_PIP-SCONN,HA    I56 @BASEBOARD_FAB2_LIB.BASEBOARD_FAB2(SCH_1):PAGE80
  J9U1   61 VDD<24> SCONN288_H44441003_PIP-SCONN,HA    I56 @BASEBOARD_FAB2_LIB.BASEBOARD_FAB2(SCH_1):PAGE80
  J9U1   59 VDD<25> SCONN288_H44441003_PIP-SCONN,HA    I56 @BASEBOARD_FAB2_LIB.BASEBOARD_FAB2(SCH_1):PAGE80
  J1G3  236 VDD<0> SCONN288_H44441004_PIP-SCONN,HA   I169 @BASEBOARD_FAB2_LIB.BASEBOARD_FAB2(SCH_1):PAGE81
  J1G3  233 VDD<1> SCONN288_H44441004_PIP-SCONN,HA   I169 @BASEBOARD_FAB2_LIB.BASEBOARD_FAB2(SCH_1):PAGE81
  J1G3  231 VDD<2> SCONN288_H44441004_PIP-SCONN,HA   I169 @BASEBOARD_FAB2_LIB.BASEBOARD_FAB2(SCH_1):PAGE81
  J1G3  229 VDD<3> SCONN288_H44441004_PIP-SCONN,HA   I169 @BASEBOARD_FAB2_LIB.BASEBOARD_FAB2(SCH_1):PAGE81
  J1G3  226 VDD<4> SCONN288_H44441004_PIP-SCONN,HA   I169 @BASEBOARD_FAB2_LIB.BASEBOARD_FAB2(SCH_1):PAGE81
  J1G3  223 VDD<5> SCONN288_H44441004_PIP-SCONN,HA   I169 @BASEBOARD_FAB2_LIB.BASEBOARD_FAB2(SCH_1):PAGE81
  J1G3  220 VDD<6> SCONN288_H44441004_PIP-SCONN,HA   I169 @BASEBOARD_FAB2_LIB.BASEBOARD_FAB2(SCH_1):PAGE81
  J1G3  217 VDD<7> SCONN288_H44441004_PIP-SCONN,HA   I169 @BASEBOARD_FAB2_LIB.BASEBOARD_FAB2(SCH_1):PAGE81
  J1G3  215 VDD<8> SCONN288_H44441004_PIP-SCONN,HA   I169 @BASEBOARD_FAB2_LIB.BASEBOARD_FAB2(SCH_1):PAGE81
  J1G3  212 VDD<9> SCONN288_H44441004_PIP-SCONN,HA   I169 @BASEBOARD_FAB2_LIB.BASEBOARD_FAB2(SCH_1):PAGE81
  J1G3  209 VDD<10> SCONN288_H44441004_PIP-SCONN,HA   I169 @BASEBOARD_FAB2_LIB.BASEBOARD_FAB2(SCH_1):PAGE81
  J1G3  206 VDD<11> SCONN288_H44441004_PIP-SCONN,HA   I169 @BASEBOARD_FAB2_LIB.BASEBOARD_FAB2(SCH_1):PAGE81
  J1G3  204 VDD<12> SCONN288_H44441004_PIP-SCONN,HA   I169 @BASEBOARD_FAB2_LIB.BASEBOARD_FAB2(SCH_1):PAGE81
  J1G3   92 VDD<13> SCONN288_H44441004_PIP-SCONN,HA   I169 @BASEBOARD_FAB2_LIB.BASEBOARD_FAB2(SCH_1):PAGE81
  J1G3   90 VDD<14> SCONN288_H44441004_PIP-SCONN,HA   I169 @BASEBOARD_FAB2_LIB.BASEBOARD_FAB2(SCH_1):PAGE81
  J1G3   88 VDD<15> SCONN288_H44441004_PIP-SCONN,HA   I169 @BASEBOARD_FAB2_LIB.BASEBOARD_FAB2(SCH_1):PAGE81
  J1G3   85 VDD<16> SCONN288_H44441004_PIP-SCONN,HA   I169 @BASEBOARD_FAB2_LIB.BASEBOARD_FAB2(SCH_1):PAGE81
  J1G3   83 VDD<17> SCONN288_H44441004_PIP-SCONN,HA   I169 @BASEBOARD_FAB2_LIB.BASEBOARD_FAB2(SCH_1):PAGE81
  J1G3   80 VDD<18> SCONN288_H44441004_PIP-SCONN,HA   I169 @BASEBOARD_FAB2_LIB.BASEBOARD_FAB2(SCH_1):PAGE81
  J1G3   76 VDD<19> SCONN288_H44441004_PIP-SCONN,HA   I169 @BASEBOARD_FAB2_LIB.BASEBOARD_FAB2(SCH_1):PAGE81
  J1G3   73 VDD<20> SCONN288_H44441004_PIP-SCONN,HA   I169 @BASEBOARD_FAB2_LIB.BASEBOARD_FAB2(SCH_1):PAGE81
  J1G3   70 VDD<21> SCONN288_H44441004_PIP-SCONN,HA   I169 @BASEBOARD_FAB2_LIB.BASEBOARD_FAB2(SCH_1):PAGE81
  J1G3   67 VDD<22> SCONN288_H44441004_PIP-SCONN,HA   I169 @BASEBOARD_FAB2_LIB.BASEBOARD_FAB2(SCH_1):PAGE81
  J1G3   64 VDD<23> SCONN288_H44441004_PIP-SCONN,HA   I169 @BASEBOARD_FAB2_LIB.BASEBOARD_FAB2(SCH_1):PAGE81
  J1G3   61 VDD<24> SCONN288_H44441004_PIP-SCONN,HA   I169 @BASEBOARD_FAB2_LIB.BASEBOARD_FAB2(SCH_1):PAGE81
  J1G3   59 VDD<25> SCONN288_H44441004_PIP-SCONN,HA   I169 @BASEBOARD_FAB2_LIB.BASEBOARD_FAB2(SCH_1):PAGE81
  J9U2  236 VDD<0> SCONN288_H44441003_PIP-SCONN,HA   I171 @BASEBOARD_FAB2_LIB.BASEBOARD_FAB2(SCH_1):PAGE82
  J9U2  233 VDD<1> SCONN288_H44441003_PIP-SCONN,HA   I171 @BASEBOARD_FAB2_LIB.BASEBOARD_FAB2(SCH_1):PAGE82
  J9U2  231 VDD<2> SCONN288_H44441003_PIP-SCONN,HA   I171 @BASEBOARD_FAB2_LIB.BASEBOARD_FAB2(SCH_1):PAGE82
  J9U2  229 VDD<3> SCONN288_H44441003_PIP-SCONN,HA   I171 @BASEBOARD_FAB2_LIB.BASEBOARD_FAB2(SCH_1):PAGE82
  J9U2  226 VDD<4> SCONN288_H44441003_PIP-SCONN,HA   I171 @BASEBOARD_FAB2_LIB.BASEBOARD_FAB2(SCH_1):PAGE82
  J9U2  223 VDD<5> SCONN288_H44441003_PIP-SCONN,HA   I171 @BASEBOARD_FAB2_LIB.BASEBOARD_FAB2(SCH_1):PAGE82
  J9U2  220 VDD<6> SCONN288_H44441003_PIP-SCONN,HA   I171 @BASEBOARD_FAB2_LIB.BASEBOARD_FAB2(SCH_1):PAGE82
  J9U2  217 VDD<7> SCONN288_H44441003_PIP-SCONN,HA   I171 @BASEBOARD_FAB2_LIB.BASEBOARD_FAB2(SCH_1):PAGE82
  J9U2  215 VDD<8> SCONN288_H44441003_PIP-SCONN,HA   I171 @BASEBOARD_FAB2_LIB.BASEBOARD_FAB2(SCH_1):PAGE82
  J9U2  212 VDD<9> SCONN288_H44441003_PIP-SCONN,HA   I171 @BASEBOARD_FAB2_LIB.BASEBOARD_FAB2(SCH_1):PAGE82
  J9U2  209 VDD<10> SCONN288_H44441003_PIP-SCONN,HA   I171 @BASEBOARD_FAB2_LIB.BASEBOARD_FAB2(SCH_1):PAGE82
  J9U2  206 VDD<11> SCONN288_H44441003_PIP-SCONN,HA   I171 @BASEBOARD_FAB2_LIB.BASEBOARD_FAB2(SCH_1):PAGE82
  J9U2  204 VDD<12> SCONN288_H44441003_PIP-SCONN,HA   I171 @BASEBOARD_FAB2_LIB.BASEBOARD_FAB2(SCH_1):PAGE82
  J9U2   92 VDD<13> SCONN288_H44441003_PIP-SCONN,HA   I171 @BASEBOARD_FAB2_LIB.BASEBOARD_FAB2(SCH_1):PAGE82
  J9U2   90 VDD<14> SCONN288_H44441003_PIP-SCONN,HA   I171 @BASEBOARD_FAB2_LIB.BASEBOARD_FAB2(SCH_1):PAGE82
  J9U2   88 VDD<15> SCONN288_H44441003_PIP-SCONN,HA   I171 @BASEBOARD_FAB2_LIB.BASEBOARD_FAB2(SCH_1):PAGE82
  J9U2   85 VDD<16> SCONN288_H44441003_PIP-SCONN,HA   I171 @BASEBOARD_FAB2_LIB.BASEBOARD_FAB2(SCH_1):PAGE82
  J9U2   83 VDD<17> SCONN288_H44441003_PIP-SCONN,HA   I171 @BASEBOARD_FAB2_LIB.BASEBOARD_FAB2(SCH_1):PAGE82
  J9U2   80 VDD<18> SCONN288_H44441003_PIP-SCONN,HA   I171 @BASEBOARD_FAB2_LIB.BASEBOARD_FAB2(SCH_1):PAGE82
  J9U2   76 VDD<19> SCONN288_H44441003_PIP-SCONN,HA   I171 @BASEBOARD_FAB2_LIB.BASEBOARD_FAB2(SCH_1):PAGE82
  J9U2   73 VDD<20> SCONN288_H44441003_PIP-SCONN,HA   I171 @BASEBOARD_FAB2_LIB.BASEBOARD_FAB2(SCH_1):PAGE82
  J9U2   70 VDD<21> SCONN288_H44441003_PIP-SCONN,HA   I171 @BASEBOARD_FAB2_LIB.BASEBOARD_FAB2(SCH_1):PAGE82
  J9U2   67 VDD<22> SCONN288_H44441003_PIP-SCONN,HA   I171 @BASEBOARD_FAB2_LIB.BASEBOARD_FAB2(SCH_1):PAGE82
  J9U2   64 VDD<23> SCONN288_H44441003_PIP-SCONN,HA   I171 @BASEBOARD_FAB2_LIB.BASEBOARD_FAB2(SCH_1):PAGE82
  J9U2   61 VDD<24> SCONN288_H44441003_PIP-SCONN,HA   I171 @BASEBOARD_FAB2_LIB.BASEBOARD_FAB2(SCH_1):PAGE82
  J9U2   59 VDD<25> SCONN288_H44441003_PIP-SCONN,HA   I171 @BASEBOARD_FAB2_LIB.BASEBOARD_FAB2(SCH_1):PAGE82
 R3D21    1      A RES_0402-64.9,1.0%,1/16W,CHIP,A    I30 @BASEBOARD_FAB2_LIB.BASEBOARD_FAB2(SCH_1):PAGE96
  R1F5    1      A RES_0402-1.00K,1%,1/16W,CHIP,GA     I6 @BASEBOARD_FAB2_LIB.BASEBOARD_FAB2(SCH_1):PAGE100
  R1G2    1      A RES_0402-1.00K,1%,1/16W,CHIP,GA    I19 @BASEBOARD_FAB2_LIB.BASEBOARD_FAB2(SCH_1):PAGE100
 R1G15    1      A RES_0402-1.00K,1%,1/16W,CHIP,GA    I35 @BASEBOARD_FAB2_LIB.BASEBOARD_FAB2(SCH_1):PAGE100
 C1G17    1      A CAP_0805LF-22UF,4V,20%,X6S,C95A     I6 @BASEBOARD_FAB2_LIB.BASEBOARD_FAB2(SCH_1):PAGE224
  L1G1    2    INB INDUCTOR_SM-0.12UH,IND,D92183-A    I55 @BASEBOARD_FAB2_LIB.BASEBOARD_FAB2(SCH_1):PAGE224
  L1F2    2    INB INDUCTOR_SM-0.12UH,IND,D92183-A    I65 @BASEBOARD_FAB2_LIB.BASEBOARD_FAB2(SCH_1):PAGE224
 C1G20    1      A CAP_0805LF-22UF,4V,20%,X6S,C95A    I68 @BASEBOARD_FAB2_LIB.BASEBOARD_FAB2(SCH_1):PAGE224
 EU1G1    1    VOS IR354XX_SM-IR35411,IC,H73688-0A   I110 @BASEBOARD_FAB2_LIB.BASEBOARD_FAB2(SCH_1):PAGE224
 EU1F1    1    VOS IR354XX_SM-IR35411,IC,H73688-0A   I111 @BASEBOARD_FAB2_LIB.BASEBOARD_FAB2(SCH_1):PAGE224
 R1G20    1      A RES_0603-120.0,1%,1/10W,CHIP,GA    I58 @BASEBOARD_FAB2_LIB.BASEBOARD_FAB2(SCH_1):PAGE225
  C9T5    1      A CAPP_3018-470UF,2.5V,20%,ALUM,A    I75 @BASEBOARD_FAB2_LIB.BASEBOARD_FAB2(SCH_1):PAGE225
  C9U2    1      A CAPP_3018-470UF,2.5V,20%,ALUM,A    I76 @BASEBOARD_FAB2_LIB.BASEBOARD_FAB2(SCH_1):PAGE225
  C9U9    1      A CAPP_3018-470UF,2.5V,20%,ALUM,A    I77 @BASEBOARD_FAB2_LIB.BASEBOARD_FAB2(SCH_1):PAGE225
  C9U5    1      A CAPP_3018-470UF,2.5V,20%,ALUM,A    I78 @BASEBOARD_FAB2_LIB.BASEBOARD_FAB2(SCH_1):PAGE225
  C8U1    1      A CAP_0805-100UF,4V,20%,X5R,6024A    I82 @BASEBOARD_FAB2_LIB.BASEBOARD_FAB2(SCH_1):PAGE225
  C8U8    1      A CAP_0805-100UF,4V,20%,X5R,6024A    I83 @BASEBOARD_FAB2_LIB.BASEBOARD_FAB2(SCH_1):PAGE225
 C8U12    1      A CAP_0805-100UF,4V,20%,X5R,6024A    I88 @BASEBOARD_FAB2_LIB.BASEBOARD_FAB2(SCH_1):PAGE225
 C8U11    1      A CAP_0805-100UF,4V,20%,X5R,6024A    I89 @BASEBOARD_FAB2_LIB.BASEBOARD_FAB2(SCH_1):PAGE225
  C7T1    1      A CAP_0805-100UF,4V,20%,X5R,6024A    I90 @BASEBOARD_FAB2_LIB.BASEBOARD_FAB2(SCH_1):PAGE225
  C7U7    1      A CAP_0805-100UF,4V,20%,X5R,6024A    I91 @BASEBOARD_FAB2_LIB.BASEBOARD_FAB2(SCH_1):PAGE225
  C2G7    1      A CAP_0805-100UF,4V,20%,X5R,6024A    I92 @BASEBOARD_FAB2_LIB.BASEBOARD_FAB2(SCH_1):PAGE225
 C2G16    1      A CAP_0805-100UF,4V,20%,X5R,6024A   I110 @BASEBOARD_FAB2_LIB.BASEBOARD_FAB2(SCH_1):PAGE225
 C8P31    1      A CAP_0805LF-22UF,4V,20%,X6S,C95A   I178 @BASEBOARD_FAB2_LIB.BASEBOARD_FAB2(SCH_1):PAGE225
 C2D43    1      A CAP_0603LF-10UF,4V,20%,X6S,E15A   I179 @BASEBOARD_FAB2_LIB.BASEBOARD_FAB2(SCH_1):PAGE225
 C2D41    1      A CAP_0603LF-10UF,4V,20%,X6S,E15A   I180 @BASEBOARD_FAB2_LIB.BASEBOARD_FAB2(SCH_1):PAGE225
 C2D44    1      A CAP_0603LF-10UF,4V,20%,X6S,E15A   I181 @BASEBOARD_FAB2_LIB.BASEBOARD_FAB2(SCH_1):PAGE225
 C2D42    1      A CAP_0603LF-10UF,4V,20%,X6S,E15A   I183 @BASEBOARD_FAB2_LIB.BASEBOARD_FAB2(SCH_1):PAGE225
 C8P30    1      A CAP_0805LF-22UF,4V,20%,X6S,C95A   I184 @BASEBOARD_FAB2_LIB.BASEBOARD_FAB2(SCH_1):PAGE225
  C8T4    1      A CAP_A_0603V-47UF,4V,20%,X5R,60A   I196 @BASEBOARD_FAB2_LIB.BASEBOARD_FAB2(SCH_1):PAGE225
  C2G8    1      A CAP_A_0603V-47UF,4V,20%,X5R,60A   I197 @BASEBOARD_FAB2_LIB.BASEBOARD_FAB2(SCH_1):PAGE225
  C8T2    1      A CAP_A_0603V-47UF,4V,20%,X5R,60A   I198 @BASEBOARD_FAB2_LIB.BASEBOARD_FAB2(SCH_1):PAGE225
 C8U13    1      A CAP_A_0603V-47UF,4V,20%,X5R,60A   I199 @BASEBOARD_FAB2_LIB.BASEBOARD_FAB2(SCH_1):PAGE225
 C2G15    1      A CAP_A_0603V-47UF,4V,20%,X5R,60A   I200 @BASEBOARD_FAB2_LIB.BASEBOARD_FAB2(SCH_1):PAGE225
  C2F1    1      A CAP_A_0603V-47UF,4V,20%,X5R,60A   I201 @BASEBOARD_FAB2_LIB.BASEBOARD_FAB2(SCH_1):PAGE225
  C8T1    1      A CAP_A_0603V-47UF,4V,20%,X5R,60A   I202 @BASEBOARD_FAB2_LIB.BASEBOARD_FAB2(SCH_1):PAGE225
  C8U9    1      A CAP_A_0603V-47UF,4V,20%,X5R,60A   I203 @BASEBOARD_FAB2_LIB.BASEBOARD_FAB2(SCH_1):PAGE225
 C8T11    1      A CAP_A_0603V-47UF,4V,20%,X5R,60A   I204 @BASEBOARD_FAB2_LIB.BASEBOARD_FAB2(SCH_1):PAGE225
  C3G6    1      A CAP_A_0603V-22.0UF,4V,20%,X6S,A   I207 @BASEBOARD_FAB2_LIB.BASEBOARD_FAB2(SCH_1):PAGE225
  C3G5    1      A CAP_A_0603V-22.0UF,4V,20%,X6S,A   I208 @BASEBOARD_FAB2_LIB.BASEBOARD_FAB2(SCH_1):PAGE225
 C2G14    1      A CAP_A_0603V-22.0UF,4V,20%,X6S,A   I209 @BASEBOARD_FAB2_LIB.BASEBOARD_FAB2(SCH_1):PAGE225
 C2G13    1      A CAP_A_0603V-22.0UF,4V,20%,X6S,A   I210 @BASEBOARD_FAB2_LIB.BASEBOARD_FAB2(SCH_1):PAGE225
  C3G2    1      A CAP_A_0603V-22.0UF,4V,20%,X6S,A   I211 @BASEBOARD_FAB2_LIB.BASEBOARD_FAB2(SCH_1):PAGE225
  C3G1    1      A CAP_A_0603V-22.0UF,4V,20%,X6S,A   I212 @BASEBOARD_FAB2_LIB.BASEBOARD_FAB2(SCH_1):PAGE225
  C2G6    1      A CAP_A_0603V-22.0UF,4V,20%,X6S,A   I213 @BASEBOARD_FAB2_LIB.BASEBOARD_FAB2(SCH_1):PAGE225
  C2G5    1      A CAP_A_0603V-22.0UF,4V,20%,X6S,A   I214 @BASEBOARD_FAB2_LIB.BASEBOARD_FAB2(SCH_1):PAGE225
  C2G4    1      A CAP_A_0603V-22.0UF,4V,20%,X6S,A   I215 @BASEBOARD_FAB2_LIB.BASEBOARD_FAB2(SCH_1):PAGE225
  C2G3    1      A CAP_A_0603V-22.0UF,4V,20%,X6S,A   I216 @BASEBOARD_FAB2_LIB.BASEBOARD_FAB2(SCH_1):PAGE225
  C2G2    1      A CAP_A_0603V-22.0UF,4V,20%,X6S,A   I217 @BASEBOARD_FAB2_LIB.BASEBOARD_FAB2(SCH_1):PAGE225
  C2G9    1      A CAP_A_0603V-22.0UF,4V,20%,X6S,A   I218 @BASEBOARD_FAB2_LIB.BASEBOARD_FAB2(SCH_1):PAGE225
  C2G1    1      A CAP_A_0603V-22.0UF,4V,20%,X6S,A   I219 @BASEBOARD_FAB2_LIB.BASEBOARD_FAB2(SCH_1):PAGE225
 C2G12    1      A CAP_A_0603V-22.0UF,4V,20%,X6S,A   I220 @BASEBOARD_FAB2_LIB.BASEBOARD_FAB2(SCH_1):PAGE225
 C2G11    1      A CAP_A_0603V-22.0UF,4V,20%,X6S,A   I221 @BASEBOARD_FAB2_LIB.BASEBOARD_FAB2(SCH_1):PAGE225
 C2G10    1      A CAP_A_0603V-22.0UF,4V,20%,X6S,A   I223 @BASEBOARD_FAB2_LIB.BASEBOARD_FAB2(SCH_1):PAGE225
  C8U4    1      A CAP_A_0603V-22.0UF,4V,20%,X6S,A   I225 @BASEBOARD_FAB2_LIB.BASEBOARD_FAB2(SCH_1):PAGE225
 C8T10    1      A CAP_A_0603V-22.0UF,4V,20%,X6S,A   I226 @BASEBOARD_FAB2_LIB.BASEBOARD_FAB2(SCH_1):PAGE225
  C8T9    1      A CAP_A_0603V-22.0UF,4V,20%,X6S,A   I227 @BASEBOARD_FAB2_LIB.BASEBOARD_FAB2(SCH_1):PAGE225
  C8U5    1      A CAP_A_0603V-22.0UF,4V,20%,X6S,A   I228 @BASEBOARD_FAB2_LIB.BASEBOARD_FAB2(SCH_1):PAGE225
  C8T8    1      A CAP_A_0603V-22.0UF,4V,20%,X6S,A   I229 @BASEBOARD_FAB2_LIB.BASEBOARD_FAB2(SCH_1):PAGE225
  C8T7    1      A CAP_A_0603V-22.0UF,4V,20%,X6S,A   I230 @BASEBOARD_FAB2_LIB.BASEBOARD_FAB2(SCH_1):PAGE225
  C8T6    1      A CAP_A_0603V-22.0UF,4V,20%,X6S,A   I231 @BASEBOARD_FAB2_LIB.BASEBOARD_FAB2(SCH_1):PAGE225
  C8U6    1      A CAP_A_0603V-22.0UF,4V,20%,X6S,A   I232 @BASEBOARD_FAB2_LIB.BASEBOARD_FAB2(SCH_1):PAGE225
  C8T5    1      A CAP_A_0603V-22.0UF,4V,20%,X6S,A   I233 @BASEBOARD_FAB2_LIB.BASEBOARD_FAB2(SCH_1):PAGE225
  C7T5    1      A CAP_A_0603V-22.0UF,4V,20%,X6S,A   I234 @BASEBOARD_FAB2_LIB.BASEBOARD_FAB2(SCH_1):PAGE225
  C7T4    1      A CAP_A_0603V-22.0UF,4V,20%,X6S,A   I235 @BASEBOARD_FAB2_LIB.BASEBOARD_FAB2(SCH_1):PAGE225
  C8U3    1      A CAP_A_0603V-22.0UF,4V,20%,X6S,A   I236 @BASEBOARD_FAB2_LIB.BASEBOARD_FAB2(SCH_1):PAGE225
  C7U1    1      A CAP_A_0603V-22.0UF,4V,20%,X6S,A   I237 @BASEBOARD_FAB2_LIB.BASEBOARD_FAB2(SCH_1):PAGE225
  C7U2    1      A CAP_A_0603V-22.0UF,4V,20%,X6S,A   I238 @BASEBOARD_FAB2_LIB.BASEBOARD_FAB2(SCH_1):PAGE225
  C8U2    1      A CAP_A_0603V-22.0UF,4V,20%,X6S,A   I239 @BASEBOARD_FAB2_LIB.BASEBOARD_FAB2(SCH_1):PAGE225
  C8U7    1      A CAP_A_0603V-22.0UF,4V,20%,X6S,A   I241 @BASEBOARD_FAB2_LIB.BASEBOARD_FAB2(SCH_1):PAGE225
 SH7U1    2      B SHUNT_SH0201-EMPTY,N_A   I243 @BASEBOARD_FAB2_LIB.BASEBOARD_FAB2(SCH_1):PAGE225
 EU4G2   10    VIN MIC5166_DFN-IC,H55101-001    I24 @BASEBOARD_FAB2_LIB.BASEBOARD_FAB2(SCH_1):PAGE229
 C6U14    1      A CAP_0603LF-10UF,4V,20%,X6S,E15A    I25 @BASEBOARD_FAB2_LIB.BASEBOARD_FAB2(SCH_1):PAGE229
 C6U13    1      A CAP_0603LF-10UF,4V,20%,X6S,E15A    I29 @BASEBOARD_FAB2_LIB.BASEBOARD_FAB2(SCH_1):PAGE229
  R6U6    1      A RES_0402-0.0,5%,1/16W,CHIP,G21A    I39 @BASEBOARD_FAB2_LIB.BASEBOARD_FAB2(SCH_1):PAGE229
C5G117    1      A CAP_0805-100UF,4V,20%,X5R,6024A    I12 @BASEBOARD_FAB2_LIB.BASEBOARD_FAB2(SCH_1):PAGE243
C5G118    1      A CAP_0805-100UF,4V,20%,X5R,6024A    I13 @BASEBOARD_FAB2_LIB.BASEBOARD_FAB2(SCH_1):PAGE243
 C5G79    1      A CAP_A_0603V-22.0UF,4V,20%,X6S,A    I53 @BASEBOARD_FAB2_LIB.BASEBOARD_FAB2(SCH_1):PAGE243
 C5G87    1      A CAP_A_0603V-22.0UF,4V,20%,X6S,A    I54 @BASEBOARD_FAB2_LIB.BASEBOARD_FAB2(SCH_1):PAGE243
 C5G86    1      A CAP_A_0603V-22.0UF,4V,20%,X6S,A    I55 @BASEBOARD_FAB2_LIB.BASEBOARD_FAB2(SCH_1):PAGE243
 C5G85    1      A CAP_A_0603V-22.0UF,4V,20%,X6S,A    I56 @BASEBOARD_FAB2_LIB.BASEBOARD_FAB2(SCH_1):PAGE243
 C5G84    1      A CAP_A_0603V-22.0UF,4V,20%,X6S,A    I57 @BASEBOARD_FAB2_LIB.BASEBOARD_FAB2(SCH_1):PAGE243
 C5G83    1      A CAP_A_0603V-22.0UF,4V,20%,X6S,A    I58 @BASEBOARD_FAB2_LIB.BASEBOARD_FAB2(SCH_1):PAGE243
 C5G82    1      A CAP_A_0603V-22.0UF,4V,20%,X6S,A    I59 @BASEBOARD_FAB2_LIB.BASEBOARD_FAB2(SCH_1):PAGE243
 C5G81    1      A CAP_A_0603V-22.0UF,4V,20%,X6S,A    I60 @BASEBOARD_FAB2_LIB.BASEBOARD_FAB2(SCH_1):PAGE243
 C5G80    1      A CAP_A_0603V-22.0UF,4V,20%,X6S,A    I61 @BASEBOARD_FAB2_LIB.BASEBOARD_FAB2(SCH_1):PAGE243
 C5G96    1      A CAP_A_0603V-22.0UF,4V,20%,X6S,A    I62 @BASEBOARD_FAB2_LIB.BASEBOARD_FAB2(SCH_1):PAGE243
 C5G95    1      A CAP_A_0603V-22.0UF,4V,20%,X6S,A    I63 @BASEBOARD_FAB2_LIB.BASEBOARD_FAB2(SCH_1):PAGE243
 C5G94    1      A CAP_A_0603V-22.0UF,4V,20%,X6S,A    I64 @BASEBOARD_FAB2_LIB.BASEBOARD_FAB2(SCH_1):PAGE243
 C5G93    1      A CAP_A_0603V-22.0UF,4V,20%,X6S,A    I65 @BASEBOARD_FAB2_LIB.BASEBOARD_FAB2(SCH_1):PAGE243
 C5G92    1      A CAP_A_0603V-22.0UF,4V,20%,X6S,A    I66 @BASEBOARD_FAB2_LIB.BASEBOARD_FAB2(SCH_1):PAGE243
 C5G91    1      A CAP_A_0603V-22.0UF,4V,20%,X6S,A    I67 @BASEBOARD_FAB2_LIB.BASEBOARD_FAB2(SCH_1):PAGE243
 C5G90    1      A CAP_A_0603V-22.0UF,4V,20%,X6S,A    I68 @BASEBOARD_FAB2_LIB.BASEBOARD_FAB2(SCH_1):PAGE243
 C5G89    1      A CAP_A_0603V-22.0UF,4V,20%,X6S,A    I69 @BASEBOARD_FAB2_LIB.BASEBOARD_FAB2(SCH_1):PAGE243
 C5G88    1      A CAP_A_0603V-22.0UF,4V,20%,X6S,A    I70 @BASEBOARD_FAB2_LIB.BASEBOARD_FAB2(SCH_1):PAGE243

PVDDQ_KLM @BASEBOARD_FAB2_LIB.BASEBOARD_FAB2(SCH_1):PVDDQ_KLM
  U2D1 EF59 VCCD345<0> SKX_EXT_B_BGA1-IC,TBD    I32 @BASEBOARD_FAB2_LIB.BASEBOARD_FAB2(SCH_1):PAGE72
  U2D1 EF53 VCCD345<1> SKX_EXT_B_BGA1-IC,TBD    I32 @BASEBOARD_FAB2_LIB.BASEBOARD_FAB2(SCH_1):PAGE72
  U2D1 EF49 VCCD345<2> SKX_EXT_B_BGA1-IC,TBD    I32 @BASEBOARD_FAB2_LIB.BASEBOARD_FAB2(SCH_1):PAGE72
  U2D1 EC62 VCCD345<3> SKX_EXT_B_BGA1-IC,TBD    I32 @BASEBOARD_FAB2_LIB.BASEBOARD_FAB2(SCH_1):PAGE72
  U2D1 EC60 VCCD345<4> SKX_EXT_B_BGA1-IC,TBD    I32 @BASEBOARD_FAB2_LIB.BASEBOARD_FAB2(SCH_1):PAGE72
  U2D1 EC58 VCCD345<5> SKX_EXT_B_BGA1-IC,TBD    I32 @BASEBOARD_FAB2_LIB.BASEBOARD_FAB2(SCH_1):PAGE72
  U2D1 EC56 VCCD345<6> SKX_EXT_B_BGA1-IC,TBD    I32 @BASEBOARD_FAB2_LIB.BASEBOARD_FAB2(SCH_1):PAGE72
  U2D1 EC54 VCCD345<7> SKX_EXT_B_BGA1-IC,TBD    I32 @BASEBOARD_FAB2_LIB.BASEBOARD_FAB2(SCH_1):PAGE72
  U2D1 EC52 VCCD345<8> SKX_EXT_B_BGA1-IC,TBD    I32 @BASEBOARD_FAB2_LIB.BASEBOARD_FAB2(SCH_1):PAGE72
  U2D1 EC50 VCCD345<9> SKX_EXT_B_BGA1-IC,TBD    I32 @BASEBOARD_FAB2_LIB.BASEBOARD_FAB2(SCH_1):PAGE72
  U2D1 EC48 VCCD345<10> SKX_EXT_B_BGA1-IC,TBD    I32 @BASEBOARD_FAB2_LIB.BASEBOARD_FAB2(SCH_1):PAGE72
  U2D1 EC46 VCCD345<11> SKX_EXT_B_BGA1-IC,TBD    I32 @BASEBOARD_FAB2_LIB.BASEBOARD_FAB2(SCH_1):PAGE72
  U2D1 DU64 VCCD345<12> SKX_EXT_B_BGA1-IC,TBD    I32 @BASEBOARD_FAB2_LIB.BASEBOARD_FAB2(SCH_1):PAGE72
  U2D1 DU62 VCCD345<13> SKX_EXT_B_BGA1-IC,TBD    I32 @BASEBOARD_FAB2_LIB.BASEBOARD_FAB2(SCH_1):PAGE72
  U2D1 DU60 VCCD345<14> SKX_EXT_B_BGA1-IC,TBD    I32 @BASEBOARD_FAB2_LIB.BASEBOARD_FAB2(SCH_1):PAGE72
  U2D1 DU58 VCCD345<15> SKX_EXT_B_BGA1-IC,TBD    I32 @BASEBOARD_FAB2_LIB.BASEBOARD_FAB2(SCH_1):PAGE72
  U2D1 DU56 VCCD345<16> SKX_EXT_B_BGA1-IC,TBD    I32 @BASEBOARD_FAB2_LIB.BASEBOARD_FAB2(SCH_1):PAGE72
  U2D1 DU54 VCCD345<17> SKX_EXT_B_BGA1-IC,TBD    I32 @BASEBOARD_FAB2_LIB.BASEBOARD_FAB2(SCH_1):PAGE72
  U2D1 DU52 VCCD345<18> SKX_EXT_B_BGA1-IC,TBD    I32 @BASEBOARD_FAB2_LIB.BASEBOARD_FAB2(SCH_1):PAGE72
  U2D1 DU50 VCCD345<19> SKX_EXT_B_BGA1-IC,TBD    I32 @BASEBOARD_FAB2_LIB.BASEBOARD_FAB2(SCH_1):PAGE72
  U2D1 DU48 VCCD345<20> SKX_EXT_B_BGA1-IC,TBD    I32 @BASEBOARD_FAB2_LIB.BASEBOARD_FAB2(SCH_1):PAGE72
  U2D1 DU46 VCCD345<21> SKX_EXT_B_BGA1-IC,TBD    I32 @BASEBOARD_FAB2_LIB.BASEBOARD_FAB2(SCH_1):PAGE72
  U2D1 DL62 VCCD345<22> SKX_EXT_B_BGA1-IC,TBD    I32 @BASEBOARD_FAB2_LIB.BASEBOARD_FAB2(SCH_1):PAGE72
  U2D1 DL60 VCCD345<23> SKX_EXT_B_BGA1-IC,TBD    I32 @BASEBOARD_FAB2_LIB.BASEBOARD_FAB2(SCH_1):PAGE72
  U2D1 DL58 VCCD345<24> SKX_EXT_B_BGA1-IC,TBD    I32 @BASEBOARD_FAB2_LIB.BASEBOARD_FAB2(SCH_1):PAGE72
  U2D1 DL56 VCCD345<25> SKX_EXT_B_BGA1-IC,TBD    I32 @BASEBOARD_FAB2_LIB.BASEBOARD_FAB2(SCH_1):PAGE72
  U2D1 DL54 VCCD345<26> SKX_EXT_B_BGA1-IC,TBD    I32 @BASEBOARD_FAB2_LIB.BASEBOARD_FAB2(SCH_1):PAGE72
  U2D1 DL52 VCCD345<27> SKX_EXT_B_BGA1-IC,TBD    I32 @BASEBOARD_FAB2_LIB.BASEBOARD_FAB2(SCH_1):PAGE72
  U2D1 DL50 VCCD345<28> SKX_EXT_B_BGA1-IC,TBD    I32 @BASEBOARD_FAB2_LIB.BASEBOARD_FAB2(SCH_1):PAGE72
  U2D1 DL48 VCCD345<29> SKX_EXT_B_BGA1-IC,TBD    I32 @BASEBOARD_FAB2_LIB.BASEBOARD_FAB2(SCH_1):PAGE72
  U2D1 DL46 VCCD345<30> SKX_EXT_B_BGA1-IC,TBD    I32 @BASEBOARD_FAB2_LIB.BASEBOARD_FAB2(SCH_1):PAGE72
  U2D1 DJ64 VCCD345<31> SKX_EXT_B_BGA1-IC,TBD    I32 @BASEBOARD_FAB2_LIB.BASEBOARD_FAB2(SCH_1):PAGE72
  U2D1 DH63 VCCD345<32> SKX_EXT_B_BGA1-IC,TBD    I32 @BASEBOARD_FAB2_LIB.BASEBOARD_FAB2(SCH_1):PAGE72
  U2D1 DH61 VCCD345<33> SKX_EXT_B_BGA1-IC,TBD    I32 @BASEBOARD_FAB2_LIB.BASEBOARD_FAB2(SCH_1):PAGE72
  U2D1 DH59 VCCD345<34> SKX_EXT_B_BGA1-IC,TBD    I32 @BASEBOARD_FAB2_LIB.BASEBOARD_FAB2(SCH_1):PAGE72
  U2D1 DH57 VCCD345<35> SKX_EXT_B_BGA1-IC,TBD    I32 @BASEBOARD_FAB2_LIB.BASEBOARD_FAB2(SCH_1):PAGE72
  U2D1 DH55 VCCD345<36> SKX_EXT_B_BGA1-IC,TBD    I32 @BASEBOARD_FAB2_LIB.BASEBOARD_FAB2(SCH_1):PAGE72
  U2D1 DH53 VCCD345<37> SKX_EXT_B_BGA1-IC,TBD    I32 @BASEBOARD_FAB2_LIB.BASEBOARD_FAB2(SCH_1):PAGE72
  U2D1 DH51 VCCD345<38> SKX_EXT_B_BGA1-IC,TBD    I32 @BASEBOARD_FAB2_LIB.BASEBOARD_FAB2(SCH_1):PAGE72
  U2D1 DH49 VCCD345<39> SKX_EXT_B_BGA1-IC,TBD    I32 @BASEBOARD_FAB2_LIB.BASEBOARD_FAB2(SCH_1):PAGE72
  U2D1 DH47 VCCD345<40> SKX_EXT_B_BGA1-IC,TBD    I32 @BASEBOARD_FAB2_LIB.BASEBOARD_FAB2(SCH_1):PAGE72
  U2D1 DH45 VCCD345<41> SKX_EXT_B_BGA1-IC,TBD    I32 @BASEBOARD_FAB2_LIB.BASEBOARD_FAB2(SCH_1):PAGE72
  U2D1 DD45 VCCD345<42> SKX_EXT_B_BGA1-IC,TBD    I32 @BASEBOARD_FAB2_LIB.BASEBOARD_FAB2(SCH_1):PAGE72
  U2D1 DB63 VCCD345<43> SKX_EXT_B_BGA1-IC,TBD    I32 @BASEBOARD_FAB2_LIB.BASEBOARD_FAB2(SCH_1):PAGE72
  U2D1 DB61 VCCD345<44> SKX_EXT_B_BGA1-IC,TBD    I32 @BASEBOARD_FAB2_LIB.BASEBOARD_FAB2(SCH_1):PAGE72
  U2D1 DB59 VCCD345<45> SKX_EXT_B_BGA1-IC,TBD    I32 @BASEBOARD_FAB2_LIB.BASEBOARD_FAB2(SCH_1):PAGE72
  U2D1 DB57 VCCD345<46> SKX_EXT_B_BGA1-IC,TBD    I32 @BASEBOARD_FAB2_LIB.BASEBOARD_FAB2(SCH_1):PAGE72
  U2D1 DB55 VCCD345<47> SKX_EXT_B_BGA1-IC,TBD    I32 @BASEBOARD_FAB2_LIB.BASEBOARD_FAB2(SCH_1):PAGE72
  U2D1 DB53 VCCD345<48> SKX_EXT_B_BGA1-IC,TBD    I32 @BASEBOARD_FAB2_LIB.BASEBOARD_FAB2(SCH_1):PAGE72
  U2D1 EF45 VCCD345<49> SKX_EXT_B_BGA1-IC,TBD    I32 @BASEBOARD_FAB2_LIB.BASEBOARD_FAB2(SCH_1):PAGE72
  U2D1 EE44 VCCD345<50> SKX_EXT_B_BGA1-IC,TBD    I32 @BASEBOARD_FAB2_LIB.BASEBOARD_FAB2(SCH_1):PAGE72
  J1B1  236 VDD<0> SCONN288_H44441004_PIP-SCONN,HA   I167 @BASEBOARD_FAB2_LIB.BASEBOARD_FAB2(SCH_1):PAGE83
  J1B1  233 VDD<1> SCONN288_H44441004_PIP-SCONN,HA   I167 @BASEBOARD_FAB2_LIB.BASEBOARD_FAB2(SCH_1):PAGE83
  J1B1  231 VDD<2> SCONN288_H44441004_PIP-SCONN,HA   I167 @BASEBOARD_FAB2_LIB.BASEBOARD_FAB2(SCH_1):PAGE83
  J1B1  229 VDD<3> SCONN288_H44441004_PIP-SCONN,HA   I167 @BASEBOARD_FAB2_LIB.BASEBOARD_FAB2(SCH_1):PAGE83
  J1B1  226 VDD<4> SCONN288_H44441004_PIP-SCONN,HA   I167 @BASEBOARD_FAB2_LIB.BASEBOARD_FAB2(SCH_1):PAGE83
  J1B1  223 VDD<5> SCONN288_H44441004_PIP-SCONN,HA   I167 @BASEBOARD_FAB2_LIB.BASEBOARD_FAB2(SCH_1):PAGE83
  J1B1  220 VDD<6> SCONN288_H44441004_PIP-SCONN,HA   I167 @BASEBOARD_FAB2_LIB.BASEBOARD_FAB2(SCH_1):PAGE83
  J1B1  217 VDD<7> SCONN288_H44441004_PIP-SCONN,HA   I167 @BASEBOARD_FAB2_LIB.BASEBOARD_FAB2(SCH_1):PAGE83
  J1B1  215 VDD<8> SCONN288_H44441004_PIP-SCONN,HA   I167 @BASEBOARD_FAB2_LIB.BASEBOARD_FAB2(SCH_1):PAGE83
  J1B1  212 VDD<9> SCONN288_H44441004_PIP-SCONN,HA   I167 @BASEBOARD_FAB2_LIB.BASEBOARD_FAB2(SCH_1):PAGE83
  J1B1  209 VDD<10> SCONN288_H44441004_PIP-SCONN,HA   I167 @BASEBOARD_FAB2_LIB.BASEBOARD_FAB2(SCH_1):PAGE83
  J1B1  206 VDD<11> SCONN288_H44441004_PIP-SCONN,HA   I167 @BASEBOARD_FAB2_LIB.BASEBOARD_FAB2(SCH_1):PAGE83
  J1B1  204 VDD<12> SCONN288_H44441004_PIP-SCONN,HA   I167 @BASEBOARD_FAB2_LIB.BASEBOARD_FAB2(SCH_1):PAGE83
  J1B1   92 VDD<13> SCONN288_H44441004_PIP-SCONN,HA   I167 @BASEBOARD_FAB2_LIB.BASEBOARD_FAB2(SCH_1):PAGE83
  J1B1   90 VDD<14> SCONN288_H44441004_PIP-SCONN,HA   I167 @BASEBOARD_FAB2_LIB.BASEBOARD_FAB2(SCH_1):PAGE83
  J1B1   88 VDD<15> SCONN288_H44441004_PIP-SCONN,HA   I167 @BASEBOARD_FAB2_LIB.BASEBOARD_FAB2(SCH_1):PAGE83
  J1B1   85 VDD<16> SCONN288_H44441004_PIP-SCONN,HA   I167 @BASEBOARD_FAB2_LIB.BASEBOARD_FAB2(SCH_1):PAGE83
  J1B1   83 VDD<17> SCONN288_H44441004_PIP-SCONN,HA   I167 @BASEBOARD_FAB2_LIB.BASEBOARD_FAB2(SCH_1):PAGE83
  J1B1   80 VDD<18> SCONN288_H44441004_PIP-SCONN,HA   I167 @BASEBOARD_FAB2_LIB.BASEBOARD_FAB2(SCH_1):PAGE83
  J1B1   76 VDD<19> SCONN288_H44441004_PIP-SCONN,HA   I167 @BASEBOARD_FAB2_LIB.BASEBOARD_FAB2(SCH_1):PAGE83
  J1B1   73 VDD<20> SCONN288_H44441004_PIP-SCONN,HA   I167 @BASEBOARD_FAB2_LIB.BASEBOARD_FAB2(SCH_1):PAGE83
  J1B1   70 VDD<21> SCONN288_H44441004_PIP-SCONN,HA   I167 @BASEBOARD_FAB2_LIB.BASEBOARD_FAB2(SCH_1):PAGE83
  J1B1   67 VDD<22> SCONN288_H44441004_PIP-SCONN,HA   I167 @BASEBOARD_FAB2_LIB.BASEBOARD_FAB2(SCH_1):PAGE83
  J1B1   64 VDD<23> SCONN288_H44441004_PIP-SCONN,HA   I167 @BASEBOARD_FAB2_LIB.BASEBOARD_FAB2(SCH_1):PAGE83
  J1B1   61 VDD<24> SCONN288_H44441004_PIP-SCONN,HA   I167 @BASEBOARD_FAB2_LIB.BASEBOARD_FAB2(SCH_1):PAGE83
  J1B1   59 VDD<25> SCONN288_H44441004_PIP-SCONN,HA   I167 @BASEBOARD_FAB2_LIB.BASEBOARD_FAB2(SCH_1):PAGE83
  J9M1  236 VDD<0> SCONN288_H44441003_PIP-SCONN,HA    I57 @BASEBOARD_FAB2_LIB.BASEBOARD_FAB2(SCH_1):PAGE84
  J9M1  233 VDD<1> SCONN288_H44441003_PIP-SCONN,HA    I57 @BASEBOARD_FAB2_LIB.BASEBOARD_FAB2(SCH_1):PAGE84
  J9M1  231 VDD<2> SCONN288_H44441003_PIP-SCONN,HA    I57 @BASEBOARD_FAB2_LIB.BASEBOARD_FAB2(SCH_1):PAGE84
  J9M1  229 VDD<3> SCONN288_H44441003_PIP-SCONN,HA    I57 @BASEBOARD_FAB2_LIB.BASEBOARD_FAB2(SCH_1):PAGE84
  J9M1  226 VDD<4> SCONN288_H44441003_PIP-SCONN,HA    I57 @BASEBOARD_FAB2_LIB.BASEBOARD_FAB2(SCH_1):PAGE84
  J9M1  223 VDD<5> SCONN288_H44441003_PIP-SCONN,HA    I57 @BASEBOARD_FAB2_LIB.BASEBOARD_FAB2(SCH_1):PAGE84
  J9M1  220 VDD<6> SCONN288_H44441003_PIP-SCONN,HA    I57 @BASEBOARD_FAB2_LIB.BASEBOARD_FAB2(SCH_1):PAGE84
  J9M1  217 VDD<7> SCONN288_H44441003_PIP-SCONN,HA    I57 @BASEBOARD_FAB2_LIB.BASEBOARD_FAB2(SCH_1):PAGE84
  J9M1  215 VDD<8> SCONN288_H44441003_PIP-SCONN,HA    I57 @BASEBOARD_FAB2_LIB.BASEBOARD_FAB2(SCH_1):PAGE84
  J9M1  212 VDD<9> SCONN288_H44441003_PIP-SCONN,HA    I57 @BASEBOARD_FAB2_LIB.BASEBOARD_FAB2(SCH_1):PAGE84
  J9M1  209 VDD<10> SCONN288_H44441003_PIP-SCONN,HA    I57 @BASEBOARD_FAB2_LIB.BASEBOARD_FAB2(SCH_1):PAGE84
  J9M1  206 VDD<11> SCONN288_H44441003_PIP-SCONN,HA    I57 @BASEBOARD_FAB2_LIB.BASEBOARD_FAB2(SCH_1):PAGE84
  J9M1  204 VDD<12> SCONN288_H44441003_PIP-SCONN,HA    I57 @BASEBOARD_FAB2_LIB.BASEBOARD_FAB2(SCH_1):PAGE84
  J9M1   92 VDD<13> SCONN288_H44441003_PIP-SCONN,HA    I57 @BASEBOARD_FAB2_LIB.BASEBOARD_FAB2(SCH_1):PAGE84
  J9M1   90 VDD<14> SCONN288_H44441003_PIP-SCONN,HA    I57 @BASEBOARD_FAB2_LIB.BASEBOARD_FAB2(SCH_1):PAGE84
  J9M1   88 VDD<15> SCONN288_H44441003_PIP-SCONN,HA    I57 @BASEBOARD_FAB2_LIB.BASEBOARD_FAB2(SCH_1):PAGE84
  J9M1   85 VDD<16> SCONN288_H44441003_PIP-SCONN,HA    I57 @BASEBOARD_FAB2_LIB.BASEBOARD_FAB2(SCH_1):PAGE84
  J9M1   83 VDD<17> SCONN288_H44441003_PIP-SCONN,HA    I57 @BASEBOARD_FAB2_LIB.BASEBOARD_FAB2(SCH_1):PAGE84
  J9M1   80 VDD<18> SCONN288_H44441003_PIP-SCONN,HA    I57 @BASEBOARD_FAB2_LIB.BASEBOARD_FAB2(SCH_1):PAGE84
  J9M1   76 VDD<19> SCONN288_H44441003_PIP-SCONN,HA    I57 @BASEBOARD_FAB2_LIB.BASEBOARD_FAB2(SCH_1):PAGE84
  J9M1   73 VDD<20> SCONN288_H44441003_PIP-SCONN,HA    I57 @BASEBOARD_FAB2_LIB.BASEBOARD_FAB2(SCH_1):PAGE84
  J9M1   70 VDD<21> SCONN288_H44441003_PIP-SCONN,HA    I57 @BASEBOARD_FAB2_LIB.BASEBOARD_FAB2(SCH_1):PAGE84
  J9M1   67 VDD<22> SCONN288_H44441003_PIP-SCONN,HA    I57 @BASEBOARD_FAB2_LIB.BASEBOARD_FAB2(SCH_1):PAGE84
  J9M1   64 VDD<23> SCONN288_H44441003_PIP-SCONN,HA    I57 @BASEBOARD_FAB2_LIB.BASEBOARD_FAB2(SCH_1):PAGE84
  J9M1   61 VDD<24> SCONN288_H44441003_PIP-SCONN,HA    I57 @BASEBOARD_FAB2_LIB.BASEBOARD_FAB2(SCH_1):PAGE84
  J9M1   59 VDD<25> SCONN288_H44441003_PIP-SCONN,HA    I57 @BASEBOARD_FAB2_LIB.BASEBOARD_FAB2(SCH_1):PAGE84
  J1A2  236 VDD<0> SCONN288_H44441004_PIP-SCONN,HA   I172 @BASEBOARD_FAB2_LIB.BASEBOARD_FAB2(SCH_1):PAGE85
  J1A2  233 VDD<1> SCONN288_H44441004_PIP-SCONN,HA   I172 @BASEBOARD_FAB2_LIB.BASEBOARD_FAB2(SCH_1):PAGE85
  J1A2  231 VDD<2> SCONN288_H44441004_PIP-SCONN,HA   I172 @BASEBOARD_FAB2_LIB.BASEBOARD_FAB2(SCH_1):PAGE85
  J1A2  229 VDD<3> SCONN288_H44441004_PIP-SCONN,HA   I172 @BASEBOARD_FAB2_LIB.BASEBOARD_FAB2(SCH_1):PAGE85
  J1A2  226 VDD<4> SCONN288_H44441004_PIP-SCONN,HA   I172 @BASEBOARD_FAB2_LIB.BASEBOARD_FAB2(SCH_1):PAGE85
  J1A2  223 VDD<5> SCONN288_H44441004_PIP-SCONN,HA   I172 @BASEBOARD_FAB2_LIB.BASEBOARD_FAB2(SCH_1):PAGE85
  J1A2  220 VDD<6> SCONN288_H44441004_PIP-SCONN,HA   I172 @BASEBOARD_FAB2_LIB.BASEBOARD_FAB2(SCH_1):PAGE85
  J1A2  217 VDD<7> SCONN288_H44441004_PIP-SCONN,HA   I172 @BASEBOARD_FAB2_LIB.BASEBOARD_FAB2(SCH_1):PAGE85
  J1A2  215 VDD<8> SCONN288_H44441004_PIP-SCONN,HA   I172 @BASEBOARD_FAB2_LIB.BASEBOARD_FAB2(SCH_1):PAGE85
  J1A2  212 VDD<9> SCONN288_H44441004_PIP-SCONN,HA   I172 @BASEBOARD_FAB2_LIB.BASEBOARD_FAB2(SCH_1):PAGE85
  J1A2  209 VDD<10> SCONN288_H44441004_PIP-SCONN,HA   I172 @BASEBOARD_FAB2_LIB.BASEBOARD_FAB2(SCH_1):PAGE85
  J1A2  206 VDD<11> SCONN288_H44441004_PIP-SCONN,HA   I172 @BASEBOARD_FAB2_LIB.BASEBOARD_FAB2(SCH_1):PAGE85
  J1A2  204 VDD<12> SCONN288_H44441004_PIP-SCONN,HA   I172 @BASEBOARD_FAB2_LIB.BASEBOARD_FAB2(SCH_1):PAGE85
  J1A2   92 VDD<13> SCONN288_H44441004_PIP-SCONN,HA   I172 @BASEBOARD_FAB2_LIB.BASEBOARD_FAB2(SCH_1):PAGE85
  J1A2   90 VDD<14> SCONN288_H44441004_PIP-SCONN,HA   I172 @BASEBOARD_FAB2_LIB.BASEBOARD_FAB2(SCH_1):PAGE85
  J1A2   88 VDD<15> SCONN288_H44441004_PIP-SCONN,HA   I172 @BASEBOARD_FAB2_LIB.BASEBOARD_FAB2(SCH_1):PAGE85
  J1A2   85 VDD<16> SCONN288_H44441004_PIP-SCONN,HA   I172 @BASEBOARD_FAB2_LIB.BASEBOARD_FAB2(SCH_1):PAGE85
  J1A2   83 VDD<17> SCONN288_H44441004_PIP-SCONN,HA   I172 @BASEBOARD_FAB2_LIB.BASEBOARD_FAB2(SCH_1):PAGE85
  J1A2   80 VDD<18> SCONN288_H44441004_PIP-SCONN,HA   I172 @BASEBOARD_FAB2_LIB.BASEBOARD_FAB2(SCH_1):PAGE85
  J1A2   76 VDD<19> SCONN288_H44441004_PIP-SCONN,HA   I172 @BASEBOARD_FAB2_LIB.BASEBOARD_FAB2(SCH_1):PAGE85
  J1A2   73 VDD<20> SCONN288_H44441004_PIP-SCONN,HA   I172 @BASEBOARD_FAB2_LIB.BASEBOARD_FAB2(SCH_1):PAGE85
  J1A2   70 VDD<21> SCONN288_H44441004_PIP-SCONN,HA   I172 @BASEBOARD_FAB2_LIB.BASEBOARD_FAB2(SCH_1):PAGE85
  J1A2   67 VDD<22> SCONN288_H44441004_PIP-SCONN,HA   I172 @BASEBOARD_FAB2_LIB.BASEBOARD_FAB2(SCH_1):PAGE85
  J1A2   64 VDD<23> SCONN288_H44441004_PIP-SCONN,HA   I172 @BASEBOARD_FAB2_LIB.BASEBOARD_FAB2(SCH_1):PAGE85
  J1A2   61 VDD<24> SCONN288_H44441004_PIP-SCONN,HA   I172 @BASEBOARD_FAB2_LIB.BASEBOARD_FAB2(SCH_1):PAGE85
  J1A2   59 VDD<25> SCONN288_H44441004_PIP-SCONN,HA   I172 @BASEBOARD_FAB2_LIB.BASEBOARD_FAB2(SCH_1):PAGE85
  J9L2  236 VDD<0> SCONN288_H44441003_PIP-SCONN,HA    I55 @BASEBOARD_FAB2_LIB.BASEBOARD_FAB2(SCH_1):PAGE86
  J9L2  233 VDD<1> SCONN288_H44441003_PIP-SCONN,HA    I55 @BASEBOARD_FAB2_LIB.BASEBOARD_FAB2(SCH_1):PAGE86
  J9L2  231 VDD<2> SCONN288_H44441003_PIP-SCONN,HA    I55 @BASEBOARD_FAB2_LIB.BASEBOARD_FAB2(SCH_1):PAGE86
  J9L2  229 VDD<3> SCONN288_H44441003_PIP-SCONN,HA    I55 @BASEBOARD_FAB2_LIB.BASEBOARD_FAB2(SCH_1):PAGE86
  J9L2  226 VDD<4> SCONN288_H44441003_PIP-SCONN,HA    I55 @BASEBOARD_FAB2_LIB.BASEBOARD_FAB2(SCH_1):PAGE86
  J9L2  223 VDD<5> SCONN288_H44441003_PIP-SCONN,HA    I55 @BASEBOARD_FAB2_LIB.BASEBOARD_FAB2(SCH_1):PAGE86
  J9L2  220 VDD<6> SCONN288_H44441003_PIP-SCONN,HA    I55 @BASEBOARD_FAB2_LIB.BASEBOARD_FAB2(SCH_1):PAGE86
  J9L2  217 VDD<7> SCONN288_H44441003_PIP-SCONN,HA    I55 @BASEBOARD_FAB2_LIB.BASEBOARD_FAB2(SCH_1):PAGE86
  J9L2  215 VDD<8> SCONN288_H44441003_PIP-SCONN,HA    I55 @BASEBOARD_FAB2_LIB.BASEBOARD_FAB2(SCH_1):PAGE86
  J9L2  212 VDD<9> SCONN288_H44441003_PIP-SCONN,HA    I55 @BASEBOARD_FAB2_LIB.BASEBOARD_FAB2(SCH_1):PAGE86
  J9L2  209 VDD<10> SCONN288_H44441003_PIP-SCONN,HA    I55 @BASEBOARD_FAB2_LIB.BASEBOARD_FAB2(SCH_1):PAGE86
  J9L2  206 VDD<11> SCONN288_H44441003_PIP-SCONN,HA    I55 @BASEBOARD_FAB2_LIB.BASEBOARD_FAB2(SCH_1):PAGE86
  J9L2  204 VDD<12> SCONN288_H44441003_PIP-SCONN,HA    I55 @BASEBOARD_FAB2_LIB.BASEBOARD_FAB2(SCH_1):PAGE86
  J9L2   92 VDD<13> SCONN288_H44441003_PIP-SCONN,HA    I55 @BASEBOARD_FAB2_LIB.BASEBOARD_FAB2(SCH_1):PAGE86
  J9L2   90 VDD<14> SCONN288_H44441003_PIP-SCONN,HA    I55 @BASEBOARD_FAB2_LIB.BASEBOARD_FAB2(SCH_1):PAGE86
  J9L2   88 VDD<15> SCONN288_H44441003_PIP-SCONN,HA    I55 @BASEBOARD_FAB2_LIB.BASEBOARD_FAB2(SCH_1):PAGE86
  J9L2   85 VDD<16> SCONN288_H44441003_PIP-SCONN,HA    I55 @BASEBOARD_FAB2_LIB.BASEBOARD_FAB2(SCH_1):PAGE86
  J9L2   83 VDD<17> SCONN288_H44441003_PIP-SCONN,HA    I55 @BASEBOARD_FAB2_LIB.BASEBOARD_FAB2(SCH_1):PAGE86
  J9L2   80 VDD<18> SCONN288_H44441003_PIP-SCONN,HA    I55 @BASEBOARD_FAB2_LIB.BASEBOARD_FAB2(SCH_1):PAGE86
  J9L2   76 VDD<19> SCONN288_H44441003_PIP-SCONN,HA    I55 @BASEBOARD_FAB2_LIB.BASEBOARD_FAB2(SCH_1):PAGE86
  J9L2   73 VDD<20> SCONN288_H44441003_PIP-SCONN,HA    I55 @BASEBOARD_FAB2_LIB.BASEBOARD_FAB2(SCH_1):PAGE86
  J9L2   70 VDD<21> SCONN288_H44441003_PIP-SCONN,HA    I55 @BASEBOARD_FAB2_LIB.BASEBOARD_FAB2(SCH_1):PAGE86
  J9L2   67 VDD<22> SCONN288_H44441003_PIP-SCONN,HA    I55 @BASEBOARD_FAB2_LIB.BASEBOARD_FAB2(SCH_1):PAGE86
  J9L2   64 VDD<23> SCONN288_H44441003_PIP-SCONN,HA    I55 @BASEBOARD_FAB2_LIB.BASEBOARD_FAB2(SCH_1):PAGE86
  J9L2   61 VDD<24> SCONN288_H44441003_PIP-SCONN,HA    I55 @BASEBOARD_FAB2_LIB.BASEBOARD_FAB2(SCH_1):PAGE86
  J9L2   59 VDD<25> SCONN288_H44441003_PIP-SCONN,HA    I55 @BASEBOARD_FAB2_LIB.BASEBOARD_FAB2(SCH_1):PAGE86
  J1A1  236 VDD<0> SCONN288_H44441004_PIP-SCONN,HA   I169 @BASEBOARD_FAB2_LIB.BASEBOARD_FAB2(SCH_1):PAGE87
  J1A1  233 VDD<1> SCONN288_H44441004_PIP-SCONN,HA   I169 @BASEBOARD_FAB2_LIB.BASEBOARD_FAB2(SCH_1):PAGE87
  J1A1  231 VDD<2> SCONN288_H44441004_PIP-SCONN,HA   I169 @BASEBOARD_FAB2_LIB.BASEBOARD_FAB2(SCH_1):PAGE87
  J1A1  229 VDD<3> SCONN288_H44441004_PIP-SCONN,HA   I169 @BASEBOARD_FAB2_LIB.BASEBOARD_FAB2(SCH_1):PAGE87
  J1A1  226 VDD<4> SCONN288_H44441004_PIP-SCONN,HA   I169 @BASEBOARD_FAB2_LIB.BASEBOARD_FAB2(SCH_1):PAGE87
  J1A1  223 VDD<5> SCONN288_H44441004_PIP-SCONN,HA   I169 @BASEBOARD_FAB2_LIB.BASEBOARD_FAB2(SCH_1):PAGE87
  J1A1  220 VDD<6> SCONN288_H44441004_PIP-SCONN,HA   I169 @BASEBOARD_FAB2_LIB.BASEBOARD_FAB2(SCH_1):PAGE87
  J1A1  217 VDD<7> SCONN288_H44441004_PIP-SCONN,HA   I169 @BASEBOARD_FAB2_LIB.BASEBOARD_FAB2(SCH_1):PAGE87
  J1A1  215 VDD<8> SCONN288_H44441004_PIP-SCONN,HA   I169 @BASEBOARD_FAB2_LIB.BASEBOARD_FAB2(SCH_1):PAGE87
  J1A1  212 VDD<9> SCONN288_H44441004_PIP-SCONN,HA   I169 @BASEBOARD_FAB2_LIB.BASEBOARD_FAB2(SCH_1):PAGE87
  J1A1  209 VDD<10> SCONN288_H44441004_PIP-SCONN,HA   I169 @BASEBOARD_FAB2_LIB.BASEBOARD_FAB2(SCH_1):PAGE87
  J1A1  206 VDD<11> SCONN288_H44441004_PIP-SCONN,HA   I169 @BASEBOARD_FAB2_LIB.BASEBOARD_FAB2(SCH_1):PAGE87
  J1A1  204 VDD<12> SCONN288_H44441004_PIP-SCONN,HA   I169 @BASEBOARD_FAB2_LIB.BASEBOARD_FAB2(SCH_1):PAGE87
  J1A1   92 VDD<13> SCONN288_H44441004_PIP-SCONN,HA   I169 @BASEBOARD_FAB2_LIB.BASEBOARD_FAB2(SCH_1):PAGE87
  J1A1   90 VDD<14> SCONN288_H44441004_PIP-SCONN,HA   I169 @BASEBOARD_FAB2_LIB.BASEBOARD_FAB2(SCH_1):PAGE87
  J1A1   88 VDD<15> SCONN288_H44441004_PIP-SCONN,HA   I169 @BASEBOARD_FAB2_LIB.BASEBOARD_FAB2(SCH_1):PAGE87
  J1A1   85 VDD<16> SCONN288_H44441004_PIP-SCONN,HA   I169 @BASEBOARD_FAB2_LIB.BASEBOARD_FAB2(SCH_1):PAGE87
  J1A1   83 VDD<17> SCONN288_H44441004_PIP-SCONN,HA   I169 @BASEBOARD_FAB2_LIB.BASEBOARD_FAB2(SCH_1):PAGE87
  J1A1   80 VDD<18> SCONN288_H44441004_PIP-SCONN,HA   I169 @BASEBOARD_FAB2_LIB.BASEBOARD_FAB2(SCH_1):PAGE87
  J1A1   76 VDD<19> SCONN288_H44441004_PIP-SCONN,HA   I169 @BASEBOARD_FAB2_LIB.BASEBOARD_FAB2(SCH_1):PAGE87
  J1A1   73 VDD<20> SCONN288_H44441004_PIP-SCONN,HA   I169 @BASEBOARD_FAB2_LIB.BASEBOARD_FAB2(SCH_1):PAGE87
  J1A1   70 VDD<21> SCONN288_H44441004_PIP-SCONN,HA   I169 @BASEBOARD_FAB2_LIB.BASEBOARD_FAB2(SCH_1):PAGE87
  J1A1   67 VDD<22> SCONN288_H44441004_PIP-SCONN,HA   I169 @BASEBOARD_FAB2_LIB.BASEBOARD_FAB2(SCH_1):PAGE87
  J1A1   64 VDD<23> SCONN288_H44441004_PIP-SCONN,HA   I169 @BASEBOARD_FAB2_LIB.BASEBOARD_FAB2(SCH_1):PAGE87
  J1A1   61 VDD<24> SCONN288_H44441004_PIP-SCONN,HA   I169 @BASEBOARD_FAB2_LIB.BASEBOARD_FAB2(SCH_1):PAGE87
  J1A1   59 VDD<25> SCONN288_H44441004_PIP-SCONN,HA   I169 @BASEBOARD_FAB2_LIB.BASEBOARD_FAB2(SCH_1):PAGE87
  J9L1  236 VDD<0> SCONN288_H44441003_PIP-SCONN,HA   I168 @BASEBOARD_FAB2_LIB.BASEBOARD_FAB2(SCH_1):PAGE88
  J9L1  233 VDD<1> SCONN288_H44441003_PIP-SCONN,HA   I168 @BASEBOARD_FAB2_LIB.BASEBOARD_FAB2(SCH_1):PAGE88
  J9L1  231 VDD<2> SCONN288_H44441003_PIP-SCONN,HA   I168 @BASEBOARD_FAB2_LIB.BASEBOARD_FAB2(SCH_1):PAGE88
  J9L1  229 VDD<3> SCONN288_H44441003_PIP-SCONN,HA   I168 @BASEBOARD_FAB2_LIB.BASEBOARD_FAB2(SCH_1):PAGE88
  J9L1  226 VDD<4> SCONN288_H44441003_PIP-SCONN,HA   I168 @BASEBOARD_FAB2_LIB.BASEBOARD_FAB2(SCH_1):PAGE88
  J9L1  223 VDD<5> SCONN288_H44441003_PIP-SCONN,HA   I168 @BASEBOARD_FAB2_LIB.BASEBOARD_FAB2(SCH_1):PAGE88
  J9L1  220 VDD<6> SCONN288_H44441003_PIP-SCONN,HA   I168 @BASEBOARD_FAB2_LIB.BASEBOARD_FAB2(SCH_1):PAGE88
  J9L1  217 VDD<7> SCONN288_H44441003_PIP-SCONN,HA   I168 @BASEBOARD_FAB2_LIB.BASEBOARD_FAB2(SCH_1):PAGE88
  J9L1  215 VDD<8> SCONN288_H44441003_PIP-SCONN,HA   I168 @BASEBOARD_FAB2_LIB.BASEBOARD_FAB2(SCH_1):PAGE88
  J9L1  212 VDD<9> SCONN288_H44441003_PIP-SCONN,HA   I168 @BASEBOARD_FAB2_LIB.BASEBOARD_FAB2(SCH_1):PAGE88
  J9L1  209 VDD<10> SCONN288_H44441003_PIP-SCONN,HA   I168 @BASEBOARD_FAB2_LIB.BASEBOARD_FAB2(SCH_1):PAGE88
  J9L1  206 VDD<11> SCONN288_H44441003_PIP-SCONN,HA   I168 @BASEBOARD_FAB2_LIB.BASEBOARD_FAB2(SCH_1):PAGE88
  J9L1  204 VDD<12> SCONN288_H44441003_PIP-SCONN,HA   I168 @BASEBOARD_FAB2_LIB.BASEBOARD_FAB2(SCH_1):PAGE88
  J9L1   92 VDD<13> SCONN288_H44441003_PIP-SCONN,HA   I168 @BASEBOARD_FAB2_LIB.BASEBOARD_FAB2(SCH_1):PAGE88
  J9L1   90 VDD<14> SCONN288_H44441003_PIP-SCONN,HA   I168 @BASEBOARD_FAB2_LIB.BASEBOARD_FAB2(SCH_1):PAGE88
  J9L1   88 VDD<15> SCONN288_H44441003_PIP-SCONN,HA   I168 @BASEBOARD_FAB2_LIB.BASEBOARD_FAB2(SCH_1):PAGE88
  J9L1   85 VDD<16> SCONN288_H44441003_PIP-SCONN,HA   I168 @BASEBOARD_FAB2_LIB.BASEBOARD_FAB2(SCH_1):PAGE88
  J9L1   83 VDD<17> SCONN288_H44441003_PIP-SCONN,HA   I168 @BASEBOARD_FAB2_LIB.BASEBOARD_FAB2(SCH_1):PAGE88
  J9L1   80 VDD<18> SCONN288_H44441003_PIP-SCONN,HA   I168 @BASEBOARD_FAB2_LIB.BASEBOARD_FAB2(SCH_1):PAGE88
  J9L1   76 VDD<19> SCONN288_H44441003_PIP-SCONN,HA   I168 @BASEBOARD_FAB2_LIB.BASEBOARD_FAB2(SCH_1):PAGE88
  J9L1   73 VDD<20> SCONN288_H44441003_PIP-SCONN,HA   I168 @BASEBOARD_FAB2_LIB.BASEBOARD_FAB2(SCH_1):PAGE88
  J9L1   70 VDD<21> SCONN288_H44441003_PIP-SCONN,HA   I168 @BASEBOARD_FAB2_LIB.BASEBOARD_FAB2(SCH_1):PAGE88
  J9L1   67 VDD<22> SCONN288_H44441003_PIP-SCONN,HA   I168 @BASEBOARD_FAB2_LIB.BASEBOARD_FAB2(SCH_1):PAGE88
  J9L1   64 VDD<23> SCONN288_H44441003_PIP-SCONN,HA   I168 @BASEBOARD_FAB2_LIB.BASEBOARD_FAB2(SCH_1):PAGE88
  J9L1   61 VDD<24> SCONN288_H44441003_PIP-SCONN,HA   I168 @BASEBOARD_FAB2_LIB.BASEBOARD_FAB2(SCH_1):PAGE88
  J9L1   59 VDD<25> SCONN288_H44441003_PIP-SCONN,HA   I168 @BASEBOARD_FAB2_LIB.BASEBOARD_FAB2(SCH_1):PAGE88
  R7M9    1      A RES_0402-64.9,1.0%,1/16W,CHIP,A    I28 @BASEBOARD_FAB2_LIB.BASEBOARD_FAB2(SCH_1):PAGE96
  R9M1    1      A RES_0402-1.00K,1%,1/16W,CHIP,GA    I11 @BASEBOARD_FAB2_LIB.BASEBOARD_FAB2(SCH_1):PAGE100
  R9L7    1      A RES_0402-1.00K,1%,1/16W,CHIP,GA    I22 @BASEBOARD_FAB2_LIB.BASEBOARD_FAB2(SCH_1):PAGE100
  R9L2    1      A RES_0402-1.00K,1%,1/16W,CHIP,GA    I38 @BASEBOARD_FAB2_LIB.BASEBOARD_FAB2(SCH_1):PAGE100
 C1A12    1      A CAP_0805LF-22UF,4V,20%,X6S,C95A     I6 @BASEBOARD_FAB2_LIB.BASEBOARD_FAB2(SCH_1):PAGE227
  L1A2    2    INB INDUCTOR_SM-0.12UH,IND,D92183-A    I55 @BASEBOARD_FAB2_LIB.BASEBOARD_FAB2(SCH_1):PAGE227
  L1A1    2    INB INDUCTOR_SM-0.12UH,IND,D92183-A    I65 @BASEBOARD_FAB2_LIB.BASEBOARD_FAB2(SCH_1):PAGE227
  C1A1    1      A CAP_0805LF-22UF,4V,20%,X6S,C95A    I68 @BASEBOARD_FAB2_LIB.BASEBOARD_FAB2(SCH_1):PAGE227
 EU1A2    1    VOS IR354XX_SM-IR35411,IC,H73688-0A   I101 @BASEBOARD_FAB2_LIB.BASEBOARD_FAB2(SCH_1):PAGE227
 EU1A1    1    VOS IR354XX_SM-IR35411,IC,H73688-0A   I102 @BASEBOARD_FAB2_LIB.BASEBOARD_FAB2(SCH_1):PAGE227
  R1A1    1      A RES_0603-120.0,1%,1/10W,CHIP,GA    I58 @BASEBOARD_FAB2_LIB.BASEBOARD_FAB2(SCH_1):PAGE228
  C9L9    1      A CAPP_3018-470UF,2.5V,20%,ALUM,A    I75 @BASEBOARD_FAB2_LIB.BASEBOARD_FAB2(SCH_1):PAGE228
 C9L12    1      A CAPP_3018-470UF,2.5V,20%,ALUM,A    I76 @BASEBOARD_FAB2_LIB.BASEBOARD_FAB2(SCH_1):PAGE228
  C9L4    1      A CAPP_3018-470UF,2.5V,20%,ALUM,A    I77 @BASEBOARD_FAB2_LIB.BASEBOARD_FAB2(SCH_1):PAGE228
  C9L2    1      A CAPP_3018-470UF,2.5V,20%,ALUM,A    I78 @BASEBOARD_FAB2_LIB.BASEBOARD_FAB2(SCH_1):PAGE228
  C2A8    1      A CAP_0805-100UF,4V,20%,X5R,6024A    I82 @BASEBOARD_FAB2_LIB.BASEBOARD_FAB2(SCH_1):PAGE228
  C8L2    1      A CAP_0805-100UF,4V,20%,X5R,6024A    I83 @BASEBOARD_FAB2_LIB.BASEBOARD_FAB2(SCH_1):PAGE228
 C8L11    1      A CAP_0805-100UF,4V,20%,X5R,6024A    I88 @BASEBOARD_FAB2_LIB.BASEBOARD_FAB2(SCH_1):PAGE228
 C2A16    1      A CAP_0805-100UF,4V,20%,X5R,6024A    I89 @BASEBOARD_FAB2_LIB.BASEBOARD_FAB2(SCH_1):PAGE228
  C8M7    1      A CAP_0805-100UF,4V,20%,X5R,6024A    I90 @BASEBOARD_FAB2_LIB.BASEBOARD_FAB2(SCH_1):PAGE228
 C8M11    1      A CAP_0805-100UF,4V,20%,X5R,6024A    I91 @BASEBOARD_FAB2_LIB.BASEBOARD_FAB2(SCH_1):PAGE228
  C7L1    1      A CAP_0805-100UF,4V,20%,X5R,6024A    I92 @BASEBOARD_FAB2_LIB.BASEBOARD_FAB2(SCH_1):PAGE228
  C8L1    1      A CAP_0805-100UF,4V,20%,X5R,6024A   I110 @BASEBOARD_FAB2_LIB.BASEBOARD_FAB2(SCH_1):PAGE228
  C8P2    1      A CAP_0805LF-22UF,4V,20%,X6S,C95A   I183 @BASEBOARD_FAB2_LIB.BASEBOARD_FAB2(SCH_1):PAGE228
  C8P1    1      A CAP_0805LF-22UF,4V,20%,X6S,C95A   I185 @BASEBOARD_FAB2_LIB.BASEBOARD_FAB2(SCH_1):PAGE228
  C2D7    1      A CAP_0603LF-10UF,4V,20%,X6S,E15A   I186 @BASEBOARD_FAB2_LIB.BASEBOARD_FAB2(SCH_1):PAGE228
  C2D4    1      A CAP_0603LF-10UF,4V,20%,X6S,E15A   I187 @BASEBOARD_FAB2_LIB.BASEBOARD_FAB2(SCH_1):PAGE228
  C2D5    1      A CAP_0603LF-10UF,4V,20%,X6S,E15A   I188 @BASEBOARD_FAB2_LIB.BASEBOARD_FAB2(SCH_1):PAGE228
  C2D6    1      A CAP_0603LF-10UF,4V,20%,X6S,E15A   I190 @BASEBOARD_FAB2_LIB.BASEBOARD_FAB2(SCH_1):PAGE228
  C8M8    1      A CAP_A_0603V-47UF,4V,20%,X5R,60A   I198 @BASEBOARD_FAB2_LIB.BASEBOARD_FAB2(SCH_1):PAGE228
  C2A5    1      A CAP_A_0603V-47UF,4V,20%,X5R,60A   I199 @BASEBOARD_FAB2_LIB.BASEBOARD_FAB2(SCH_1):PAGE228
  C2B1    1      A CAP_A_0603V-47UF,4V,20%,X5R,60A   I200 @BASEBOARD_FAB2_LIB.BASEBOARD_FAB2(SCH_1):PAGE228
 C8L12    1      A CAP_A_0603V-47UF,4V,20%,X5R,60A   I201 @BASEBOARD_FAB2_LIB.BASEBOARD_FAB2(SCH_1):PAGE228
  C7M5    1      A CAP_A_0603V-47UF,4V,20%,X5R,60A   I202 @BASEBOARD_FAB2_LIB.BASEBOARD_FAB2(SCH_1):PAGE228
 C8M10    1      A CAP_A_0603V-47UF,4V,20%,X5R,60A   I203 @BASEBOARD_FAB2_LIB.BASEBOARD_FAB2(SCH_1):PAGE228
  C2B2    1      A CAP_A_0603V-47UF,4V,20%,X5R,60A   I204 @BASEBOARD_FAB2_LIB.BASEBOARD_FAB2(SCH_1):PAGE228
  C8M9    1      A CAP_A_0603V-47UF,4V,20%,X5R,60A   I205 @BASEBOARD_FAB2_LIB.BASEBOARD_FAB2(SCH_1):PAGE228
  C8M2    1      A CAP_A_0603V-47UF,4V,20%,X5R,60A   I206 @BASEBOARD_FAB2_LIB.BASEBOARD_FAB2(SCH_1):PAGE228
  C2A2    1      A CAP_A_0603V-22.0UF,4V,20%,X6S,A   I209 @BASEBOARD_FAB2_LIB.BASEBOARD_FAB2(SCH_1):PAGE228
  C2A1    1      A CAP_A_0603V-22.0UF,4V,20%,X6S,A   I210 @BASEBOARD_FAB2_LIB.BASEBOARD_FAB2(SCH_1):PAGE228
 C2A12    1      A CAP_A_0603V-22.0UF,4V,20%,X6S,A   I211 @BASEBOARD_FAB2_LIB.BASEBOARD_FAB2(SCH_1):PAGE228
 C2A13    1      A CAP_A_0603V-22.0UF,4V,20%,X6S,A   I212 @BASEBOARD_FAB2_LIB.BASEBOARD_FAB2(SCH_1):PAGE228
 C2A11    1      A CAP_A_0603V-22.0UF,4V,20%,X6S,A   I213 @BASEBOARD_FAB2_LIB.BASEBOARD_FAB2(SCH_1):PAGE228
 C2A10    1      A CAP_A_0603V-22.0UF,4V,20%,X6S,A   I214 @BASEBOARD_FAB2_LIB.BASEBOARD_FAB2(SCH_1):PAGE228
  C2A9    1      A CAP_A_0603V-22.0UF,4V,20%,X6S,A   I215 @BASEBOARD_FAB2_LIB.BASEBOARD_FAB2(SCH_1):PAGE228
  C3A2    1      A CAP_A_0603V-22.0UF,4V,20%,X6S,A   I216 @BASEBOARD_FAB2_LIB.BASEBOARD_FAB2(SCH_1):PAGE228
  C3A1    1      A CAP_A_0603V-22.0UF,4V,20%,X6S,A   I217 @BASEBOARD_FAB2_LIB.BASEBOARD_FAB2(SCH_1):PAGE228
  C2A7    1      A CAP_A_0603V-22.0UF,4V,20%,X6S,A   I218 @BASEBOARD_FAB2_LIB.BASEBOARD_FAB2(SCH_1):PAGE228
  C2A6    1      A CAP_A_0603V-22.0UF,4V,20%,X6S,A   I219 @BASEBOARD_FAB2_LIB.BASEBOARD_FAB2(SCH_1):PAGE228
 C2A14    1      A CAP_A_0603V-22.0UF,4V,20%,X6S,A   I220 @BASEBOARD_FAB2_LIB.BASEBOARD_FAB2(SCH_1):PAGE228
 C2A15    1      A CAP_A_0603V-22.0UF,4V,20%,X6S,A   I221 @BASEBOARD_FAB2_LIB.BASEBOARD_FAB2(SCH_1):PAGE228
  C3A5    1      A CAP_A_0603V-22.0UF,4V,20%,X6S,A   I222 @BASEBOARD_FAB2_LIB.BASEBOARD_FAB2(SCH_1):PAGE228
  C3A6    1      A CAP_A_0603V-22.0UF,4V,20%,X6S,A   I223 @BASEBOARD_FAB2_LIB.BASEBOARD_FAB2(SCH_1):PAGE228
  C7L5    1      A CAP_A_0603V-22.0UF,4V,20%,X6S,A   I225 @BASEBOARD_FAB2_LIB.BASEBOARD_FAB2(SCH_1):PAGE228
  C8M3    1      A CAP_A_0603V-22.0UF,4V,20%,X6S,A   I227 @BASEBOARD_FAB2_LIB.BASEBOARD_FAB2(SCH_1):PAGE228
  C8M5    1      A CAP_A_0603V-22.0UF,4V,20%,X6S,A   I228 @BASEBOARD_FAB2_LIB.BASEBOARD_FAB2(SCH_1):PAGE228
 C8L10    1      A CAP_A_0603V-22.0UF,4V,20%,X6S,A   I229 @BASEBOARD_FAB2_LIB.BASEBOARD_FAB2(SCH_1):PAGE228
  C2A3    1      A CAP_A_0603V-22.0UF,4V,20%,X6S,A   I230 @BASEBOARD_FAB2_LIB.BASEBOARD_FAB2(SCH_1):PAGE228
  C7M1    1      A CAP_A_0603V-22.0UF,4V,20%,X6S,A   I231 @BASEBOARD_FAB2_LIB.BASEBOARD_FAB2(SCH_1):PAGE228
  C7M2    1      A CAP_A_0603V-22.0UF,4V,20%,X6S,A   I232 @BASEBOARD_FAB2_LIB.BASEBOARD_FAB2(SCH_1):PAGE228
  C8M4    1      A CAP_A_0603V-22.0UF,4V,20%,X6S,A   I233 @BASEBOARD_FAB2_LIB.BASEBOARD_FAB2(SCH_1):PAGE228
  C2A4    1      A CAP_A_0603V-22.0UF,4V,20%,X6S,A   I234 @BASEBOARD_FAB2_LIB.BASEBOARD_FAB2(SCH_1):PAGE228
  C8M6    1      A CAP_A_0603V-22.0UF,4V,20%,X6S,A   I235 @BASEBOARD_FAB2_LIB.BASEBOARD_FAB2(SCH_1):PAGE228
  C8L9    1      A CAP_A_0603V-22.0UF,4V,20%,X6S,A   I236 @BASEBOARD_FAB2_LIB.BASEBOARD_FAB2(SCH_1):PAGE228
  C8L8    1      A CAP_A_0603V-22.0UF,4V,20%,X6S,A   I237 @BASEBOARD_FAB2_LIB.BASEBOARD_FAB2(SCH_1):PAGE228
  C7L4    1      A CAP_A_0603V-22.0UF,4V,20%,X6S,A   I238 @BASEBOARD_FAB2_LIB.BASEBOARD_FAB2(SCH_1):PAGE228
  C8L7    1      A CAP_A_0603V-22.0UF,4V,20%,X6S,A   I239 @BASEBOARD_FAB2_LIB.BASEBOARD_FAB2(SCH_1):PAGE228
  C8L6    1      A CAP_A_0603V-22.0UF,4V,20%,X6S,A   I240 @BASEBOARD_FAB2_LIB.BASEBOARD_FAB2(SCH_1):PAGE228
  C8L5    1      A CAP_A_0603V-22.0UF,4V,20%,X6S,A   I241 @BASEBOARD_FAB2_LIB.BASEBOARD_FAB2(SCH_1):PAGE228
  C8M1    1      A CAP_A_0603V-22.0UF,4V,20%,X6S,A   I243 @BASEBOARD_FAB2_LIB.BASEBOARD_FAB2(SCH_1):PAGE228
 SH7L2    2      B SHUNT_SH0201-EMPTY,N_A   I245 @BASEBOARD_FAB2_LIB.BASEBOARD_FAB2(SCH_1):PAGE228
 C4A15    1      A CAP_0603LF-10UF,4V,20%,X6S,E15A    I25 @BASEBOARD_FAB2_LIB.BASEBOARD_FAB2(SCH_1):PAGE230
  C6L5    1      A CAP_0603LF-10UF,4V,20%,X6S,E15A    I26 @BASEBOARD_FAB2_LIB.BASEBOARD_FAB2(SCH_1):PAGE230
 EU4A2   10    VIN MIC5166_DFN-IC,H55101-001    I31 @BASEBOARD_FAB2_LIB.BASEBOARD_FAB2(SCH_1):PAGE230
  R6L6    1      A RES_0402-0.0,5%,1/16W,CHIP,G21A    I34 @BASEBOARD_FAB2_LIB.BASEBOARD_FAB2(SCH_1):PAGE230
C5G115    1      A CAP_0805-100UF,4V,20%,X5R,6024A    I39 @BASEBOARD_FAB2_LIB.BASEBOARD_FAB2(SCH_1):PAGE243
C5G116    1      A CAP_0805-100UF,4V,20%,X5R,6024A    I43 @BASEBOARD_FAB2_LIB.BASEBOARD_FAB2(SCH_1):PAGE243
C5G103    1      A CAP_A_0603V-22.0UF,4V,20%,X6S,A    I71 @BASEBOARD_FAB2_LIB.BASEBOARD_FAB2(SCH_1):PAGE243
C5G104    1      A CAP_A_0603V-22.0UF,4V,20%,X6S,A    I72 @BASEBOARD_FAB2_LIB.BASEBOARD_FAB2(SCH_1):PAGE243
C5G105    1      A CAP_A_0603V-22.0UF,4V,20%,X6S,A    I73 @BASEBOARD_FAB2_LIB.BASEBOARD_FAB2(SCH_1):PAGE243
C5G102    1      A CAP_A_0603V-22.0UF,4V,20%,X6S,A    I74 @BASEBOARD_FAB2_LIB.BASEBOARD_FAB2(SCH_1):PAGE243
C5G101    1      A CAP_A_0603V-22.0UF,4V,20%,X6S,A    I75 @BASEBOARD_FAB2_LIB.BASEBOARD_FAB2(SCH_1):PAGE243
C5G100    1      A CAP_A_0603V-22.0UF,4V,20%,X6S,A    I76 @BASEBOARD_FAB2_LIB.BASEBOARD_FAB2(SCH_1):PAGE243
 C5G99    1      A CAP_A_0603V-22.0UF,4V,20%,X6S,A    I77 @BASEBOARD_FAB2_LIB.BASEBOARD_FAB2(SCH_1):PAGE243
 C5G98    1      A CAP_A_0603V-22.0UF,4V,20%,X6S,A    I78 @BASEBOARD_FAB2_LIB.BASEBOARD_FAB2(SCH_1):PAGE243
 C5G97    1      A CAP_A_0603V-22.0UF,4V,20%,X6S,A    I79 @BASEBOARD_FAB2_LIB.BASEBOARD_FAB2(SCH_1):PAGE243
C5G114    1      A CAP_A_0603V-22.0UF,4V,20%,X6S,A    I80 @BASEBOARD_FAB2_LIB.BASEBOARD_FAB2(SCH_1):PAGE243
C5G113    1      A CAP_A_0603V-22.0UF,4V,20%,X6S,A    I81 @BASEBOARD_FAB2_LIB.BASEBOARD_FAB2(SCH_1):PAGE243
C5G112    1      A CAP_A_0603V-22.0UF,4V,20%,X6S,A    I82 @BASEBOARD_FAB2_LIB.BASEBOARD_FAB2(SCH_1):PAGE243
C5G111    1      A CAP_A_0603V-22.0UF,4V,20%,X6S,A    I83 @BASEBOARD_FAB2_LIB.BASEBOARD_FAB2(SCH_1):PAGE243
C5G110    1      A CAP_A_0603V-22.0UF,4V,20%,X6S,A    I84 @BASEBOARD_FAB2_LIB.BASEBOARD_FAB2(SCH_1):PAGE243
C5G109    1      A CAP_A_0603V-22.0UF,4V,20%,X6S,A    I85 @BASEBOARD_FAB2_LIB.BASEBOARD_FAB2(SCH_1):PAGE243
C5G108    1      A CAP_A_0603V-22.0UF,4V,20%,X6S,A    I86 @BASEBOARD_FAB2_LIB.BASEBOARD_FAB2(SCH_1):PAGE243
C5G107    1      A CAP_A_0603V-22.0UF,4V,20%,X6S,A    I87 @BASEBOARD_FAB2_LIB.BASEBOARD_FAB2(SCH_1):PAGE243
C5G106    1      A CAP_A_0603V-22.0UF,4V,20%,X6S,A    I88 @BASEBOARD_FAB2_LIB.BASEBOARD_FAB2(SCH_1):PAGE243

PVNN_PCH_STBY @BASEBOARD_FAB2_LIB.BASEBOARD_FAB2(SCH_1):PVNN_PCH_STBY
  U7C1 AU36 VCCPRIM_AVID<0> LBG_CORE_QAT_EXT_D_BGA1-IC,H91A    I21 @BASEBOARD_FAB2_LIB.BASEBOARD_FAB2(SCH_1):PAGE123
  U7C1 AU34 VCCPRIM_AVID<1> LBG_CORE_QAT_EXT_D_BGA1-IC,H91A    I21 @BASEBOARD_FAB2_LIB.BASEBOARD_FAB2(SCH_1):PAGE123
  U7C1 AU32 VCCPRIM_AVID<2> LBG_CORE_QAT_EXT_D_BGA1-IC,H91A    I21 @BASEBOARD_FAB2_LIB.BASEBOARD_FAB2(SCH_1):PAGE123
  U7C1 AT36 VCCPRIM_AVID<3> LBG_CORE_QAT_EXT_D_BGA1-IC,H91A    I21 @BASEBOARD_FAB2_LIB.BASEBOARD_FAB2(SCH_1):PAGE123
  U7C1 AT34 VCCPRIM_AVID<4> LBG_CORE_QAT_EXT_D_BGA1-IC,H91A    I21 @BASEBOARD_FAB2_LIB.BASEBOARD_FAB2(SCH_1):PAGE123
  U7C1 AT32 VCCPRIM_AVID<5> LBG_CORE_QAT_EXT_D_BGA1-IC,H91A    I21 @BASEBOARD_FAB2_LIB.BASEBOARD_FAB2(SCH_1):PAGE123
  U7C1 AP39 VCCPRIM_AVID<6> LBG_CORE_QAT_EXT_D_BGA1-IC,H91A    I21 @BASEBOARD_FAB2_LIB.BASEBOARD_FAB2(SCH_1):PAGE123
  U7C1 AP37 VCCPRIM_AVID<7> LBG_CORE_QAT_EXT_D_BGA1-IC,H91A    I21 @BASEBOARD_FAB2_LIB.BASEBOARD_FAB2(SCH_1):PAGE123
  U7C1 AP36 VCCPRIM_AVID<8> LBG_CORE_QAT_EXT_D_BGA1-IC,H91A    I21 @BASEBOARD_FAB2_LIB.BASEBOARD_FAB2(SCH_1):PAGE123
  U7C1 AP34 VCCPRIM_AVID<9> LBG_CORE_QAT_EXT_D_BGA1-IC,H91A    I21 @BASEBOARD_FAB2_LIB.BASEBOARD_FAB2(SCH_1):PAGE123
  U7C1 AP32 VCCPRIM_AVID<10> LBG_CORE_QAT_EXT_D_BGA1-IC,H91A    I21 @BASEBOARD_FAB2_LIB.BASEBOARD_FAB2(SCH_1):PAGE123
  U7C1 AM39 VCCPRIM_AVID<11> LBG_CORE_QAT_EXT_D_BGA1-IC,H91A    I21 @BASEBOARD_FAB2_LIB.BASEBOARD_FAB2(SCH_1):PAGE123
  U7C1 AM37 VCCPRIM_AVID<12> LBG_CORE_QAT_EXT_D_BGA1-IC,H91A    I21 @BASEBOARD_FAB2_LIB.BASEBOARD_FAB2(SCH_1):PAGE123
  U7C1 AM36 VCCPRIM_AVID<13> LBG_CORE_QAT_EXT_D_BGA1-IC,H91A    I21 @BASEBOARD_FAB2_LIB.BASEBOARD_FAB2(SCH_1):PAGE123
  U7C1 AM34 VCCPRIM_AVID<14> LBG_CORE_QAT_EXT_D_BGA1-IC,H91A    I21 @BASEBOARD_FAB2_LIB.BASEBOARD_FAB2(SCH_1):PAGE123
  U7C1 AM32 VCCPRIM_AVID<15> LBG_CORE_QAT_EXT_D_BGA1-IC,H91A    I21 @BASEBOARD_FAB2_LIB.BASEBOARD_FAB2(SCH_1):PAGE123
  U7C1 AK39 VCCPRIM_AVID<16> LBG_CORE_QAT_EXT_D_BGA1-IC,H91A    I21 @BASEBOARD_FAB2_LIB.BASEBOARD_FAB2(SCH_1):PAGE123
  U7C1 AK37 VCCPRIM_AVID<17> LBG_CORE_QAT_EXT_D_BGA1-IC,H91A    I21 @BASEBOARD_FAB2_LIB.BASEBOARD_FAB2(SCH_1):PAGE123
  U7C1 AK34 VCCPRIM_AVID<18> LBG_CORE_QAT_EXT_D_BGA1-IC,H91A    I21 @BASEBOARD_FAB2_LIB.BASEBOARD_FAB2(SCH_1):PAGE123
  U7C1 AG39 VCCPRIM_AVID<19> LBG_CORE_QAT_EXT_D_BGA1-IC,H91A    I21 @BASEBOARD_FAB2_LIB.BASEBOARD_FAB2(SCH_1):PAGE123
  U7C1 AG37 VCCPRIM_AVID<20> LBG_CORE_QAT_EXT_D_BGA1-IC,H91A    I21 @BASEBOARD_FAB2_LIB.BASEBOARD_FAB2(SCH_1):PAGE123
  U7C1 AG36 VCCPRIM_AVID<21> LBG_CORE_QAT_EXT_D_BGA1-IC,H91A    I21 @BASEBOARD_FAB2_LIB.BASEBOARD_FAB2(SCH_1):PAGE123
  U7C1 AG34 VCCPRIM_AVID<22> LBG_CORE_QAT_EXT_D_BGA1-IC,H91A    I21 @BASEBOARD_FAB2_LIB.BASEBOARD_FAB2(SCH_1):PAGE123
  U7C1 AG32 VCCPRIM_AVID<23> LBG_CORE_QAT_EXT_D_BGA1-IC,H91A    I21 @BASEBOARD_FAB2_LIB.BASEBOARD_FAB2(SCH_1):PAGE123
  U7C1 AE41 VCCPRIM_AVID<24> LBG_CORE_QAT_EXT_D_BGA1-IC,H91A    I21 @BASEBOARD_FAB2_LIB.BASEBOARD_FAB2(SCH_1):PAGE123
  U7C1 AE39 VCCPRIM_AVID<25> LBG_CORE_QAT_EXT_D_BGA1-IC,H91A    I21 @BASEBOARD_FAB2_LIB.BASEBOARD_FAB2(SCH_1):PAGE123
  U7C1 AE37 VCCPRIM_AVID<26> LBG_CORE_QAT_EXT_D_BGA1-IC,H91A    I21 @BASEBOARD_FAB2_LIB.BASEBOARD_FAB2(SCH_1):PAGE123
  U7C1 AE36 VCCPRIM_AVID<27> LBG_CORE_QAT_EXT_D_BGA1-IC,H91A    I21 @BASEBOARD_FAB2_LIB.BASEBOARD_FAB2(SCH_1):PAGE123
  U7C1 AE34 VCCPRIM_AVID<28> LBG_CORE_QAT_EXT_D_BGA1-IC,H91A    I21 @BASEBOARD_FAB2_LIB.BASEBOARD_FAB2(SCH_1):PAGE123
  U7C1 AE32 VCCPRIM_AVID<29> LBG_CORE_QAT_EXT_D_BGA1-IC,H91A    I21 @BASEBOARD_FAB2_LIB.BASEBOARD_FAB2(SCH_1):PAGE123
  U7C1 AE30 VCCPRIM_AVID<30> LBG_CORE_QAT_EXT_D_BGA1-IC,H91A    I21 @BASEBOARD_FAB2_LIB.BASEBOARD_FAB2(SCH_1):PAGE123
  U7C1  U27 VCCPRIM_AVID<31> LBG_CORE_QAT_EXT_D_BGA1-IC,H91A    I21 @BASEBOARD_FAB2_LIB.BASEBOARD_FAB2(SCH_1):PAGE123
  U7C1 AC41 VCCPRIM_AVID<32> LBG_CORE_QAT_EXT_D_BGA1-IC,H91A    I21 @BASEBOARD_FAB2_LIB.BASEBOARD_FAB2(SCH_1):PAGE123
  U7C1 AC39 VCCPRIM_AVID<33> LBG_CORE_QAT_EXT_D_BGA1-IC,H91A    I21 @BASEBOARD_FAB2_LIB.BASEBOARD_FAB2(SCH_1):PAGE123
  U7C1 AC37 VCCPRIM_AVID<34> LBG_CORE_QAT_EXT_D_BGA1-IC,H91A    I21 @BASEBOARD_FAB2_LIB.BASEBOARD_FAB2(SCH_1):PAGE123
  U7C1 AC36 VCCPRIM_AVID<35> LBG_CORE_QAT_EXT_D_BGA1-IC,H91A    I21 @BASEBOARD_FAB2_LIB.BASEBOARD_FAB2(SCH_1):PAGE123
  U7C1 AC34 VCCPRIM_AVID<36> LBG_CORE_QAT_EXT_D_BGA1-IC,H91A    I21 @BASEBOARD_FAB2_LIB.BASEBOARD_FAB2(SCH_1):PAGE123
  U7C1 AC32 VCCPRIM_AVID<37> LBG_CORE_QAT_EXT_D_BGA1-IC,H91A    I21 @BASEBOARD_FAB2_LIB.BASEBOARD_FAB2(SCH_1):PAGE123
  U7C1 AC30 VCCPRIM_AVID<38> LBG_CORE_QAT_EXT_D_BGA1-IC,H91A    I21 @BASEBOARD_FAB2_LIB.BASEBOARD_FAB2(SCH_1):PAGE123
  U7C1 AC29 VCCPRIM_AVID<39> LBG_CORE_QAT_EXT_D_BGA1-IC,H91A    I21 @BASEBOARD_FAB2_LIB.BASEBOARD_FAB2(SCH_1):PAGE123
  U7C1 AA41 VCCPRIM_AVID<40> LBG_CORE_QAT_EXT_D_BGA1-IC,H91A    I21 @BASEBOARD_FAB2_LIB.BASEBOARD_FAB2(SCH_1):PAGE123
  U7C1 AA39 VCCPRIM_AVID<41> LBG_CORE_QAT_EXT_D_BGA1-IC,H91A    I21 @BASEBOARD_FAB2_LIB.BASEBOARD_FAB2(SCH_1):PAGE123
  U7C1 AA37 VCCPRIM_AVID<42> LBG_CORE_QAT_EXT_D_BGA1-IC,H91A    I21 @BASEBOARD_FAB2_LIB.BASEBOARD_FAB2(SCH_1):PAGE123
  U7C1 AA36 VCCPRIM_AVID<43> LBG_CORE_QAT_EXT_D_BGA1-IC,H91A    I21 @BASEBOARD_FAB2_LIB.BASEBOARD_FAB2(SCH_1):PAGE123
  U7C1 AA34 VCCPRIM_AVID<44> LBG_CORE_QAT_EXT_D_BGA1-IC,H91A    I21 @BASEBOARD_FAB2_LIB.BASEBOARD_FAB2(SCH_1):PAGE123
  U7C1 AA32 VCCPRIM_AVID<45> LBG_CORE_QAT_EXT_D_BGA1-IC,H91A    I21 @BASEBOARD_FAB2_LIB.BASEBOARD_FAB2(SCH_1):PAGE123
  U7C1 AA30 VCCPRIM_AVID<46> LBG_CORE_QAT_EXT_D_BGA1-IC,H91A    I21 @BASEBOARD_FAB2_LIB.BASEBOARD_FAB2(SCH_1):PAGE123
  U7C1 AA29 VCCPRIM_AVID<47> LBG_CORE_QAT_EXT_D_BGA1-IC,H91A    I21 @BASEBOARD_FAB2_LIB.BASEBOARD_FAB2(SCH_1):PAGE123
  U7C1  Y41 VCCPRIM_AVID<48> LBG_CORE_QAT_EXT_D_BGA1-IC,H91A    I21 @BASEBOARD_FAB2_LIB.BASEBOARD_FAB2(SCH_1):PAGE123
  U7C1  Y39 VCCPRIM_AVID<49> LBG_CORE_QAT_EXT_D_BGA1-IC,H91A    I21 @BASEBOARD_FAB2_LIB.BASEBOARD_FAB2(SCH_1):PAGE123
  U7C1  Y37 VCCPRIM_AVID<50> LBG_CORE_QAT_EXT_D_BGA1-IC,H91A    I21 @BASEBOARD_FAB2_LIB.BASEBOARD_FAB2(SCH_1):PAGE123
  U7C1  Y36 VCCPRIM_AVID<51> LBG_CORE_QAT_EXT_D_BGA1-IC,H91A    I21 @BASEBOARD_FAB2_LIB.BASEBOARD_FAB2(SCH_1):PAGE123
  U7C1  Y34 VCCPRIM_AVID<52> LBG_CORE_QAT_EXT_D_BGA1-IC,H91A    I21 @BASEBOARD_FAB2_LIB.BASEBOARD_FAB2(SCH_1):PAGE123
  U7C1  Y32 VCCPRIM_AVID<53> LBG_CORE_QAT_EXT_D_BGA1-IC,H91A    I21 @BASEBOARD_FAB2_LIB.BASEBOARD_FAB2(SCH_1):PAGE123
  U7C1  Y30 VCCPRIM_AVID<54> LBG_CORE_QAT_EXT_D_BGA1-IC,H91A    I21 @BASEBOARD_FAB2_LIB.BASEBOARD_FAB2(SCH_1):PAGE123
  U7C1  Y29 VCCPRIM_AVID<55> LBG_CORE_QAT_EXT_D_BGA1-IC,H91A    I21 @BASEBOARD_FAB2_LIB.BASEBOARD_FAB2(SCH_1):PAGE123
  U7C1  V40 VCCPRIM_AVID<56> LBG_CORE_QAT_EXT_D_BGA1-IC,H91A    I21 @BASEBOARD_FAB2_LIB.BASEBOARD_FAB2(SCH_1):PAGE123
  U7C1  V33 VCCPRIM_AVID<57> LBG_CORE_QAT_EXT_D_BGA1-IC,H91A    I21 @BASEBOARD_FAB2_LIB.BASEBOARD_FAB2(SCH_1):PAGE123
  U7C1  V29 VCCPRIM_AVID<58> LBG_CORE_QAT_EXT_D_BGA1-IC,H91A    I21 @BASEBOARD_FAB2_LIB.BASEBOARD_FAB2(SCH_1):PAGE123
  U7C1  U38 VCCPRIM_AVID<59> LBG_CORE_QAT_EXT_D_BGA1-IC,H91A    I21 @BASEBOARD_FAB2_LIB.BASEBOARD_FAB2(SCH_1):PAGE123
  U7C1  U35 VCCPRIM_AVID<60> LBG_CORE_QAT_EXT_D_BGA1-IC,H91A    I21 @BASEBOARD_FAB2_LIB.BASEBOARD_FAB2(SCH_1):PAGE123
  U7C1  U31 VCCPRIM_AVID<61> LBG_CORE_QAT_EXT_D_BGA1-IC,H91A    I21 @BASEBOARD_FAB2_LIB.BASEBOARD_FAB2(SCH_1):PAGE123
  U7C1 AK32 VCCPRIM_AVID<62> LBG_CORE_QAT_EXT_D_BGA1-IC,H91A    I21 @BASEBOARD_FAB2_LIB.BASEBOARD_FAB2(SCH_1):PAGE123
 C3L25    1      A CAP_A_0603V-22.0UF,4V,20%,X6S,A     I1 @BASEBOARD_FAB2_LIB.BASEBOARD_FAB2(SCH_1):PAGE132
  C3M7    1      A CAP_A_0603V-22.0UF,4V,20%,X6S,A     I2 @BASEBOARD_FAB2_LIB.BASEBOARD_FAB2(SCH_1):PAGE132
 C3L26    1      A CAP_A_0603V-22.0UF,4V,20%,X6S,A     I3 @BASEBOARD_FAB2_LIB.BASEBOARD_FAB2(SCH_1):PAGE132
 C3L27    1      A CAP_A_0603V-22.0UF,4V,20%,X6S,A     I4 @BASEBOARD_FAB2_LIB.BASEBOARD_FAB2(SCH_1):PAGE132
  C3M6    1      A CAP_A_0603V-22.0UF,4V,20%,X6S,A     I6 @BASEBOARD_FAB2_LIB.BASEBOARD_FAB2(SCH_1):PAGE132
  C7C9    1      A CAP_A_0603V-22.0UF,4V,20%,X6S,A     I7 @BASEBOARD_FAB2_LIB.BASEBOARD_FAB2(SCH_1):PAGE132
 C3N27    1      A CAP_A_0603V-22.0UF,4V,20%,X6S,A     I8 @BASEBOARD_FAB2_LIB.BASEBOARD_FAB2(SCH_1):PAGE132
 C3N30    1      A CAP_A_0603V-22.0UF,4V,20%,X6S,A     I9 @BASEBOARD_FAB2_LIB.BASEBOARD_FAB2(SCH_1):PAGE132
 C7A36    1      A CAP_A_0603V-22.0UF,4V,20%,X6S,A    I11 @BASEBOARD_FAB2_LIB.BASEBOARD_FAB2(SCH_1):PAGE132
 C3N12    1      A CAP_A_0603V-22.0UF,4V,20%,X6S,A    I12 @BASEBOARD_FAB2_LIB.BASEBOARD_FAB2(SCH_1):PAGE132
 C3N10    1      A CAP_A_0603V-22.0UF,4V,20%,X6S,A    I13 @BASEBOARD_FAB2_LIB.BASEBOARD_FAB2(SCH_1):PAGE132
 C3N24    1      A CAP_A_0603V-22.0UF,4V,20%,X6S,A    I16 @BASEBOARD_FAB2_LIB.BASEBOARD_FAB2(SCH_1):PAGE132
 C3N28    1      A CAP_A_0603V-22.0UF,4V,20%,X6S,A    I17 @BASEBOARD_FAB2_LIB.BASEBOARD_FAB2(SCH_1):PAGE132
 C3N11    1      A CAP_A_0603V-22.0UF,4V,20%,X6S,A    I19 @BASEBOARD_FAB2_LIB.BASEBOARD_FAB2(SCH_1):PAGE132
 C3N31    1      A CAP_A_0603V-22.0UF,4V,20%,X6S,A    I20 @BASEBOARD_FAB2_LIB.BASEBOARD_FAB2(SCH_1):PAGE132
 C7A33    1      A CAP_0805-47UF,4V,20%,X6S,C9533A    I23 @BASEBOARD_FAB2_LIB.BASEBOARD_FAB2(SCH_1):PAGE132
  C7B4    1      A CAP_0805-47UF,4V,20%,X6S,C9533A    I24 @BASEBOARD_FAB2_LIB.BASEBOARD_FAB2(SCH_1):PAGE132
  C2N9    1      A CAP_A_0402V-1.0UF,6.3V,10%,X6SA    I26 @BASEBOARD_FAB2_LIB.BASEBOARD_FAB2(SCH_1):PAGE132
  C2N3    1      A CAP_A_0402V-1.0UF,6.3V,10%,X6SA    I27 @BASEBOARD_FAB2_LIB.BASEBOARD_FAB2(SCH_1):PAGE132
  C2N4    1      A CAP_A_0402V-1.0UF,6.3V,10%,X6SA    I28 @BASEBOARD_FAB2_LIB.BASEBOARD_FAB2(SCH_1):PAGE132
 C2N12    1      A CAP_A_0402V-1.0UF,6.3V,10%,X6SA    I29 @BASEBOARD_FAB2_LIB.BASEBOARD_FAB2(SCH_1):PAGE132
 C2N11    1      A CAP_A_0402V-1.0UF,6.3V,10%,X6SA    I30 @BASEBOARD_FAB2_LIB.BASEBOARD_FAB2(SCH_1):PAGE132
 C3N19    1      A CAP_A_0402V-1.0UF,6.3V,10%,X6SA    I31 @BASEBOARD_FAB2_LIB.BASEBOARD_FAB2(SCH_1):PAGE132
  C3N3    1      A CAP_A_0402V-1.0UF,6.3V,10%,X6SA    I32 @BASEBOARD_FAB2_LIB.BASEBOARD_FAB2(SCH_1):PAGE132
  C3N1    1      A CAP_A_0402V-1.0UF,6.3V,10%,X6SA    I34 @BASEBOARD_FAB2_LIB.BASEBOARD_FAB2(SCH_1):PAGE132
  C3N7    1      A CAP_A_0402V-1.0UF,6.3V,10%,X6SA    I35 @BASEBOARD_FAB2_LIB.BASEBOARD_FAB2(SCH_1):PAGE132
 C3N16    1      A CAP_A_0402V-1.0UF,6.3V,10%,X6SA    I36 @BASEBOARD_FAB2_LIB.BASEBOARD_FAB2(SCH_1):PAGE132
 C7A32    1      A CAP_0805-47UF,4V,20%,X6S,C9533A    I38 @BASEBOARD_FAB2_LIB.BASEBOARD_FAB2(SCH_1):PAGE132
 C7A31    1      A CAP_0805-47UF,4V,20%,X6S,C9533A    I40 @BASEBOARD_FAB2_LIB.BASEBOARD_FAB2(SCH_1):PAGE132
 C3N18    1      A CAP_A_0402V-1.0UF,6.3V,10%,X6SA    I42 @BASEBOARD_FAB2_LIB.BASEBOARD_FAB2(SCH_1):PAGE132
  C3N2    1      A CAP_A_0402V-1.0UF,6.3V,10%,X6SA    I43 @BASEBOARD_FAB2_LIB.BASEBOARD_FAB2(SCH_1):PAGE132
  C3N6    1      A CAP_A_0402V-1.0UF,6.3V,10%,X6SA    I44 @BASEBOARD_FAB2_LIB.BASEBOARD_FAB2(SCH_1):PAGE132
 C3N17    1      A CAP_A_0402V-1.0UF,6.3V,10%,X6SA    I45 @BASEBOARD_FAB2_LIB.BASEBOARD_FAB2(SCH_1):PAGE132
  C3N4    1      A CAP_A_0402V-1.0UF,6.3V,10%,X6SA    I46 @BASEBOARD_FAB2_LIB.BASEBOARD_FAB2(SCH_1):PAGE132
  C3N5    1      A CAP_A_0402V-1.0UF,6.3V,10%,X6SA    I48 @BASEBOARD_FAB2_LIB.BASEBOARD_FAB2(SCH_1):PAGE132
 C3N15    1      A CAP_A_0402V-1.0UF,6.3V,10%,X6SA    I49 @BASEBOARD_FAB2_LIB.BASEBOARD_FAB2(SCH_1):PAGE132
 C3N20    1      A CAP_A_0402V-1.0UF,6.3V,10%,X6SA    I51 @BASEBOARD_FAB2_LIB.BASEBOARD_FAB2(SCH_1):PAGE132
 C3L23    1      A CAP_A_0603V-22.0UF,4V,20%,X6S,A    I52 @BASEBOARD_FAB2_LIB.BASEBOARD_FAB2(SCH_1):PAGE132
 C3L22    1      A CAP_A_0603V-22.0UF,4V,20%,X6S,A    I54 @BASEBOARD_FAB2_LIB.BASEBOARD_FAB2(SCH_1):PAGE132
 C3L24    1      A CAP_A_0603V-22.0UF,4V,20%,X6S,A    I56 @BASEBOARD_FAB2_LIB.BASEBOARD_FAB2(SCH_1):PAGE132
 FB1U4    2      B FERRITE_SMLF-30,FB,693286-021   I155 @BASEBOARD_FAB2_LIB.BASEBOARD_FAB2(SCH_1):PAGE169
 C7A30    1      A CAP_0805LF-22UF,4V,20%,X6S,C95A     I9 @BASEBOARD_FAB2_LIB.BASEBOARD_FAB2(SCH_1):PAGE236
  L7A2    2    INB INDUCTOR_SM-0.3UH,IND,D92183-0A    I10 @BASEBOARD_FAB2_LIB.BASEBOARD_FAB2(SCH_1):PAGE236
 C3L18    1      A CAPP_SM-470UF,2V,20%,ALUM,6990A    I71 @BASEBOARD_FAB2_LIB.BASEBOARD_FAB2(SCH_1):PAGE236
 C3L20    1      A CAPP_SM-470UF,2V,20%,ALUM,6990A    I73 @BASEBOARD_FAB2_LIB.BASEBOARD_FAB2(SCH_1):PAGE236
 C3L21    1      A CAPP_SM-470UF,2V,20%,ALUM,6990A    I74 @BASEBOARD_FAB2_LIB.BASEBOARD_FAB2(SCH_1):PAGE236
 C7A27    1      A CAPP_SM-470UF,2V,20%,ALUM,6990A    I75 @BASEBOARD_FAB2_LIB.BASEBOARD_FAB2(SCH_1):PAGE236
 R7A13    2      B RES_0402-100.0,1%,1/16W,CHIP,GA    I90 @BASEBOARD_FAB2_LIB.BASEBOARD_FAB2(SCH_1):PAGE236
 EU7A3    1    VOS IR354XX_SM-IR35412,IC,H73684-0A   I116 @BASEBOARD_FAB2_LIB.BASEBOARD_FAB2(SCH_1):PAGE236

PVPP_ABC @BASEBOARD_FAB2_LIB.BASEBOARD_FAB2(SCH_1):PVPP_ABC
  U5D1  B11 CD_VPP<0> SKX_EXT_B_BGA1-IC,TBD    I34 @BASEBOARD_FAB2_LIB.BASEBOARD_FAB2(SCH_1):PAGE38
  U5D1  A12 CD_VPP<1> SKX_EXT_B_BGA1-IC,TBD    I34 @BASEBOARD_FAB2_LIB.BASEBOARD_FAB2(SCH_1):PAGE38
  U5D1  A10 CD_VPP<2> SKX_EXT_B_BGA1-IC,TBD    I34 @BASEBOARD_FAB2_LIB.BASEBOARD_FAB2(SCH_1):PAGE38
  U5D1   A8 CD_VPP<3> SKX_EXT_B_BGA1-IC,TBD    I34 @BASEBOARD_FAB2_LIB.BASEBOARD_FAB2(SCH_1):PAGE38
  J4G1  284 VDDSPD SCONN288_H44441004_PIP-SCONN,HA     I1 @BASEBOARD_FAB2_LIB.BASEBOARD_FAB2(SCH_1):PAGE43
  J4G1  287 VPP<0> SCONN288_H44441004_PIP-SCONN,HA   I260 @BASEBOARD_FAB2_LIB.BASEBOARD_FAB2(SCH_1):PAGE43
  J4G1  286 VPP<1> SCONN288_H44441004_PIP-SCONN,HA   I260 @BASEBOARD_FAB2_LIB.BASEBOARD_FAB2(SCH_1):PAGE43
  J4G1  288 VPP<2> SCONN288_H44441004_PIP-SCONN,HA   I260 @BASEBOARD_FAB2_LIB.BASEBOARD_FAB2(SCH_1):PAGE43
  J4G1  143 VPP<3> SCONN288_H44441004_PIP-SCONN,HA   I260 @BASEBOARD_FAB2_LIB.BASEBOARD_FAB2(SCH_1):PAGE43
  J4G1  142 VPP<4> SCONN288_H44441004_PIP-SCONN,HA   I260 @BASEBOARD_FAB2_LIB.BASEBOARD_FAB2(SCH_1):PAGE43
  J6T1  139  SA<0> SCONN288_H44441003_PIP-SCONN,HA    I13 @BASEBOARD_FAB2_LIB.BASEBOARD_FAB2(SCH_1):PAGE44
  J6T1  284 VDDSPD SCONN288_H44441003_PIP-SCONN,HA    I13 @BASEBOARD_FAB2_LIB.BASEBOARD_FAB2(SCH_1):PAGE44
  J6T1  287 VPP<0> SCONN288_H44441003_PIP-SCONN,HA    I75 @BASEBOARD_FAB2_LIB.BASEBOARD_FAB2(SCH_1):PAGE44
  J6T1  286 VPP<1> SCONN288_H44441003_PIP-SCONN,HA    I75 @BASEBOARD_FAB2_LIB.BASEBOARD_FAB2(SCH_1):PAGE44
  J6T1  288 VPP<2> SCONN288_H44441003_PIP-SCONN,HA    I75 @BASEBOARD_FAB2_LIB.BASEBOARD_FAB2(SCH_1):PAGE44
  J6T1  143 VPP<3> SCONN288_H44441003_PIP-SCONN,HA    I75 @BASEBOARD_FAB2_LIB.BASEBOARD_FAB2(SCH_1):PAGE44
  J6T1  142 VPP<4> SCONN288_H44441003_PIP-SCONN,HA    I75 @BASEBOARD_FAB2_LIB.BASEBOARD_FAB2(SCH_1):PAGE44
  J4G2  140  SA<1> SCONN288_H44441004_PIP-SCONN,HA   I111 @BASEBOARD_FAB2_LIB.BASEBOARD_FAB2(SCH_1):PAGE45
  J4G2  284 VDDSPD SCONN288_H44441004_PIP-SCONN,HA   I111 @BASEBOARD_FAB2_LIB.BASEBOARD_FAB2(SCH_1):PAGE45
  J4G2  287 VPP<0> SCONN288_H44441004_PIP-SCONN,HA   I169 @BASEBOARD_FAB2_LIB.BASEBOARD_FAB2(SCH_1):PAGE45
  J4G2  286 VPP<1> SCONN288_H44441004_PIP-SCONN,HA   I169 @BASEBOARD_FAB2_LIB.BASEBOARD_FAB2(SCH_1):PAGE45
  J4G2  288 VPP<2> SCONN288_H44441004_PIP-SCONN,HA   I169 @BASEBOARD_FAB2_LIB.BASEBOARD_FAB2(SCH_1):PAGE45
  J4G2  143 VPP<3> SCONN288_H44441004_PIP-SCONN,HA   I169 @BASEBOARD_FAB2_LIB.BASEBOARD_FAB2(SCH_1):PAGE45
  J4G2  142 VPP<4> SCONN288_H44441004_PIP-SCONN,HA   I169 @BASEBOARD_FAB2_LIB.BASEBOARD_FAB2(SCH_1):PAGE45
  J6U1  139  SA<0> SCONN288_H44441003_PIP-SCONN,HA    I14 @BASEBOARD_FAB2_LIB.BASEBOARD_FAB2(SCH_1):PAGE46
  J6U1  140  SA<1> SCONN288_H44441003_PIP-SCONN,HA    I14 @BASEBOARD_FAB2_LIB.BASEBOARD_FAB2(SCH_1):PAGE46
  J6U1  284 VDDSPD SCONN288_H44441003_PIP-SCONN,HA    I14 @BASEBOARD_FAB2_LIB.BASEBOARD_FAB2(SCH_1):PAGE46
  J6U1  287 VPP<0> SCONN288_H44441003_PIP-SCONN,HA    I67 @BASEBOARD_FAB2_LIB.BASEBOARD_FAB2(SCH_1):PAGE46
  J6U1  286 VPP<1> SCONN288_H44441003_PIP-SCONN,HA    I67 @BASEBOARD_FAB2_LIB.BASEBOARD_FAB2(SCH_1):PAGE46
  J6U1  288 VPP<2> SCONN288_H44441003_PIP-SCONN,HA    I67 @BASEBOARD_FAB2_LIB.BASEBOARD_FAB2(SCH_1):PAGE46
  J6U1  143 VPP<3> SCONN288_H44441003_PIP-SCONN,HA    I67 @BASEBOARD_FAB2_LIB.BASEBOARD_FAB2(SCH_1):PAGE46
  J6U1  142 VPP<4> SCONN288_H44441003_PIP-SCONN,HA    I67 @BASEBOARD_FAB2_LIB.BASEBOARD_FAB2(SCH_1):PAGE46
  J4G3  238  SA<2> SCONN288_H44441004_PIP-SCONN,HA   I111 @BASEBOARD_FAB2_LIB.BASEBOARD_FAB2(SCH_1):PAGE47
  J4G3  284 VDDSPD SCONN288_H44441004_PIP-SCONN,HA   I111 @BASEBOARD_FAB2_LIB.BASEBOARD_FAB2(SCH_1):PAGE47
  J4G3  287 VPP<0> SCONN288_H44441004_PIP-SCONN,HA   I179 @BASEBOARD_FAB2_LIB.BASEBOARD_FAB2(SCH_1):PAGE47
  J4G3  286 VPP<1> SCONN288_H44441004_PIP-SCONN,HA   I179 @BASEBOARD_FAB2_LIB.BASEBOARD_FAB2(SCH_1):PAGE47
  J4G3  288 VPP<2> SCONN288_H44441004_PIP-SCONN,HA   I179 @BASEBOARD_FAB2_LIB.BASEBOARD_FAB2(SCH_1):PAGE47
  J4G3  143 VPP<3> SCONN288_H44441004_PIP-SCONN,HA   I179 @BASEBOARD_FAB2_LIB.BASEBOARD_FAB2(SCH_1):PAGE47
  J4G3  142 VPP<4> SCONN288_H44441004_PIP-SCONN,HA   I179 @BASEBOARD_FAB2_LIB.BASEBOARD_FAB2(SCH_1):PAGE47
  J6U2  139  SA<0> SCONN288_H44441003_PIP-SCONN,HA   I111 @BASEBOARD_FAB2_LIB.BASEBOARD_FAB2(SCH_1):PAGE48
  J6U2  238  SA<2> SCONN288_H44441003_PIP-SCONN,HA   I111 @BASEBOARD_FAB2_LIB.BASEBOARD_FAB2(SCH_1):PAGE48
  J6U2  284 VDDSPD SCONN288_H44441003_PIP-SCONN,HA   I111 @BASEBOARD_FAB2_LIB.BASEBOARD_FAB2(SCH_1):PAGE48
  J6U2  287 VPP<0> SCONN288_H44441003_PIP-SCONN,HA   I171 @BASEBOARD_FAB2_LIB.BASEBOARD_FAB2(SCH_1):PAGE48
  J6U2  286 VPP<1> SCONN288_H44441003_PIP-SCONN,HA   I171 @BASEBOARD_FAB2_LIB.BASEBOARD_FAB2(SCH_1):PAGE48
  J6U2  288 VPP<2> SCONN288_H44441003_PIP-SCONN,HA   I171 @BASEBOARD_FAB2_LIB.BASEBOARD_FAB2(SCH_1):PAGE48
  J6U2  143 VPP<3> SCONN288_H44441003_PIP-SCONN,HA   I171 @BASEBOARD_FAB2_LIB.BASEBOARD_FAB2(SCH_1):PAGE48
  J6U2  142 VPP<4> SCONN288_H44441003_PIP-SCONN,HA   I171 @BASEBOARD_FAB2_LIB.BASEBOARD_FAB2(SCH_1):PAGE48
  R6F3    1      A RES_0402-10.0K,1%,1/16W,CHIP,GA     I7 @BASEBOARD_FAB2_LIB.BASEBOARD_FAB2(SCH_1):PAGE89
  J8B1   21   IO21 SCONN24_H46321001_SM-SCONN,H46A     I1 @BASEBOARD_FAB2_LIB.BASEBOARD_FAB2(SCH_1):PAGE91
  R8B8    1      A RES_0402-4.75K,1%,1/16W,CHIP,GA    I14 @BASEBOARD_FAB2_LIB.BASEBOARD_FAB2(SCH_1):PAGE91
 R8B10    1      A RES_0402-4.75K,1%,1/16W,CHIP,GA    I16 @BASEBOARD_FAB2_LIB.BASEBOARD_FAB2(SCH_1):PAGE91
 R8B16    1      A RES_0402-4.75K,1%,1/16W,CHIP,GA    I17 @BASEBOARD_FAB2_LIB.BASEBOARD_FAB2(SCH_1):PAGE91
 R8B17    1      A RES_0402-4.75K,1%,1/16W,CHIP,GA    I18 @BASEBOARD_FAB2_LIB.BASEBOARD_FAB2(SCH_1):PAGE91
 R8B18    1      A RES_0402-4.75K,1%,1/16W,CHIP,GA    I20 @BASEBOARD_FAB2_LIB.BASEBOARD_FAB2(SCH_1):PAGE91
 R8B19    1      A RES_0402-4.75K,1%,1/16W,CHIP,GA    I21 @BASEBOARD_FAB2_LIB.BASEBOARD_FAB2(SCH_1):PAGE91
  R8B5    1      A RES_0402-4.75K,1%,1/16W,CHIP,GA    I22 @BASEBOARD_FAB2_LIB.BASEBOARD_FAB2(SCH_1):PAGE91
  R8B3    1      A RES_0402-4.75K,1%,1/16W,CHIP,GA    I24 @BASEBOARD_FAB2_LIB.BASEBOARD_FAB2(SCH_1):PAGE91
 R8B13    1      A RES_0402-1.8K,1%,1/16W,CHIP,G2A    I34 @BASEBOARD_FAB2_LIB.BASEBOARD_FAB2(SCH_1):PAGE91
 R8B11    1      A RES_0402-1.8K,1%,1/16W,CHIP,G2A    I35 @BASEBOARD_FAB2_LIB.BASEBOARD_FAB2(SCH_1):PAGE91
  R8B7    1      A RES_0402-1.8K,1%,1/16W,CHIP,G2A    I36 @BASEBOARD_FAB2_LIB.BASEBOARD_FAB2(SCH_1):PAGE91
  R8B6    1      A RES_0402-1.8K,1%,1/16W,CHIP,G2A    I37 @BASEBOARD_FAB2_LIB.BASEBOARD_FAB2(SCH_1):PAGE91
  R4U3    1      A RES_0402-4.75K,1%,1/16W,CHIP,GA    I94 @BASEBOARD_FAB2_LIB.BASEBOARD_FAB2(SCH_1):PAGE94
  R4U2    1      A RES_0402-2.21K,1%,1/16W,CHIP,GA   I100 @BASEBOARD_FAB2_LIB.BASEBOARD_FAB2(SCH_1):PAGE94
  C6F3    1      A CAP_A_0402V-0.1UF,16V,10%,X7R,A     I7 @BASEBOARD_FAB2_LIB.BASEBOARD_FAB2(SCH_1):PAGE99
  R4T8    1      A RES_0402-665,1.0%,1/16W,CHIP,GA    I11 @BASEBOARD_FAB2_LIB.BASEBOARD_FAB2(SCH_1):PAGE99
  R4T7    1      A RES_0402-665,1.0%,1/16W,CHIP,GA    I13 @BASEBOARD_FAB2_LIB.BASEBOARD_FAB2(SCH_1):PAGE99
  U6F1    8   VCCB PCA9617_SSOP-IC,G81764-001-GNDA    I15 @BASEBOARD_FAB2_LIB.BASEBOARD_FAB2(SCH_1):PAGE99
 R3R16    1      A RES_0402-4.75K,1%,1/16W,CHIP,GA    I48 @BASEBOARD_FAB2_LIB.BASEBOARD_FAB2(SCH_1):PAGE192
  C6F6    1      A CAP_0603LF-10UF,4V,20%,X6S,E15A   I122 @BASEBOARD_FAB2_LIB.BASEBOARD_FAB2(SCH_1):PAGE231
  C4T6    1      A CAP_0603LF-10UF,4V,20%,X6S,E15A   I124 @BASEBOARD_FAB2_LIB.BASEBOARD_FAB2(SCH_1):PAGE231
  C4T5    1      A CAP_0603LF-10UF,4V,20%,X6S,E15A   I125 @BASEBOARD_FAB2_LIB.BASEBOARD_FAB2(SCH_1):PAGE231
  C6G1    1      A CAP_0603LF-10UF,4V,20%,X6S,E15A   I126 @BASEBOARD_FAB2_LIB.BASEBOARD_FAB2(SCH_1):PAGE231
  C6G2    1      A CAP_0603LF-10UF,4V,20%,X6S,E15A   I128 @BASEBOARD_FAB2_LIB.BASEBOARD_FAB2(SCH_1):PAGE231
  C4U2    1      A CAP_0603LF-10UF,4V,20%,X6S,E15A   I129 @BASEBOARD_FAB2_LIB.BASEBOARD_FAB2(SCH_1):PAGE231
  C4U1    1      A CAP_0603LF-10UF,4V,20%,X6S,E15A   I130 @BASEBOARD_FAB2_LIB.BASEBOARD_FAB2(SCH_1):PAGE231
  C6G4    1      A CAP_0603LF-10UF,4V,20%,X6S,E15A   I131 @BASEBOARD_FAB2_LIB.BASEBOARD_FAB2(SCH_1):PAGE231
  C6G5    1      A CAP_0603LF-10UF,4V,20%,X6S,E15A   I145 @BASEBOARD_FAB2_LIB.BASEBOARD_FAB2(SCH_1):PAGE231
  C4U4    1      A CAP_0603LF-10UF,4V,20%,X6S,E15A   I146 @BASEBOARD_FAB2_LIB.BASEBOARD_FAB2(SCH_1):PAGE231
  C4U3    1      A CAP_0603LF-10UF,4V,20%,X6S,E15A   I148 @BASEBOARD_FAB2_LIB.BASEBOARD_FAB2(SCH_1):PAGE231
  C6F5    1      A CAP_0603LF-10UF,4V,20%,X6S,E15A   I149 @BASEBOARD_FAB2_LIB.BASEBOARD_FAB2(SCH_1):PAGE231
 R7F12    1      A RES_0402-0.0,5%,1/16W,CHIP,G21A   I168 @BASEBOARD_FAB2_LIB.BASEBOARD_FAB2(SCH_1):PAGE231
 R7F10    1      A RES_0603-120.0,1%,1/10W,CHIP,GA   I177 @BASEBOARD_FAB2_LIB.BASEBOARD_FAB2(SCH_1):PAGE231
  L7F1    2    INB INDUCTOR_SM-0.47UH,IND,E13358-A   I178 @BASEBOARD_FAB2_LIB.BASEBOARD_FAB2(SCH_1):PAGE231
  C6F4    1      A CAPP_7343LF-330UF,6.3V,20%,POSA   I180 @BASEBOARD_FAB2_LIB.BASEBOARD_FAB2(SCH_1):PAGE231
  C3T7    1      A CAP_0805-47UF,4V,20%,X6S,C9533A   I184 @BASEBOARD_FAB2_LIB.BASEBOARD_FAB2(SCH_1):PAGE231
  C3T9    1      A CAP_0805-47UF,4V,20%,X6S,C9533A   I186 @BASEBOARD_FAB2_LIB.BASEBOARD_FAB2(SCH_1):PAGE231
  C4T3    1      A CAPP_7343-220UF,4V,20%,POSCAP,A   I217 @BASEBOARD_FAB2_LIB.BASEBOARD_FAB2(SCH_1):PAGE231

PVPP_DEF @BASEBOARD_FAB2_LIB.BASEBOARD_FAB2(SCH_1):PVPP_DEF
  J4B1  284 VDDSPD SCONN288_H44441004_PIP-SCONN,HA   I111 @BASEBOARD_FAB2_LIB.BASEBOARD_FAB2(SCH_1):PAGE49
  J4B1  287 VPP<0> SCONN288_H44441004_PIP-SCONN,HA   I169 @BASEBOARD_FAB2_LIB.BASEBOARD_FAB2(SCH_1):PAGE49
  J4B1  286 VPP<1> SCONN288_H44441004_PIP-SCONN,HA   I169 @BASEBOARD_FAB2_LIB.BASEBOARD_FAB2(SCH_1):PAGE49
  J4B1  288 VPP<2> SCONN288_H44441004_PIP-SCONN,HA   I169 @BASEBOARD_FAB2_LIB.BASEBOARD_FAB2(SCH_1):PAGE49
  J4B1  143 VPP<3> SCONN288_H44441004_PIP-SCONN,HA   I169 @BASEBOARD_FAB2_LIB.BASEBOARD_FAB2(SCH_1):PAGE49
  J4B1  142 VPP<4> SCONN288_H44441004_PIP-SCONN,HA   I169 @BASEBOARD_FAB2_LIB.BASEBOARD_FAB2(SCH_1):PAGE49
  J6M1  287 VPP<0> SCONN288_H44441003_PIP-SCONN,HA    I50 @BASEBOARD_FAB2_LIB.BASEBOARD_FAB2(SCH_1):PAGE50
  J6M1  286 VPP<1> SCONN288_H44441003_PIP-SCONN,HA    I50 @BASEBOARD_FAB2_LIB.BASEBOARD_FAB2(SCH_1):PAGE50
  J6M1  288 VPP<2> SCONN288_H44441003_PIP-SCONN,HA    I50 @BASEBOARD_FAB2_LIB.BASEBOARD_FAB2(SCH_1):PAGE50
  J6M1  143 VPP<3> SCONN288_H44441003_PIP-SCONN,HA    I50 @BASEBOARD_FAB2_LIB.BASEBOARD_FAB2(SCH_1):PAGE50
  J6M1  142 VPP<4> SCONN288_H44441003_PIP-SCONN,HA    I50 @BASEBOARD_FAB2_LIB.BASEBOARD_FAB2(SCH_1):PAGE50
  J6M1  139  SA<0> SCONN288_H44441003_PIP-SCONN,HA   I158 @BASEBOARD_FAB2_LIB.BASEBOARD_FAB2(SCH_1):PAGE50
  J6M1  284 VDDSPD SCONN288_H44441003_PIP-SCONN,HA   I158 @BASEBOARD_FAB2_LIB.BASEBOARD_FAB2(SCH_1):PAGE50
  J4A2  140  SA<1> SCONN288_H44441004_PIP-SCONN,HA   I111 @BASEBOARD_FAB2_LIB.BASEBOARD_FAB2(SCH_1):PAGE51
  J4A2  284 VDDSPD SCONN288_H44441004_PIP-SCONN,HA   I111 @BASEBOARD_FAB2_LIB.BASEBOARD_FAB2(SCH_1):PAGE51
  J4A2  287 VPP<0> SCONN288_H44441004_PIP-SCONN,HA   I167 @BASEBOARD_FAB2_LIB.BASEBOARD_FAB2(SCH_1):PAGE51
  J4A2  286 VPP<1> SCONN288_H44441004_PIP-SCONN,HA   I167 @BASEBOARD_FAB2_LIB.BASEBOARD_FAB2(SCH_1):PAGE51
  J4A2  288 VPP<2> SCONN288_H44441004_PIP-SCONN,HA   I167 @BASEBOARD_FAB2_LIB.BASEBOARD_FAB2(SCH_1):PAGE51
  J4A2  143 VPP<3> SCONN288_H44441004_PIP-SCONN,HA   I167 @BASEBOARD_FAB2_LIB.BASEBOARD_FAB2(SCH_1):PAGE51
  J4A2  142 VPP<4> SCONN288_H44441004_PIP-SCONN,HA   I167 @BASEBOARD_FAB2_LIB.BASEBOARD_FAB2(SCH_1):PAGE51
  J6L2  139  SA<0> SCONN288_H44441003_PIP-SCONN,HA    I12 @BASEBOARD_FAB2_LIB.BASEBOARD_FAB2(SCH_1):PAGE52
  J6L2  140  SA<1> SCONN288_H44441003_PIP-SCONN,HA    I12 @BASEBOARD_FAB2_LIB.BASEBOARD_FAB2(SCH_1):PAGE52
  J6L2  284 VDDSPD SCONN288_H44441003_PIP-SCONN,HA    I12 @BASEBOARD_FAB2_LIB.BASEBOARD_FAB2(SCH_1):PAGE52
  J6L2  287 VPP<0> SCONN288_H44441003_PIP-SCONN,HA    I55 @BASEBOARD_FAB2_LIB.BASEBOARD_FAB2(SCH_1):PAGE52
  J6L2  286 VPP<1> SCONN288_H44441003_PIP-SCONN,HA    I55 @BASEBOARD_FAB2_LIB.BASEBOARD_FAB2(SCH_1):PAGE52
  J6L2  288 VPP<2> SCONN288_H44441003_PIP-SCONN,HA    I55 @BASEBOARD_FAB2_LIB.BASEBOARD_FAB2(SCH_1):PAGE52
  J6L2  143 VPP<3> SCONN288_H44441003_PIP-SCONN,HA    I55 @BASEBOARD_FAB2_LIB.BASEBOARD_FAB2(SCH_1):PAGE52
  J6L2  142 VPP<4> SCONN288_H44441003_PIP-SCONN,HA    I55 @BASEBOARD_FAB2_LIB.BASEBOARD_FAB2(SCH_1):PAGE52
  J4A1  238  SA<2> SCONN288_H44441004_PIP-SCONN,HA   I111 @BASEBOARD_FAB2_LIB.BASEBOARD_FAB2(SCH_1):PAGE53
  J4A1  284 VDDSPD SCONN288_H44441004_PIP-SCONN,HA   I111 @BASEBOARD_FAB2_LIB.BASEBOARD_FAB2(SCH_1):PAGE53
  J4A1  287 VPP<0> SCONN288_H44441004_PIP-SCONN,HA   I171 @BASEBOARD_FAB2_LIB.BASEBOARD_FAB2(SCH_1):PAGE53
  J4A1  286 VPP<1> SCONN288_H44441004_PIP-SCONN,HA   I171 @BASEBOARD_FAB2_LIB.BASEBOARD_FAB2(SCH_1):PAGE53
  J4A1  288 VPP<2> SCONN288_H44441004_PIP-SCONN,HA   I171 @BASEBOARD_FAB2_LIB.BASEBOARD_FAB2(SCH_1):PAGE53
  J4A1  143 VPP<3> SCONN288_H44441004_PIP-SCONN,HA   I171 @BASEBOARD_FAB2_LIB.BASEBOARD_FAB2(SCH_1):PAGE53
  J4A1  142 VPP<4> SCONN288_H44441004_PIP-SCONN,HA   I171 @BASEBOARD_FAB2_LIB.BASEBOARD_FAB2(SCH_1):PAGE53
  J6L1  139  SA<0> SCONN288_H44441003_PIP-SCONN,HA   I111 @BASEBOARD_FAB2_LIB.BASEBOARD_FAB2(SCH_1):PAGE54
  J6L1  238  SA<2> SCONN288_H44441003_PIP-SCONN,HA   I111 @BASEBOARD_FAB2_LIB.BASEBOARD_FAB2(SCH_1):PAGE54
  J6L1  284 VDDSPD SCONN288_H44441003_PIP-SCONN,HA   I111 @BASEBOARD_FAB2_LIB.BASEBOARD_FAB2(SCH_1):PAGE54
  J6L1  287 VPP<0> SCONN288_H44441003_PIP-SCONN,HA   I170 @BASEBOARD_FAB2_LIB.BASEBOARD_FAB2(SCH_1):PAGE54
  J6L1  286 VPP<1> SCONN288_H44441003_PIP-SCONN,HA   I170 @BASEBOARD_FAB2_LIB.BASEBOARD_FAB2(SCH_1):PAGE54
  J6L1  288 VPP<2> SCONN288_H44441003_PIP-SCONN,HA   I170 @BASEBOARD_FAB2_LIB.BASEBOARD_FAB2(SCH_1):PAGE54
  J6L1  143 VPP<3> SCONN288_H44441003_PIP-SCONN,HA   I170 @BASEBOARD_FAB2_LIB.BASEBOARD_FAB2(SCH_1):PAGE54
  J6L1  142 VPP<4> SCONN288_H44441003_PIP-SCONN,HA   I170 @BASEBOARD_FAB2_LIB.BASEBOARD_FAB2(SCH_1):PAGE54
  C7E2    1      A CAP_A_0402V-0.1UF,16V,10%,X7R,A    I32 @BASEBOARD_FAB2_LIB.BASEBOARD_FAB2(SCH_1):PAGE99
  U7E1    8   VCCB PCA9617_SSOP-IC,G81764-001-GNDA    I61 @BASEBOARD_FAB2_LIB.BASEBOARD_FAB2(SCH_1):PAGE99
 R3R12    1      A RES_0402-665,1.0%,1/16W,CHIP,GA   I101 @BASEBOARD_FAB2_LIB.BASEBOARD_FAB2(SCH_1):PAGE99
  R3R5    1      A RES_0402-665,1.0%,1/16W,CHIP,GA   I103 @BASEBOARD_FAB2_LIB.BASEBOARD_FAB2(SCH_1):PAGE99
  C4L2    1      A CAP_0603LF-10UF,4V,20%,X6S,E15A   I102 @BASEBOARD_FAB2_LIB.BASEBOARD_FAB2(SCH_1):PAGE232
  C6A3    1      A CAP_0603LF-10UF,4V,20%,X6S,E15A   I104 @BASEBOARD_FAB2_LIB.BASEBOARD_FAB2(SCH_1):PAGE232
  C6A2    1      A CAP_0603LF-10UF,4V,20%,X6S,E15A   I105 @BASEBOARD_FAB2_LIB.BASEBOARD_FAB2(SCH_1):PAGE232
  C4L3    1      A CAP_0603LF-10UF,4V,20%,X6S,E15A   I106 @BASEBOARD_FAB2_LIB.BASEBOARD_FAB2(SCH_1):PAGE232
  C4L4    1      A CAP_0603LF-10UF,4V,20%,X6S,E15A   I108 @BASEBOARD_FAB2_LIB.BASEBOARD_FAB2(SCH_1):PAGE232
  C6A7    1      A CAP_0603LF-10UF,4V,20%,X6S,E15A   I109 @BASEBOARD_FAB2_LIB.BASEBOARD_FAB2(SCH_1):PAGE232
  C6A6    1      A CAP_0603LF-10UF,4V,20%,X6S,E15A   I110 @BASEBOARD_FAB2_LIB.BASEBOARD_FAB2(SCH_1):PAGE232
  C4M3    1      A CAP_0603LF-10UF,4V,20%,X6S,E15A   I111 @BASEBOARD_FAB2_LIB.BASEBOARD_FAB2(SCH_1):PAGE232
  C4M4    1      A CAP_0603LF-10UF,4V,20%,X6S,E15A   I125 @BASEBOARD_FAB2_LIB.BASEBOARD_FAB2(SCH_1):PAGE232
  C6B2    1      A CAP_0603LF-10UF,4V,20%,X6S,E15A   I126 @BASEBOARD_FAB2_LIB.BASEBOARD_FAB2(SCH_1):PAGE232
  C6B1    1      A CAP_0603LF-10UF,4V,20%,X6S,E15A   I128 @BASEBOARD_FAB2_LIB.BASEBOARD_FAB2(SCH_1):PAGE232
  C4L1    1      A CAP_0603LF-10UF,4V,20%,X6S,E15A   I129 @BASEBOARD_FAB2_LIB.BASEBOARD_FAB2(SCH_1):PAGE232
 R7B10    1      A RES_0603-120.0,1%,1/10W,CHIP,GA   I227 @BASEBOARD_FAB2_LIB.BASEBOARD_FAB2(SCH_1):PAGE232
  C6B7    1      A CAPP_7343LF-330UF,6.3V,20%,POSA   I229 @BASEBOARD_FAB2_LIB.BASEBOARD_FAB2(SCH_1):PAGE232
  C6B3    1      A CAP_0805-47UF,4V,20%,X6S,C9533A   I236 @BASEBOARD_FAB2_LIB.BASEBOARD_FAB2(SCH_1):PAGE232
  C7B7    1      A CAP_0805-47UF,4V,20%,X6S,C9533A   I238 @BASEBOARD_FAB2_LIB.BASEBOARD_FAB2(SCH_1):PAGE232
  L7B1    2    INB INDUCTOR_SM-0.47UH,IND,E13358-A   I239 @BASEBOARD_FAB2_LIB.BASEBOARD_FAB2(SCH_1):PAGE232
  C4M1    1      A CAPP_7343-220UF,4V,20%,POSCAP,A   I267 @BASEBOARD_FAB2_LIB.BASEBOARD_FAB2(SCH_1):PAGE232
 R7B11    1      A RES_0402-0.0,5%,1/16W,CHIP,G21A   I299 @BASEBOARD_FAB2_LIB.BASEBOARD_FAB2(SCH_1):PAGE232

PVPP_GHJ @BASEBOARD_FAB2_LIB.BASEBOARD_FAB2(SCH_1):PVPP_GHJ
  U2D1  B11 CD_VPP<0> SKX_EXT_B_BGA1-IC,TBD    I33 @BASEBOARD_FAB2_LIB.BASEBOARD_FAB2(SCH_1):PAGE72
  U2D1  A12 CD_VPP<1> SKX_EXT_B_BGA1-IC,TBD    I33 @BASEBOARD_FAB2_LIB.BASEBOARD_FAB2(SCH_1):PAGE72
  U2D1  A10 CD_VPP<2> SKX_EXT_B_BGA1-IC,TBD    I33 @BASEBOARD_FAB2_LIB.BASEBOARD_FAB2(SCH_1):PAGE72
  U2D1   A8 CD_VPP<3> SKX_EXT_B_BGA1-IC,TBD    I33 @BASEBOARD_FAB2_LIB.BASEBOARD_FAB2(SCH_1):PAGE72
  J1G1  284 VDDSPD SCONN288_H44441004_PIP-SCONN,HA   I111 @BASEBOARD_FAB2_LIB.BASEBOARD_FAB2(SCH_1):PAGE77
  J1G1  287 VPP<0> SCONN288_H44441004_PIP-SCONN,HA   I171 @BASEBOARD_FAB2_LIB.BASEBOARD_FAB2(SCH_1):PAGE77
  J1G1  286 VPP<1> SCONN288_H44441004_PIP-SCONN,HA   I171 @BASEBOARD_FAB2_LIB.BASEBOARD_FAB2(SCH_1):PAGE77
  J1G1  288 VPP<2> SCONN288_H44441004_PIP-SCONN,HA   I171 @BASEBOARD_FAB2_LIB.BASEBOARD_FAB2(SCH_1):PAGE77
  J1G1  143 VPP<3> SCONN288_H44441004_PIP-SCONN,HA   I171 @BASEBOARD_FAB2_LIB.BASEBOARD_FAB2(SCH_1):PAGE77
  J1G1  142 VPP<4> SCONN288_H44441004_PIP-SCONN,HA   I171 @BASEBOARD_FAB2_LIB.BASEBOARD_FAB2(SCH_1):PAGE77
  J9T1  139  SA<0> SCONN288_H44441003_PIP-SCONN,HA    I13 @BASEBOARD_FAB2_LIB.BASEBOARD_FAB2(SCH_1):PAGE78
  J9T1  284 VDDSPD SCONN288_H44441003_PIP-SCONN,HA    I13 @BASEBOARD_FAB2_LIB.BASEBOARD_FAB2(SCH_1):PAGE78
  J9T1  287 VPP<0> SCONN288_H44441003_PIP-SCONN,HA    I75 @BASEBOARD_FAB2_LIB.BASEBOARD_FAB2(SCH_1):PAGE78
  J9T1  286 VPP<1> SCONN288_H44441003_PIP-SCONN,HA    I75 @BASEBOARD_FAB2_LIB.BASEBOARD_FAB2(SCH_1):PAGE78
  J9T1  288 VPP<2> SCONN288_H44441003_PIP-SCONN,HA    I75 @BASEBOARD_FAB2_LIB.BASEBOARD_FAB2(SCH_1):PAGE78
  J9T1  143 VPP<3> SCONN288_H44441003_PIP-SCONN,HA    I75 @BASEBOARD_FAB2_LIB.BASEBOARD_FAB2(SCH_1):PAGE78
  J9T1  142 VPP<4> SCONN288_H44441003_PIP-SCONN,HA    I75 @BASEBOARD_FAB2_LIB.BASEBOARD_FAB2(SCH_1):PAGE78
  J1G2  140  SA<1> SCONN288_H44441004_PIP-SCONN,HA   I111 @BASEBOARD_FAB2_LIB.BASEBOARD_FAB2(SCH_1):PAGE79
  J1G2  284 VDDSPD SCONN288_H44441004_PIP-SCONN,HA   I111 @BASEBOARD_FAB2_LIB.BASEBOARD_FAB2(SCH_1):PAGE79
  J1G2  287 VPP<0> SCONN288_H44441004_PIP-SCONN,HA   I169 @BASEBOARD_FAB2_LIB.BASEBOARD_FAB2(SCH_1):PAGE79
  J1G2  286 VPP<1> SCONN288_H44441004_PIP-SCONN,HA   I169 @BASEBOARD_FAB2_LIB.BASEBOARD_FAB2(SCH_1):PAGE79
  J1G2  288 VPP<2> SCONN288_H44441004_PIP-SCONN,HA   I169 @BASEBOARD_FAB2_LIB.BASEBOARD_FAB2(SCH_1):PAGE79
  J1G2  143 VPP<3> SCONN288_H44441004_PIP-SCONN,HA   I169 @BASEBOARD_FAB2_LIB.BASEBOARD_FAB2(SCH_1):PAGE79
  J1G2  142 VPP<4> SCONN288_H44441004_PIP-SCONN,HA   I169 @BASEBOARD_FAB2_LIB.BASEBOARD_FAB2(SCH_1):PAGE79
  J9U1  139  SA<0> SCONN288_H44441003_PIP-SCONN,HA    I24 @BASEBOARD_FAB2_LIB.BASEBOARD_FAB2(SCH_1):PAGE80
  J9U1  140  SA<1> SCONN288_H44441003_PIP-SCONN,HA    I24 @BASEBOARD_FAB2_LIB.BASEBOARD_FAB2(SCH_1):PAGE80
  J9U1  284 VDDSPD SCONN288_H44441003_PIP-SCONN,HA    I24 @BASEBOARD_FAB2_LIB.BASEBOARD_FAB2(SCH_1):PAGE80
  J9U1  287 VPP<0> SCONN288_H44441003_PIP-SCONN,HA    I56 @BASEBOARD_FAB2_LIB.BASEBOARD_FAB2(SCH_1):PAGE80
  J9U1  286 VPP<1> SCONN288_H44441003_PIP-SCONN,HA    I56 @BASEBOARD_FAB2_LIB.BASEBOARD_FAB2(SCH_1):PAGE80
  J9U1  288 VPP<2> SCONN288_H44441003_PIP-SCONN,HA    I56 @BASEBOARD_FAB2_LIB.BASEBOARD_FAB2(SCH_1):PAGE80
  J9U1  143 VPP<3> SCONN288_H44441003_PIP-SCONN,HA    I56 @BASEBOARD_FAB2_LIB.BASEBOARD_FAB2(SCH_1):PAGE80
  J9U1  142 VPP<4> SCONN288_H44441003_PIP-SCONN,HA    I56 @BASEBOARD_FAB2_LIB.BASEBOARD_FAB2(SCH_1):PAGE80
  J1G3  287 VPP<0> SCONN288_H44441004_PIP-SCONN,HA   I169 @BASEBOARD_FAB2_LIB.BASEBOARD_FAB2(SCH_1):PAGE81
  J1G3  286 VPP<1> SCONN288_H44441004_PIP-SCONN,HA   I169 @BASEBOARD_FAB2_LIB.BASEBOARD_FAB2(SCH_1):PAGE81
  J1G3  288 VPP<2> SCONN288_H44441004_PIP-SCONN,HA   I169 @BASEBOARD_FAB2_LIB.BASEBOARD_FAB2(SCH_1):PAGE81
  J1G3  143 VPP<3> SCONN288_H44441004_PIP-SCONN,HA   I169 @BASEBOARD_FAB2_LIB.BASEBOARD_FAB2(SCH_1):PAGE81
  J1G3  142 VPP<4> SCONN288_H44441004_PIP-SCONN,HA   I169 @BASEBOARD_FAB2_LIB.BASEBOARD_FAB2(SCH_1):PAGE81
  J1G3  238  SA<2> SCONN288_H44441004_PIP-SCONN,HA   I186 @BASEBOARD_FAB2_LIB.BASEBOARD_FAB2(SCH_1):PAGE81
  J1G3  284 VDDSPD SCONN288_H44441004_PIP-SCONN,HA   I186 @BASEBOARD_FAB2_LIB.BASEBOARD_FAB2(SCH_1):PAGE81
  J9U2  287 VPP<0> SCONN288_H44441003_PIP-SCONN,HA   I171 @BASEBOARD_FAB2_LIB.BASEBOARD_FAB2(SCH_1):PAGE82
  J9U2  286 VPP<1> SCONN288_H44441003_PIP-SCONN,HA   I171 @BASEBOARD_FAB2_LIB.BASEBOARD_FAB2(SCH_1):PAGE82
  J9U2  288 VPP<2> SCONN288_H44441003_PIP-SCONN,HA   I171 @BASEBOARD_FAB2_LIB.BASEBOARD_FAB2(SCH_1):PAGE82
  J9U2  143 VPP<3> SCONN288_H44441003_PIP-SCONN,HA   I171 @BASEBOARD_FAB2_LIB.BASEBOARD_FAB2(SCH_1):PAGE82
  J9U2  142 VPP<4> SCONN288_H44441003_PIP-SCONN,HA   I171 @BASEBOARD_FAB2_LIB.BASEBOARD_FAB2(SCH_1):PAGE82
  J9U2  139  SA<0> SCONN288_H44441003_PIP-SCONN,HA   I187 @BASEBOARD_FAB2_LIB.BASEBOARD_FAB2(SCH_1):PAGE82
  J9U2  238  SA<2> SCONN288_H44441003_PIP-SCONN,HA   I187 @BASEBOARD_FAB2_LIB.BASEBOARD_FAB2(SCH_1):PAGE82
  J9U2  284 VDDSPD SCONN288_H44441003_PIP-SCONN,HA   I187 @BASEBOARD_FAB2_LIB.BASEBOARD_FAB2(SCH_1):PAGE82
 C4G25    1      A CAP_A_0402V-0.1UF,16V,10%,X7R,A    I41 @BASEBOARD_FAB2_LIB.BASEBOARD_FAB2(SCH_1):PAGE99
  U4G1    8   VCCB PCA9617_SSOP-IC,G81764-001-GNDA    I63 @BASEBOARD_FAB2_LIB.BASEBOARD_FAB2(SCH_1):PAGE99
 R6U18    1      A RES_0402-665,1.0%,1/16W,CHIP,GA   I104 @BASEBOARD_FAB2_LIB.BASEBOARD_FAB2(SCH_1):PAGE99
 R6U17    1      A RES_0402-665,1.0%,1/16W,CHIP,GA   I106 @BASEBOARD_FAB2_LIB.BASEBOARD_FAB2(SCH_1):PAGE99
  C7U4    1      A CAP_0603LF-10UF,4V,20%,X6S,E15A   I109 @BASEBOARD_FAB2_LIB.BASEBOARD_FAB2(SCH_1):PAGE233
  C7U5    1      A CAP_0603LF-10UF,4V,20%,X6S,E15A   I111 @BASEBOARD_FAB2_LIB.BASEBOARD_FAB2(SCH_1):PAGE233
  C7T2    1      A CAP_0603LF-10UF,4V,20%,X6S,E15A   I112 @BASEBOARD_FAB2_LIB.BASEBOARD_FAB2(SCH_1):PAGE233
  C7T3    1      A CAP_0603LF-10UF,4V,20%,X6S,E15A   I113 @BASEBOARD_FAB2_LIB.BASEBOARD_FAB2(SCH_1):PAGE233
  C7U6    1      A CAP_0603LF-10UF,4V,20%,X6S,E15A   I115 @BASEBOARD_FAB2_LIB.BASEBOARD_FAB2(SCH_1):PAGE233
  C3F3    1      A CAP_0603LF-10UF,4V,20%,X6S,E15A   I116 @BASEBOARD_FAB2_LIB.BASEBOARD_FAB2(SCH_1):PAGE233
  C3F4    1      A CAP_0603LF-10UF,4V,20%,X6S,E15A   I117 @BASEBOARD_FAB2_LIB.BASEBOARD_FAB2(SCH_1):PAGE233
  C3G3    1      A CAP_0603LF-10UF,4V,20%,X6S,E15A   I118 @BASEBOARD_FAB2_LIB.BASEBOARD_FAB2(SCH_1):PAGE233
  C3G7    1      A CAP_0603LF-10UF,4V,20%,X6S,E15A   I132 @BASEBOARD_FAB2_LIB.BASEBOARD_FAB2(SCH_1):PAGE233
  C3G4    1      A CAP_0603LF-10UF,4V,20%,X6S,E15A   I133 @BASEBOARD_FAB2_LIB.BASEBOARD_FAB2(SCH_1):PAGE233
  C3G8    1      A CAP_0603LF-10UF,4V,20%,X6S,E15A   I135 @BASEBOARD_FAB2_LIB.BASEBOARD_FAB2(SCH_1):PAGE233
  C7U3    1      A CAP_0603LF-10UF,4V,20%,X6S,E15A   I136 @BASEBOARD_FAB2_LIB.BASEBOARD_FAB2(SCH_1):PAGE233
  R4G6    1      A RES_0603-120.0,1%,1/10W,CHIP,GA   I211 @BASEBOARD_FAB2_LIB.BASEBOARD_FAB2(SCH_1):PAGE233
  C4F7    1      A CAPP_7343LF-330UF,6.3V,20%,POSA   I217 @BASEBOARD_FAB2_LIB.BASEBOARD_FAB2(SCH_1):PAGE233
  C6U3    1      A CAP_0805-47UF,4V,20%,X6S,C9533A   I221 @BASEBOARD_FAB2_LIB.BASEBOARD_FAB2(SCH_1):PAGE233
  C6U2    1      A CAP_0805-47UF,4V,20%,X6S,C9533A   I223 @BASEBOARD_FAB2_LIB.BASEBOARD_FAB2(SCH_1):PAGE233
 C4F11    1      A CAPP_7343-220UF,4V,20%,POSCAP,A   I256 @BASEBOARD_FAB2_LIB.BASEBOARD_FAB2(SCH_1):PAGE233
  R4G8    1      A RES_0402-0.0,5%,1/16W,CHIP,G21A   I271 @BASEBOARD_FAB2_LIB.BASEBOARD_FAB2(SCH_1):PAGE233
  L4G1    2    INB INDUCTOR_SM-0.47UH,IND,E13358-A   I277 @BASEBOARD_FAB2_LIB.BASEBOARD_FAB2(SCH_1):PAGE233

PVPP_KLM @BASEBOARD_FAB2_LIB.BASEBOARD_FAB2(SCH_1):PVPP_KLM
  J1B1  284 VDDSPD SCONN288_H44441004_PIP-SCONN,HA   I111 @BASEBOARD_FAB2_LIB.BASEBOARD_FAB2(SCH_1):PAGE83
  J1B1  287 VPP<0> SCONN288_H44441004_PIP-SCONN,HA   I167 @BASEBOARD_FAB2_LIB.BASEBOARD_FAB2(SCH_1):PAGE83
  J1B1  286 VPP<1> SCONN288_H44441004_PIP-SCONN,HA   I167 @BASEBOARD_FAB2_LIB.BASEBOARD_FAB2(SCH_1):PAGE83
  J1B1  288 VPP<2> SCONN288_H44441004_PIP-SCONN,HA   I167 @BASEBOARD_FAB2_LIB.BASEBOARD_FAB2(SCH_1):PAGE83
  J1B1  143 VPP<3> SCONN288_H44441004_PIP-SCONN,HA   I167 @BASEBOARD_FAB2_LIB.BASEBOARD_FAB2(SCH_1):PAGE83
  J1B1  142 VPP<4> SCONN288_H44441004_PIP-SCONN,HA   I167 @BASEBOARD_FAB2_LIB.BASEBOARD_FAB2(SCH_1):PAGE83
  J9M1  139  SA<0> SCONN288_H44441003_PIP-SCONN,HA    I14 @BASEBOARD_FAB2_LIB.BASEBOARD_FAB2(SCH_1):PAGE84
  J9M1  284 VDDSPD SCONN288_H44441003_PIP-SCONN,HA    I14 @BASEBOARD_FAB2_LIB.BASEBOARD_FAB2(SCH_1):PAGE84
  J9M1  287 VPP<0> SCONN288_H44441003_PIP-SCONN,HA    I57 @BASEBOARD_FAB2_LIB.BASEBOARD_FAB2(SCH_1):PAGE84
  J9M1  286 VPP<1> SCONN288_H44441003_PIP-SCONN,HA    I57 @BASEBOARD_FAB2_LIB.BASEBOARD_FAB2(SCH_1):PAGE84
  J9M1  288 VPP<2> SCONN288_H44441003_PIP-SCONN,HA    I57 @BASEBOARD_FAB2_LIB.BASEBOARD_FAB2(SCH_1):PAGE84
  J9M1  143 VPP<3> SCONN288_H44441003_PIP-SCONN,HA    I57 @BASEBOARD_FAB2_LIB.BASEBOARD_FAB2(SCH_1):PAGE84
  J9M1  142 VPP<4> SCONN288_H44441003_PIP-SCONN,HA    I57 @BASEBOARD_FAB2_LIB.BASEBOARD_FAB2(SCH_1):PAGE84
  J1A2  140  SA<1> SCONN288_H44441004_PIP-SCONN,HA   I111 @BASEBOARD_FAB2_LIB.BASEBOARD_FAB2(SCH_1):PAGE85
  J1A2  284 VDDSPD SCONN288_H44441004_PIP-SCONN,HA   I111 @BASEBOARD_FAB2_LIB.BASEBOARD_FAB2(SCH_1):PAGE85
  J1A2  287 VPP<0> SCONN288_H44441004_PIP-SCONN,HA   I172 @BASEBOARD_FAB2_LIB.BASEBOARD_FAB2(SCH_1):PAGE85
  J1A2  286 VPP<1> SCONN288_H44441004_PIP-SCONN,HA   I172 @BASEBOARD_FAB2_LIB.BASEBOARD_FAB2(SCH_1):PAGE85
  J1A2  288 VPP<2> SCONN288_H44441004_PIP-SCONN,HA   I172 @BASEBOARD_FAB2_LIB.BASEBOARD_FAB2(SCH_1):PAGE85
  J1A2  143 VPP<3> SCONN288_H44441004_PIP-SCONN,HA   I172 @BASEBOARD_FAB2_LIB.BASEBOARD_FAB2(SCH_1):PAGE85
  J1A2  142 VPP<4> SCONN288_H44441004_PIP-SCONN,HA   I172 @BASEBOARD_FAB2_LIB.BASEBOARD_FAB2(SCH_1):PAGE85
  J9L2  139  SA<0> SCONN288_H44441003_PIP-SCONN,HA    I12 @BASEBOARD_FAB2_LIB.BASEBOARD_FAB2(SCH_1):PAGE86
  J9L2  140  SA<1> SCONN288_H44441003_PIP-SCONN,HA    I12 @BASEBOARD_FAB2_LIB.BASEBOARD_FAB2(SCH_1):PAGE86
  J9L2  284 VDDSPD SCONN288_H44441003_PIP-SCONN,HA    I12 @BASEBOARD_FAB2_LIB.BASEBOARD_FAB2(SCH_1):PAGE86
  J9L2  287 VPP<0> SCONN288_H44441003_PIP-SCONN,HA    I55 @BASEBOARD_FAB2_LIB.BASEBOARD_FAB2(SCH_1):PAGE86
  J9L2  286 VPP<1> SCONN288_H44441003_PIP-SCONN,HA    I55 @BASEBOARD_FAB2_LIB.BASEBOARD_FAB2(SCH_1):PAGE86
  J9L2  288 VPP<2> SCONN288_H44441003_PIP-SCONN,HA    I55 @BASEBOARD_FAB2_LIB.BASEBOARD_FAB2(SCH_1):PAGE86
  J9L2  143 VPP<3> SCONN288_H44441003_PIP-SCONN,HA    I55 @BASEBOARD_FAB2_LIB.BASEBOARD_FAB2(SCH_1):PAGE86
  J9L2  142 VPP<4> SCONN288_H44441003_PIP-SCONN,HA    I55 @BASEBOARD_FAB2_LIB.BASEBOARD_FAB2(SCH_1):PAGE86
  J1A1  287 VPP<0> SCONN288_H44441004_PIP-SCONN,HA   I169 @BASEBOARD_FAB2_LIB.BASEBOARD_FAB2(SCH_1):PAGE87
  J1A1  286 VPP<1> SCONN288_H44441004_PIP-SCONN,HA   I169 @BASEBOARD_FAB2_LIB.BASEBOARD_FAB2(SCH_1):PAGE87
  J1A1  288 VPP<2> SCONN288_H44441004_PIP-SCONN,HA   I169 @BASEBOARD_FAB2_LIB.BASEBOARD_FAB2(SCH_1):PAGE87
  J1A1  143 VPP<3> SCONN288_H44441004_PIP-SCONN,HA   I169 @BASEBOARD_FAB2_LIB.BASEBOARD_FAB2(SCH_1):PAGE87
  J1A1  142 VPP<4> SCONN288_H44441004_PIP-SCONN,HA   I169 @BASEBOARD_FAB2_LIB.BASEBOARD_FAB2(SCH_1):PAGE87
  J1A1  238  SA<2> SCONN288_H44441004_PIP-SCONN,HA   I186 @BASEBOARD_FAB2_LIB.BASEBOARD_FAB2(SCH_1):PAGE87
  J1A1  284 VDDSPD SCONN288_H44441004_PIP-SCONN,HA   I186 @BASEBOARD_FAB2_LIB.BASEBOARD_FAB2(SCH_1):PAGE87
  J9L1  139  SA<0> SCONN288_H44441003_PIP-SCONN,HA   I111 @BASEBOARD_FAB2_LIB.BASEBOARD_FAB2(SCH_1):PAGE88
  J9L1  238  SA<2> SCONN288_H44441003_PIP-SCONN,HA   I111 @BASEBOARD_FAB2_LIB.BASEBOARD_FAB2(SCH_1):PAGE88
  J9L1  284 VDDSPD SCONN288_H44441003_PIP-SCONN,HA   I111 @BASEBOARD_FAB2_LIB.BASEBOARD_FAB2(SCH_1):PAGE88
  J9L1  287 VPP<0> SCONN288_H44441003_PIP-SCONN,HA   I168 @BASEBOARD_FAB2_LIB.BASEBOARD_FAB2(SCH_1):PAGE88
  J9L1  286 VPP<1> SCONN288_H44441003_PIP-SCONN,HA   I168 @BASEBOARD_FAB2_LIB.BASEBOARD_FAB2(SCH_1):PAGE88
  J9L1  288 VPP<2> SCONN288_H44441003_PIP-SCONN,HA   I168 @BASEBOARD_FAB2_LIB.BASEBOARD_FAB2(SCH_1):PAGE88
  J9L1  143 VPP<3> SCONN288_H44441003_PIP-SCONN,HA   I168 @BASEBOARD_FAB2_LIB.BASEBOARD_FAB2(SCH_1):PAGE88
  J9L1  142 VPP<4> SCONN288_H44441003_PIP-SCONN,HA   I168 @BASEBOARD_FAB2_LIB.BASEBOARD_FAB2(SCH_1):PAGE88
  C3B5    1      A CAP_A_0402V-0.1UF,16V,10%,X7R,A    I53 @BASEBOARD_FAB2_LIB.BASEBOARD_FAB2(SCH_1):PAGE99
  U3B1    8   VCCB PCA9617_SSOP-IC,G81764-001-GNDA    I75 @BASEBOARD_FAB2_LIB.BASEBOARD_FAB2(SCH_1):PAGE99
  R7M6    1      A RES_0402-665,1.0%,1/16W,CHIP,GA   I107 @BASEBOARD_FAB2_LIB.BASEBOARD_FAB2(SCH_1):PAGE99
  R7M1    1      A RES_0402-665,1.0%,1/16W,CHIP,GA   I109 @BASEBOARD_FAB2_LIB.BASEBOARD_FAB2(SCH_1):PAGE99
  R6M9    1      A RES_0402-4.75K,1%,1/16W,CHIP,GA    I49 @BASEBOARD_FAB2_LIB.BASEBOARD_FAB2(SCH_1):PAGE192
  C3B2    1      A CAP_0603LF-10UF,4V,20%,X6S,E15A    I84 @BASEBOARD_FAB2_LIB.BASEBOARD_FAB2(SCH_1):PAGE234
  C3A8    1      A CAP_0603LF-10UF,4V,20%,X6S,E15A    I86 @BASEBOARD_FAB2_LIB.BASEBOARD_FAB2(SCH_1):PAGE234
  C7L3    1      A CAP_0603LF-10UF,4V,20%,X6S,E15A    I87 @BASEBOARD_FAB2_LIB.BASEBOARD_FAB2(SCH_1):PAGE234
  C7L2    1      A CAP_0603LF-10UF,4V,20%,X6S,E15A    I88 @BASEBOARD_FAB2_LIB.BASEBOARD_FAB2(SCH_1):PAGE234
  C7L7    1      A CAP_0603LF-10UF,4V,20%,X6S,E15A    I89 @BASEBOARD_FAB2_LIB.BASEBOARD_FAB2(SCH_1):PAGE234
  C7L6    1      A CAP_0603LF-10UF,4V,20%,X6S,E15A    I90 @BASEBOARD_FAB2_LIB.BASEBOARD_FAB2(SCH_1):PAGE234
  C7M4    1      A CAP_0603LF-10UF,4V,20%,X6S,E15A    I91 @BASEBOARD_FAB2_LIB.BASEBOARD_FAB2(SCH_1):PAGE234
  C7M3    1      A CAP_0603LF-10UF,4V,20%,X6S,E15A    I92 @BASEBOARD_FAB2_LIB.BASEBOARD_FAB2(SCH_1):PAGE234
  C3A4    1      A CAP_0603LF-10UF,4V,20%,X6S,E15A    I93 @BASEBOARD_FAB2_LIB.BASEBOARD_FAB2(SCH_1):PAGE234
  C3B1    1      A CAP_0603LF-10UF,4V,20%,X6S,E15A    I94 @BASEBOARD_FAB2_LIB.BASEBOARD_FAB2(SCH_1):PAGE234
  C3A7    1      A CAP_0603LF-10UF,4V,20%,X6S,E15A    I95 @BASEBOARD_FAB2_LIB.BASEBOARD_FAB2(SCH_1):PAGE234
  C3A3    1      A CAP_0603LF-10UF,4V,20%,X6S,E15A    I97 @BASEBOARD_FAB2_LIB.BASEBOARD_FAB2(SCH_1):PAGE234
  L4A1    2    INB INDUCTOR_SM-0.47UH,IND,E13358-A   I164 @BASEBOARD_FAB2_LIB.BASEBOARD_FAB2(SCH_1):PAGE234
  C3B3    1      A CAPP_7343LF-330UF,6.3V,20%,POSA   I167 @BASEBOARD_FAB2_LIB.BASEBOARD_FAB2(SCH_1):PAGE234
  C4B3    1      A CAP_0805-47UF,4V,20%,X6S,C9533A   I177 @BASEBOARD_FAB2_LIB.BASEBOARD_FAB2(SCH_1):PAGE234
  C4B2    1      A CAP_0805-47UF,4V,20%,X6S,C9533A   I180 @BASEBOARD_FAB2_LIB.BASEBOARD_FAB2(SCH_1):PAGE234
  R4B2    1      A RES_0603-120.0,1%,1/10W,CHIP,GA   I183 @BASEBOARD_FAB2_LIB.BASEBOARD_FAB2(SCH_1):PAGE234
  C6L8    1      A CAPP_7343-220UF,4V,20%,POSCAP,A   I210 @BASEBOARD_FAB2_LIB.BASEBOARD_FAB2(SCH_1):PAGE234
  R4B3    1      A RES_0402-0.0,5%,1/16W,CHIP,G21A   I214 @BASEBOARD_FAB2_LIB.BASEBOARD_FAB2(SCH_1):PAGE234

PVSA_CPU0 @BASEBOARD_FAB2_LIB.BASEBOARD_FAB2(SCH_1):PVSA_CPU0
  U5D1 CJ66 VCCSA<0> SKX_EXT_B_BGA1-IC,TBD    I34 @BASEBOARD_FAB2_LIB.BASEBOARD_FAB2(SCH_1):PAGE38
  U5D1 CJ64 VCCSA<1> SKX_EXT_B_BGA1-IC,TBD    I34 @BASEBOARD_FAB2_LIB.BASEBOARD_FAB2(SCH_1):PAGE38
  U5D1 CH75 VCCSA<2> SKX_EXT_B_BGA1-IC,TBD    I34 @BASEBOARD_FAB2_LIB.BASEBOARD_FAB2(SCH_1):PAGE38
  U5D1 CH65 VCCSA<3> SKX_EXT_B_BGA1-IC,TBD    I34 @BASEBOARD_FAB2_LIB.BASEBOARD_FAB2(SCH_1):PAGE38
  U5D1 CG74 VCCSA<4> SKX_EXT_B_BGA1-IC,TBD    I34 @BASEBOARD_FAB2_LIB.BASEBOARD_FAB2(SCH_1):PAGE38
  U5D1 CG66 VCCSA<5> SKX_EXT_B_BGA1-IC,TBD    I34 @BASEBOARD_FAB2_LIB.BASEBOARD_FAB2(SCH_1):PAGE38
  U5D1 CG64 VCCSA<6> SKX_EXT_B_BGA1-IC,TBD    I34 @BASEBOARD_FAB2_LIB.BASEBOARD_FAB2(SCH_1):PAGE38
  U5D1 CF75 VCCSA<7> SKX_EXT_B_BGA1-IC,TBD    I34 @BASEBOARD_FAB2_LIB.BASEBOARD_FAB2(SCH_1):PAGE38
  U5D1 CF73 VCCSA<8> SKX_EXT_B_BGA1-IC,TBD    I34 @BASEBOARD_FAB2_LIB.BASEBOARD_FAB2(SCH_1):PAGE38
  U5D1 CF67 VCCSA<9> SKX_EXT_B_BGA1-IC,TBD    I34 @BASEBOARD_FAB2_LIB.BASEBOARD_FAB2(SCH_1):PAGE38
  U5D1 CF65 VCCSA<10> SKX_EXT_B_BGA1-IC,TBD    I34 @BASEBOARD_FAB2_LIB.BASEBOARD_FAB2(SCH_1):PAGE38
  U5D1 CE74 VCCSA<11> SKX_EXT_B_BGA1-IC,TBD    I34 @BASEBOARD_FAB2_LIB.BASEBOARD_FAB2(SCH_1):PAGE38
  U5D1 CE72 VCCSA<12> SKX_EXT_B_BGA1-IC,TBD    I34 @BASEBOARD_FAB2_LIB.BASEBOARD_FAB2(SCH_1):PAGE38
  U5D1 CE68 VCCSA<13> SKX_EXT_B_BGA1-IC,TBD    I34 @BASEBOARD_FAB2_LIB.BASEBOARD_FAB2(SCH_1):PAGE38
  U5D1 CE66 VCCSA<14> SKX_EXT_B_BGA1-IC,TBD    I34 @BASEBOARD_FAB2_LIB.BASEBOARD_FAB2(SCH_1):PAGE38
  U5D1 CE64 VCCSA<15> SKX_EXT_B_BGA1-IC,TBD    I34 @BASEBOARD_FAB2_LIB.BASEBOARD_FAB2(SCH_1):PAGE38
  U5D1 CD71 VCCSA<16> SKX_EXT_B_BGA1-IC,TBD    I34 @BASEBOARD_FAB2_LIB.BASEBOARD_FAB2(SCH_1):PAGE38
  U5D1 CD69 VCCSA<17> SKX_EXT_B_BGA1-IC,TBD    I34 @BASEBOARD_FAB2_LIB.BASEBOARD_FAB2(SCH_1):PAGE38
  U5D1 CD67 VCCSA<18> SKX_EXT_B_BGA1-IC,TBD    I34 @BASEBOARD_FAB2_LIB.BASEBOARD_FAB2(SCH_1):PAGE38
  U5D1 CD65 VCCSA<19> SKX_EXT_B_BGA1-IC,TBD    I34 @BASEBOARD_FAB2_LIB.BASEBOARD_FAB2(SCH_1):PAGE38
  U5D1 CC70 VCCSA<20> SKX_EXT_B_BGA1-IC,TBD    I34 @BASEBOARD_FAB2_LIB.BASEBOARD_FAB2(SCH_1):PAGE38
  U5D1 CC68 VCCSA<21> SKX_EXT_B_BGA1-IC,TBD    I34 @BASEBOARD_FAB2_LIB.BASEBOARD_FAB2(SCH_1):PAGE38
  U5D1 CC66 VCCSA<22> SKX_EXT_B_BGA1-IC,TBD    I34 @BASEBOARD_FAB2_LIB.BASEBOARD_FAB2(SCH_1):PAGE38
  U5D1 CB69 VCCSA<23> SKX_EXT_B_BGA1-IC,TBD    I34 @BASEBOARD_FAB2_LIB.BASEBOARD_FAB2(SCH_1):PAGE38
  U5D1 CB67 VCCSA<24> SKX_EXT_B_BGA1-IC,TBD    I34 @BASEBOARD_FAB2_LIB.BASEBOARD_FAB2(SCH_1):PAGE38
  U5D1 CB65 VCCSA<25> SKX_EXT_B_BGA1-IC,TBD    I34 @BASEBOARD_FAB2_LIB.BASEBOARD_FAB2(SCH_1):PAGE38
  C5P9    1      A CAP_0805LF-22UF,4V,20%,X6S,C95A    I18 @BASEBOARD_FAB2_LIB.BASEBOARD_FAB2(SCH_1):PAGE42
  C5P8    1      A CAP_0805LF-22UF,4V,20%,X6S,C95A    I19 @BASEBOARD_FAB2_LIB.BASEBOARD_FAB2(SCH_1):PAGE42
  C5P7    1      A CAP_0805LF-22UF,4V,20%,X6S,C95A    I25 @BASEBOARD_FAB2_LIB.BASEBOARD_FAB2(SCH_1):PAGE42
 C5D13    1      A CAP_0603LF-10UF,4V,20%,X6S,E15A    I91 @BASEBOARD_FAB2_LIB.BASEBOARD_FAB2(SCH_1):PAGE42
 C5D11    1      A CAP_0603LF-10UF,4V,20%,X6S,E15A    I93 @BASEBOARD_FAB2_LIB.BASEBOARD_FAB2(SCH_1):PAGE42
 C5D12    1      A CAP_0603LF-10UF,4V,20%,X6S,E15A    I94 @BASEBOARD_FAB2_LIB.BASEBOARD_FAB2(SCH_1):PAGE42
 C5D10    1      A CAP_0603LF-10UF,4V,20%,X6S,E15A   I108 @BASEBOARD_FAB2_LIB.BASEBOARD_FAB2(SCH_1):PAGE42
  C6N7    1      A CAP_A_0603V-22.0UF,4V,20%,X6S,A     I5 @BASEBOARD_FAB2_LIB.BASEBOARD_FAB2(SCH_1):PAGE205
  L4C2    2    INB INDUCTOR_SM-0.3UH,IND,D92183-0A     I7 @BASEBOARD_FAB2_LIB.BASEBOARD_FAB2(SCH_1):PAGE205
  C6N1    1      A CAPP_3018-470UF,2.5V,20%,ALUM,A    I12 @BASEBOARD_FAB2_LIB.BASEBOARD_FAB2(SCH_1):PAGE205
  C6N4    1      A CAPP_3018-470UF,2.5V,20%,ALUM,A    I14 @BASEBOARD_FAB2_LIB.BASEBOARD_FAB2(SCH_1):PAGE205
  R4C5    2      B RES_0402-100.0,1%,1/16W,CHIP,GA    I24 @BASEBOARD_FAB2_LIB.BASEBOARD_FAB2(SCH_1):PAGE205
 C4C11    1      A CAP_A_0603V-22.0UF,4V,20%,X6S,A    I43 @BASEBOARD_FAB2_LIB.BASEBOARD_FAB2(SCH_1):PAGE205
  R6N4    1      A RES_0402-51.1,1.0%,1/16W,CHIP,A    I45 @BASEBOARD_FAB2_LIB.BASEBOARD_FAB2(SCH_1):PAGE205
 EU4C1    1    VOS IR354XX_SM-IR35412,IC,H73684-0A    I46 @BASEBOARD_FAB2_LIB.BASEBOARD_FAB2(SCH_1):PAGE205

PVSA_CPU1 @BASEBOARD_FAB2_LIB.BASEBOARD_FAB2(SCH_1):PVSA_CPU1
  U2D1 CJ66 VCCSA<0> SKX_EXT_B_BGA1-IC,TBD    I33 @BASEBOARD_FAB2_LIB.BASEBOARD_FAB2(SCH_1):PAGE72
  U2D1 CJ64 VCCSA<1> SKX_EXT_B_BGA1-IC,TBD    I33 @BASEBOARD_FAB2_LIB.BASEBOARD_FAB2(SCH_1):PAGE72
  U2D1 CH75 VCCSA<2> SKX_EXT_B_BGA1-IC,TBD    I33 @BASEBOARD_FAB2_LIB.BASEBOARD_FAB2(SCH_1):PAGE72
  U2D1 CH65 VCCSA<3> SKX_EXT_B_BGA1-IC,TBD    I33 @BASEBOARD_FAB2_LIB.BASEBOARD_FAB2(SCH_1):PAGE72
  U2D1 CG74 VCCSA<4> SKX_EXT_B_BGA1-IC,TBD    I33 @BASEBOARD_FAB2_LIB.BASEBOARD_FAB2(SCH_1):PAGE72
  U2D1 CG66 VCCSA<5> SKX_EXT_B_BGA1-IC,TBD    I33 @BASEBOARD_FAB2_LIB.BASEBOARD_FAB2(SCH_1):PAGE72
  U2D1 CG64 VCCSA<6> SKX_EXT_B_BGA1-IC,TBD    I33 @BASEBOARD_FAB2_LIB.BASEBOARD_FAB2(SCH_1):PAGE72
  U2D1 CF75 VCCSA<7> SKX_EXT_B_BGA1-IC,TBD    I33 @BASEBOARD_FAB2_LIB.BASEBOARD_FAB2(SCH_1):PAGE72
  U2D1 CF73 VCCSA<8> SKX_EXT_B_BGA1-IC,TBD    I33 @BASEBOARD_FAB2_LIB.BASEBOARD_FAB2(SCH_1):PAGE72
  U2D1 CF67 VCCSA<9> SKX_EXT_B_BGA1-IC,TBD    I33 @BASEBOARD_FAB2_LIB.BASEBOARD_FAB2(SCH_1):PAGE72
  U2D1 CF65 VCCSA<10> SKX_EXT_B_BGA1-IC,TBD    I33 @BASEBOARD_FAB2_LIB.BASEBOARD_FAB2(SCH_1):PAGE72
  U2D1 CE74 VCCSA<11> SKX_EXT_B_BGA1-IC,TBD    I33 @BASEBOARD_FAB2_LIB.BASEBOARD_FAB2(SCH_1):PAGE72
  U2D1 CE72 VCCSA<12> SKX_EXT_B_BGA1-IC,TBD    I33 @BASEBOARD_FAB2_LIB.BASEBOARD_FAB2(SCH_1):PAGE72
  U2D1 CE68 VCCSA<13> SKX_EXT_B_BGA1-IC,TBD    I33 @BASEBOARD_FAB2_LIB.BASEBOARD_FAB2(SCH_1):PAGE72
  U2D1 CE66 VCCSA<14> SKX_EXT_B_BGA1-IC,TBD    I33 @BASEBOARD_FAB2_LIB.BASEBOARD_FAB2(SCH_1):PAGE72
  U2D1 CE64 VCCSA<15> SKX_EXT_B_BGA1-IC,TBD    I33 @BASEBOARD_FAB2_LIB.BASEBOARD_FAB2(SCH_1):PAGE72
  U2D1 CD71 VCCSA<16> SKX_EXT_B_BGA1-IC,TBD    I33 @BASEBOARD_FAB2_LIB.BASEBOARD_FAB2(SCH_1):PAGE72
  U2D1 CD69 VCCSA<17> SKX_EXT_B_BGA1-IC,TBD    I33 @BASEBOARD_FAB2_LIB.BASEBOARD_FAB2(SCH_1):PAGE72
  U2D1 CD67 VCCSA<18> SKX_EXT_B_BGA1-IC,TBD    I33 @BASEBOARD_FAB2_LIB.BASEBOARD_FAB2(SCH_1):PAGE72
  U2D1 CD65 VCCSA<19> SKX_EXT_B_BGA1-IC,TBD    I33 @BASEBOARD_FAB2_LIB.BASEBOARD_FAB2(SCH_1):PAGE72
  U2D1 CC70 VCCSA<20> SKX_EXT_B_BGA1-IC,TBD    I33 @BASEBOARD_FAB2_LIB.BASEBOARD_FAB2(SCH_1):PAGE72
  U2D1 CC68 VCCSA<21> SKX_EXT_B_BGA1-IC,TBD    I33 @BASEBOARD_FAB2_LIB.BASEBOARD_FAB2(SCH_1):PAGE72
  U2D1 CC66 VCCSA<22> SKX_EXT_B_BGA1-IC,TBD    I33 @BASEBOARD_FAB2_LIB.BASEBOARD_FAB2(SCH_1):PAGE72
  U2D1 CB69 VCCSA<23> SKX_EXT_B_BGA1-IC,TBD    I33 @BASEBOARD_FAB2_LIB.BASEBOARD_FAB2(SCH_1):PAGE72
  U2D1 CB67 VCCSA<24> SKX_EXT_B_BGA1-IC,TBD    I33 @BASEBOARD_FAB2_LIB.BASEBOARD_FAB2(SCH_1):PAGE72
  U2D1 CB65 VCCSA<25> SKX_EXT_B_BGA1-IC,TBD    I33 @BASEBOARD_FAB2_LIB.BASEBOARD_FAB2(SCH_1):PAGE72
  C2D8    1      A CAP_0603LF-10UF,4V,20%,X6S,E15A    I33 @BASEBOARD_FAB2_LIB.BASEBOARD_FAB2(SCH_1):PAGE76
 C2D10    1      A CAP_0603LF-10UF,4V,20%,X6S,E15A    I37 @BASEBOARD_FAB2_LIB.BASEBOARD_FAB2(SCH_1):PAGE76
 C2D11    1      A CAP_0603LF-10UF,4V,20%,X6S,E15A    I42 @BASEBOARD_FAB2_LIB.BASEBOARD_FAB2(SCH_1):PAGE76
  C2D9    1      A CAP_0603LF-10UF,4V,20%,X6S,E15A    I43 @BASEBOARD_FAB2_LIB.BASEBOARD_FAB2(SCH_1):PAGE76
  C8P7    1      A CAP_0805LF-22UF,4V,20%,X6S,C95A    I50 @BASEBOARD_FAB2_LIB.BASEBOARD_FAB2(SCH_1):PAGE76
  C8P6    1      A CAP_0805LF-22UF,4V,20%,X6S,C95A    I55 @BASEBOARD_FAB2_LIB.BASEBOARD_FAB2(SCH_1):PAGE76
  C8P5    1      A CAP_0805LF-22UF,4V,20%,X6S,C95A    I58 @BASEBOARD_FAB2_LIB.BASEBOARD_FAB2(SCH_1):PAGE76
 C1C19    1      A CAP_A_0603V-22.0UF,4V,20%,X6S,A     I8 @BASEBOARD_FAB2_LIB.BASEBOARD_FAB2(SCH_1):PAGE210
  L1C1    2    INB INDUCTOR_SM-0.3UH,IND,D92183-0A    I10 @BASEBOARD_FAB2_LIB.BASEBOARD_FAB2(SCH_1):PAGE210
 C9N11    1      A CAPP_3018-470UF,2.5V,20%,ALUM,A    I12 @BASEBOARD_FAB2_LIB.BASEBOARD_FAB2(SCH_1):PAGE210
 C9N20    1      A CAPP_3018-470UF,2.5V,20%,ALUM,A    I14 @BASEBOARD_FAB2_LIB.BASEBOARD_FAB2(SCH_1):PAGE210
 R1C12    2      B RES_0402-100.0,1%,1/16W,CHIP,GA    I29 @BASEBOARD_FAB2_LIB.BASEBOARD_FAB2(SCH_1):PAGE210
 C9N22    1      A CAP_A_0603V-22.0UF,4V,20%,X6S,A    I44 @BASEBOARD_FAB2_LIB.BASEBOARD_FAB2(SCH_1):PAGE210
  R9N4    1      A RES_0402-51.1,1.0%,1/16W,CHIP,A    I45 @BASEBOARD_FAB2_LIB.BASEBOARD_FAB2(SCH_1):PAGE210
 EU1C1    1    VOS IR354XX_SM-IR35412,IC,H73684-0A    I51 @BASEBOARD_FAB2_LIB.BASEBOARD_FAB2(SCH_1):PAGE210

PVTT_ABC @BASEBOARD_FAB2_LIB.BASEBOARD_FAB2(SCH_1):PVTT_ABC
  J4G1  221 VTT<0> SCONN288_H44441004_PIP-SCONN,HA   I260 @BASEBOARD_FAB2_LIB.BASEBOARD_FAB2(SCH_1):PAGE43
  J4G1   77 VTT<1> SCONN288_H44441004_PIP-SCONN,HA   I260 @BASEBOARD_FAB2_LIB.BASEBOARD_FAB2(SCH_1):PAGE43
  J6T1  221 VTT<0> SCONN288_H44441003_PIP-SCONN,HA    I75 @BASEBOARD_FAB2_LIB.BASEBOARD_FAB2(SCH_1):PAGE44
  J6T1   77 VTT<1> SCONN288_H44441003_PIP-SCONN,HA    I75 @BASEBOARD_FAB2_LIB.BASEBOARD_FAB2(SCH_1):PAGE44
  J4G2  221 VTT<0> SCONN288_H44441004_PIP-SCONN,HA   I169 @BASEBOARD_FAB2_LIB.BASEBOARD_FAB2(SCH_1):PAGE45
  J4G2   77 VTT<1> SCONN288_H44441004_PIP-SCONN,HA   I169 @BASEBOARD_FAB2_LIB.BASEBOARD_FAB2(SCH_1):PAGE45
  J6U1  221 VTT<0> SCONN288_H44441003_PIP-SCONN,HA    I67 @BASEBOARD_FAB2_LIB.BASEBOARD_FAB2(SCH_1):PAGE46
  J6U1   77 VTT<1> SCONN288_H44441003_PIP-SCONN,HA    I67 @BASEBOARD_FAB2_LIB.BASEBOARD_FAB2(SCH_1):PAGE46
  J4G3  221 VTT<0> SCONN288_H44441004_PIP-SCONN,HA   I179 @BASEBOARD_FAB2_LIB.BASEBOARD_FAB2(SCH_1):PAGE47
  J4G3   77 VTT<1> SCONN288_H44441004_PIP-SCONN,HA   I179 @BASEBOARD_FAB2_LIB.BASEBOARD_FAB2(SCH_1):PAGE47
  J6U2  221 VTT<0> SCONN288_H44441003_PIP-SCONN,HA   I171 @BASEBOARD_FAB2_LIB.BASEBOARD_FAB2(SCH_1):PAGE48
  J6U2   77 VTT<1> SCONN288_H44441003_PIP-SCONN,HA   I171 @BASEBOARD_FAB2_LIB.BASEBOARD_FAB2(SCH_1):PAGE48
 EU4G3    9    VTT MIC5166_DFN-IC,H55101-001     I1 @BASEBOARD_FAB2_LIB.BASEBOARD_FAB2(SCH_1):PAGE221
 C4G24    1      A CAP_0805LF-22UF,4V,20%,X6S,C95A    I20 @BASEBOARD_FAB2_LIB.BASEBOARD_FAB2(SCH_1):PAGE221
 C5U12    1      A CAP_A_0603V-47UF,4V,20%,X5R,60A    I50 @BASEBOARD_FAB2_LIB.BASEBOARD_FAB2(SCH_1):PAGE221
  C5T3    1      A CAP_A_0603V-47UF,4V,20%,X5R,60A    I51 @BASEBOARD_FAB2_LIB.BASEBOARD_FAB2(SCH_1):PAGE221
 C5U16    1      A CAP_A_0603V-47UF,4V,20%,X5R,60A    I52 @BASEBOARD_FAB2_LIB.BASEBOARD_FAB2(SCH_1):PAGE221
 R6U16    2      B RES_0402-51.1,1.0%,1/16W,CHIP,A    I55 @BASEBOARD_FAB2_LIB.BASEBOARD_FAB2(SCH_1):PAGE221
 SH5U1    2      B SHUNT_SH0201-EMPTY,N_A    I56 @BASEBOARD_FAB2_LIB.BASEBOARD_FAB2(SCH_1):PAGE221

PVTT_DEF @BASEBOARD_FAB2_LIB.BASEBOARD_FAB2(SCH_1):PVTT_DEF
  J4B1  221 VTT<0> SCONN288_H44441004_PIP-SCONN,HA   I169 @BASEBOARD_FAB2_LIB.BASEBOARD_FAB2(SCH_1):PAGE49
  J4B1   77 VTT<1> SCONN288_H44441004_PIP-SCONN,HA   I169 @BASEBOARD_FAB2_LIB.BASEBOARD_FAB2(SCH_1):PAGE49
  J6M1  221 VTT<0> SCONN288_H44441003_PIP-SCONN,HA    I50 @BASEBOARD_FAB2_LIB.BASEBOARD_FAB2(SCH_1):PAGE50
  J6M1   77 VTT<1> SCONN288_H44441003_PIP-SCONN,HA    I50 @BASEBOARD_FAB2_LIB.BASEBOARD_FAB2(SCH_1):PAGE50
  J4A2  221 VTT<0> SCONN288_H44441004_PIP-SCONN,HA   I167 @BASEBOARD_FAB2_LIB.BASEBOARD_FAB2(SCH_1):PAGE51
  J4A2   77 VTT<1> SCONN288_H44441004_PIP-SCONN,HA   I167 @BASEBOARD_FAB2_LIB.BASEBOARD_FAB2(SCH_1):PAGE51
  J6L2  221 VTT<0> SCONN288_H44441003_PIP-SCONN,HA    I55 @BASEBOARD_FAB2_LIB.BASEBOARD_FAB2(SCH_1):PAGE52
  J6L2   77 VTT<1> SCONN288_H44441003_PIP-SCONN,HA    I55 @BASEBOARD_FAB2_LIB.BASEBOARD_FAB2(SCH_1):PAGE52
  J4A1  221 VTT<0> SCONN288_H44441004_PIP-SCONN,HA   I171 @BASEBOARD_FAB2_LIB.BASEBOARD_FAB2(SCH_1):PAGE53
  J4A1   77 VTT<1> SCONN288_H44441004_PIP-SCONN,HA   I171 @BASEBOARD_FAB2_LIB.BASEBOARD_FAB2(SCH_1):PAGE53
  J6L1  221 VTT<0> SCONN288_H44441003_PIP-SCONN,HA   I170 @BASEBOARD_FAB2_LIB.BASEBOARD_FAB2(SCH_1):PAGE54
  J6L1   77 VTT<1> SCONN288_H44441003_PIP-SCONN,HA   I170 @BASEBOARD_FAB2_LIB.BASEBOARD_FAB2(SCH_1):PAGE54
  C4A1    1      A CAP_0805LF-22UF,4V,20%,X6S,C95A    I16 @BASEBOARD_FAB2_LIB.BASEBOARD_FAB2(SCH_1):PAGE222
 EU4A1    9    VTT MIC5166_DFN-IC,H55101-001    I31 @BASEBOARD_FAB2_LIB.BASEBOARD_FAB2(SCH_1):PAGE222
  C5L4    1      A CAP_A_0603V-47UF,4V,20%,X5R,60A    I47 @BASEBOARD_FAB2_LIB.BASEBOARD_FAB2(SCH_1):PAGE222
 C5M13    1      A CAP_A_0603V-47UF,4V,20%,X5R,60A    I48 @BASEBOARD_FAB2_LIB.BASEBOARD_FAB2(SCH_1):PAGE222
  C5L5    1      A CAP_A_0603V-47UF,4V,20%,X5R,60A    I49 @BASEBOARD_FAB2_LIB.BASEBOARD_FAB2(SCH_1):PAGE222
  R4A1    2      B RES_0402-51.1,1.0%,1/16W,CHIP,A    I52 @BASEBOARD_FAB2_LIB.BASEBOARD_FAB2(SCH_1):PAGE222
 SH5L1    2      B SHUNT_SH0201-EMPTY,N_A    I53 @BASEBOARD_FAB2_LIB.BASEBOARD_FAB2(SCH_1):PAGE222

PVTT_GHJ @BASEBOARD_FAB2_LIB.BASEBOARD_FAB2(SCH_1):PVTT_GHJ
  J1G1  221 VTT<0> SCONN288_H44441004_PIP-SCONN,HA   I171 @BASEBOARD_FAB2_LIB.BASEBOARD_FAB2(SCH_1):PAGE77
  J1G1   77 VTT<1> SCONN288_H44441004_PIP-SCONN,HA   I171 @BASEBOARD_FAB2_LIB.BASEBOARD_FAB2(SCH_1):PAGE77
  J9T1  221 VTT<0> SCONN288_H44441003_PIP-SCONN,HA    I75 @BASEBOARD_FAB2_LIB.BASEBOARD_FAB2(SCH_1):PAGE78
  J9T1   77 VTT<1> SCONN288_H44441003_PIP-SCONN,HA    I75 @BASEBOARD_FAB2_LIB.BASEBOARD_FAB2(SCH_1):PAGE78
  J1G2  221 VTT<0> SCONN288_H44441004_PIP-SCONN,HA   I169 @BASEBOARD_FAB2_LIB.BASEBOARD_FAB2(SCH_1):PAGE79
  J1G2   77 VTT<1> SCONN288_H44441004_PIP-SCONN,HA   I169 @BASEBOARD_FAB2_LIB.BASEBOARD_FAB2(SCH_1):PAGE79
  J9U1  221 VTT<0> SCONN288_H44441003_PIP-SCONN,HA    I56 @BASEBOARD_FAB2_LIB.BASEBOARD_FAB2(SCH_1):PAGE80
  J9U1   77 VTT<1> SCONN288_H44441003_PIP-SCONN,HA    I56 @BASEBOARD_FAB2_LIB.BASEBOARD_FAB2(SCH_1):PAGE80
  J1G3  221 VTT<0> SCONN288_H44441004_PIP-SCONN,HA   I169 @BASEBOARD_FAB2_LIB.BASEBOARD_FAB2(SCH_1):PAGE81
  J1G3   77 VTT<1> SCONN288_H44441004_PIP-SCONN,HA   I169 @BASEBOARD_FAB2_LIB.BASEBOARD_FAB2(SCH_1):PAGE81
  J9U2  221 VTT<0> SCONN288_H44441003_PIP-SCONN,HA   I171 @BASEBOARD_FAB2_LIB.BASEBOARD_FAB2(SCH_1):PAGE82
  J9U2   77 VTT<1> SCONN288_H44441003_PIP-SCONN,HA   I171 @BASEBOARD_FAB2_LIB.BASEBOARD_FAB2(SCH_1):PAGE82
 C4G20    1      A CAP_0805LF-22UF,4V,20%,X6S,C95A    I17 @BASEBOARD_FAB2_LIB.BASEBOARD_FAB2(SCH_1):PAGE229
 EU4G2    9    VTT MIC5166_DFN-IC,H55101-001    I24 @BASEBOARD_FAB2_LIB.BASEBOARD_FAB2(SCH_1):PAGE229
  C2F2    1      A CAP_A_0603V-47UF,4V,20%,X5R,60A    I47 @BASEBOARD_FAB2_LIB.BASEBOARD_FAB2(SCH_1):PAGE229
  C8T3    1      A CAP_A_0603V-47UF,4V,20%,X5R,60A    I48 @BASEBOARD_FAB2_LIB.BASEBOARD_FAB2(SCH_1):PAGE229
 C8U10    1      A CAP_A_0603V-47UF,4V,20%,X5R,60A    I49 @BASEBOARD_FAB2_LIB.BASEBOARD_FAB2(SCH_1):PAGE229
  R6U8    2      B RES_0402-51.1,1.0%,1/16W,CHIP,A    I52 @BASEBOARD_FAB2_LIB.BASEBOARD_FAB2(SCH_1):PAGE229
 SH8U1    2      B SHUNT_SH0201-EMPTY,N_A    I53 @BASEBOARD_FAB2_LIB.BASEBOARD_FAB2(SCH_1):PAGE229

PVTT_KLM @BASEBOARD_FAB2_LIB.BASEBOARD_FAB2(SCH_1):PVTT_KLM
  J1B1  221 VTT<0> SCONN288_H44441004_PIP-SCONN,HA   I167 @BASEBOARD_FAB2_LIB.BASEBOARD_FAB2(SCH_1):PAGE83
  J1B1   77 VTT<1> SCONN288_H44441004_PIP-SCONN,HA   I167 @BASEBOARD_FAB2_LIB.BASEBOARD_FAB2(SCH_1):PAGE83
  J9M1  221 VTT<0> SCONN288_H44441003_PIP-SCONN,HA    I57 @BASEBOARD_FAB2_LIB.BASEBOARD_FAB2(SCH_1):PAGE84
  J9M1   77 VTT<1> SCONN288_H44441003_PIP-SCONN,HA    I57 @BASEBOARD_FAB2_LIB.BASEBOARD_FAB2(SCH_1):PAGE84
  J1A2  221 VTT<0> SCONN288_H44441004_PIP-SCONN,HA   I172 @BASEBOARD_FAB2_LIB.BASEBOARD_FAB2(SCH_1):PAGE85
  J1A2   77 VTT<1> SCONN288_H44441004_PIP-SCONN,HA   I172 @BASEBOARD_FAB2_LIB.BASEBOARD_FAB2(SCH_1):PAGE85
  J9L2  221 VTT<0> SCONN288_H44441003_PIP-SCONN,HA    I55 @BASEBOARD_FAB2_LIB.BASEBOARD_FAB2(SCH_1):PAGE86
  J9L2   77 VTT<1> SCONN288_H44441003_PIP-SCONN,HA    I55 @BASEBOARD_FAB2_LIB.BASEBOARD_FAB2(SCH_1):PAGE86
  J1A1  221 VTT<0> SCONN288_H44441004_PIP-SCONN,HA   I169 @BASEBOARD_FAB2_LIB.BASEBOARD_FAB2(SCH_1):PAGE87
  J1A1   77 VTT<1> SCONN288_H44441004_PIP-SCONN,HA   I169 @BASEBOARD_FAB2_LIB.BASEBOARD_FAB2(SCH_1):PAGE87
  J9L1  221 VTT<0> SCONN288_H44441003_PIP-SCONN,HA   I168 @BASEBOARD_FAB2_LIB.BASEBOARD_FAB2(SCH_1):PAGE88
  J9L1   77 VTT<1> SCONN288_H44441003_PIP-SCONN,HA   I168 @BASEBOARD_FAB2_LIB.BASEBOARD_FAB2(SCH_1):PAGE88
 C4A13    1      A CAP_0805LF-22UF,4V,20%,X6S,C95A    I18 @BASEBOARD_FAB2_LIB.BASEBOARD_FAB2(SCH_1):PAGE230
 EU4A2    9    VTT MIC5166_DFN-IC,H55101-001    I31 @BASEBOARD_FAB2_LIB.BASEBOARD_FAB2(SCH_1):PAGE230
 C8M12    1      A CAP_A_0603V-47UF,4V,20%,X5R,60A    I47 @BASEBOARD_FAB2_LIB.BASEBOARD_FAB2(SCH_1):PAGE230
  C8L3    1      A CAP_A_0603V-47UF,4V,20%,X5R,60A    I48 @BASEBOARD_FAB2_LIB.BASEBOARD_FAB2(SCH_1):PAGE230
  C8L4    1      A CAP_A_0603V-47UF,4V,20%,X5R,60A    I49 @BASEBOARD_FAB2_LIB.BASEBOARD_FAB2(SCH_1):PAGE230
  R6L7    2      B RES_0402-51.1,1.0%,1/16W,CHIP,A    I52 @BASEBOARD_FAB2_LIB.BASEBOARD_FAB2(SCH_1):PAGE230
 SH8L1    2      B SHUNT_SH0201-EMPTY,N_A    I53 @BASEBOARD_FAB2_LIB.BASEBOARD_FAB2(SCH_1):PAGE230

PWRGD_CPU0_DRAMPWROK_ABC_G @BASEBOARD_FAB2_LIB.BASEBOARD_FAB2(SCH_1):PWRGD_CPU0_DRAMPWROK_ABC_G
  U5D1 AN30 DDR012_DRAM_PWR_OK SKX_EXT_B_BGA1-IC,TBD   I259 @BASEBOARD_FAB2_LIB.BASEBOARD_FAB2(SCH_1):PAGE21
 R3P38    2      B RES_0402-64.9,1.0%,1/16W,CHIP,A     I7 @BASEBOARD_FAB2_LIB.BASEBOARD_FAB2(SCH_1):PAGE96
  U3P1    3     B1 GTL2014_SM-IC,D66151-001    I42 @BASEBOARD_FAB2_LIB.BASEBOARD_FAB2(SCH_1):PAGE96

PWRGD_CPU0_DRAMPWROK_DEF_G @BASEBOARD_FAB2_LIB.BASEBOARD_FAB2(SCH_1):PWRGD_CPU0_DRAMPWROK_DEF_G
  U5D1 CR28 DDR345_DRAM_PWR_OK SKX_EXT_B_BGA1-IC,TBD   I259 @BASEBOARD_FAB2_LIB.BASEBOARD_FAB2(SCH_1):PAGE21
 R3P29    2      B RES_0402-64.9,1.0%,1/16W,CHIP,A     I5 @BASEBOARD_FAB2_LIB.BASEBOARD_FAB2(SCH_1):PAGE96
  U3P1    2     B0 GTL2014_SM-IC,D66151-001    I42 @BASEBOARD_FAB2_LIB.BASEBOARD_FAB2(SCH_1):PAGE96

PWRGD_CPU0_G @BASEBOARD_FAB2_LIB.BASEBOARD_FAB2(SCH_1):PWRGD_CPU0_G
  U5D1 BC24 PWRGOOD SKX_EXT_B_BGA1-IC,TBD   I259 @BASEBOARD_FAB2_LIB.BASEBOARD_FAB2(SCH_1):PAGE21
  R6D8    2      B RES_0402-49.9,1%,1/16W,CHIP,G2A     I3 @BASEBOARD_FAB2_LIB.BASEBOARD_FAB2(SCH_1):PAGE96
  U3P1    6     B3 GTL2014_SM-IC,D66151-001    I42 @BASEBOARD_FAB2_LIB.BASEBOARD_FAB2(SCH_1):PAGE96
 R9B14    1      A RES_0402-1.00K,1%,1/16W,CHIP,GA   I168 @BASEBOARD_FAB2_LIB.BASEBOARD_FAB2(SCH_1):PAGE113

PWRGD_CPU0_G_R @BASEBOARD_FAB2_LIB.BASEBOARD_FAB2(SCH_1):PWRGD_CPU0_G_R
 R9B14    2      B RES_0402-1.00K,1%,1/16W,CHIP,GA   I168 @BASEBOARD_FAB2_LIB.BASEBOARD_FAB2(SCH_1):PAGE113
  J9B4    7    IO7 SCONN10_C12536004_SMLF-CONN,C1A   I175 @BASEBOARD_FAB2_LIB.BASEBOARD_FAB2(SCH_1):PAGE113

PWRGD_CPU0_LVC3 @BASEBOARD_FAB2_LIB.BASEBOARD_FAB2(SCH_1):PWRGD_CPU0_LVC3
  U3P1    9     A3 GTL2014_SM-IC,D66151-001    I42 @BASEBOARD_FAB2_LIB.BASEBOARD_FAB2(SCH_1):PAGE96
  U8D7   L5  PL11D LCMXO2_A_256BGA-IC,H63395-001   I179 @BASEBOARD_FAB2_LIB.BASEBOARD_FAB2(SCH_1):PAGE190

PWRGD_CPU1_DRAMPWROK_GHJ_G @BASEBOARD_FAB2_LIB.BASEBOARD_FAB2(SCH_1):PWRGD_CPU1_DRAMPWROK_GHJ_G
  U2D1 AN30 DDR012_DRAM_PWR_OK SKX_EXT_B_BGA1-IC,TBD   I172 @BASEBOARD_FAB2_LIB.BASEBOARD_FAB2(SCH_1):PAGE55
 R3D21    2      B RES_0402-64.9,1.0%,1/16W,CHIP,A    I30 @BASEBOARD_FAB2_LIB.BASEBOARD_FAB2(SCH_1):PAGE96
  U4C2    3     B1 GTL2014_SM-IC,D66151-001    I46 @BASEBOARD_FAB2_LIB.BASEBOARD_FAB2(SCH_1):PAGE96

PWRGD_CPU1_DRAMPWROK_KLM_G @BASEBOARD_FAB2_LIB.BASEBOARD_FAB2(SCH_1):PWRGD_CPU1_DRAMPWROK_KLM_G
  U2D1 CR28 DDR345_DRAM_PWR_OK SKX_EXT_B_BGA1-IC,TBD   I172 @BASEBOARD_FAB2_LIB.BASEBOARD_FAB2(SCH_1):PAGE55
  R7M9    2      B RES_0402-64.9,1.0%,1/16W,CHIP,A    I28 @BASEBOARD_FAB2_LIB.BASEBOARD_FAB2(SCH_1):PAGE96
  U4C2    2     B0 GTL2014_SM-IC,D66151-001    I46 @BASEBOARD_FAB2_LIB.BASEBOARD_FAB2(SCH_1):PAGE96

PWRGD_CPU1_G @BASEBOARD_FAB2_LIB.BASEBOARD_FAB2(SCH_1):PWRGD_CPU1_G
  U2D1 BC24 PWRGOOD SKX_EXT_B_BGA1-IC,TBD   I172 @BASEBOARD_FAB2_LIB.BASEBOARD_FAB2(SCH_1):PAGE55
 R3D15    2      B RES_0402-49.9,1%,1/16W,CHIP,G2A    I26 @BASEBOARD_FAB2_LIB.BASEBOARD_FAB2(SCH_1):PAGE96
  U4C2    6     B3 GTL2014_SM-IC,D66151-001    I46 @BASEBOARD_FAB2_LIB.BASEBOARD_FAB2(SCH_1):PAGE96

PWRGD_CPU1_LVC3 @BASEBOARD_FAB2_LIB.BASEBOARD_FAB2(SCH_1):PWRGD_CPU1_LVC3
  U4C2    9     A3 GTL2014_SM-IC,D66151-001    I46 @BASEBOARD_FAB2_LIB.BASEBOARD_FAB2(SCH_1):PAGE96
  U8D7  M10  PB21C LCMXO2_A_256BGA-IC,H63395-001   I179 @BASEBOARD_FAB2_LIB.BASEBOARD_FAB2(SCH_1):PAGE190

PWRGD_CPUPWRGD @BASEBOARD_FAB2_LIB.BASEBOARD_FAB2(SCH_1):PWRGD_CPUPWRGD
  R3R3    2      B RES_0402-33.2,1%,1/16W,CHIP,G2A    I61 @BASEBOARD_FAB2_LIB.BASEBOARD_FAB2(SCH_1):PAGE92
  U8D7  F13   PR3C LCMXO2_A_256BGA-IC,H63395-001    I59 @BASEBOARD_FAB2_LIB.BASEBOARD_FAB2(SCH_1):PAGE191

PWRGD_CPUPWRGD_GTL @BASEBOARD_FAB2_LIB.BASEBOARD_FAB2(SCH_1):PWRGD_CPUPWRGD_GTL
  U3P2    2     B0 GTL2014_SM-IC,D66151-001     I1 @BASEBOARD_FAB2_LIB.BASEBOARD_FAB2(SCH_1):PAGE92
  U7C1   R9 PROC_PWRGD LBG_CORE_QAT_EXT_D_BGA1-IC,H91A    I73 @BASEBOARD_FAB2_LIB.BASEBOARD_FAB2(SCH_1):PAGE118

PWRGD_CPUPWRGD_R1 @BASEBOARD_FAB2_LIB.BASEBOARD_FAB2(SCH_1):PWRGD_CPUPWRGD_R1
  U3P2   13     A0 GTL2014_SM-IC,D66151-001     I1 @BASEBOARD_FAB2_LIB.BASEBOARD_FAB2(SCH_1):PAGE92
  R3R3    1      A RES_0402-33.2,1%,1/16W,CHIP,G2A    I61 @BASEBOARD_FAB2_LIB.BASEBOARD_FAB2(SCH_1):PAGE92

PWRGD_DRAMPWRGD @BASEBOARD_FAB2_LIB.BASEBOARD_FAB2(SCH_1):PWRGD_DRAMPWRGD
  U3P1   13     A0 GTL2014_SM-IC,D66151-001    I42 @BASEBOARD_FAB2_LIB.BASEBOARD_FAB2(SCH_1):PAGE96
  U3P1   12     A1 GTL2014_SM-IC,D66151-001    I42 @BASEBOARD_FAB2_LIB.BASEBOARD_FAB2(SCH_1):PAGE96
  U4C2   13     A0 GTL2014_SM-IC,D66151-001    I46 @BASEBOARD_FAB2_LIB.BASEBOARD_FAB2(SCH_1):PAGE96
  U4C2   12     A1 GTL2014_SM-IC,D66151-001    I46 @BASEBOARD_FAB2_LIB.BASEBOARD_FAB2(SCH_1):PAGE96
  U8D7  T15  PB25C LCMXO2_A_256BGA-IC,H63395-001   I179 @BASEBOARD_FAB2_LIB.BASEBOARD_FAB2(SCH_1):PAGE190

PWRGD_DSW_PWROK @BASEBOARD_FAB2_LIB.BASEBOARD_FAB2(SCH_1):PWRGD_DSW_PWROK
  U7C1  K13 DSW_PWROK LBG_CORE_QAT_EXT_D_BGA1-IC,H91A    I73 @BASEBOARD_FAB2_LIB.BASEBOARD_FAB2(SCH_1):PAGE118
  U8D2    2      A TTL1G07_A_SOP-74LVC1G07,IC,C88B   I374 @BASEBOARD_FAB2_LIB.BASEBOARD_FAB2(SCH_1):PAGE157
 EU9F3   24 RESET_N PI7C9X1172_QFN-IC,H66899-001     I1 @BASEBOARD_FAB2_LIB.BASEBOARD_FAB2(SCH_1):PAGE183
  U8D7  B11  PT22A LCMXO2_A_256BGA-IC,H63395-001    I59 @BASEBOARD_FAB2_LIB.BASEBOARD_FAB2(SCH_1):PAGE191
 R3P44    2      B RES_0402-4.75K,1%,1/16W,CHIP,GA    I59 @BASEBOARD_FAB2_LIB.BASEBOARD_FAB2(SCH_1):PAGE196
  U7D3    4  ENOUT ADM1085_SMT-IC,H46130-001    I70 @BASEBOARD_FAB2_LIB.BASEBOARD_FAB2(SCH_1):PAGE196
 CR7E1    2      A DIODE_SMLF-BAT54WS,IC,C73510-0A   I103 @BASEBOARD_FAB2_LIB.BASEBOARD_FAB2(SCH_1):PAGE196
  U9P2    6   OUTA TPS3700_SM-IC,H69492-001   I200 @BASEBOARD_FAB2_LIB.BASEBOARD_FAB2(SCH_1):PAGE200

PWRGD_P12V_HSC @BASEBOARD_FAB2_LIB.BASEBOARD_FAB2(SCH_1):PWRGD_P12V_HSC
  U8E2    3    VCC ADM809_SMLF-IC,D23047-001-GND=A    I89 @BASEBOARD_FAB2_LIB.BASEBOARD_FAB2(SCH_1):PAGE196
  C8E3    1      A CAP_A_0402V-0.1UF,16V,10%,X7R,A    I94 @BASEBOARD_FAB2_LIB.BASEBOARD_FAB2(SCH_1):PAGE196
 CR8E1    1      C DIODE_SMLF-BAT54WS,IC,C73510-0A   I128 @BASEBOARD_FAB2_LIB.BASEBOARD_FAB2(SCH_1):PAGE196
 R1D33    2      B RES_0402-33.2,1%,1/16W,CHIP,G2A   I108 @BASEBOARD_FAB2_LIB.BASEBOARD_FAB2(SCH_1):PAGE199

PWRGD_P12V_HSC_DLY @BASEBOARD_FAB2_LIB.BASEBOARD_FAB2(SCH_1):PWRGD_P12V_HSC_DLY
  U8E1   10   B<0> TTL08_QFN15-74LVC08A,IC,D90404B   I243 @BASEBOARD_FAB2_LIB.BASEBOARD_FAB2(SCH_1):PAGE181
  R8E7    2      B RES_0402-22.1,1.0%,1/16W,CHIP,A    I90 @BASEBOARD_FAB2_LIB.BASEBOARD_FAB2(SCH_1):PAGE196
 CR8E1    2      A DIODE_SMLF-BAT54WS,IC,C73510-0A   I128 @BASEBOARD_FAB2_LIB.BASEBOARD_FAB2(SCH_1):PAGE196
 C8E13    1      A CAP_0402LF-1000PF,50V,10%,EMPTA    I41 @BASEBOARD_FAB2_LIB.BASEBOARD_FAB2(SCH_1):PAGE241
 R8E33    1      A RES_0402-0.0,5%,1/16W,CHIP,G21A    I91 @BASEBOARD_FAB2_LIB.BASEBOARD_FAB2(SCH_1):PAGE241

PWRGD_P12V_HSC_DLY_R @BASEBOARD_FAB2_LIB.BASEBOARD_FAB2(SCH_1):PWRGD_P12V_HSC_DLY_R
  U8E2    2 RESET_N ADM809_SMLF-IC,D23047-001-GND=A    I89 @BASEBOARD_FAB2_LIB.BASEBOARD_FAB2(SCH_1):PAGE196
  R8E7    1      A RES_0402-22.1,1.0%,1/16W,CHIP,A    I90 @BASEBOARD_FAB2_LIB.BASEBOARD_FAB2(SCH_1):PAGE196

PWRGD_P12V_MAIN @BASEBOARD_FAB2_LIB.BASEBOARD_FAB2(SCH_1):PWRGD_P12V_MAIN
  U8D7   B5   PT9B LCMXO2_A_256BGA-IC,H63395-001    I59 @BASEBOARD_FAB2_LIB.BASEBOARD_FAB2(SCH_1):PAGE191
 R8D42    2      B RES_0402-100.0,1%,1/16W,CHIP,GA   I106 @BASEBOARD_FAB2_LIB.BASEBOARD_FAB2(SCH_1):PAGE196

PWRGD_P12V_MAIN_R @BASEBOARD_FAB2_LIB.BASEBOARD_FAB2(SCH_1):PWRGD_P12V_MAIN_R
  U8D8    6   OUTA TPS3700_SM-IC,H69492-001   I104 @BASEBOARD_FAB2_LIB.BASEBOARD_FAB2(SCH_1):PAGE196
 R8D42    1      A RES_0402-100.0,1%,1/16W,CHIP,GA   I106 @BASEBOARD_FAB2_LIB.BASEBOARD_FAB2(SCH_1):PAGE196
 R8D41    2      B RES_0402-10.0K,1%,1/16W,CHIP,GA   I120 @BASEBOARD_FAB2_LIB.BASEBOARD_FAB2(SCH_1):PAGE196

PWRGD_P12V_R @BASEBOARD_FAB2_LIB.BASEBOARD_FAB2(SCH_1):PWRGD_P12V_R
 EU1D2   18  PWRGD ADM1278_SM-IC,G99251-001    I10 @BASEBOARD_FAB2_LIB.BASEBOARD_FAB2(SCH_1):PAGE199
 R9P18    2      B RES_0402-15.0K,1%,1/16W,CHIP,GA    I41 @BASEBOARD_FAB2_LIB.BASEBOARD_FAB2(SCH_1):PAGE199
 R1D31    1      A RES_0402-6.19K,1%,1/16W,CHIP,GA    I43 @BASEBOARD_FAB2_LIB.BASEBOARD_FAB2(SCH_1):PAGE199
 R1D33    1      A RES_0402-33.2,1%,1/16W,CHIP,G2A   I108 @BASEBOARD_FAB2_LIB.BASEBOARD_FAB2(SCH_1):PAGE199

PWRGD_P1V26_BMC_STBY @BASEBOARD_FAB2_LIB.BASEBOARD_FAB2(SCH_1):PWRGD_P1V26_BMC_STBY
  U8D7   E7  PT12B LCMXO2_A_256BGA-IC,H63395-001    I59 @BASEBOARD_FAB2_LIB.BASEBOARD_FAB2(SCH_1):PAGE191
 R9F11    2      B RES_0402-22.1,1.0%,1/16W,CHIP,A    I41 @BASEBOARD_FAB2_LIB.BASEBOARD_FAB2(SCH_1):PAGE238

PWRGD_P1V26_BMC_STBY_R @BASEBOARD_FAB2_LIB.BASEBOARD_FAB2(SCH_1):PWRGD_P1V26_BMC_STBY_R
  C9F8    1      A CAP_0402LF-1000PF,50V,10%,X7R,A    I19 @BASEBOARD_FAB2_LIB.BASEBOARD_FAB2(SCH_1):PAGE238
 R9F13    2      B RES_0402-10.0K,1%,1/16W,CHIP,GA    I21 @BASEBOARD_FAB2_LIB.BASEBOARD_FAB2(SCH_1):PAGE238
 EU9F1    5  PGOOD RT9059_DFN-IC,H65765-001    I40 @BASEBOARD_FAB2_LIB.BASEBOARD_FAB2(SCH_1):PAGE238
 R9F11    1      A RES_0402-22.1,1.0%,1/16W,CHIP,A    I41 @BASEBOARD_FAB2_LIB.BASEBOARD_FAB2(SCH_1):PAGE238

PWRGD_P1V538_BMC_STBY @BASEBOARD_FAB2_LIB.BASEBOARD_FAB2(SCH_1):PWRGD_P1V538_BMC_STBY
  C9F9    1      A CAP_0402LF-1000PF,50V,10%,EMPTA     I5 @BASEBOARD_FAB2_LIB.BASEBOARD_FAB2(SCH_1):PAGE238
 EU9F1    6     EN RT9059_DFN-IC,H65765-001    I40 @BASEBOARD_FAB2_LIB.BASEBOARD_FAB2(SCH_1):PAGE238
  R1T9    2      B RES_0402-22.1,1.0%,1/16W,CHIP,A    I72 @BASEBOARD_FAB2_LIB.BASEBOARD_FAB2(SCH_1):PAGE239

PWRGD_P1V538_BMC_STBY_R @BASEBOARD_FAB2_LIB.BASEBOARD_FAB2(SCH_1):PWRGD_P1V538_BMC_STBY_R
 C9F10    1      A CAP_0402LF-1000PF,50V,10%,X7R,A     I4 @BASEBOARD_FAB2_LIB.BASEBOARD_FAB2(SCH_1):PAGE239
 R9F12    2      B RES_0402-10.0K,1%,1/16W,CHIP,GA     I6 @BASEBOARD_FAB2_LIB.BASEBOARD_FAB2(SCH_1):PAGE239
 EU9F2    5  PGOOD RT9059_DFN-IC,H65765-001    I70 @BASEBOARD_FAB2_LIB.BASEBOARD_FAB2(SCH_1):PAGE239
  R1T9    1      A RES_0402-22.1,1.0%,1/16W,CHIP,A    I72 @BASEBOARD_FAB2_LIB.BASEBOARD_FAB2(SCH_1):PAGE239

PWRGD_P1V8MCP_CPU0 @BASEBOARD_FAB2_LIB.BASEBOARD_FAB2(SCH_1):PWRGD_P1V8MCP_CPU0
  U8D7  D15   PR2D LCMXO2_A_256BGA-IC,H63395-001    I59 @BASEBOARD_FAB2_LIB.BASEBOARD_FAB2(SCH_1):PAGE191
  J6B1  B15  IOB15 SCONN120_H61426002_SM-CONN,H61A    I56 @BASEBOARD_FAB2_LIB.BASEBOARD_FAB2(SCH_1):PAGE194

PWRGD_P1V8MCP_CPU1 @BASEBOARD_FAB2_LIB.BASEBOARD_FAB2(SCH_1):PWRGD_P1V8MCP_CPU1
  U8D7  D16   PR2A LCMXO2_A_256BGA-IC,H63395-001    I59 @BASEBOARD_FAB2_LIB.BASEBOARD_FAB2(SCH_1):PAGE191
  J4B2  B15  IOB15 SCONN120_H61426002_SM-CONN,H61A    I46 @BASEBOARD_FAB2_LIB.BASEBOARD_FAB2(SCH_1):PAGE193

PWRGD_P1V8_PCH_STBY @BASEBOARD_FAB2_LIB.BASEBOARD_FAB2(SCH_1):PWRGD_P1V8_PCH_STBY
 R2L17    1      A RES_0402-0.0,5%,1/16W,CHIP,G21A   I221 @BASEBOARD_FAB2_LIB.BASEBOARD_FAB2(SCH_1):PAGE235
 R8A11    2      B RES_0402-22.1,1.0%,1/16W,CHIP,A    I90 @BASEBOARD_FAB2_LIB.BASEBOARD_FAB2(SCH_1):PAGE237

PWRGD_P1V8_PCH_STBY_R @BASEBOARD_FAB2_LIB.BASEBOARD_FAB2(SCH_1):PWRGD_P1V8_PCH_STBY_R
 R8A10    2      B RES_0402-5.11K,1%,1/16W,CHIP,GA     I3 @BASEBOARD_FAB2_LIB.BASEBOARD_FAB2(SCH_1):PAGE237
 C8A11    1      A CAP_0402LF-1000PF,50V,10%,X7R,A     I5 @BASEBOARD_FAB2_LIB.BASEBOARD_FAB2(SCH_1):PAGE237
 EU8A2    5  PGOOD RT9059_DFN-IC,H65765-001    I86 @BASEBOARD_FAB2_LIB.BASEBOARD_FAB2(SCH_1):PAGE237
 R8A11    1      A RES_0402-22.1,1.0%,1/16W,CHIP,A    I90 @BASEBOARD_FAB2_LIB.BASEBOARD_FAB2(SCH_1):PAGE237

PWRGD_P3V3 @BASEBOARD_FAB2_LIB.BASEBOARD_FAB2(SCH_1):PWRGD_P3V3
 R1L12    1      A RES_0402-0.0,5%,1/16W,CHIP,G21A    I63 @BASEBOARD_FAB2_LIB.BASEBOARD_FAB2(SCH_1):PAGE175
  U8D7   H6   PL5D LCMXO2_A_256BGA-IC,H63395-001   I179 @BASEBOARD_FAB2_LIB.BASEBOARD_FAB2(SCH_1):PAGE190
 R1L16    2      B RES_0402-49.9,1%,1/16W,CHIP,G2A    I68 @BASEBOARD_FAB2_LIB.BASEBOARD_FAB2(SCH_1):PAGE196

PWRGD_P3V3_R @BASEBOARD_FAB2_LIB.BASEBOARD_FAB2(SCH_1):PWRGD_P3V3_R
  U1L2    1      A TTL1G86_SOTLF-74AHCT1G86,IC,D3B    I57 @BASEBOARD_FAB2_LIB.BASEBOARD_FAB2(SCH_1):PAGE175
 R1L12    2      B RES_0402-0.0,5%,1/16W,CHIP,G21A    I63 @BASEBOARD_FAB2_LIB.BASEBOARD_FAB2(SCH_1):PAGE175

PWRGD_P3V3_R1 @BASEBOARD_FAB2_LIB.BASEBOARD_FAB2(SCH_1):PWRGD_P3V3_R1
 R1L16    1      A RES_0402-49.9,1%,1/16W,CHIP,G2A    I68 @BASEBOARD_FAB2_LIB.BASEBOARD_FAB2(SCH_1):PAGE196
  U1L3    2 RESET_N ADM809_SMLF-IC,D23047-001-GND=A    I80 @BASEBOARD_FAB2_LIB.BASEBOARD_FAB2(SCH_1):PAGE196

PWRGD_P3V3_STBY @BASEBOARD_FAB2_LIB.BASEBOARD_FAB2(SCH_1):PWRGD_P3V3_STBY
 EU8F2   40 VTTPWR_GD_PD_N ICS9FGP204_MLFP-IC,E95226-001    I34 @BASEBOARD_FAB2_LIB.BASEBOARD_FAB2(SCH_1):PAGE101
  J7G2    5    IO5 CONN8_C77962004_PIP-CONN,C7796A    I47 @BASEBOARD_FAB2_LIB.BASEBOARD_FAB2(SCH_1):PAGE189
  U8D7  L12  PR10D LCMXO2_A_256BGA-IC,H63395-001    I59 @BASEBOARD_FAB2_LIB.BASEBOARD_FAB2(SCH_1):PAGE191
  U7D3    1   ENIN ADM1085_SMT-IC,H46130-001    I70 @BASEBOARD_FAB2_LIB.BASEBOARD_FAB2(SCH_1):PAGE196
 R3P50    2      B RES_0402-10.0K,1%,1/16W,EMPTY,A    I71 @BASEBOARD_FAB2_LIB.BASEBOARD_FAB2(SCH_1):PAGE196
 CR7E1    1      C DIODE_SMLF-BAT54WS,IC,C73510-0A   I103 @BASEBOARD_FAB2_LIB.BASEBOARD_FAB2(SCH_1):PAGE196
 C8A10    1      A CAP_0402LF-1000PF,50V,10%,EMPTA    I55 @BASEBOARD_FAB2_LIB.BASEBOARD_FAB2(SCH_1):PAGE237
 EU8A2    6     EN RT9059_DFN-IC,H65765-001    I86 @BASEBOARD_FAB2_LIB.BASEBOARD_FAB2(SCH_1):PAGE237
  C9F6    1      A CAP_0402LF-1000PF,50V,10%,EMPTA    I30 @BASEBOARD_FAB2_LIB.BASEBOARD_FAB2(SCH_1):PAGE239
 EU9F2    6     EN RT9059_DFN-IC,H65765-001    I70 @BASEBOARD_FAB2_LIB.BASEBOARD_FAB2(SCH_1):PAGE239
 R8F10    2      B RES_0402-22.1,1.0%,1/16W,CHIP,A   I171 @BASEBOARD_FAB2_LIB.BASEBOARD_FAB2(SCH_1):PAGE240

PWRGD_P3V3_STBY_R @BASEBOARD_FAB2_LIB.BASEBOARD_FAB2(SCH_1):PWRGD_P3V3_STBY_R
  C8F2    1      A CAP_0402LF-1000PF,50V,10%,X7R,A   I116 @BASEBOARD_FAB2_LIB.BASEBOARD_FAB2(SCH_1):PAGE240
  R8F5    2      B RES_0402-1.00K,1%,1/16W,CHIP,GA   I117 @BASEBOARD_FAB2_LIB.BASEBOARD_FAB2(SCH_1):PAGE240
 EU8F1    9  PGOOD RT8240_QFN-IC,H66262-001   I125 @BASEBOARD_FAB2_LIB.BASEBOARD_FAB2(SCH_1):PAGE240
 R8F10    1      A RES_0402-22.1,1.0%,1/16W,CHIP,A   I171 @BASEBOARD_FAB2_LIB.BASEBOARD_FAB2(SCH_1):PAGE240

PWRGD_P5V @BASEBOARD_FAB2_LIB.BASEBOARD_FAB2(SCH_1):PWRGD_P5V
  U8D7   J6   PL6D LCMXO2_A_256BGA-IC,H63395-001   I179 @BASEBOARD_FAB2_LIB.BASEBOARD_FAB2(SCH_1):PAGE190
 R2P20    2      B RES_0402-100.0,1%,1/16W,CHIP,GA    I65 @BASEBOARD_FAB2_LIB.BASEBOARD_FAB2(SCH_1):PAGE196

PWRGD_P5V_N @BASEBOARD_FAB2_LIB.BASEBOARD_FAB2(SCH_1):PWRGD_P5V_N
  U8D8    1   OUTB TPS3700_SM-IC,H69492-001   I104 @BASEBOARD_FAB2_LIB.BASEBOARD_FAB2(SCH_1):PAGE196
 R2P18    2      B RES_0402-10.0K,1%,1/16W,CHIP,GA   I121 @BASEBOARD_FAB2_LIB.BASEBOARD_FAB2(SCH_1):PAGE196
  Q2P2    1   GATE FET_N_SOT23-2N7002,FET,C79254-A   I124 @BASEBOARD_FAB2_LIB.BASEBOARD_FAB2(SCH_1):PAGE196

PWRGD_P5V_R @BASEBOARD_FAB2_LIB.BASEBOARD_FAB2(SCH_1):PWRGD_P5V_R
 R2P20    1      A RES_0402-100.0,1%,1/16W,CHIP,GA    I65 @BASEBOARD_FAB2_LIB.BASEBOARD_FAB2(SCH_1):PAGE196
 R2P21    2      B RES_0402-10.0K,1%,1/16W,CHIP,GA   I122 @BASEBOARD_FAB2_LIB.BASEBOARD_FAB2(SCH_1):PAGE196
  Q2P2    3    DRN FET_N_SOT23-2N7002,FET,C79254-A   I124 @BASEBOARD_FAB2_LIB.BASEBOARD_FAB2(SCH_1):PAGE196

PWRGD_P5V_STBY @BASEBOARD_FAB2_LIB.BASEBOARD_FAB2(SCH_1):PWRGD_P5V_STBY
  R8F1    1      A RES_0402-10.0K,1%,1/16W,EMPTY,A   I111 @BASEBOARD_FAB2_LIB.BASEBOARD_FAB2(SCH_1):PAGE240
 C8E17    1      A CAP_0402LF-1000PF,50V,10%,EMPTA   I113 @BASEBOARD_FAB2_LIB.BASEBOARD_FAB2(SCH_1):PAGE240
  R8F2    1      A RES_0402-0.0,5%,1/16W,CHIP,G21A   I176 @BASEBOARD_FAB2_LIB.BASEBOARD_FAB2(SCH_1):PAGE240
 R7E15    2      B RES_0402-22.1,1.0%,1/16W,CHIP,A    I89 @BASEBOARD_FAB2_LIB.BASEBOARD_FAB2(SCH_1):PAGE241

PWRGD_P5V_STBY_R @BASEBOARD_FAB2_LIB.BASEBOARD_FAB2(SCH_1):PWRGD_P5V_STBY_R
 R7E12    2      B RES_0402-1.00K,1%,1/16W,CHIP,GA    I11 @BASEBOARD_FAB2_LIB.BASEBOARD_FAB2(SCH_1):PAGE241
 C7E10    1      A CAP_0402LF-1000PF,50V,10%,X7R,A    I14 @BASEBOARD_FAB2_LIB.BASEBOARD_FAB2(SCH_1):PAGE241
 EU7E2   14  PWRGD TPS54821_LCC-IC,H63269-001    I83 @BASEBOARD_FAB2_LIB.BASEBOARD_FAB2(SCH_1):PAGE241
 R7E15    1      A RES_0402-22.1,1.0%,1/16W,CHIP,A    I89 @BASEBOARD_FAB2_LIB.BASEBOARD_FAB2(SCH_1):PAGE241

PWRGD_PCH_PWROK @BASEBOARD_FAB2_LIB.BASEBOARD_FAB2(SCH_1):PWRGD_PCH_PWROK
  U7C1  R17 PCH_PWROK LBG_CORE_QAT_EXT_D_BGA1-IC,H91A    I73 @BASEBOARD_FAB2_LIB.BASEBOARD_FAB2(SCH_1):PAGE118
  R3N3    2      B RES_0402-2.0K,1%,1/16W,CHIP,G2A   I120 @BASEBOARD_FAB2_LIB.BASEBOARD_FAB2(SCH_1):PAGE133
  U8D7  C16   PR2C LCMXO2_A_256BGA-IC,H63395-001    I59 @BASEBOARD_FAB2_LIB.BASEBOARD_FAB2(SCH_1):PAGE191
 U25W4  K19 GPIOB0 AST2520A1-GP-GP_ASIC2-GB1-AST2A    I95 @BASEBOARD_FAB2_LIB.BASEBOARD_FAB2(SCH_1):PAGE144

PWRGD_PVCCIN_CPU0 @BASEBOARD_FAB2_LIB.BASEBOARD_FAB2(SCH_1):PWRGD_PVCCIN_CPU0
  U1L1   13  OE<0> TTL3126_QFNLF-74CBTLV3126,IC,DB   I108 @BASEBOARD_FAB2_LIB.BASEBOARD_FAB2(SCH_1):PAGE112
  U1L1   10  OE<1> TTL3126_QFNLF-74CBTLV3126,IC,DB   I108 @BASEBOARD_FAB2_LIB.BASEBOARD_FAB2(SCH_1):PAGE112
  U1L1    4  OE<2> TTL3126_QFNLF-74CBTLV3126,IC,DB   I108 @BASEBOARD_FAB2_LIB.BASEBOARD_FAB2(SCH_1):PAGE112
  U1L1    1  OE<3> TTL3126_QFNLF-74CBTLV3126,IC,DB   I108 @BASEBOARD_FAB2_LIB.BASEBOARD_FAB2(SCH_1):PAGE112
  U1L5   13  OE<0> TTL3126_QFNLF-74CBTLV3126,IC,DB   I109 @BASEBOARD_FAB2_LIB.BASEBOARD_FAB2(SCH_1):PAGE112
  U1L5   10  OE<1> TTL3126_QFNLF-74CBTLV3126,IC,DB   I109 @BASEBOARD_FAB2_LIB.BASEBOARD_FAB2(SCH_1):PAGE112
  U1L5    4  OE<2> TTL3126_QFNLF-74CBTLV3126,IC,DB   I109 @BASEBOARD_FAB2_LIB.BASEBOARD_FAB2(SCH_1):PAGE112
  U1L5    1  OE<3> TTL3126_QFNLF-74CBTLV3126,IC,DB   I109 @BASEBOARD_FAB2_LIB.BASEBOARD_FAB2(SCH_1):PAGE112
  U8D7   K5  PL12C LCMXO2_A_256BGA-IC,H63395-001   I179 @BASEBOARD_FAB2_LIB.BASEBOARD_FAB2(SCH_1):PAGE190
 R4D63    2      B RES_0402-22.1,1.0%,1/16W,CHIP,A   I124 @BASEBOARD_FAB2_LIB.BASEBOARD_FAB2(SCH_1):PAGE201

PWRGD_PVCCIN_CPU1 @BASEBOARD_FAB2_LIB.BASEBOARD_FAB2(SCH_1):PWRGD_PVCCIN_CPU1
  U8D7   N1  PL13B LCMXO2_A_256BGA-IC,H63395-001   I179 @BASEBOARD_FAB2_LIB.BASEBOARD_FAB2(SCH_1):PAGE190
 R1C30    2      B RES_0402-22.1,1.0%,1/16W,CHIP,A   I113 @BASEBOARD_FAB2_LIB.BASEBOARD_FAB2(SCH_1):PAGE206

PWRGD_PVCCIOMCP_CPU0 @BASEBOARD_FAB2_LIB.BASEBOARD_FAB2(SCH_1):PWRGD_PVCCIOMCP_CPU0
  U8D7   N6   PB8C LCMXO2_A_256BGA-IC,H63395-001   I179 @BASEBOARD_FAB2_LIB.BASEBOARD_FAB2(SCH_1):PAGE190
  J6B1  B16  IOB16 SCONN120_H61426002_SM-CONN,H61A    I56 @BASEBOARD_FAB2_LIB.BASEBOARD_FAB2(SCH_1):PAGE194

PWRGD_PVCCIOMCP_CPU1 @BASEBOARD_FAB2_LIB.BASEBOARD_FAB2(SCH_1):PWRGD_PVCCIOMCP_CPU1
  U8D7   T5   PB6A LCMXO2_A_256BGA-IC,H63395-001   I179 @BASEBOARD_FAB2_LIB.BASEBOARD_FAB2(SCH_1):PAGE190
  J4B2  B16  IOB16 SCONN120_H61426002_SM-CONN,H61A    I46 @BASEBOARD_FAB2_LIB.BASEBOARD_FAB2(SCH_1):PAGE193

PWRGD_PVCCIO_CPU0 @BASEBOARD_FAB2_LIB.BASEBOARD_FAB2(SCH_1):PWRGD_PVCCIO_CPU0
  U7D1    1   OE_N 74CBTLV1G125_SMLF-IC,C88177-00A   I142 @BASEBOARD_FAB2_LIB.BASEBOARD_FAB2(SCH_1):PAGE118
  U8D7   L8  PB11D LCMXO2_A_256BGA-IC,H63395-001   I179 @BASEBOARD_FAB2_LIB.BASEBOARD_FAB2(SCH_1):PAGE190
 R3P20    2      B RES_0402-22.1,1.0%,1/16W,CHIP,A    I58 @BASEBOARD_FAB2_LIB.BASEBOARD_FAB2(SCH_1):PAGE211

PWRGD_PVCCIO_CPU0_R @BASEBOARD_FAB2_LIB.BASEBOARD_FAB2(SCH_1):PWRGD_PVCCIO_CPU0_R
 R3P25    2      B RES_0402-1.00K,1%,1/16W,CHIP,GA    I56 @BASEBOARD_FAB2_LIB.BASEBOARD_FAB2(SCH_1):PAGE211
 R3P20    1      A RES_0402-22.1,1.0%,1/16W,CHIP,A    I58 @BASEBOARD_FAB2_LIB.BASEBOARD_FAB2(SCH_1):PAGE211
  C3P6    1      A CAP_0402LF-1000PF,50V,10%,X7R,A    I71 @BASEBOARD_FAB2_LIB.BASEBOARD_FAB2(SCH_1):PAGE211
 EU3P1    9 AVRRDY PXE1110B_QFN-IC,H89187-001    I93 @BASEBOARD_FAB2_LIB.BASEBOARD_FAB2(SCH_1):PAGE211

PWRGD_PVCCIO_CPU1 @BASEBOARD_FAB2_LIB.BASEBOARD_FAB2(SCH_1):PWRGD_PVCCIO_CPU1
  U8D7  L16  PR11A LCMXO2_A_256BGA-IC,H63395-001    I59 @BASEBOARD_FAB2_LIB.BASEBOARD_FAB2(SCH_1):PAGE191
 R4D46    2      B RES_0402-22.1,1.0%,1/16W,CHIP,A    I13 @BASEBOARD_FAB2_LIB.BASEBOARD_FAB2(SCH_1):PAGE213

PWRGD_PVCCIO_CPU1_R @BASEBOARD_FAB2_LIB.BASEBOARD_FAB2(SCH_1):PWRGD_PVCCIO_CPU1_R
 R4D46    1      A RES_0402-22.1,1.0%,1/16W,CHIP,A    I13 @BASEBOARD_FAB2_LIB.BASEBOARD_FAB2(SCH_1):PAGE213
 R4D42    2      B RES_0402-1.00K,1%,1/16W,CHIP,GA    I15 @BASEBOARD_FAB2_LIB.BASEBOARD_FAB2(SCH_1):PAGE213
 C4D33    1      A CAP_0402LF-1000PF,50V,10%,X7R,A    I73 @BASEBOARD_FAB2_LIB.BASEBOARD_FAB2(SCH_1):PAGE213
 EU4D5    9 AVRRDY PXE1110B_QFN-IC,H89187-001    I96 @BASEBOARD_FAB2_LIB.BASEBOARD_FAB2(SCH_1):PAGE213

PWRGD_PVCCMCP_CPU0 @BASEBOARD_FAB2_LIB.BASEBOARD_FAB2(SCH_1):PWRGD_PVCCMCP_CPU0
  U8D7   P5   PB5B LCMXO2_A_256BGA-IC,H63395-001   I179 @BASEBOARD_FAB2_LIB.BASEBOARD_FAB2(SCH_1):PAGE190
  J6B1  D20  IOD20 SCONN120_H61426002_SM-CONN,H61A    I56 @BASEBOARD_FAB2_LIB.BASEBOARD_FAB2(SCH_1):PAGE194

PWRGD_PVCCMCP_CPU1 @BASEBOARD_FAB2_LIB.BASEBOARD_FAB2(SCH_1):PWRGD_PVCCMCP_CPU1
  U8D7   L4  PL12D LCMXO2_A_256BGA-IC,H63395-001   I179 @BASEBOARD_FAB2_LIB.BASEBOARD_FAB2(SCH_1):PAGE190
  J4B2  D20  IOD20 SCONN120_H61426002_SM-CONN,H61A    I46 @BASEBOARD_FAB2_LIB.BASEBOARD_FAB2(SCH_1):PAGE193

PWRGD_PVDDQ_ABC @BASEBOARD_FAB2_LIB.BASEBOARD_FAB2(SCH_1):PWRGD_PVDDQ_ABC
 R7F24    2      B RES_0402-22.1,1.0%,1/16W,CHIP,A   I296 @BASEBOARD_FAB2_LIB.BASEBOARD_FAB2(SCH_1):PAGE215
 R4G23    1      A RES_0402-0.0,5%,1/16W,CHIP,G21A    I38 @BASEBOARD_FAB2_LIB.BASEBOARD_FAB2(SCH_1):PAGE221

PWRGD_PVDDQ_ABC_R @BASEBOARD_FAB2_LIB.BASEBOARD_FAB2(SCH_1):PWRGD_PVDDQ_ABC_R
 R7F24    1      A RES_0402-22.1,1.0%,1/16W,CHIP,A   I296 @BASEBOARD_FAB2_LIB.BASEBOARD_FAB2(SCH_1):PAGE215
 R7F22    2      B RES_0402-1.00K,1%,1/16W,CHIP,GA   I301 @BASEBOARD_FAB2_LIB.BASEBOARD_FAB2(SCH_1):PAGE215
 C7F14    1      A CAP_0402LF-1000PF,50V,10%,X7R,A   I305 @BASEBOARD_FAB2_LIB.BASEBOARD_FAB2(SCH_1):PAGE215
 EU7G1    9 AVRRDY PXM1310B_QFN-IC,H89186-001   I358 @BASEBOARD_FAB2_LIB.BASEBOARD_FAB2(SCH_1):PAGE215

PWRGD_PVDDQ_DEF @BASEBOARD_FAB2_LIB.BASEBOARD_FAB2(SCH_1):PWRGD_PVDDQ_DEF
  R3M3    2      B RES_0402-22.1,1.0%,1/16W,CHIP,A    I11 @BASEBOARD_FAB2_LIB.BASEBOARD_FAB2(SCH_1):PAGE218
  R4A2    1      A RES_0402-0.0,5%,1/16W,CHIP,G21A    I38 @BASEBOARD_FAB2_LIB.BASEBOARD_FAB2(SCH_1):PAGE222

PWRGD_PVDDQ_DEF_R @BASEBOARD_FAB2_LIB.BASEBOARD_FAB2(SCH_1):PWRGD_PVDDQ_DEF_R
  R3M3    1      A RES_0402-22.1,1.0%,1/16W,CHIP,A    I11 @BASEBOARD_FAB2_LIB.BASEBOARD_FAB2(SCH_1):PAGE218
  R7B5    2      B RES_0402-1.00K,1%,1/16W,CHIP,GA    I16 @BASEBOARD_FAB2_LIB.BASEBOARD_FAB2(SCH_1):PAGE218
  C7B3    1      A CAP_0402LF-1000PF,50V,10%,X7R,A    I26 @BASEBOARD_FAB2_LIB.BASEBOARD_FAB2(SCH_1):PAGE218
 EU7A5    9 AVRRDY PXM1310B_QFN-IC,H89186-001    I75 @BASEBOARD_FAB2_LIB.BASEBOARD_FAB2(SCH_1):PAGE218

PWRGD_PVDDQ_GHJ @BASEBOARD_FAB2_LIB.BASEBOARD_FAB2(SCH_1):PWRGD_PVDDQ_GHJ
 R1G12    2      B RES_0402-22.1,1.0%,1/16W,CHIP,A    I14 @BASEBOARD_FAB2_LIB.BASEBOARD_FAB2(SCH_1):PAGE223
 R4G16    1      A RES_0402-0.0,5%,1/16W,CHIP,G21A    I35 @BASEBOARD_FAB2_LIB.BASEBOARD_FAB2(SCH_1):PAGE229

PWRGD_PVDDQ_GHJ_R @BASEBOARD_FAB2_LIB.BASEBOARD_FAB2(SCH_1):PWRGD_PVDDQ_GHJ_R
 R1G12    1      A RES_0402-22.1,1.0%,1/16W,CHIP,A    I14 @BASEBOARD_FAB2_LIB.BASEBOARD_FAB2(SCH_1):PAGE223
 R1G16    2      B RES_0402-1.00K,1%,1/16W,CHIP,GA    I17 @BASEBOARD_FAB2_LIB.BASEBOARD_FAB2(SCH_1):PAGE223
 C1G21    1      A CAP_0402LF-1000PF,50V,10%,X7R,A    I80 @BASEBOARD_FAB2_LIB.BASEBOARD_FAB2(SCH_1):PAGE223
 EU1G2    9 AVRRDY PXM1310B_QFN-IC,H89186-001    I90 @BASEBOARD_FAB2_LIB.BASEBOARD_FAB2(SCH_1):PAGE223

PWRGD_PVDDQ_KLM @BASEBOARD_FAB2_LIB.BASEBOARD_FAB2(SCH_1):PWRGD_PVDDQ_KLM
  R1B5    2      B RES_0402-22.1,1.0%,1/16W,CHIP,A    I14 @BASEBOARD_FAB2_LIB.BASEBOARD_FAB2(SCH_1):PAGE226
  R4A3    1      A RES_0402-0.0,5%,1/16W,CHIP,G21A    I38 @BASEBOARD_FAB2_LIB.BASEBOARD_FAB2(SCH_1):PAGE230

PWRGD_PVDDQ_KLM_R @BASEBOARD_FAB2_LIB.BASEBOARD_FAB2(SCH_1):PWRGD_PVDDQ_KLM_R
  R1B5    1      A RES_0402-22.1,1.0%,1/16W,CHIP,A    I14 @BASEBOARD_FAB2_LIB.BASEBOARD_FAB2(SCH_1):PAGE226
  R1B2    2      B RES_0402-1.00K,1%,1/16W,CHIP,GA    I17 @BASEBOARD_FAB2_LIB.BASEBOARD_FAB2(SCH_1):PAGE226
  C1B4    1      A CAP_0402LF-1000PF,50V,10%,X7R,A    I80 @BASEBOARD_FAB2_LIB.BASEBOARD_FAB2(SCH_1):PAGE226
 EU1B1    9 AVRRDY PXM1310B_QFN-IC,H89186-001    I90 @BASEBOARD_FAB2_LIB.BASEBOARD_FAB2(SCH_1):PAGE226

PWRGD_PVNN_P1V05_PCH @BASEBOARD_FAB2_LIB.BASEBOARD_FAB2(SCH_1):PWRGD_PVNN_P1V05_PCH
  U8D7   P8  PB12A LCMXO2_A_256BGA-IC,H63395-001   I179 @BASEBOARD_FAB2_LIB.BASEBOARD_FAB2(SCH_1):PAGE190
 R2L16    2      B RES_0402-22.1,1.0%,1/16W,CHIP,A   I147 @BASEBOARD_FAB2_LIB.BASEBOARD_FAB2(SCH_1):PAGE235

PWRGD_PVNN_PCH_R @BASEBOARD_FAB2_LIB.BASEBOARD_FAB2(SCH_1):PWRGD_PVNN_PCH_R
 R2L16    1      A RES_0402-22.1,1.0%,1/16W,CHIP,A   I147 @BASEBOARD_FAB2_LIB.BASEBOARD_FAB2(SCH_1):PAGE235
  R8A6    2      B RES_0402-1.00K,1%,1/16W,CHIP,GA   I149 @BASEBOARD_FAB2_LIB.BASEBOARD_FAB2(SCH_1):PAGE235
  C8A9    1      A CAP_0402LF-1000PF,50V,10%,X7R,A   I218 @BASEBOARD_FAB2_LIB.BASEBOARD_FAB2(SCH_1):PAGE235
 EU8A1    9 AVRRDY PXE1110B_QFN-IC,H89187-001   I229 @BASEBOARD_FAB2_LIB.BASEBOARD_FAB2(SCH_1):PAGE235

PWRGD_PVPP_ABC @BASEBOARD_FAB2_LIB.BASEBOARD_FAB2(SCH_1):PWRGD_PVPP_ABC
  J8B1   19   IO19 SCONN24_H46321001_SM-SCONN,H46A     I1 @BASEBOARD_FAB2_LIB.BASEBOARD_FAB2(SCH_1):PAGE91
  U8D7   N7   PB9D LCMXO2_A_256BGA-IC,H63395-001   I179 @BASEBOARD_FAB2_LIB.BASEBOARD_FAB2(SCH_1):PAGE190
 R7F16    2      B RES_0402-22.1,1.0%,1/16W,CHIP,A   I208 @BASEBOARD_FAB2_LIB.BASEBOARD_FAB2(SCH_1):PAGE231

PWRGD_PVPP_ABC_R @BASEBOARD_FAB2_LIB.BASEBOARD_FAB2(SCH_1):PWRGD_PVPP_ABC_R
 C7F11    1      A CAP_0402LF-1000PF,50V,10%,X7R,A   I142 @BASEBOARD_FAB2_LIB.BASEBOARD_FAB2(SCH_1):PAGE231
 R7F19    2      B RES_0402-1.00K,1%,1/16W,CHIP,GA   I143 @BASEBOARD_FAB2_LIB.BASEBOARD_FAB2(SCH_1):PAGE231
 EU7F1    7     PG NCP3232L_SM-IC,H86355-001   I193 @BASEBOARD_FAB2_LIB.BASEBOARD_FAB2(SCH_1):PAGE231
 R7F16    1      A RES_0402-22.1,1.0%,1/16W,CHIP,A   I208 @BASEBOARD_FAB2_LIB.BASEBOARD_FAB2(SCH_1):PAGE231

PWRGD_PVPP_DEF @BASEBOARD_FAB2_LIB.BASEBOARD_FAB2(SCH_1):PWRGD_PVPP_DEF
  U8D7   M6  PB11C LCMXO2_A_256BGA-IC,H63395-001   I179 @BASEBOARD_FAB2_LIB.BASEBOARD_FAB2(SCH_1):PAGE190
 R7B12    2      B RES_0402-22.1,1.0%,1/16W,CHIP,A   I257 @BASEBOARD_FAB2_LIB.BASEBOARD_FAB2(SCH_1):PAGE232

PWRGD_PVPP_DEF_R @BASEBOARD_FAB2_LIB.BASEBOARD_FAB2(SCH_1):PWRGD_PVPP_DEF_R
 C7B12    1      A CAP_0402LF-1000PF,50V,10%,X7R,A   I209 @BASEBOARD_FAB2_LIB.BASEBOARD_FAB2(SCH_1):PAGE232
 R7B17    2      B RES_0402-1.00K,1%,1/16W,CHIP,GA   I210 @BASEBOARD_FAB2_LIB.BASEBOARD_FAB2(SCH_1):PAGE232
 EU7B1    7     PG NCP3232L_SM-IC,H86355-001   I214 @BASEBOARD_FAB2_LIB.BASEBOARD_FAB2(SCH_1):PAGE232
 R7B12    1      A RES_0402-22.1,1.0%,1/16W,CHIP,A   I257 @BASEBOARD_FAB2_LIB.BASEBOARD_FAB2(SCH_1):PAGE232

PWRGD_PVPP_GHJ @BASEBOARD_FAB2_LIB.BASEBOARD_FAB2(SCH_1):PWRGD_PVPP_GHJ
  U8D7   M2  PL14A LCMXO2_A_256BGA-IC,H63395-001   I179 @BASEBOARD_FAB2_LIB.BASEBOARD_FAB2(SCH_1):PAGE190
 R4G12    2      B RES_0402-22.1,1.0%,1/16W,CHIP,A   I247 @BASEBOARD_FAB2_LIB.BASEBOARD_FAB2(SCH_1):PAGE233

PWRGD_PVPP_GHJ_R @BASEBOARD_FAB2_LIB.BASEBOARD_FAB2(SCH_1):PWRGD_PVPP_GHJ_R
 R4G14    2      B RES_0402-1.00K,1%,1/16W,CHIP,GA   I185 @BASEBOARD_FAB2_LIB.BASEBOARD_FAB2(SCH_1):PAGE233
  C4G9    1      A CAP_0402LF-1000PF,50V,10%,X7R,A   I201 @BASEBOARD_FAB2_LIB.BASEBOARD_FAB2(SCH_1):PAGE233
 EU4G1    7     PG NCP3232L_SM-IC,H86355-001   I225 @BASEBOARD_FAB2_LIB.BASEBOARD_FAB2(SCH_1):PAGE233
 R4G12    1      A RES_0402-22.1,1.0%,1/16W,CHIP,A   I247 @BASEBOARD_FAB2_LIB.BASEBOARD_FAB2(SCH_1):PAGE233

PWRGD_PVPP_KLM @BASEBOARD_FAB2_LIB.BASEBOARD_FAB2(SCH_1):PWRGD_PVPP_KLM
  U8D7   N2  PL13C LCMXO2_A_256BGA-IC,H63395-001   I179 @BASEBOARD_FAB2_LIB.BASEBOARD_FAB2(SCH_1):PAGE190
  R4B7    2      B RES_0402-22.1,1.0%,1/16W,CHIP,A   I201 @BASEBOARD_FAB2_LIB.BASEBOARD_FAB2(SCH_1):PAGE234

PWRGD_PVPP_KLM_R @BASEBOARD_FAB2_LIB.BASEBOARD_FAB2(SCH_1):PWRGD_PVPP_KLM_R
  C4B8    1      A CAP_0402LF-1000PF,50V,10%,X7R,A   I139 @BASEBOARD_FAB2_LIB.BASEBOARD_FAB2(SCH_1):PAGE234
 R4B10    2      B RES_0402-1.00K,1%,1/16W,CHIP,GA   I143 @BASEBOARD_FAB2_LIB.BASEBOARD_FAB2(SCH_1):PAGE234
 EU4A3    7     PG NCP3232L_SM-IC,H86355-001   I184 @BASEBOARD_FAB2_LIB.BASEBOARD_FAB2(SCH_1):PAGE234
  R4B7    1      A RES_0402-22.1,1.0%,1/16W,CHIP,A   I201 @BASEBOARD_FAB2_LIB.BASEBOARD_FAB2(SCH_1):PAGE234

PWRGD_PVSA_CPU0 @BASEBOARD_FAB2_LIB.BASEBOARD_FAB2(SCH_1):PWRGD_PVSA_CPU0
  U8D7   L1  PL11A LCMXO2_A_256BGA-IC,H63395-001   I179 @BASEBOARD_FAB2_LIB.BASEBOARD_FAB2(SCH_1):PAGE190
 R4D65    2      B RES_0402-33.2,1%,1/16W,CHIP,G2A   I127 @BASEBOARD_FAB2_LIB.BASEBOARD_FAB2(SCH_1):PAGE201

PWRGD_PVSA_CPU0_R @BASEBOARD_FAB2_LIB.BASEBOARD_FAB2(SCH_1):PWRGD_PVSA_CPU0_R
  R4E5    2      B RES_0402-1.00K,1%,1/16W,CHIP,GA    I27 @BASEBOARD_FAB2_LIB.BASEBOARD_FAB2(SCH_1):PAGE201
 R4D65    1      A RES_0402-33.2,1%,1/16W,CHIP,G2A   I127 @BASEBOARD_FAB2_LIB.BASEBOARD_FAB2(SCH_1):PAGE201
 EU4D4   15    MP0 PXE1610B_QFN-IC,H79206-001   I155 @BASEBOARD_FAB2_LIB.BASEBOARD_FAB2(SCH_1):PAGE201

PWRGD_PVSA_CPU1 @BASEBOARD_FAB2_LIB.BASEBOARD_FAB2(SCH_1):PWRGD_PVSA_CPU1
  U8D7   T4   PB3B LCMXO2_A_256BGA-IC,H63395-001   I179 @BASEBOARD_FAB2_LIB.BASEBOARD_FAB2(SCH_1):PAGE190
  R1D1    2      B RES_0402-33.2,1%,1/16W,CHIP,G2A   I116 @BASEBOARD_FAB2_LIB.BASEBOARD_FAB2(SCH_1):PAGE206

PWRGD_PVSA_CPU1_R @BASEBOARD_FAB2_LIB.BASEBOARD_FAB2(SCH_1):PWRGD_PVSA_CPU1_R
  R1D8    2      B RES_0402-1.00K,1%,1/16W,CHIP,GA    I36 @BASEBOARD_FAB2_LIB.BASEBOARD_FAB2(SCH_1):PAGE206
  R1D1    1      A RES_0402-33.2,1%,1/16W,CHIP,G2A   I116 @BASEBOARD_FAB2_LIB.BASEBOARD_FAB2(SCH_1):PAGE206
 EU1C2   15    MP0 PXE1610B_QFN-IC,H79206-001   I130 @BASEBOARD_FAB2_LIB.BASEBOARD_FAB2(SCH_1):PAGE206

PWRGD_PVTT_ABC_CPU0_R @BASEBOARD_FAB2_LIB.BASEBOARD_FAB2(SCH_1):PWRGD_PVTT_ABC_CPU0_R
 EU4G3    5     PG MIC5166_DFN-IC,H55101-001     I1 @BASEBOARD_FAB2_LIB.BASEBOARD_FAB2(SCH_1):PAGE221
 C4G14    1      A CAP_0402LF-1000PF,50V,10%,X7R,A    I15 @BASEBOARD_FAB2_LIB.BASEBOARD_FAB2(SCH_1):PAGE221
 R4G18    2      B RES_0402-10.0K,1%,1/16W,CHIP,GA    I45 @BASEBOARD_FAB2_LIB.BASEBOARD_FAB2(SCH_1):PAGE221
 R4G19    1      A RES_0402-33.2,1%,1/16W,CHIP,G2A    I54 @BASEBOARD_FAB2_LIB.BASEBOARD_FAB2(SCH_1):PAGE221

PWRGD_PVTT_CPU0 @BASEBOARD_FAB2_LIB.BASEBOARD_FAB2(SCH_1):PWRGD_PVTT_CPU0
  U8D7   B4  PT11D LCMXO2_A_256BGA-IC,H63395-001    I59 @BASEBOARD_FAB2_LIB.BASEBOARD_FAB2(SCH_1):PAGE191
 R4G19    2      B RES_0402-33.2,1%,1/16W,CHIP,G2A    I54 @BASEBOARD_FAB2_LIB.BASEBOARD_FAB2(SCH_1):PAGE221
  R4A6    2      B RES_0402-33.2,1%,1/16W,CHIP,G2A    I51 @BASEBOARD_FAB2_LIB.BASEBOARD_FAB2(SCH_1):PAGE222

PWRGD_PVTT_CPU1 @BASEBOARD_FAB2_LIB.BASEBOARD_FAB2(SCH_1):PWRGD_PVTT_CPU1
  U8D7   R7   PB9A LCMXO2_A_256BGA-IC,H63395-001   I179 @BASEBOARD_FAB2_LIB.BASEBOARD_FAB2(SCH_1):PAGE190
 R4G15    2      B RES_0402-33.2,1%,1/16W,CHIP,G2A    I51 @BASEBOARD_FAB2_LIB.BASEBOARD_FAB2(SCH_1):PAGE229
  R4A4    2      B RES_0402-33.2,1%,1/16W,CHIP,G2A    I51 @BASEBOARD_FAB2_LIB.BASEBOARD_FAB2(SCH_1):PAGE230

PWRGD_PVTT_DEF_CPU0_R @BASEBOARD_FAB2_LIB.BASEBOARD_FAB2(SCH_1):PWRGD_PVTT_DEF_CPU0_R
 C4A12    1      A CAP_0402LF-1000PF,50V,10%,X7R,A    I12 @BASEBOARD_FAB2_LIB.BASEBOARD_FAB2(SCH_1):PAGE222
  R6L9    2      B RES_0402-10.0K,1%,1/16W,CHIP,GA    I19 @BASEBOARD_FAB2_LIB.BASEBOARD_FAB2(SCH_1):PAGE222
 EU4A1    5     PG MIC5166_DFN-IC,H55101-001    I31 @BASEBOARD_FAB2_LIB.BASEBOARD_FAB2(SCH_1):PAGE222
  R4A6    1      A RES_0402-33.2,1%,1/16W,CHIP,G2A    I51 @BASEBOARD_FAB2_LIB.BASEBOARD_FAB2(SCH_1):PAGE222

PWRGD_PVTT_GHJ_CPU1_R @BASEBOARD_FAB2_LIB.BASEBOARD_FAB2(SCH_1):PWRGD_PVTT_GHJ_CPU1_R
 R4G17    2      B RES_0402-10.0K,1%,1/16W,CHIP,GA    I14 @BASEBOARD_FAB2_LIB.BASEBOARD_FAB2(SCH_1):PAGE229
 C4G13    1      A CAP_0402LF-1000PF,50V,10%,X7R,A    I15 @BASEBOARD_FAB2_LIB.BASEBOARD_FAB2(SCH_1):PAGE229
 EU4G2    5     PG MIC5166_DFN-IC,H55101-001    I24 @BASEBOARD_FAB2_LIB.BASEBOARD_FAB2(SCH_1):PAGE229
 R4G15    1      A RES_0402-33.2,1%,1/16W,CHIP,G2A    I51 @BASEBOARD_FAB2_LIB.BASEBOARD_FAB2(SCH_1):PAGE229

PWRGD_PVTT_KLM_CPU1_R @BASEBOARD_FAB2_LIB.BASEBOARD_FAB2(SCH_1):PWRGD_PVTT_KLM_CPU1_R
  C4A3    1      A CAP_0402LF-1000PF,50V,10%,X7R,A    I16 @BASEBOARD_FAB2_LIB.BASEBOARD_FAB2(SCH_1):PAGE230
  R4A5    2      B RES_0402-10.0K,1%,1/16W,CHIP,GA    I17 @BASEBOARD_FAB2_LIB.BASEBOARD_FAB2(SCH_1):PAGE230
 EU4A2    5     PG MIC5166_DFN-IC,H55101-001    I31 @BASEBOARD_FAB2_LIB.BASEBOARD_FAB2(SCH_1):PAGE230
  R4A4    1      A RES_0402-33.2,1%,1/16W,CHIP,G2A    I51 @BASEBOARD_FAB2_LIB.BASEBOARD_FAB2(SCH_1):PAGE230

PWRGD_SYS_PWROK @BASEBOARD_FAB2_LIB.BASEBOARD_FAB2(SCH_1):PWRGD_SYS_PWROK
  U7C1 BY19 SYS_PWROK LBG_CORE_QAT_EXT_D_BGA1-IC,H91A    I73 @BASEBOARD_FAB2_LIB.BASEBOARD_FAB2(SCH_1):PAGE118
 R2N12    2      B RES_0402-10.0K,1%,1/16W,EMPTY,A   I122 @BASEBOARD_FAB2_LIB.BASEBOARD_FAB2(SCH_1):PAGE133
  U8D7  D14   PR1A LCMXO2_A_256BGA-IC,H63395-001    I59 @BASEBOARD_FAB2_LIB.BASEBOARD_FAB2(SCH_1):PAGE191
 U25W4  H22 GPIOB6_LPCPME# AST2520A1-GP-GP_ASIC2-GB1-AST2A    I95 @BASEBOARD_FAB2_LIB.BASEBOARD_FAB2(SCH_1):PAGE144

RCC_DFX_1940_1 @BASEBOARD_FAB2_LIB.BASEBOARD_FAB2(SCH_1):RCC_DFX_1940_1
 TC1A1    2    IO1 RCC_DFX1940_ID4-EMPTY,N_A     I7 @BASEBOARD_FAB2_LIB.BASEBOARD_FAB2(SCH_1):PAGE110
 TC1A1    3    IO2 RCC_DFX1940_ID4-EMPTY,N_A     I7 @BASEBOARD_FAB2_LIB.BASEBOARD_FAB2(SCH_1):PAGE110

RCC_DFX_1940_2 @BASEBOARD_FAB2_LIB.BASEBOARD_FAB2(SCH_1):RCC_DFX_1940_2
 TC9A1    2    IO1 RCC_DFX1940_ID4-EMPTY,N_A     I9 @BASEBOARD_FAB2_LIB.BASEBOARD_FAB2(SCH_1):PAGE110
 TC9A1    3    IO2 RCC_DFX1940_ID4-EMPTY,N_A     I9 @BASEBOARD_FAB2_LIB.BASEBOARD_FAB2(SCH_1):PAGE110

RCC_DFX_1940_3 @BASEBOARD_FAB2_LIB.BASEBOARD_FAB2(SCH_1):RCC_DFX_1940_3
 TC9F1    2    IO1 RCC_DFX1940_ID4-EMPTY,N_A     I1 @BASEBOARD_FAB2_LIB.BASEBOARD_FAB2(SCH_1):PAGE110
 TC9F1    3    IO2 RCC_DFX1940_ID4-EMPTY,N_A     I1 @BASEBOARD_FAB2_LIB.BASEBOARD_FAB2(SCH_1):PAGE110

RCC_DFX_1940_4 @BASEBOARD_FAB2_LIB.BASEBOARD_FAB2(SCH_1):RCC_DFX_1940_4
 TC1G1    2    IO1 RCC_DFX1940_ID4-EMPTY,N_A     I3 @BASEBOARD_FAB2_LIB.BASEBOARD_FAB2(SCH_1):PAGE110
 TC1G1    3    IO2 RCC_DFX1940_ID4-EMPTY,N_A     I3 @BASEBOARD_FAB2_LIB.BASEBOARD_FAB2(SCH_1):PAGE110

RMII_BMC_OCP_CRSDV @BASEBOARD_FAB2_LIB.BASEBOARD_FAB2(SCH_1):RMII_BMC_OCP_CRSDV
 R1M15    1      A RES_0402-0.0,5%,1/16W,CHIP,G21A   I339 @BASEBOARD_FAB2_LIB.BASEBOARD_FAB2(SCH_1):PAGE186
 U25W4   C5 RGMII1RXD2_RMII1CRSDV_GPIOV0 AST2520A1-GP-GP_ASIC2-GB1-AST2A   I106 @BASEBOARD_FAB2_LIB.BASEBOARD_FAB2(SCH_1):PAGE147

RMII_BMC_OCP_CRSDV_R @BASEBOARD_FAB2_LIB.BASEBOARD_FAB2(SCH_1):RMII_BMC_OCP_CRSDV_R
  J9B3   27   IO27 SCONN120_A28699018_SM-SCONN,A2A   I336 @BASEBOARD_FAB2_LIB.BASEBOARD_FAB2(SCH_1):PAGE186
 R1M15    2      B RES_0402-0.0,5%,1/16W,CHIP,G21A   I339 @BASEBOARD_FAB2_LIB.BASEBOARD_FAB2(SCH_1):PAGE186

RMII_BMC_OCP_RXD0 @BASEBOARD_FAB2_LIB.BASEBOARD_FAB2(SCH_1):RMII_BMC_OCP_RXD0
 R1M17    1      A RES_0402-0.0,5%,1/16W,CHIP,G21A   I338 @BASEBOARD_FAB2_LIB.BASEBOARD_FAB2(SCH_1):PAGE186
 U25W4   A3 RGMII1RXD0_RMII1RXD0_GPIOU6 AST2520A1-GP-GP_ASIC2-GB1-AST2A   I106 @BASEBOARD_FAB2_LIB.BASEBOARD_FAB2(SCH_1):PAGE147

RMII_BMC_OCP_RXD0_R @BASEBOARD_FAB2_LIB.BASEBOARD_FAB2(SCH_1):RMII_BMC_OCP_RXD0_R
  J9B3   43   IO43 SCONN120_A28699018_SM-SCONN,A2A   I336 @BASEBOARD_FAB2_LIB.BASEBOARD_FAB2(SCH_1):PAGE186
 R1M17    2      B RES_0402-0.0,5%,1/16W,CHIP,G21A   I338 @BASEBOARD_FAB2_LIB.BASEBOARD_FAB2(SCH_1):PAGE186

RMII_BMC_OCP_RXD1 @BASEBOARD_FAB2_LIB.BASEBOARD_FAB2(SCH_1):RMII_BMC_OCP_RXD1
 R1M16    1      A RES_0402-0.0,5%,1/16W,CHIP,G21A   I337 @BASEBOARD_FAB2_LIB.BASEBOARD_FAB2(SCH_1):PAGE186
 U25W4   D6 RGMII1RXD1_RMII1RXD1_GPIOU7 AST2520A1-GP-GP_ASIC2-GB1-AST2A   I106 @BASEBOARD_FAB2_LIB.BASEBOARD_FAB2(SCH_1):PAGE147

RMII_BMC_OCP_RXD1_R @BASEBOARD_FAB2_LIB.BASEBOARD_FAB2(SCH_1):RMII_BMC_OCP_RXD1_R
  J9B3   45   IO45 SCONN120_A28699018_SM-SCONN,A2A   I336 @BASEBOARD_FAB2_LIB.BASEBOARD_FAB2(SCH_1):PAGE186
 R1M16    2      B RES_0402-0.0,5%,1/16W,CHIP,G21A   I337 @BASEBOARD_FAB2_LIB.BASEBOARD_FAB2(SCH_1):PAGE186

RMII_BMC_OCP_RXER @BASEBOARD_FAB2_LIB.BASEBOARD_FAB2(SCH_1):RMII_BMC_OCP_RXER
 R1M18    2      B RES_0402-0.0,5%,1/16W,CHIP,G21A   I340 @BASEBOARD_FAB2_LIB.BASEBOARD_FAB2(SCH_1):PAGE186
 U25W4   C4 RGMII1RXD3_RMII1RXER_GPIOV1 AST2520A1-GP-GP_ASIC2-GB1-AST2A   I106 @BASEBOARD_FAB2_LIB.BASEBOARD_FAB2(SCH_1):PAGE147

RMII_BMC_OCP_RXER_R @BASEBOARD_FAB2_LIB.BASEBOARD_FAB2(SCH_1):RMII_BMC_OCP_RXER_R
  J9B3   36   IO36 SCONN120_A28699018_SM-SCONN,A2A   I336 @BASEBOARD_FAB2_LIB.BASEBOARD_FAB2(SCH_1):PAGE186
 R1M18    1      A RES_0402-0.0,5%,1/16W,CHIP,G21A   I340 @BASEBOARD_FAB2_LIB.BASEBOARD_FAB2(SCH_1):PAGE186

RMII_BMC_OCP_TXD0 @BASEBOARD_FAB2_LIB.BASEBOARD_FAB2(SCH_1):RMII_BMC_OCP_TXD0
  J9B3   40   IO40 SCONN120_A28699018_SM-SCONN,A2A   I336 @BASEBOARD_FAB2_LIB.BASEBOARD_FAB2(SCH_1):PAGE186
R25W86    2      B RES_0402-22.1,1.0%,1/16W,CHIP,A    I24 @BASEBOARD_FAB2_LIB.BASEBOARD_FAB2(SCH_1):PAGE147

RMII_BMC_OCP_TXD0_R @BASEBOARD_FAB2_LIB.BASEBOARD_FAB2(SCH_1):RMII_BMC_OCP_TXD0_R
R25W107    2      B RES_0402-4.75K,1%,1/16W,EMPTY,A    I33 @BASEBOARD_FAB2_LIB.BASEBOARD_FAB2(SCH_1):PAGE151
R25W86    1      A RES_0402-22.1,1.0%,1/16W,CHIP,A    I24 @BASEBOARD_FAB2_LIB.BASEBOARD_FAB2(SCH_1):PAGE147
 U25W4   F9 RGMII1TXD0_RMII1TXD0_GPIOT2 AST2520A1-GP-GP_ASIC2-GB1-AST2A   I106 @BASEBOARD_FAB2_LIB.BASEBOARD_FAB2(SCH_1):PAGE147

RMII_BMC_OCP_TXD1 @BASEBOARD_FAB2_LIB.BASEBOARD_FAB2(SCH_1):RMII_BMC_OCP_TXD1
  J9B3   42   IO42 SCONN120_A28699018_SM-SCONN,A2A   I336 @BASEBOARD_FAB2_LIB.BASEBOARD_FAB2(SCH_1):PAGE186
R25W87    2      B RES_0402-22.1,1.0%,1/16W,CHIP,A    I25 @BASEBOARD_FAB2_LIB.BASEBOARD_FAB2(SCH_1):PAGE147

RMII_BMC_OCP_TXD1_R @BASEBOARD_FAB2_LIB.BASEBOARD_FAB2(SCH_1):RMII_BMC_OCP_TXD1_R
R25W108    2      B RES_0402-4.75K,1%,1/16W,CHIP,GA    I34 @BASEBOARD_FAB2_LIB.BASEBOARD_FAB2(SCH_1):PAGE151
R25W87    1      A RES_0402-22.1,1.0%,1/16W,CHIP,A    I25 @BASEBOARD_FAB2_LIB.BASEBOARD_FAB2(SCH_1):PAGE147
 U25W4   A5 RGMII1TXD1_RMII1TXD1_GPIOT3 AST2520A1-GP-GP_ASIC2-GB1-AST2A   I106 @BASEBOARD_FAB2_LIB.BASEBOARD_FAB2(SCH_1):PAGE147

RMII_BMC_OCP_TXEN @BASEBOARD_FAB2_LIB.BASEBOARD_FAB2(SCH_1):RMII_BMC_OCP_TXEN
  J9B3   31   IO31 SCONN120_A28699018_SM-SCONN,A2A   I336 @BASEBOARD_FAB2_LIB.BASEBOARD_FAB2(SCH_1):PAGE186
R25W106    2      B RES_0402-4.75K,1%,1/16W,EMPTY,A    I32 @BASEBOARD_FAB2_LIB.BASEBOARD_FAB2(SCH_1):PAGE151
R25W85    2      B RES_0402-22.1,1.0%,1/16W,CHIP,A    I23 @BASEBOARD_FAB2_LIB.BASEBOARD_FAB2(SCH_1):PAGE147

RMII_BMC_OCP_TXEN_R @BASEBOARD_FAB2_LIB.BASEBOARD_FAB2(SCH_1):RMII_BMC_OCP_TXEN_R
R25W85    1      A RES_0402-22.1,1.0%,1/16W,CHIP,A    I23 @BASEBOARD_FAB2_LIB.BASEBOARD_FAB2(SCH_1):PAGE147
 U25W4   E9 RGMII1TXCTL_RMII1TXEN_GPIOT1 AST2520A1-GP-GP_ASIC2-GB1-AST2A   I106 @BASEBOARD_FAB2_LIB.BASEBOARD_FAB2(SCH_1):PAGE147

RMII_BMC_PCH_SPRNGVLLE_CRSDV @BASEBOARD_FAB2_LIB.BASEBOARD_FAB2(SCH_1):RMII_BMC_PCH_SPRNGVLLE_CRSDV
  R3P2    1      A RES_0402-0.0,5%,1/16W,CHIP,G21A    I90 @BASEBOARD_FAB2_LIB.BASEBOARD_FAB2(SCH_1):PAGE121
  R1T1    1      A RES_0402-10.0K,1%,1/16W,CHIP,GA   I214 @BASEBOARD_FAB2_LIB.BASEBOARD_FAB2(SCH_1):PAGE139
  R9F1    2      B RES_0402-22.1,1.0%,1/16W,CHIP,A   I225 @BASEBOARD_FAB2_LIB.BASEBOARD_FAB2(SCH_1):PAGE139
 U25W4   D2 RGMII2RXD2_RMII2CRSDV_GPIOV6 AST2520A1-GP-GP_ASIC2-GB1-AST2A   I106 @BASEBOARD_FAB2_LIB.BASEBOARD_FAB2(SCH_1):PAGE147

RMII_BMC_PCH_SPRNGVLLE_CRSDV_R @BASEBOARD_FAB2_LIB.BASEBOARD_FAB2(SCH_1):RMII_BMC_PCH_SPRNGVLLE_CRSDV_R
 EU9E1    3 NC_SI_CRS_DV SPRINGVILLE_SM1-IC,G47144-004    I72 @BASEBOARD_FAB2_LIB.BASEBOARD_FAB2(SCH_1):PAGE139
  R9F1    1      A RES_0402-22.1,1.0%,1/16W,CHIP,A   I225 @BASEBOARD_FAB2_LIB.BASEBOARD_FAB2(SCH_1):PAGE139

RMII_BMC_PCH_SPRNGVLLE_CRSDV_R1 @BASEBOARD_FAB2_LIB.BASEBOARD_FAB2(SCH_1):RMII_BMC_PCH_SPRNGVLLE_CRSDV_R1
  U7C1  AN3 GPP_K4_LAN_NCSI_CRS_DV LBG_CORE_QAT_EXT_D_BGA1-IC,H91A    I34 @BASEBOARD_FAB2_LIB.BASEBOARD_FAB2(SCH_1):PAGE121
  R3P2    2      B RES_0402-0.0,5%,1/16W,CHIP,G21A    I90 @BASEBOARD_FAB2_LIB.BASEBOARD_FAB2(SCH_1):PAGE121

RMII_BMC_PCH_SPRNGVLLE_RXER @BASEBOARD_FAB2_LIB.BASEBOARD_FAB2(SCH_1):RMII_BMC_PCH_SPRNGVLLE_RXER
 R7C14    1      A RES_0402-33.2,1%,1/16W,CHIP,G2A    I98 @BASEBOARD_FAB2_LIB.BASEBOARD_FAB2(SCH_1):PAGE121
 R7D13    2      B RES_0402-8.2K,1%,1/16W,EMPTY,GA    I60 @BASEBOARD_FAB2_LIB.BASEBOARD_FAB2(SCH_1):PAGE125
 U25W4   E6 RGMII2RXD3_RMII2RXER_GPIOV7 AST2520A1-GP-GP_ASIC2-GB1-AST2A   I106 @BASEBOARD_FAB2_LIB.BASEBOARD_FAB2(SCH_1):PAGE147

RMII_BMC_PCH_SPRNGVLLE_RXER_R @BASEBOARD_FAB2_LIB.BASEBOARD_FAB2(SCH_1):RMII_BMC_PCH_SPRNGVLLE_RXER_R
  U7C1  AH2 GPP_K7 LBG_CORE_QAT_EXT_D_BGA1-IC,H91A    I34 @BASEBOARD_FAB2_LIB.BASEBOARD_FAB2(SCH_1):PAGE121
 R7C14    2      B RES_0402-33.2,1%,1/16W,CHIP,G2A    I98 @BASEBOARD_FAB2_LIB.BASEBOARD_FAB2(SCH_1):PAGE121

RMII_BMC_PCH_SPRNGVLLE_TXD0 @BASEBOARD_FAB2_LIB.BASEBOARD_FAB2(SCH_1):RMII_BMC_PCH_SPRNGVLLE_TXD0
  U7C1  AM2 GPP_K1_LAN_NCSI_TXD0 LBG_CORE_QAT_EXT_D_BGA1-IC,H91A    I34 @BASEBOARD_FAB2_LIB.BASEBOARD_FAB2(SCH_1):PAGE121
 EU9E1    9 NC_SI_TXD0 SPRINGVILLE_SM1-IC,G47144-004    I72 @BASEBOARD_FAB2_LIB.BASEBOARD_FAB2(SCH_1):PAGE139
R25W91    2      B RES_0402-10.0K,1%,1/16W,CHIP,GA     I4 @BASEBOARD_FAB2_LIB.BASEBOARD_FAB2(SCH_1):PAGE147
R25W89    2      B RES_0402-22.1,1.0%,1/16W,CHIP,A    I22 @BASEBOARD_FAB2_LIB.BASEBOARD_FAB2(SCH_1):PAGE147

RMII_BMC_PCH_SPRNGVLLE_TXD0_R @BASEBOARD_FAB2_LIB.BASEBOARD_FAB2(SCH_1):RMII_BMC_PCH_SPRNGVLLE_TXD0_R
R25W112    2      B RES_0402-4.75K,1%,1/16W,EMPTY,A    I44 @BASEBOARD_FAB2_LIB.BASEBOARD_FAB2(SCH_1):PAGE151
R25W89    1      A RES_0402-22.1,1.0%,1/16W,CHIP,A    I22 @BASEBOARD_FAB2_LIB.BASEBOARD_FAB2(SCH_1):PAGE147
 U25W4   A2 RGMII2TXD0_RMII2TXD0_GPIOU0 AST2520A1-GP-GP_ASIC2-GB1-AST2A   I106 @BASEBOARD_FAB2_LIB.BASEBOARD_FAB2(SCH_1):PAGE147

RMII_BMC_PCH_SPRNGVLLE_TXD1 @BASEBOARD_FAB2_LIB.BASEBOARD_FAB2(SCH_1):RMII_BMC_PCH_SPRNGVLLE_TXD1
  U7C1  AK2 GPP_K2_LAN_NCSI_TXD1 LBG_CORE_QAT_EXT_D_BGA1-IC,H91A    I34 @BASEBOARD_FAB2_LIB.BASEBOARD_FAB2(SCH_1):PAGE121
 EU9E1    8 NC_SI_TXD1 SPRINGVILLE_SM1-IC,G47144-004    I72 @BASEBOARD_FAB2_LIB.BASEBOARD_FAB2(SCH_1):PAGE139
R25W90    2      B RES_0402-22.1,1.0%,1/16W,CHIP,A    I21 @BASEBOARD_FAB2_LIB.BASEBOARD_FAB2(SCH_1):PAGE147
R25W92    2      B RES_0402-10.0K,1%,1/16W,CHIP,GA     I3 @BASEBOARD_FAB2_LIB.BASEBOARD_FAB2(SCH_1):PAGE147

RMII_BMC_PCH_SPRNGVLLE_TXD1_R @BASEBOARD_FAB2_LIB.BASEBOARD_FAB2(SCH_1):RMII_BMC_PCH_SPRNGVLLE_TXD1_R
R25W90    1      A RES_0402-22.1,1.0%,1/16W,CHIP,A    I21 @BASEBOARD_FAB2_LIB.BASEBOARD_FAB2(SCH_1):PAGE147
R25W113    2      B RES_0402-4.75K,1%,1/16W,EMPTY,A    I45 @BASEBOARD_FAB2_LIB.BASEBOARD_FAB2(SCH_1):PAGE151
 U25W4   B3 RGMII2TXD1_RMII2TXD1_GPIOU1 AST2520A1-GP-GP_ASIC2-GB1-AST2A   I106 @BASEBOARD_FAB2_LIB.BASEBOARD_FAB2(SCH_1):PAGE147

RMII_BMC_PCH_SPRNGVLLE_TXEN @BASEBOARD_FAB2_LIB.BASEBOARD_FAB2(SCH_1):RMII_BMC_PCH_SPRNGVLLE_TXEN
  U7C1  AL3 GPP_K3_LAN_NCSI_TX_EN LBG_CORE_QAT_EXT_D_BGA1-IC,H91A    I34 @BASEBOARD_FAB2_LIB.BASEBOARD_FAB2(SCH_1):PAGE121
 EU9E1    7 NC_SI_TX_EN SPRINGVILLE_SM1-IC,G47144-004    I72 @BASEBOARD_FAB2_LIB.BASEBOARD_FAB2(SCH_1):PAGE139
 R9E13    1      A RES_0402-10.0K,1%,1/16W,CHIP,GA   I212 @BASEBOARD_FAB2_LIB.BASEBOARD_FAB2(SCH_1):PAGE139
R25W111    2      B RES_0402-4.75K,1%,1/16W,EMPTY,A    I43 @BASEBOARD_FAB2_LIB.BASEBOARD_FAB2(SCH_1):PAGE151
R25W88    2      B RES_0402-22.1,1.0%,1/16W,CHIP,A     I8 @BASEBOARD_FAB2_LIB.BASEBOARD_FAB2(SCH_1):PAGE147

RMII_BMC_SPRNGVLLE_TXEN_R @BASEBOARD_FAB2_LIB.BASEBOARD_FAB2(SCH_1):RMII_BMC_SPRNGVLLE_TXEN_R
R25W88    1      A RES_0402-22.1,1.0%,1/16W,CHIP,A     I8 @BASEBOARD_FAB2_LIB.BASEBOARD_FAB2(SCH_1):PAGE147
 U25W4   B1 RGMII2TXCTL_RMII2TXEN_GPIOT7 AST2520A1-GP-GP_ASIC2-GB1-AST2A   I106 @BASEBOARD_FAB2_LIB.BASEBOARD_FAB2(SCH_1):PAGE147

RMII_PCH_SPRNGVLLE_ARB_IN @BASEBOARD_FAB2_LIB.BASEBOARD_FAB2(SCH_1):RMII_PCH_SPRNGVLLE_ARB_IN
  U7C1  AJ3 GPP_K8_LAN_NCSI_ARB_IN LBG_CORE_QAT_EXT_D_BGA1-IC,H91A    I34 @BASEBOARD_FAB2_LIB.BASEBOARD_FAB2(SCH_1):PAGE121
 R9E16    2      B RES_0402-33.2,1%,1/16W,CHIP,G2A   I235 @BASEBOARD_FAB2_LIB.BASEBOARD_FAB2(SCH_1):PAGE139

RMII_PCH_SPRNGVLLE_ARB_IN_R @BASEBOARD_FAB2_LIB.BASEBOARD_FAB2(SCH_1):RMII_PCH_SPRNGVLLE_ARB_IN_R
 EU9E1   44 NC_SI_ARB_OUT SPRINGVILLE_SM1-IC,G47144-004    I72 @BASEBOARD_FAB2_LIB.BASEBOARD_FAB2(SCH_1):PAGE139
 R9E16    1      A RES_0402-33.2,1%,1/16W,CHIP,G2A   I235 @BASEBOARD_FAB2_LIB.BASEBOARD_FAB2(SCH_1):PAGE139

RMII_PCH_SPRNGVLLE_ARB_OUT @BASEBOARD_FAB2_LIB.BASEBOARD_FAB2(SCH_1):RMII_PCH_SPRNGVLLE_ARB_OUT
 R8D11    1      A RES_0402-33.2,1%,1/16W,CHIP,G2A   I101 @BASEBOARD_FAB2_LIB.BASEBOARD_FAB2(SCH_1):PAGE121
  R7D1    1      A RES_0402-1.00K,1%,1/16W,CHIP,GA    I70 @BASEBOARD_FAB2_LIB.BASEBOARD_FAB2(SCH_1):PAGE125
 R8D16    2      B RES_0402-10.0K,1%,1/16W,EMPTY,A    I71 @BASEBOARD_FAB2_LIB.BASEBOARD_FAB2(SCH_1):PAGE125
 EU9E1   43 NC_SI_ARB_IN SPRINGVILLE_SM1-IC,G47144-004    I72 @BASEBOARD_FAB2_LIB.BASEBOARD_FAB2(SCH_1):PAGE139

RMII_PCH_SPRNGVLLE_ARB_OUT_R @BASEBOARD_FAB2_LIB.BASEBOARD_FAB2(SCH_1):RMII_PCH_SPRNGVLLE_ARB_OUT_R
  U7C1  AK4 GPP_K9_LAN_NCSI_ARB_OUT LBG_CORE_QAT_EXT_D_BGA1-IC,H91A    I34 @BASEBOARD_FAB2_LIB.BASEBOARD_FAB2(SCH_1):PAGE121
 R8D11    2      B RES_0402-33.2,1%,1/16W,CHIP,G2A   I101 @BASEBOARD_FAB2_LIB.BASEBOARD_FAB2(SCH_1):PAGE121

RMII_SPRNGVLLE_BMC_PCH_RXD0 @BASEBOARD_FAB2_LIB.BASEBOARD_FAB2(SCH_1):RMII_SPRNGVLLE_BMC_PCH_RXD0
  R3P3    1      A RES_0402-0.0,5%,1/16W,CHIP,G21A    I89 @BASEBOARD_FAB2_LIB.BASEBOARD_FAB2(SCH_1):PAGE121
 R9E17    2      B RES_0402-22.1,1.0%,1/16W,CHIP,A   I229 @BASEBOARD_FAB2_LIB.BASEBOARD_FAB2(SCH_1):PAGE139
R25W79    2      B RES_0402-10.0K,1%,1/16W,CHIP,GA    I42 @BASEBOARD_FAB2_LIB.BASEBOARD_FAB2(SCH_1):PAGE147
 U25W4   C3 RGMII2RXD0_RMII2RXD0_GPIOV4 AST2520A1-GP-GP_ASIC2-GB1-AST2A   I106 @BASEBOARD_FAB2_LIB.BASEBOARD_FAB2(SCH_1):PAGE147

RMII_SPRNGVLLE_BMC_PCH_RXD0_R @BASEBOARD_FAB2_LIB.BASEBOARD_FAB2(SCH_1):RMII_SPRNGVLLE_BMC_PCH_RXD0_R
 EU9E1    6 NC_SI_RXD0 SPRINGVILLE_SM1-IC,G47144-004    I72 @BASEBOARD_FAB2_LIB.BASEBOARD_FAB2(SCH_1):PAGE139
 R9E17    1      A RES_0402-22.1,1.0%,1/16W,CHIP,A   I229 @BASEBOARD_FAB2_LIB.BASEBOARD_FAB2(SCH_1):PAGE139

RMII_SPRNGVLLE_BMC_PCH_RXD0_R1 @BASEBOARD_FAB2_LIB.BASEBOARD_FAB2(SCH_1):RMII_SPRNGVLLE_BMC_PCH_RXD0_R1
  U7C1  AL1 GPP_K5_LAN_NCSI_RXD0 LBG_CORE_QAT_EXT_D_BGA1-IC,H91A    I34 @BASEBOARD_FAB2_LIB.BASEBOARD_FAB2(SCH_1):PAGE121
  R3P3    2      B RES_0402-0.0,5%,1/16W,CHIP,G21A    I89 @BASEBOARD_FAB2_LIB.BASEBOARD_FAB2(SCH_1):PAGE121

RMII_SPRNGVLLE_BMC_PCH_RXD1 @BASEBOARD_FAB2_LIB.BASEBOARD_FAB2(SCH_1):RMII_SPRNGVLLE_BMC_PCH_RXD1
  R2P1    1      A RES_0402-0.0,5%,1/16W,CHIP,G21A    I91 @BASEBOARD_FAB2_LIB.BASEBOARD_FAB2(SCH_1):PAGE121
 R9E19    2      B RES_0402-22.1,1.0%,1/16W,CHIP,A   I228 @BASEBOARD_FAB2_LIB.BASEBOARD_FAB2(SCH_1):PAGE139
R25W80    2      B RES_0402-10.0K,1%,1/16W,CHIP,GA    I43 @BASEBOARD_FAB2_LIB.BASEBOARD_FAB2(SCH_1):PAGE147
 U25W4   D1 RGMII2RXD1_RMII2RXD1_GPIOV5 AST2520A1-GP-GP_ASIC2-GB1-AST2A   I106 @BASEBOARD_FAB2_LIB.BASEBOARD_FAB2(SCH_1):PAGE147

RMII_SPRNGVLLE_BMC_PCH_RXD1_R @BASEBOARD_FAB2_LIB.BASEBOARD_FAB2(SCH_1):RMII_SPRNGVLLE_BMC_PCH_RXD1_R
 EU9E1    5 NC_SI_RXD1 SPRINGVILLE_SM1-IC,G47144-004    I72 @BASEBOARD_FAB2_LIB.BASEBOARD_FAB2(SCH_1):PAGE139
 R9E19    1      A RES_0402-22.1,1.0%,1/16W,CHIP,A   I228 @BASEBOARD_FAB2_LIB.BASEBOARD_FAB2(SCH_1):PAGE139

RMII_SPRNGVLLE_BMC_PCH_RXD1_R1 @BASEBOARD_FAB2_LIB.BASEBOARD_FAB2(SCH_1):RMII_SPRNGVLLE_BMC_PCH_RXD1_R1
  U7C1  AN1 GPP_K6_LAN_NCSI_RXD1 LBG_CORE_QAT_EXT_D_BGA1-IC,H91A    I34 @BASEBOARD_FAB2_LIB.BASEBOARD_FAB2(SCH_1):PAGE121
  R2P1    2      B RES_0402-0.0,5%,1/16W,CHIP,G21A    I91 @BASEBOARD_FAB2_LIB.BASEBOARD_FAB2(SCH_1):PAGE121

RST_BMC_DDR3_BUF_IN_N @BASEBOARD_FAB2_LIB.BASEBOARD_FAB2(SCH_1):RST_BMC_DDR3_BUF_IN_N
 R8D36    2      B RES_0402-33.2,1%,1/16W,CHIP,G2A   I388 @BASEBOARD_FAB2_LIB.BASEBOARD_FAB2(SCH_1):PAGE157
  U9F3    2      A TTL1G07_A_SOP-74LVC1G07,IC,C88B    I34 @BASEBOARD_FAB2_LIB.BASEBOARD_FAB2(SCH_1):PAGE149

RST_BMC_DDR3_R_N @BASEBOARD_FAB2_LIB.BASEBOARD_FAB2(SCH_1):RST_BMC_DDR3_R_N
 R9F34    1      A RES_0402-33.2,1%,1/16W,CHIP,G2A    I14 @BASEBOARD_FAB2_LIB.BASEBOARD_FAB2(SCH_1):PAGE149
 R9F29    2      B RES_0402-4.75K,1%,1/16W,CHIP,GA    I16 @BASEBOARD_FAB2_LIB.BASEBOARD_FAB2(SCH_1):PAGE149
  U9F3    4      Y TTL1G07_A_SOP-74LVC1G07,IC,C88B    I34 @BASEBOARD_FAB2_LIB.BASEBOARD_FAB2(SCH_1):PAGE149

RST_BMC_LVC3_N @BASEBOARD_FAB2_LIB.BASEBOARD_FAB2(SCH_1):RST_BMC_LVC3_N
R25W74    2      B RES_0402-0.0,5%,1/16W,CHIP,G21A    I70 @BASEBOARD_FAB2_LIB.BASEBOARD_FAB2(SCH_1):PAGE146
 U25W4  G22 GPIOAC7_ESPIRST#_LPCRST# AST2520A1-GP-GP_ASIC2-GB1-AST2A   I105 @BASEBOARD_FAB2_LIB.BASEBOARD_FAB2(SCH_1):PAGE146

RST_BMC_SRST_N @BASEBOARD_FAB2_LIB.BASEBOARD_FAB2(SCH_1):RST_BMC_SRST_N
 R7D23    1      A RES_0402-0.0,5%,1/16W,CHIP,G21A   I131 @BASEBOARD_FAB2_LIB.BASEBOARD_FAB2(SCH_1):PAGE118
  J8G2    3    IO3 CONN12_C73564003_PIP-CONN,C735A   I124 @BASEBOARD_FAB2_LIB.BASEBOARD_FAB2(SCH_1):PAGE135
  Q9W3    3      C NPN_SM-MMBT3904,IC,C52245-001    I26 @BASEBOARD_FAB2_LIB.BASEBOARD_FAB2(SCH_1):PAGE249
  R3W6    2      B RES_0402-4.75K,1%,1/16W,CHIP,GA    I27 @BASEBOARD_FAB2_LIB.BASEBOARD_FAB2(SCH_1):PAGE249
 U25W4  U18  SRST# AST2520A1-GP-GP_ASIC2-GB1-AST2A   I117 @BASEBOARD_FAB2_LIB.BASEBOARD_FAB2(SCH_1):PAGE145

RST_BMC_SRST_R2_N @BASEBOARD_FAB2_LIB.BASEBOARD_FAB2(SCH_1):RST_BMC_SRST_R2_N
 R8D25    2      B RES_0402-4.75K,1%,1/16W,CHIP,GA   I335 @BASEBOARD_FAB2_LIB.BASEBOARD_FAB2(SCH_1):PAGE157
  U8D2    4      Y TTL1G07_A_SOP-74LVC1G07,IC,C88B   I374 @BASEBOARD_FAB2_LIB.BASEBOARD_FAB2(SCH_1):PAGE157
 R8D22    1      A RES_0402-33.2,1%,1/16W,CHIP,G2A   I386 @BASEBOARD_FAB2_LIB.BASEBOARD_FAB2(SCH_1):PAGE157
 R8D36    1      A RES_0402-33.2,1%,1/16W,CHIP,G2A   I388 @BASEBOARD_FAB2_LIB.BASEBOARD_FAB2(SCH_1):PAGE157

RST_BMC_SRST_R_N @BASEBOARD_FAB2_LIB.BASEBOARD_FAB2(SCH_1):RST_BMC_SRST_R_N
  U7C1  M11 GPD2_GBE_WAKE_N LBG_CORE_QAT_EXT_D_BGA1-IC,H91A    I73 @BASEBOARD_FAB2_LIB.BASEBOARD_FAB2(SCH_1):PAGE118
 R7D23    2      B RES_0402-0.0,5%,1/16W,CHIP,G21A   I131 @BASEBOARD_FAB2_LIB.BASEBOARD_FAB2(SCH_1):PAGE118

RST_BMC_SYSRST_BTN_OUT_B_N @BASEBOARD_FAB2_LIB.BASEBOARD_FAB2(SCH_1):RST_BMC_SYSRST_BTN_OUT_B_N
  U7C1 BV19 SYS_RESET_N LBG_CORE_QAT_EXT_D_BGA1-IC,H91A    I73 @BASEBOARD_FAB2_LIB.BASEBOARD_FAB2(SCH_1):PAGE118
 R2T18    2      B RES_0402-49.9,1%,1/16W,CHIP,G2A   I288 @BASEBOARD_FAB2_LIB.BASEBOARD_FAB2(SCH_1):PAGE156
  U8D7  F14   PR4A LCMXO2_A_256BGA-IC,H63395-001    I59 @BASEBOARD_FAB2_LIB.BASEBOARD_FAB2(SCH_1):PAGE191

RST_BMC_SYSRST_BTN_OUT_B_R_N @BASEBOARD_FAB2_LIB.BASEBOARD_FAB2(SCH_1):RST_BMC_SYSRST_BTN_OUT_B_R_N
  U8F3    6     1Y TTL2G07_SOT23LF-74LVC2G07,IC,DB   I201 @BASEBOARD_FAB2_LIB.BASEBOARD_FAB2(SCH_1):PAGE156
 R2T22    2      B RES_0402-10.0K,1%,1/16W,CHIP,GA   I210 @BASEBOARD_FAB2_LIB.BASEBOARD_FAB2(SCH_1):PAGE156
  U8G1    6     1Y TTL2G07_SOT23LF-74LVC2G07,IC,DB   I269 @BASEBOARD_FAB2_LIB.BASEBOARD_FAB2(SCH_1):PAGE156
 R2T18    1      A RES_0402-49.9,1%,1/16W,CHIP,G2A   I288 @BASEBOARD_FAB2_LIB.BASEBOARD_FAB2(SCH_1):PAGE156

RST_BMC_SYSRST_BTN_OUT_N @BASEBOARD_FAB2_LIB.BASEBOARD_FAB2(SCH_1):RST_BMC_SYSRST_BTN_OUT_N
  U8F3    1     1A TTL2G07_SOT23LF-74LVC2G07,IC,DB   I201 @BASEBOARD_FAB2_LIB.BASEBOARD_FAB2(SCH_1):PAGE156
 R2T35    2      B RES_0402-4.75K,1%,1/16W,CHIP,GA   I207 @BASEBOARD_FAB2_LIB.BASEBOARD_FAB2(SCH_1):PAGE156
 U25W4  C20 GPIOE1_NDCD3 AST2520A1-GP-GP_ASIC2-GB1-AST2A   I117 @BASEBOARD_FAB2_LIB.BASEBOARD_FAB2(SCH_1):PAGE145

RST_CD_CPU0_POR_N @BASEBOARD_FAB2_LIB.BASEBOARD_FAB2(SCH_1):RST_CD_CPU0_POR_N
  U5D1 CF25 CD_POR_N SKX_EXT_B_BGA1-IC,TBD    I61 @BASEBOARD_FAB2_LIB.BASEBOARD_FAB2(SCH_1):PAGE29
  U8D7   N3  PL14B LCMXO2_A_256BGA-IC,H63395-001   I179 @BASEBOARD_FAB2_LIB.BASEBOARD_FAB2(SCH_1):PAGE190
 R3R16    2      B RES_0402-4.75K,1%,1/16W,CHIP,GA    I48 @BASEBOARD_FAB2_LIB.BASEBOARD_FAB2(SCH_1):PAGE192

RST_CD_CPU1_POR_N @BASEBOARD_FAB2_LIB.BASEBOARD_FAB2(SCH_1):RST_CD_CPU1_POR_N
  U2D1 CF25 CD_POR_N SKX_EXT_B_BGA1-IC,TBD    I23 @BASEBOARD_FAB2_LIB.BASEBOARD_FAB2(SCH_1):PAGE63
  U8D7  P10  PB19A LCMXO2_A_256BGA-IC,H63395-001   I179 @BASEBOARD_FAB2_LIB.BASEBOARD_FAB2(SCH_1):PAGE190
  R6M9    2      B RES_0402-4.75K,1%,1/16W,CHIP,GA    I49 @BASEBOARD_FAB2_LIB.BASEBOARD_FAB2(SCH_1):PAGE192

RST_CPU0_G_N @BASEBOARD_FAB2_LIB.BASEBOARD_FAB2(SCH_1):RST_CPU0_G_N
  U5D1 AP21 RESET_N SKX_EXT_B_BGA1-IC,TBD   I259 @BASEBOARD_FAB2_LIB.BASEBOARD_FAB2(SCH_1):PAGE21
 R6D12    2      B RES_0402-49.9,1%,1/16W,CHIP,G2A     I2 @BASEBOARD_FAB2_LIB.BASEBOARD_FAB2(SCH_1):PAGE96
  U3P1    5     B2 GTL2014_SM-IC,D66151-001    I42 @BASEBOARD_FAB2_LIB.BASEBOARD_FAB2(SCH_1):PAGE96

RST_CPU0_LVC3_N @BASEBOARD_FAB2_LIB.BASEBOARD_FAB2(SCH_1):RST_CPU0_LVC3_N
  U3P1   10     A2 GTL2014_SM-IC,D66151-001    I42 @BASEBOARD_FAB2_LIB.BASEBOARD_FAB2(SCH_1):PAGE96
 R3P34    2      B RES_0402-0.0,5%,1/16W,CHIP,G21A   I116 @BASEBOARD_FAB2_LIB.BASEBOARD_FAB2(SCH_1):PAGE190

RST_CPU0_LVC3_R1_N @BASEBOARD_FAB2_LIB.BASEBOARD_FAB2(SCH_1):RST_CPU0_LVC3_R1_N
 R3P34    1      A RES_0402-0.0,5%,1/16W,CHIP,G21A   I116 @BASEBOARD_FAB2_LIB.BASEBOARD_FAB2(SCH_1):PAGE190
  U8D7  R10  PB19B LCMXO2_A_256BGA-IC,H63395-001   I179 @BASEBOARD_FAB2_LIB.BASEBOARD_FAB2(SCH_1):PAGE190

RST_CPU1_G_N @BASEBOARD_FAB2_LIB.BASEBOARD_FAB2(SCH_1):RST_CPU1_G_N
  U2D1 AP21 RESET_N SKX_EXT_B_BGA1-IC,TBD   I172 @BASEBOARD_FAB2_LIB.BASEBOARD_FAB2(SCH_1):PAGE55
 R3D20    2      B RES_0402-49.9,1%,1/16W,CHIP,G2A    I25 @BASEBOARD_FAB2_LIB.BASEBOARD_FAB2(SCH_1):PAGE96
  U4C2    5     B2 GTL2014_SM-IC,D66151-001    I46 @BASEBOARD_FAB2_LIB.BASEBOARD_FAB2(SCH_1):PAGE96

RST_CPU1_LVC3_N @BASEBOARD_FAB2_LIB.BASEBOARD_FAB2(SCH_1):RST_CPU1_LVC3_N
  U4C2   10     A2 GTL2014_SM-IC,D66151-001    I46 @BASEBOARD_FAB2_LIB.BASEBOARD_FAB2(SCH_1):PAGE96
 R3P35    2      B RES_0402-0.0,5%,1/16W,CHIP,G21A   I117 @BASEBOARD_FAB2_LIB.BASEBOARD_FAB2(SCH_1):PAGE190

RST_CPU1_LVC3_R1_N @BASEBOARD_FAB2_LIB.BASEBOARD_FAB2(SCH_1):RST_CPU1_LVC3_R1_N
 R3P35    1      A RES_0402-0.0,5%,1/16W,CHIP,G21A   I117 @BASEBOARD_FAB2_LIB.BASEBOARD_FAB2(SCH_1):PAGE190
  U8D7  N10  PB19C LCMXO2_A_256BGA-IC,H63395-001   I179 @BASEBOARD_FAB2_LIB.BASEBOARD_FAB2(SCH_1):PAGE190

RST_HFI0_CPU0_LVT2_N @BASEBOARD_FAB2_LIB.BASEBOARD_FAB2(SCH_1):RST_HFI0_CPU0_LVT2_N
  U5D1 BN24 CD_HFI0_RESET_N SKX_EXT_B_BGA1-IC,TBD    I61 @BASEBOARD_FAB2_LIB.BASEBOARD_FAB2(SCH_1):PAGE29
  J8B1    6    IO6 SCONN24_H46321001_SM-SCONN,H46A     I1 @BASEBOARD_FAB2_LIB.BASEBOARD_FAB2(SCH_1):PAGE91
  R8B8    2      B RES_0402-4.75K,1%,1/16W,CHIP,GA    I14 @BASEBOARD_FAB2_LIB.BASEBOARD_FAB2(SCH_1):PAGE91

RST_HFI1_CPU0_LVT2_N @BASEBOARD_FAB2_LIB.BASEBOARD_FAB2(SCH_1):RST_HFI1_CPU0_LVT2_N
  U5D1 BK23 CD_HFI1_RESET_N SKX_EXT_B_BGA1-IC,TBD    I61 @BASEBOARD_FAB2_LIB.BASEBOARD_FAB2(SCH_1):PAGE29
  J8B1   14   IO14 SCONN24_H46321001_SM-SCONN,H46A     I1 @BASEBOARD_FAB2_LIB.BASEBOARD_FAB2(SCH_1):PAGE91
 R8B16    2      B RES_0402-4.75K,1%,1/16W,CHIP,GA    I17 @BASEBOARD_FAB2_LIB.BASEBOARD_FAB2(SCH_1):PAGE91

RST_PCH_SYSRST_BTN_OUT_N @BASEBOARD_FAB2_LIB.BASEBOARD_FAB2(SCH_1):RST_PCH_SYSRST_BTN_OUT_N
  U7C1  AD3 GPP_A18 LBG_CORE_QAT_EXT_D_BGA1-IC,H91A   I115 @BASEBOARD_FAB2_LIB.BASEBOARD_FAB2(SCH_1):PAGE119
  R2U2    2      B RES_0402-4.75K,1%,1/16W,CHIP,GA   I265 @BASEBOARD_FAB2_LIB.BASEBOARD_FAB2(SCH_1):PAGE156
  U8G1    1     1A TTL2G07_SOT23LF-74LVC2G07,IC,DB   I269 @BASEBOARD_FAB2_LIB.BASEBOARD_FAB2(SCH_1):PAGE156

RST_PCIE_CPU_DEV0_N @BASEBOARD_FAB2_LIB.BASEBOARD_FAB2(SCH_1):RST_PCIE_CPU_DEV0_N
 R1M14    1      A RES_0402-200.0,1%,1/16W,CHIP,GA   I220 @BASEBOARD_FAB2_LIB.BASEBOARD_FAB2(SCH_1):PAGE186
  U8D7   D6  PT12A LCMXO2_A_256BGA-IC,H63395-001    I59 @BASEBOARD_FAB2_LIB.BASEBOARD_FAB2(SCH_1):PAGE191

RST_PCIE_CPU_DEV0_R_N @BASEBOARD_FAB2_LIB.BASEBOARD_FAB2(SCH_1):RST_PCIE_CPU_DEV0_R_N
 R1M14    2      B RES_0402-200.0,1%,1/16W,CHIP,GA   I220 @BASEBOARD_FAB2_LIB.BASEBOARD_FAB2(SCH_1):PAGE186
  J9B3   33   IO33 SCONN120_A28699018_SM-SCONN,A2A   I336 @BASEBOARD_FAB2_LIB.BASEBOARD_FAB2(SCH_1):PAGE186

RST_PCIE_CPU_DEV1_N @BASEBOARD_FAB2_LIB.BASEBOARD_FAB2(SCH_1):RST_PCIE_CPU_DEV1_N
 R9E10    2      B RES_0402-200.0,1%,1/16W,CHIP,GA   I145 @BASEBOARD_FAB2_LIB.BASEBOARD_FAB2(SCH_1):PAGE187
  U8D7   C1   PL2C LCMXO2_A_256BGA-IC,H63395-001   I179 @BASEBOARD_FAB2_LIB.BASEBOARD_FAB2(SCH_1):PAGE190

RST_PCIE_CPU_DEV1_R_N @BASEBOARD_FAB2_LIB.BASEBOARD_FAB2(SCH_1):RST_PCIE_CPU_DEV1_R_N
  J8E3   75   IO75 SCONN80_E67482007_SM-CONN,E674A   I119 @BASEBOARD_FAB2_LIB.BASEBOARD_FAB2(SCH_1):PAGE187
 R9E10    1      A RES_0402-200.0,1%,1/16W,CHIP,GA   I145 @BASEBOARD_FAB2_LIB.BASEBOARD_FAB2(SCH_1):PAGE187

RST_PCIE_CPU_DEV2_N @BASEBOARD_FAB2_LIB.BASEBOARD_FAB2(SCH_1):RST_PCIE_CPU_DEV2_N
 R9E11    2      B RES_0402-200.0,1%,1/16W,CHIP,GA   I150 @BASEBOARD_FAB2_LIB.BASEBOARD_FAB2(SCH_1):PAGE187
  U8D7   H3   PL7A LCMXO2_A_256BGA-IC,H63395-001   I179 @BASEBOARD_FAB2_LIB.BASEBOARD_FAB2(SCH_1):PAGE190

RST_PCIE_CPU_DEV2_R_N @BASEBOARD_FAB2_LIB.BASEBOARD_FAB2(SCH_1):RST_PCIE_CPU_DEV2_R_N
  J8E3   77   IO77 SCONN80_E67482007_SM-CONN,E674A   I119 @BASEBOARD_FAB2_LIB.BASEBOARD_FAB2(SCH_1):PAGE187
 R9E11    1      A RES_0402-200.0,1%,1/16W,CHIP,GA   I150 @BASEBOARD_FAB2_LIB.BASEBOARD_FAB2(SCH_1):PAGE187

RST_PCIE_CPU_DEV3_N @BASEBOARD_FAB2_LIB.BASEBOARD_FAB2(SCH_1):RST_PCIE_CPU_DEV3_N
 R9E12    2      B RES_0402-200.0,1%,1/16W,CHIP,GA   I153 @BASEBOARD_FAB2_LIB.BASEBOARD_FAB2(SCH_1):PAGE187
  U8D7   H1   PL7B LCMXO2_A_256BGA-IC,H63395-001   I179 @BASEBOARD_FAB2_LIB.BASEBOARD_FAB2(SCH_1):PAGE190

RST_PCIE_CPU_DEV3_R_N @BASEBOARD_FAB2_LIB.BASEBOARD_FAB2(SCH_1):RST_PCIE_CPU_DEV3_R_N
  J8E3   79   IO79 SCONN80_E67482007_SM-CONN,E674A   I119 @BASEBOARD_FAB2_LIB.BASEBOARD_FAB2(SCH_1):PAGE187
 R9E12    1      A RES_0402-200.0,1%,1/16W,CHIP,GA   I153 @BASEBOARD_FAB2_LIB.BASEBOARD_FAB2(SCH_1):PAGE187

RST_PCIE_M2_DEV_N @BASEBOARD_FAB2_LIB.BASEBOARD_FAB2(SCH_1):RST_PCIE_M2_DEV_N
  J8F1   50 PERST_N_NC SCONN75K_H17033002_SMT1-SCONN,A    I53 @BASEBOARD_FAB2_LIB.BASEBOARD_FAB2(SCH_1):PAGE185
  U8D7   R6   PB6B LCMXO2_A_256BGA-IC,H63395-001   I179 @BASEBOARD_FAB2_LIB.BASEBOARD_FAB2(SCH_1):PAGE190

RST_PCIE_MIDPLANE_N @BASEBOARD_FAB2_LIB.BASEBOARD_FAB2(SCH_1):RST_PCIE_MIDPLANE_N
  J1F1   I5  GNDI5 CONN76_H22707001_THMT1-CONN,H2A   I111 @BASEBOARD_FAB2_LIB.BASEBOARD_FAB2(SCH_1):PAGE181
  U8D7   D9  PT18B LCMXO2_A_256BGA-IC,H63395-001    I59 @BASEBOARD_FAB2_LIB.BASEBOARD_FAB2(SCH_1):PAGE191

RST_PCIE_PCH_PERST_N @BASEBOARD_FAB2_LIB.BASEBOARD_FAB2(SCH_1):RST_PCIE_PCH_PERST_N
  U7C1  AH4 GPP_K10_PE_RST_N LBG_CORE_QAT_EXT_D_BGA1-IC,H91A    I34 @BASEBOARD_FAB2_LIB.BASEBOARD_FAB2(SCH_1):PAGE121
  U8D7   B1   PL1C LCMXO2_A_256BGA-IC,H63395-001   I179 @BASEBOARD_FAB2_LIB.BASEBOARD_FAB2(SCH_1):PAGE190

RST_PCIE_RISER1_PERST_N @BASEBOARD_FAB2_LIB.BASEBOARD_FAB2(SCH_1):RST_PCIE_RISER1_PERST_N
 R2U37    1      A RES_0402-0.0,5%,1/16W,CHIP,G21A   I173 @BASEBOARD_FAB2_LIB.BASEBOARD_FAB2(SCH_1):PAGE108
  U8D7   M3  PL13A LCMXO2_A_256BGA-IC,H63395-001   I179 @BASEBOARD_FAB2_LIB.BASEBOARD_FAB2(SCH_1):PAGE190

RST_PCIE_RISER1_PERST_R_N @BASEBOARD_FAB2_LIB.BASEBOARD_FAB2(SCH_1):RST_PCIE_RISER1_PERST_R_N
 R2U37    2      B RES_0402-0.0,5%,1/16W,CHIP,G21A   I173 @BASEBOARD_FAB2_LIB.BASEBOARD_FAB2(SCH_1):PAGE108
  J8G1   29   IO29 SCONN200_H68296001_SM-CONN,H68A   I258 @BASEBOARD_FAB2_LIB.BASEBOARD_FAB2(SCH_1):PAGE108

RST_PLTRST_BUF_N @BASEBOARD_FAB2_LIB.BASEBOARD_FAB2(SCH_1):RST_PLTRST_BUF_N
  Q8D2    1   GATE FET_N_SOT23-2N7002,FET,C79254-A     I4 @BASEBOARD_FAB2_LIB.BASEBOARD_FAB2(SCH_1):PAGE134
  J8E1    2    IO2 SCONN11_H67026001_SM-CONN,H670A    I87 @BASEBOARD_FAB2_LIB.BASEBOARD_FAB2(SCH_1):PAGE184
  U8D7  K11  PR12C LCMXO2_A_256BGA-IC,H63395-001    I59 @BASEBOARD_FAB2_LIB.BASEBOARD_FAB2(SCH_1):PAGE191
R25W62    1      A RES_0402-100.0K,1%,1/16W,CHIP,A    I31 @BASEBOARD_FAB2_LIB.BASEBOARD_FAB2(SCH_1):PAGE145
R25W74    1      A RES_0402-0.0,5%,1/16W,CHIP,G21A    I70 @BASEBOARD_FAB2_LIB.BASEBOARD_FAB2(SCH_1):PAGE146
 U25W4  L20 PERST# AST2520A1-GP-GP_ASIC2-GB1-AST2A   I117 @BASEBOARD_FAB2_LIB.BASEBOARD_FAB2(SCH_1):PAGE145

RST_PLTRST_N @BASEBOARD_FAB2_LIB.BASEBOARD_FAB2(SCH_1):RST_PLTRST_N
  U7C1 BN18 GPP_B13_PLTRST_N LBG_CORE_QAT_EXT_D_BGA1-IC,H91A   I115 @BASEBOARD_FAB2_LIB.BASEBOARD_FAB2(SCH_1):PAGE119
  Q8E1    1   GATE FET_N_SOT23LF-2N7002,FET,C7925A   I134 @BASEBOARD_FAB2_LIB.BASEBOARD_FAB2(SCH_1):PAGE136
  R1R1    1      A RES_0402-0.0,5%,1/16W,CHIP,G21A   I195 @BASEBOARD_FAB2_LIB.BASEBOARD_FAB2(SCH_1):PAGE139
  U8D7  E15   PR1B LCMXO2_A_256BGA-IC,H63395-001    I59 @BASEBOARD_FAB2_LIB.BASEBOARD_FAB2(SCH_1):PAGE191

RST_PLTRST_SPRV_R_N @BASEBOARD_FAB2_LIB.BASEBOARD_FAB2(SCH_1):RST_PLTRST_SPRV_R_N
 EU9E1   17 PE_RST_N SPRINGVILLE_SM1-IC,G47144-004    I72 @BASEBOARD_FAB2_LIB.BASEBOARD_FAB2(SCH_1):PAGE139
  R1R1    2      B RES_0402-0.0,5%,1/16W,CHIP,G21A   I195 @BASEBOARD_FAB2_LIB.BASEBOARD_FAB2(SCH_1):PAGE139
  R9E4    2      B RES_0402-10.0K,1%,1/16W,CHIP,GA   I200 @BASEBOARD_FAB2_LIB.BASEBOARD_FAB2(SCH_1):PAGE139

RST_PLTRST_TOP_SWAP @BASEBOARD_FAB2_LIB.BASEBOARD_FAB2(SCH_1):RST_PLTRST_TOP_SWAP
  U8E3    1     OE TTL1G126_A_SOT-74HC1G126,IC,A7B   I130 @BASEBOARD_FAB2_LIB.BASEBOARD_FAB2(SCH_1):PAGE136
 R8E14    2      B RES_0402-4.75K,1%,1/16W,CHIP,GA   I133 @BASEBOARD_FAB2_LIB.BASEBOARD_FAB2(SCH_1):PAGE136
  Q8E1    3    DRN FET_N_SOT23LF-2N7002,FET,C7925A   I134 @BASEBOARD_FAB2_LIB.BASEBOARD_FAB2(SCH_1):PAGE136

RST_RSMRST_DLY @BASEBOARD_FAB2_LIB.BASEBOARD_FAB2(SCH_1):RST_RSMRST_DLY
  Q8E2    1   GATE FET_N_SOT23LF-2N7002,FET,C7925A    I13 @BASEBOARD_FAB2_LIB.BASEBOARD_FAB2(SCH_1):PAGE126
  U8D7   M1 PL12B_PCLKC3_0 LCMXO2_A_256BGA-IC,H63395-001   I179 @BASEBOARD_FAB2_LIB.BASEBOARD_FAB2(SCH_1):PAGE190

RST_RSMRST_N @BASEBOARD_FAB2_LIB.BASEBOARD_FAB2(SCH_1):RST_RSMRST_N
 R9A15    1      A RES_0402-1.00K,1%,1/16W,CHIP,GA    I60 @BASEBOARD_FAB2_LIB.BASEBOARD_FAB2(SCH_1):PAGE111
  U7C1  P15 RSMRST_N LBG_CORE_QAT_EXT_D_BGA1-IC,H91A    I73 @BASEBOARD_FAB2_LIB.BASEBOARD_FAB2(SCH_1):PAGE118
  R2R2    2      B RES_0402-33.2,1%,1/16W,CHIP,G2A   I338 @BASEBOARD_FAB2_LIB.BASEBOARD_FAB2(SCH_1):PAGE190
 R7E18    2      B RES_0402-4.75K,1%,1/16W,CHIP,GA    I55 @BASEBOARD_FAB2_LIB.BASEBOARD_FAB2(SCH_1):PAGE192

RST_RSMRST_R_N @BASEBOARD_FAB2_LIB.BASEBOARD_FAB2(SCH_1):RST_RSMRST_R_N
  U8D7   G4   PL4D LCMXO2_A_256BGA-IC,H63395-001   I179 @BASEBOARD_FAB2_LIB.BASEBOARD_FAB2(SCH_1):PAGE190
  R2R2    1      A RES_0402-33.2,1%,1/16W,CHIP,G2A   I338 @BASEBOARD_FAB2_LIB.BASEBOARD_FAB2(SCH_1):PAGE190

RST_RTCRST_N @BASEBOARD_FAB2_LIB.BASEBOARD_FAB2(SCH_1):RST_RTCRST_N
  U7C1  P11 RTCRST_N LBG_CORE_QAT_EXT_D_BGA1-IC,H91A    I34 @BASEBOARD_FAB2_LIB.BASEBOARD_FAB2(SCH_1):PAGE121
 R7C11    2      B RES_0402-1.0M,1%,1/16W,EMPTY,GA    I11 @BASEBOARD_FAB2_LIB.BASEBOARD_FAB2(SCH_1):PAGE137
 R7C10    2      B RES_0402-20.0K,1%,1/16W,CHIP,GA    I13 @BASEBOARD_FAB2_LIB.BASEBOARD_FAB2(SCH_1):PAGE137
 C7C19    1      A CAP_A_0402V-1.0UF,6.3V,10%,X6SA    I14 @BASEBOARD_FAB2_LIB.BASEBOARD_FAB2(SCH_1):PAGE137
  J9G1    4    IO4 CONN12_C73564003_PIP-CONN,C735A   I128 @BASEBOARD_FAB2_LIB.BASEBOARD_FAB2(SCH_1):PAGE137

RST_SRTCRST_N @BASEBOARD_FAB2_LIB.BASEBOARD_FAB2(SCH_1):RST_SRTCRST_N
  U7C1  G18 SRTCRST_N LBG_CORE_QAT_EXT_D_BGA1-IC,H91A    I34 @BASEBOARD_FAB2_LIB.BASEBOARD_FAB2(SCH_1):PAGE121
  R3N4    2      B RES_0402-20.0K,1%,1/16W,CHIP,GA    I19 @BASEBOARD_FAB2_LIB.BASEBOARD_FAB2(SCH_1):PAGE137
 C3N32    1      A CAP_A_0402V-1.0UF,6.3V,10%,X6SA    I20 @BASEBOARD_FAB2_LIB.BASEBOARD_FAB2(SCH_1):PAGE137

RST_SYSTEM_BTN_BUF_N @BASEBOARD_FAB2_LIB.BASEBOARD_FAB2(SCH_1):RST_SYSTEM_BTN_BUF_N
  U9A3    4   Y<0> TTL2G14_SMLF-74LVC2G14,IC,D184B    I15 @BASEBOARD_FAB2_LIB.BASEBOARD_FAB2(SCH_1):PAGE175
  R9A9    1      A RES_0402-100.0,1%,1/16W,CHIP,GA    I35 @BASEBOARD_FAB2_LIB.BASEBOARD_FAB2(SCH_1):PAGE175

RST_SYSTEM_BTN_N @BASEBOARD_FAB2_LIB.BASEBOARD_FAB2(SCH_1):RST_SYSTEM_BTN_N
  U7C1 BL11 GPP_B10_SRCCLKREQ5_N LBG_CORE_QAT_EXT_D_BGA1-IC,H91A   I115 @BASEBOARD_FAB2_LIB.BASEBOARD_FAB2(SCH_1):PAGE119
  R9A9    2      B RES_0402-100.0,1%,1/16W,CHIP,GA    I35 @BASEBOARD_FAB2_LIB.BASEBOARD_FAB2(SCH_1):PAGE175
 U25W4  B20 GPIOE0_NCTS3 AST2520A1-GP-GP_ASIC2-GB1-AST2A   I117 @BASEBOARD_FAB2_LIB.BASEBOARD_FAB2(SCH_1):PAGE145

SATA6G_P0_RX_C_DN @BASEBOARD_FAB2_LIB.BASEBOARD_FAB2(SCH_1):SATA6G_P0_RX_C_DN
  J8A1  1B5 RXA0_DN CONN72_G97614002_A_CP-CONN,G97A   I163 @BASEBOARD_FAB2_LIB.BASEBOARD_FAB2(SCH_1):PAGE173
 C2L17    2      B CAP_A_0402V-0.01UF,25V,10%,X7RA   I174 @BASEBOARD_FAB2_LIB.BASEBOARD_FAB2(SCH_1):PAGE173

SATA6G_P0_RX_C_DP @BASEBOARD_FAB2_LIB.BASEBOARD_FAB2(SCH_1):SATA6G_P0_RX_C_DP
  J8A1  1B4 RXA0_DP CONN72_G97614002_A_CP-CONN,G97A   I163 @BASEBOARD_FAB2_LIB.BASEBOARD_FAB2(SCH_1):PAGE173
 C2L19    2      B CAP_A_0402V-0.01UF,25V,10%,X7RA   I172 @BASEBOARD_FAB2_LIB.BASEBOARD_FAB2(SCH_1):PAGE173

SATA6G_P0_TX_C_DN @BASEBOARD_FAB2_LIB.BASEBOARD_FAB2(SCH_1):SATA6G_P0_TX_C_DN
  J8A1  1D5 TXA0_DN CONN72_G97614002_A_CP-CONN,G97A   I163 @BASEBOARD_FAB2_LIB.BASEBOARD_FAB2(SCH_1):PAGE173
 C2L40    1      A CAP_A_0402V-0.01UF,25V,10%,X7RA   I220 @BASEBOARD_FAB2_LIB.BASEBOARD_FAB2(SCH_1):PAGE173

SATA6G_P0_TX_C_DP @BASEBOARD_FAB2_LIB.BASEBOARD_FAB2(SCH_1):SATA6G_P0_TX_C_DP
  J8A1  1D4 TXA0_DP CONN72_G97614002_A_CP-CONN,G97A   I163 @BASEBOARD_FAB2_LIB.BASEBOARD_FAB2(SCH_1):PAGE173
 C2L39    1      A CAP_A_0402V-0.01UF,25V,10%,X7RA   I221 @BASEBOARD_FAB2_LIB.BASEBOARD_FAB2(SCH_1):PAGE173

SATA6G_P10_RX_C_DN @BASEBOARD_FAB2_LIB.BASEBOARD_FAB2(SCH_1):SATA6G_P10_RX_C_DN
  J8A2   B8 RXA2_DN CONN36_G97614001_CP-CONN,G9761A    I26 @BASEBOARD_FAB2_LIB.BASEBOARD_FAB2(SCH_1):PAGE174
 C2L36    2      B CAP_A_0402V-0.01UF,25V,10%,X7RA    I39 @BASEBOARD_FAB2_LIB.BASEBOARD_FAB2(SCH_1):PAGE174

SATA6G_P10_RX_C_DP @BASEBOARD_FAB2_LIB.BASEBOARD_FAB2(SCH_1):SATA6G_P10_RX_C_DP
  J8A2   B7 RXA2_DP CONN36_G97614001_CP-CONN,G9761A    I26 @BASEBOARD_FAB2_LIB.BASEBOARD_FAB2(SCH_1):PAGE174
 C2L35    2      B CAP_A_0402V-0.01UF,25V,10%,X7RA    I31 @BASEBOARD_FAB2_LIB.BASEBOARD_FAB2(SCH_1):PAGE174

SATA6G_P10_TX_C_DN @BASEBOARD_FAB2_LIB.BASEBOARD_FAB2(SCH_1):SATA6G_P10_TX_C_DN
 C1L13    1      A CAP_A_0402V-0.01UF,25V,10%,X7RA    I14 @BASEBOARD_FAB2_LIB.BASEBOARD_FAB2(SCH_1):PAGE174
  J8A2   D8 TXA2_DN CONN36_G97614001_CP-CONN,G9761A    I26 @BASEBOARD_FAB2_LIB.BASEBOARD_FAB2(SCH_1):PAGE174

SATA6G_P10_TX_C_DP @BASEBOARD_FAB2_LIB.BASEBOARD_FAB2(SCH_1):SATA6G_P10_TX_C_DP
 C1L12    1      A CAP_A_0402V-0.01UF,25V,10%,X7RA    I19 @BASEBOARD_FAB2_LIB.BASEBOARD_FAB2(SCH_1):PAGE174
  J8A2   D7 TXA2_DP CONN36_G97614001_CP-CONN,G9761A    I26 @BASEBOARD_FAB2_LIB.BASEBOARD_FAB2(SCH_1):PAGE174

SATA6G_P11_RX_C_DN @BASEBOARD_FAB2_LIB.BASEBOARD_FAB2(SCH_1):SATA6G_P11_RX_C_DN
  J8A2   A8 RXA3_DN CONN36_G97614001_CP-CONN,G9761A    I26 @BASEBOARD_FAB2_LIB.BASEBOARD_FAB2(SCH_1):PAGE174
 C2L34    2      B CAP_A_0402V-0.01UF,25V,10%,X7RA    I41 @BASEBOARD_FAB2_LIB.BASEBOARD_FAB2(SCH_1):PAGE174

SATA6G_P11_RX_C_DP @BASEBOARD_FAB2_LIB.BASEBOARD_FAB2(SCH_1):SATA6G_P11_RX_C_DP
  J8A2   A7 RXA3_DP CONN36_G97614001_CP-CONN,G9761A    I26 @BASEBOARD_FAB2_LIB.BASEBOARD_FAB2(SCH_1):PAGE174
 C2L33    2      B CAP_A_0402V-0.01UF,25V,10%,X7RA    I40 @BASEBOARD_FAB2_LIB.BASEBOARD_FAB2(SCH_1):PAGE174

SATA6G_P11_TX_C_DN @BASEBOARD_FAB2_LIB.BASEBOARD_FAB2(SCH_1):SATA6G_P11_TX_C_DN
 C1L15    1      A CAP_A_0402V-0.01UF,25V,10%,X7RA    I18 @BASEBOARD_FAB2_LIB.BASEBOARD_FAB2(SCH_1):PAGE174
  J8A2   C8 TXA3_DN CONN36_G97614001_CP-CONN,G9761A    I26 @BASEBOARD_FAB2_LIB.BASEBOARD_FAB2(SCH_1):PAGE174

SATA6G_P11_TX_C_DP @BASEBOARD_FAB2_LIB.BASEBOARD_FAB2(SCH_1):SATA6G_P11_TX_C_DP
 C1L14    1      A CAP_A_0402V-0.01UF,25V,10%,X7RA    I20 @BASEBOARD_FAB2_LIB.BASEBOARD_FAB2(SCH_1):PAGE174
  J8A2   C7 TXA3_DP CONN36_G97614001_CP-CONN,G9761A    I26 @BASEBOARD_FAB2_LIB.BASEBOARD_FAB2(SCH_1):PAGE174

SATA6G_P1_RX_C_DN @BASEBOARD_FAB2_LIB.BASEBOARD_FAB2(SCH_1):SATA6G_P1_RX_C_DN
  J8A1  1A5 RXA1_DN CONN72_G97614002_A_CP-CONN,G97A   I163 @BASEBOARD_FAB2_LIB.BASEBOARD_FAB2(SCH_1):PAGE173
  C2L6    2      B CAP_A_0402V-0.01UF,25V,10%,X7RA   I166 @BASEBOARD_FAB2_LIB.BASEBOARD_FAB2(SCH_1):PAGE173

SATA6G_P1_RX_C_DP @BASEBOARD_FAB2_LIB.BASEBOARD_FAB2(SCH_1):SATA6G_P1_RX_C_DP
  J8A1  1A4 RXA1_DP CONN72_G97614002_A_CP-CONN,G97A   I163 @BASEBOARD_FAB2_LIB.BASEBOARD_FAB2(SCH_1):PAGE173
 C2L10    2      B CAP_A_0402V-0.01UF,25V,10%,X7RA   I173 @BASEBOARD_FAB2_LIB.BASEBOARD_FAB2(SCH_1):PAGE173

SATA6G_P1_TX_C_DN @BASEBOARD_FAB2_LIB.BASEBOARD_FAB2(SCH_1):SATA6G_P1_TX_C_DN
  J8A1  1C5 TXA1_DN CONN72_G97614002_A_CP-CONN,G97A   I163 @BASEBOARD_FAB2_LIB.BASEBOARD_FAB2(SCH_1):PAGE173
 C2L44    1      A CAP_A_0402V-0.01UF,25V,10%,X7RA   I228 @BASEBOARD_FAB2_LIB.BASEBOARD_FAB2(SCH_1):PAGE173

SATA6G_P1_TX_C_DP @BASEBOARD_FAB2_LIB.BASEBOARD_FAB2(SCH_1):SATA6G_P1_TX_C_DP
  J8A1  1C4 TXA1_DP CONN72_G97614002_A_CP-CONN,G97A   I163 @BASEBOARD_FAB2_LIB.BASEBOARD_FAB2(SCH_1):PAGE173
 C2L43    1      A CAP_A_0402V-0.01UF,25V,10%,X7RA   I222 @BASEBOARD_FAB2_LIB.BASEBOARD_FAB2(SCH_1):PAGE173

SATA6G_P2_RX_C_DN @BASEBOARD_FAB2_LIB.BASEBOARD_FAB2(SCH_1):SATA6G_P2_RX_C_DN
  J8A1  1B8 RXA2_DN CONN72_G97614002_A_CP-CONN,G97A   I163 @BASEBOARD_FAB2_LIB.BASEBOARD_FAB2(SCH_1):PAGE173
 C2L13    2      B CAP_A_0402V-0.01UF,25V,10%,X7RA   I165 @BASEBOARD_FAB2_LIB.BASEBOARD_FAB2(SCH_1):PAGE173

SATA6G_P2_RX_C_DP @BASEBOARD_FAB2_LIB.BASEBOARD_FAB2(SCH_1):SATA6G_P2_RX_C_DP
  J8A1  1B7 RXA2_DP CONN72_G97614002_A_CP-CONN,G97A   I163 @BASEBOARD_FAB2_LIB.BASEBOARD_FAB2(SCH_1):PAGE173
 C2L15    2      B CAP_A_0402V-0.01UF,25V,10%,X7RA   I191 @BASEBOARD_FAB2_LIB.BASEBOARD_FAB2(SCH_1):PAGE173

SATA6G_P2_TX_C_DN @BASEBOARD_FAB2_LIB.BASEBOARD_FAB2(SCH_1):SATA6G_P2_TX_C_DN
  J8A1  1D8 TXA2_DN CONN72_G97614002_A_CP-CONN,G97A   I163 @BASEBOARD_FAB2_LIB.BASEBOARD_FAB2(SCH_1):PAGE173
 C2L42    1      A CAP_A_0402V-0.01UF,25V,10%,X7RA   I233 @BASEBOARD_FAB2_LIB.BASEBOARD_FAB2(SCH_1):PAGE173

SATA6G_P2_TX_C_DP @BASEBOARD_FAB2_LIB.BASEBOARD_FAB2(SCH_1):SATA6G_P2_TX_C_DP
  J8A1  1D7 TXA2_DP CONN72_G97614002_A_CP-CONN,G97A   I163 @BASEBOARD_FAB2_LIB.BASEBOARD_FAB2(SCH_1):PAGE173
 C2L41    1      A CAP_A_0402V-0.01UF,25V,10%,X7RA   I242 @BASEBOARD_FAB2_LIB.BASEBOARD_FAB2(SCH_1):PAGE173

SATA6G_P3_RX_C_DN @BASEBOARD_FAB2_LIB.BASEBOARD_FAB2(SCH_1):SATA6G_P3_RX_C_DN
  J8A1  1A8 RXA3_DN CONN72_G97614002_A_CP-CONN,G97A   I163 @BASEBOARD_FAB2_LIB.BASEBOARD_FAB2(SCH_1):PAGE173
  C2L3    2      B CAP_A_0402V-0.01UF,25V,10%,X7RA   I194 @BASEBOARD_FAB2_LIB.BASEBOARD_FAB2(SCH_1):PAGE173

SATA6G_P3_RX_C_DP @BASEBOARD_FAB2_LIB.BASEBOARD_FAB2(SCH_1):SATA6G_P3_RX_C_DP
  J8A1  1A7 RXA3_DP CONN72_G97614002_A_CP-CONN,G97A   I163 @BASEBOARD_FAB2_LIB.BASEBOARD_FAB2(SCH_1):PAGE173
  C2L4    2      B CAP_A_0402V-0.01UF,25V,10%,X7RA   I192 @BASEBOARD_FAB2_LIB.BASEBOARD_FAB2(SCH_1):PAGE173

SATA6G_P3_TX_C_DN @BASEBOARD_FAB2_LIB.BASEBOARD_FAB2(SCH_1):SATA6G_P3_TX_C_DN
  J8A1  1C8 TXA3_DN CONN72_G97614002_A_CP-CONN,G97A   I163 @BASEBOARD_FAB2_LIB.BASEBOARD_FAB2(SCH_1):PAGE173
 C2L22    1      A CAP_A_0402V-0.01UF,25V,10%,X7RA   I234 @BASEBOARD_FAB2_LIB.BASEBOARD_FAB2(SCH_1):PAGE173

SATA6G_P3_TX_C_DP @BASEBOARD_FAB2_LIB.BASEBOARD_FAB2(SCH_1):SATA6G_P3_TX_C_DP
  J8A1  1C7 TXA3_DP CONN72_G97614002_A_CP-CONN,G97A   I163 @BASEBOARD_FAB2_LIB.BASEBOARD_FAB2(SCH_1):PAGE173
 C2L23    1      A CAP_A_0402V-0.01UF,25V,10%,X7RA   I241 @BASEBOARD_FAB2_LIB.BASEBOARD_FAB2(SCH_1):PAGE173

SATA6G_P4_RX_C_DN @BASEBOARD_FAB2_LIB.BASEBOARD_FAB2(SCH_1):SATA6G_P4_RX_C_DN
  J8A1  2B5 RXB0_DN CONN72_G97614002_A_CP-CONN,G97A   I163 @BASEBOARD_FAB2_LIB.BASEBOARD_FAB2(SCH_1):PAGE173
 C2L18    2      B CAP_A_0402V-0.01UF,25V,10%,X7RA   I197 @BASEBOARD_FAB2_LIB.BASEBOARD_FAB2(SCH_1):PAGE173

SATA6G_P4_RX_C_DP @BASEBOARD_FAB2_LIB.BASEBOARD_FAB2(SCH_1):SATA6G_P4_RX_C_DP
  J8A1  2B4 RXB0_DP CONN72_G97614002_A_CP-CONN,G97A   I163 @BASEBOARD_FAB2_LIB.BASEBOARD_FAB2(SCH_1):PAGE173
 C2L20    2      B CAP_A_0402V-0.01UF,25V,10%,X7RA   I195 @BASEBOARD_FAB2_LIB.BASEBOARD_FAB2(SCH_1):PAGE173

SATA6G_P4_TX_C_DN @BASEBOARD_FAB2_LIB.BASEBOARD_FAB2(SCH_1):SATA6G_P4_TX_C_DN
  J8A1  2D5 TXB0_DN CONN72_G97614002_A_CP-CONN,G97A   I163 @BASEBOARD_FAB2_LIB.BASEBOARD_FAB2(SCH_1):PAGE173
 C2L37    1      A CAP_A_0402V-0.01UF,25V,10%,X7RA   I238 @BASEBOARD_FAB2_LIB.BASEBOARD_FAB2(SCH_1):PAGE173

SATA6G_P4_TX_C_DP @BASEBOARD_FAB2_LIB.BASEBOARD_FAB2(SCH_1):SATA6G_P4_TX_C_DP
  J8A1  2D4 TXB0_DP CONN72_G97614002_A_CP-CONN,G97A   I163 @BASEBOARD_FAB2_LIB.BASEBOARD_FAB2(SCH_1):PAGE173
 C2L47    1      A CAP_A_0402V-0.01UF,25V,10%,X7RA   I239 @BASEBOARD_FAB2_LIB.BASEBOARD_FAB2(SCH_1):PAGE173

SATA6G_P5_RX_C_DN @BASEBOARD_FAB2_LIB.BASEBOARD_FAB2(SCH_1):SATA6G_P5_RX_C_DN
  J8A1  2A5 RXB1_DN CONN72_G97614002_A_CP-CONN,G97A   I163 @BASEBOARD_FAB2_LIB.BASEBOARD_FAB2(SCH_1):PAGE173
  C2L9    2      B CAP_A_0402V-0.01UF,25V,10%,X7RA   I207 @BASEBOARD_FAB2_LIB.BASEBOARD_FAB2(SCH_1):PAGE173

SATA6G_P5_RX_C_DP @BASEBOARD_FAB2_LIB.BASEBOARD_FAB2(SCH_1):SATA6G_P5_RX_C_DP
  J8A1  2A4 RXB1_DP CONN72_G97614002_A_CP-CONN,G97A   I163 @BASEBOARD_FAB2_LIB.BASEBOARD_FAB2(SCH_1):PAGE173
 C2L12    2      B CAP_A_0402V-0.01UF,25V,10%,X7RA   I196 @BASEBOARD_FAB2_LIB.BASEBOARD_FAB2(SCH_1):PAGE173

SATA6G_P5_TX_C_DN @BASEBOARD_FAB2_LIB.BASEBOARD_FAB2(SCH_1):SATA6G_P5_TX_C_DN
  J8A1  2C5 TXB1_DN CONN72_G97614002_A_CP-CONN,G97A   I163 @BASEBOARD_FAB2_LIB.BASEBOARD_FAB2(SCH_1):PAGE173
 C2L26    1      A CAP_A_0402V-0.01UF,25V,10%,X7RA   I255 @BASEBOARD_FAB2_LIB.BASEBOARD_FAB2(SCH_1):PAGE173

SATA6G_P5_TX_C_DP @BASEBOARD_FAB2_LIB.BASEBOARD_FAB2(SCH_1):SATA6G_P5_TX_C_DP
  J8A1  2C4 TXB1_DP CONN72_G97614002_A_CP-CONN,G97A   I163 @BASEBOARD_FAB2_LIB.BASEBOARD_FAB2(SCH_1):PAGE173
 C2L27    1      A CAP_A_0402V-0.01UF,25V,10%,X7RA   I240 @BASEBOARD_FAB2_LIB.BASEBOARD_FAB2(SCH_1):PAGE173

SATA6G_P6_RX_C_DN @BASEBOARD_FAB2_LIB.BASEBOARD_FAB2(SCH_1):SATA6G_P6_RX_C_DN
  J8A1  2B8 RXB2_DN CONN72_G97614002_A_CP-CONN,G97A   I163 @BASEBOARD_FAB2_LIB.BASEBOARD_FAB2(SCH_1):PAGE173
 C2L14    2      B CAP_A_0402V-0.01UF,25V,10%,X7RA   I208 @BASEBOARD_FAB2_LIB.BASEBOARD_FAB2(SCH_1):PAGE173

SATA6G_P6_RX_C_DP @BASEBOARD_FAB2_LIB.BASEBOARD_FAB2(SCH_1):SATA6G_P6_RX_C_DP
  J8A1  2B7 RXB2_DP CONN72_G97614002_A_CP-CONN,G97A   I163 @BASEBOARD_FAB2_LIB.BASEBOARD_FAB2(SCH_1):PAGE173
 C2L16    2      B CAP_A_0402V-0.01UF,25V,10%,X7RA   I205 @BASEBOARD_FAB2_LIB.BASEBOARD_FAB2(SCH_1):PAGE173

SATA6G_P6_TX_C_DN @BASEBOARD_FAB2_LIB.BASEBOARD_FAB2(SCH_1):SATA6G_P6_TX_C_DN
  J8A1  2D8 TXB2_DN CONN72_G97614002_A_CP-CONN,G97A   I163 @BASEBOARD_FAB2_LIB.BASEBOARD_FAB2(SCH_1):PAGE173
 C2L38    1      A CAP_A_0402V-0.01UF,25V,10%,X7RA   I256 @BASEBOARD_FAB2_LIB.BASEBOARD_FAB2(SCH_1):PAGE173

SATA6G_P6_TX_C_DP @BASEBOARD_FAB2_LIB.BASEBOARD_FAB2(SCH_1):SATA6G_P6_TX_C_DP
  J8A1  2D7 TXB2_DP CONN72_G97614002_A_CP-CONN,G97A   I163 @BASEBOARD_FAB2_LIB.BASEBOARD_FAB2(SCH_1):PAGE173
 C2L48    1      A CAP_A_0402V-0.01UF,25V,10%,X7RA   I257 @BASEBOARD_FAB2_LIB.BASEBOARD_FAB2(SCH_1):PAGE173

SATA6G_P7_RX_C_DN @BASEBOARD_FAB2_LIB.BASEBOARD_FAB2(SCH_1):SATA6G_P7_RX_C_DN
  J8A1  2A8 RXB3_DN CONN72_G97614002_A_CP-CONN,G97A   I163 @BASEBOARD_FAB2_LIB.BASEBOARD_FAB2(SCH_1):PAGE173
  C2L5    2      B CAP_A_0402V-0.01UF,25V,10%,X7RA   I209 @BASEBOARD_FAB2_LIB.BASEBOARD_FAB2(SCH_1):PAGE173

SATA6G_P7_RX_C_DP @BASEBOARD_FAB2_LIB.BASEBOARD_FAB2(SCH_1):SATA6G_P7_RX_C_DP
  J8A1  2A7 RXB3_DP CONN72_G97614002_A_CP-CONN,G97A   I163 @BASEBOARD_FAB2_LIB.BASEBOARD_FAB2(SCH_1):PAGE173
  C2L7    2      B CAP_A_0402V-0.01UF,25V,10%,X7RA   I206 @BASEBOARD_FAB2_LIB.BASEBOARD_FAB2(SCH_1):PAGE173

SATA6G_P7_TX_C_DN @BASEBOARD_FAB2_LIB.BASEBOARD_FAB2(SCH_1):SATA6G_P7_TX_C_DN
  J8A1  2C8 TXB3_DN CONN72_G97614002_A_CP-CONN,G97A   I163 @BASEBOARD_FAB2_LIB.BASEBOARD_FAB2(SCH_1):PAGE173
 C2L21    1      A CAP_A_0402V-0.01UF,25V,10%,X7RA   I259 @BASEBOARD_FAB2_LIB.BASEBOARD_FAB2(SCH_1):PAGE173

SATA6G_P7_TX_C_DP @BASEBOARD_FAB2_LIB.BASEBOARD_FAB2(SCH_1):SATA6G_P7_TX_C_DP
  J8A1  2C7 TXB3_DP CONN72_G97614002_A_CP-CONN,G97A   I163 @BASEBOARD_FAB2_LIB.BASEBOARD_FAB2(SCH_1):PAGE173
 C2L24    1      A CAP_A_0402V-0.01UF,25V,10%,X7RA   I258 @BASEBOARD_FAB2_LIB.BASEBOARD_FAB2(SCH_1):PAGE173

SATA6G_P8_RX_C_DN @BASEBOARD_FAB2_LIB.BASEBOARD_FAB2(SCH_1):SATA6G_P8_RX_C_DN
  J8A2   B5 RXA0_DN CONN36_G97614001_CP-CONN,G9761A    I26 @BASEBOARD_FAB2_LIB.BASEBOARD_FAB2(SCH_1):PAGE174
 C2L31    2      B CAP_A_0402V-0.01UF,25V,10%,X7RA    I29 @BASEBOARD_FAB2_LIB.BASEBOARD_FAB2(SCH_1):PAGE174

SATA6G_P8_RX_C_DP @BASEBOARD_FAB2_LIB.BASEBOARD_FAB2(SCH_1):SATA6G_P8_RX_C_DP
  J8A2   B4 RXA0_DP CONN36_G97614001_CP-CONN,G9761A    I26 @BASEBOARD_FAB2_LIB.BASEBOARD_FAB2(SCH_1):PAGE174
 C2L30    2      B CAP_A_0402V-0.01UF,25V,10%,X7RA    I28 @BASEBOARD_FAB2_LIB.BASEBOARD_FAB2(SCH_1):PAGE174

SATA6G_P8_TX_C_DN @BASEBOARD_FAB2_LIB.BASEBOARD_FAB2(SCH_1):SATA6G_P8_TX_C_DN
  C1L3    1      A CAP_A_0402V-0.01UF,25V,10%,X7RA     I8 @BASEBOARD_FAB2_LIB.BASEBOARD_FAB2(SCH_1):PAGE174
  J8A2   D5 TXA0_DN CONN36_G97614001_CP-CONN,G9761A    I26 @BASEBOARD_FAB2_LIB.BASEBOARD_FAB2(SCH_1):PAGE174

SATA6G_P8_TX_C_DP @BASEBOARD_FAB2_LIB.BASEBOARD_FAB2(SCH_1):SATA6G_P8_TX_C_DP
  C1L2    1      A CAP_A_0402V-0.01UF,25V,10%,X7RA     I9 @BASEBOARD_FAB2_LIB.BASEBOARD_FAB2(SCH_1):PAGE174
  J8A2   D4 TXA0_DP CONN36_G97614001_CP-CONN,G9761A    I26 @BASEBOARD_FAB2_LIB.BASEBOARD_FAB2(SCH_1):PAGE174

SATA6G_P9_RX_C_DN @BASEBOARD_FAB2_LIB.BASEBOARD_FAB2(SCH_1):SATA6G_P9_RX_C_DN
  J8A2   A5 RXA1_DN CONN36_G97614001_CP-CONN,G9761A    I26 @BASEBOARD_FAB2_LIB.BASEBOARD_FAB2(SCH_1):PAGE174
 C2L29    2      B CAP_A_0402V-0.01UF,25V,10%,X7RA    I32 @BASEBOARD_FAB2_LIB.BASEBOARD_FAB2(SCH_1):PAGE174

SATA6G_P9_RX_C_DP @BASEBOARD_FAB2_LIB.BASEBOARD_FAB2(SCH_1):SATA6G_P9_RX_C_DP
  J8A2   A4 RXA1_DP CONN36_G97614001_CP-CONN,G9761A    I26 @BASEBOARD_FAB2_LIB.BASEBOARD_FAB2(SCH_1):PAGE174
 C2L28    2      B CAP_A_0402V-0.01UF,25V,10%,X7RA    I30 @BASEBOARD_FAB2_LIB.BASEBOARD_FAB2(SCH_1):PAGE174

SATA6G_P9_TX_C_DN @BASEBOARD_FAB2_LIB.BASEBOARD_FAB2(SCH_1):SATA6G_P9_TX_C_DN
  C1L7    1      A CAP_A_0402V-0.01UF,25V,10%,X7RA    I12 @BASEBOARD_FAB2_LIB.BASEBOARD_FAB2(SCH_1):PAGE174
  J8A2   C5 TXA1_DN CONN36_G97614001_CP-CONN,G9761A    I26 @BASEBOARD_FAB2_LIB.BASEBOARD_FAB2(SCH_1):PAGE174

SATA6G_P9_TX_C_DP @BASEBOARD_FAB2_LIB.BASEBOARD_FAB2(SCH_1):SATA6G_P9_TX_C_DP
  C1L6    1      A CAP_A_0402V-0.01UF,25V,10%,X7RA    I13 @BASEBOARD_FAB2_LIB.BASEBOARD_FAB2(SCH_1):PAGE174
  J8A2   C4 TXA1_DP CONN36_G97614001_CP-CONN,G9761A    I26 @BASEBOARD_FAB2_LIB.BASEBOARD_FAB2(SCH_1):PAGE174

SATA6G_PCH_PCIE_UP_SATA_RXN<0> @BASEBOARD_FAB2_LIB.BASEBOARD_FAB2(SCH_1):SATA6G_PCH_PCIE_UP_SATA_RXN(0)
  U7C1 AR61 PCIE12_UP0_SATA0_RXN LBG_CORE_QAT_EXT_D_BGA1-IC,H91A   I220 @BASEBOARD_FAB2_LIB.BASEBOARD_FAB2(SCH_1):PAGE116
 C2L17    1      A CAP_A_0402V-0.01UF,25V,10%,X7RA   I174 @BASEBOARD_FAB2_LIB.BASEBOARD_FAB2(SCH_1):PAGE173

SATA6G_PCH_PCIE_UP_SATA_RXN<1> @BASEBOARD_FAB2_LIB.BASEBOARD_FAB2(SCH_1):SATA6G_PCH_PCIE_UP_SATA_RXN(1)
  U7C1 AL66 PCIE13_UP1_SATA1_RXN LBG_CORE_QAT_EXT_D_BGA1-IC,H91A   I220 @BASEBOARD_FAB2_LIB.BASEBOARD_FAB2(SCH_1):PAGE116
  C2L6    1      A CAP_A_0402V-0.01UF,25V,10%,X7RA   I166 @BASEBOARD_FAB2_LIB.BASEBOARD_FAB2(SCH_1):PAGE173

SATA6G_PCH_PCIE_UP_SATA_RXN<2> @BASEBOARD_FAB2_LIB.BASEBOARD_FAB2(SCH_1):SATA6G_PCH_PCIE_UP_SATA_RXN(2)
  U7C1 AK65 PCIE14_UP2_SATA2_RXN LBG_CORE_QAT_EXT_D_BGA1-IC,H91A   I220 @BASEBOARD_FAB2_LIB.BASEBOARD_FAB2(SCH_1):PAGE116
 C2L13    1      A CAP_A_0402V-0.01UF,25V,10%,X7RA   I165 @BASEBOARD_FAB2_LIB.BASEBOARD_FAB2(SCH_1):PAGE173

SATA6G_PCH_PCIE_UP_SATA_RXN<3> @BASEBOARD_FAB2_LIB.BASEBOARD_FAB2(SCH_1):SATA6G_PCH_PCIE_UP_SATA_RXN(3)
  U7C1 AP63 PCIE15_UP3_SATA3_RXN LBG_CORE_QAT_EXT_D_BGA1-IC,H91A   I220 @BASEBOARD_FAB2_LIB.BASEBOARD_FAB2(SCH_1):PAGE116
  C2L3    1      A CAP_A_0402V-0.01UF,25V,10%,X7RA   I194 @BASEBOARD_FAB2_LIB.BASEBOARD_FAB2(SCH_1):PAGE173

SATA6G_PCH_PCIE_UP_SATA_RXN<4> @BASEBOARD_FAB2_LIB.BASEBOARD_FAB2(SCH_1):SATA6G_PCH_PCIE_UP_SATA_RXN(4)
  U7C1 AF65 PCIE16_UP4_SATA4_RXN LBG_CORE_QAT_EXT_D_BGA1-IC,H91A   I220 @BASEBOARD_FAB2_LIB.BASEBOARD_FAB2(SCH_1):PAGE116
 C2L18    1      A CAP_A_0402V-0.01UF,25V,10%,X7RA   I197 @BASEBOARD_FAB2_LIB.BASEBOARD_FAB2(SCH_1):PAGE173

SATA6G_PCH_PCIE_UP_SATA_RXN<5> @BASEBOARD_FAB2_LIB.BASEBOARD_FAB2(SCH_1):SATA6G_PCH_PCIE_UP_SATA_RXN(5)
  U7C1 AH61 PCIE17_UP5_SATA5_RXN LBG_CORE_QAT_EXT_D_BGA1-IC,H91A   I220 @BASEBOARD_FAB2_LIB.BASEBOARD_FAB2(SCH_1):PAGE116
  C2L9    1      A CAP_A_0402V-0.01UF,25V,10%,X7RA   I207 @BASEBOARD_FAB2_LIB.BASEBOARD_FAB2(SCH_1):PAGE173

SATA6G_PCH_PCIE_UP_SATA_RXN<6> @BASEBOARD_FAB2_LIB.BASEBOARD_FAB2(SCH_1):SATA6G_PCH_PCIE_UP_SATA_RXN(6)
  U7C1 AP59 PCIE18_UP6_SATA6_RXN LBG_CORE_QAT_EXT_D_BGA1-IC,H91A   I220 @BASEBOARD_FAB2_LIB.BASEBOARD_FAB2(SCH_1):PAGE116
 C2L14    1      A CAP_A_0402V-0.01UF,25V,10%,X7RA   I208 @BASEBOARD_FAB2_LIB.BASEBOARD_FAB2(SCH_1):PAGE173

SATA6G_PCH_PCIE_UP_SATA_RXN<7> @BASEBOARD_FAB2_LIB.BASEBOARD_FAB2(SCH_1):SATA6G_PCH_PCIE_UP_SATA_RXN(7)
  U7C1 AA61 PCIE19_UP7_SATA7_RXN LBG_CORE_QAT_EXT_D_BGA1-IC,H91A   I220 @BASEBOARD_FAB2_LIB.BASEBOARD_FAB2(SCH_1):PAGE116
  C2L5    1      A CAP_A_0402V-0.01UF,25V,10%,X7RA   I209 @BASEBOARD_FAB2_LIB.BASEBOARD_FAB2(SCH_1):PAGE173

SATA6G_PCH_PCIE_UP_SATA_RXP<0> @BASEBOARD_FAB2_LIB.BASEBOARD_FAB2(SCH_1):SATA6G_PCH_PCIE_UP_SATA_RXP(0)
  U7C1 AT63 PCIE12_UP0_SATA0_RXP LBG_CORE_QAT_EXT_D_BGA1-IC,H91A   I220 @BASEBOARD_FAB2_LIB.BASEBOARD_FAB2(SCH_1):PAGE116
 C2L19    1      A CAP_A_0402V-0.01UF,25V,10%,X7RA   I172 @BASEBOARD_FAB2_LIB.BASEBOARD_FAB2(SCH_1):PAGE173

SATA6G_PCH_PCIE_UP_SATA_RXP<1> @BASEBOARD_FAB2_LIB.BASEBOARD_FAB2(SCH_1):SATA6G_PCH_PCIE_UP_SATA_RXP(1)
  U7C1 AN65 PCIE13_UP1_SATA1_RXP LBG_CORE_QAT_EXT_D_BGA1-IC,H91A   I220 @BASEBOARD_FAB2_LIB.BASEBOARD_FAB2(SCH_1):PAGE116
 C2L10    1      A CAP_A_0402V-0.01UF,25V,10%,X7RA   I173 @BASEBOARD_FAB2_LIB.BASEBOARD_FAB2(SCH_1):PAGE173

SATA6G_PCH_PCIE_UP_SATA_RXP<2> @BASEBOARD_FAB2_LIB.BASEBOARD_FAB2(SCH_1):SATA6G_PCH_PCIE_UP_SATA_RXP(2)
  U7C1 AJ63 PCIE14_UP2_SATA2_RXP LBG_CORE_QAT_EXT_D_BGA1-IC,H91A   I220 @BASEBOARD_FAB2_LIB.BASEBOARD_FAB2(SCH_1):PAGE116
 C2L15    1      A CAP_A_0402V-0.01UF,25V,10%,X7RA   I191 @BASEBOARD_FAB2_LIB.BASEBOARD_FAB2(SCH_1):PAGE173

SATA6G_PCH_PCIE_UP_SATA_RXP<3> @BASEBOARD_FAB2_LIB.BASEBOARD_FAB2(SCH_1):SATA6G_PCH_PCIE_UP_SATA_RXP(3)
  U7C1 AL63 PCIE15_UP3_SATA3_RXP LBG_CORE_QAT_EXT_D_BGA1-IC,H91A   I220 @BASEBOARD_FAB2_LIB.BASEBOARD_FAB2(SCH_1):PAGE116
  C2L4    1      A CAP_A_0402V-0.01UF,25V,10%,X7RA   I192 @BASEBOARD_FAB2_LIB.BASEBOARD_FAB2(SCH_1):PAGE173

SATA6G_PCH_PCIE_UP_SATA_RXP<4> @BASEBOARD_FAB2_LIB.BASEBOARD_FAB2(SCH_1):SATA6G_PCH_PCIE_UP_SATA_RXP(4)
  U7C1 AH65 PCIE16_UP4_SATA4_RXP LBG_CORE_QAT_EXT_D_BGA1-IC,H91A   I220 @BASEBOARD_FAB2_LIB.BASEBOARD_FAB2(SCH_1):PAGE116
 C2L20    1      A CAP_A_0402V-0.01UF,25V,10%,X7RA   I195 @BASEBOARD_FAB2_LIB.BASEBOARD_FAB2(SCH_1):PAGE173

SATA6G_PCH_PCIE_UP_SATA_RXP<5> @BASEBOARD_FAB2_LIB.BASEBOARD_FAB2(SCH_1):SATA6G_PCH_PCIE_UP_SATA_RXP(5)
  U7C1 AG63 PCIE17_UP5_SATA5_RXP LBG_CORE_QAT_EXT_D_BGA1-IC,H91A   I220 @BASEBOARD_FAB2_LIB.BASEBOARD_FAB2(SCH_1):PAGE116
 C2L12    1      A CAP_A_0402V-0.01UF,25V,10%,X7RA   I196 @BASEBOARD_FAB2_LIB.BASEBOARD_FAB2(SCH_1):PAGE173

SATA6G_PCH_PCIE_UP_SATA_RXP<6> @BASEBOARD_FAB2_LIB.BASEBOARD_FAB2(SCH_1):SATA6G_PCH_PCIE_UP_SATA_RXP(6)
  U7C1 AN61 PCIE18_UP6_SATA6_RXP LBG_CORE_QAT_EXT_D_BGA1-IC,H91A   I220 @BASEBOARD_FAB2_LIB.BASEBOARD_FAB2(SCH_1):PAGE116
 C2L16    1      A CAP_A_0402V-0.01UF,25V,10%,X7RA   I205 @BASEBOARD_FAB2_LIB.BASEBOARD_FAB2(SCH_1):PAGE173

SATA6G_PCH_PCIE_UP_SATA_RXP<7> @BASEBOARD_FAB2_LIB.BASEBOARD_FAB2(SCH_1):SATA6G_PCH_PCIE_UP_SATA_RXP(7)
  U7C1 AD61 PCIE19_UP7_SATA7_RXP LBG_CORE_QAT_EXT_D_BGA1-IC,H91A   I220 @BASEBOARD_FAB2_LIB.BASEBOARD_FAB2(SCH_1):PAGE116
  C2L7    1      A CAP_A_0402V-0.01UF,25V,10%,X7RA   I206 @BASEBOARD_FAB2_LIB.BASEBOARD_FAB2(SCH_1):PAGE173

SATA6G_PCH_PCIE_UP_SATA_TXN<0> @BASEBOARD_FAB2_LIB.BASEBOARD_FAB2(SCH_1):SATA6G_PCH_PCIE_UP_SATA_TXN(0)
  U7C1  W69 PCIE12_UP0_SATA0_TXN LBG_CORE_QAT_EXT_D_BGA1-IC,H91A   I220 @BASEBOARD_FAB2_LIB.BASEBOARD_FAB2(SCH_1):PAGE116
 C2L40    2      B CAP_A_0402V-0.01UF,25V,10%,X7RA   I220 @BASEBOARD_FAB2_LIB.BASEBOARD_FAB2(SCH_1):PAGE173

SATA6G_PCH_PCIE_UP_SATA_TXN<1> @BASEBOARD_FAB2_LIB.BASEBOARD_FAB2(SCH_1):SATA6G_PCH_PCIE_UP_SATA_TXN(1)
  U7C1  V70 PCIE13_UP1_SATA1_TXN LBG_CORE_QAT_EXT_D_BGA1-IC,H91A   I220 @BASEBOARD_FAB2_LIB.BASEBOARD_FAB2(SCH_1):PAGE116
 C2L44    2      B CAP_A_0402V-0.01UF,25V,10%,X7RA   I228 @BASEBOARD_FAB2_LIB.BASEBOARD_FAB2(SCH_1):PAGE173

SATA6G_PCH_PCIE_UP_SATA_TXN<2> @BASEBOARD_FAB2_LIB.BASEBOARD_FAB2(SCH_1):SATA6G_PCH_PCIE_UP_SATA_TXN(2)
  U7C1  T69 PCIE14_UP2_SATA2_TXN LBG_CORE_QAT_EXT_D_BGA1-IC,H91A   I220 @BASEBOARD_FAB2_LIB.BASEBOARD_FAB2(SCH_1):PAGE116
 C2L42    2      B CAP_A_0402V-0.01UF,25V,10%,X7RA   I233 @BASEBOARD_FAB2_LIB.BASEBOARD_FAB2(SCH_1):PAGE173

SATA6G_PCH_PCIE_UP_SATA_TXN<3> @BASEBOARD_FAB2_LIB.BASEBOARD_FAB2(SCH_1):SATA6G_PCH_PCIE_UP_SATA_TXN(3)
  U7C1  R70 PCIE15_UP3_SATA3_TXN LBG_CORE_QAT_EXT_D_BGA1-IC,H91A   I220 @BASEBOARD_FAB2_LIB.BASEBOARD_FAB2(SCH_1):PAGE116
 C2L22    2      B CAP_A_0402V-0.01UF,25V,10%,X7RA   I234 @BASEBOARD_FAB2_LIB.BASEBOARD_FAB2(SCH_1):PAGE173

SATA6G_PCH_PCIE_UP_SATA_TXN<4> @BASEBOARD_FAB2_LIB.BASEBOARD_FAB2(SCH_1):SATA6G_PCH_PCIE_UP_SATA_TXN(4)
  U7C1  P69 PCIE16_UP4_SATA4_TXN LBG_CORE_QAT_EXT_D_BGA1-IC,H91A   I220 @BASEBOARD_FAB2_LIB.BASEBOARD_FAB2(SCH_1):PAGE116
 C2L37    2      B CAP_A_0402V-0.01UF,25V,10%,X7RA   I238 @BASEBOARD_FAB2_LIB.BASEBOARD_FAB2(SCH_1):PAGE173

SATA6G_PCH_PCIE_UP_SATA_TXN<5> @BASEBOARD_FAB2_LIB.BASEBOARD_FAB2(SCH_1):SATA6G_PCH_PCIE_UP_SATA_TXN(5)
  U7C1  N70 PCIE17_UP5_SATA5_TXN LBG_CORE_QAT_EXT_D_BGA1-IC,H91A   I220 @BASEBOARD_FAB2_LIB.BASEBOARD_FAB2(SCH_1):PAGE116
 C2L26    2      B CAP_A_0402V-0.01UF,25V,10%,X7RA   I255 @BASEBOARD_FAB2_LIB.BASEBOARD_FAB2(SCH_1):PAGE173

SATA6G_PCH_PCIE_UP_SATA_TXN<6> @BASEBOARD_FAB2_LIB.BASEBOARD_FAB2(SCH_1):SATA6G_PCH_PCIE_UP_SATA_TXN(6)
  U7C1  M69 PCIE18_UP6_SATA6_TXN LBG_CORE_QAT_EXT_D_BGA1-IC,H91A   I220 @BASEBOARD_FAB2_LIB.BASEBOARD_FAB2(SCH_1):PAGE116
 C2L38    2      B CAP_A_0402V-0.01UF,25V,10%,X7RA   I256 @BASEBOARD_FAB2_LIB.BASEBOARD_FAB2(SCH_1):PAGE173

SATA6G_PCH_PCIE_UP_SATA_TXN<7> @BASEBOARD_FAB2_LIB.BASEBOARD_FAB2(SCH_1):SATA6G_PCH_PCIE_UP_SATA_TXN(7)
  U7C1  L70 PCIE19_UP7_SATA7_TXN LBG_CORE_QAT_EXT_D_BGA1-IC,H91A   I220 @BASEBOARD_FAB2_LIB.BASEBOARD_FAB2(SCH_1):PAGE116
 C2L21    2      B CAP_A_0402V-0.01UF,25V,10%,X7RA   I259 @BASEBOARD_FAB2_LIB.BASEBOARD_FAB2(SCH_1):PAGE173

SATA6G_PCH_PCIE_UP_SATA_TXP<0> @BASEBOARD_FAB2_LIB.BASEBOARD_FAB2(SCH_1):SATA6G_PCH_PCIE_UP_SATA_TXP(0)
  U7C1  W71 PCIE12_UP0_SATA0_TXP LBG_CORE_QAT_EXT_D_BGA1-IC,H91A   I220 @BASEBOARD_FAB2_LIB.BASEBOARD_FAB2(SCH_1):PAGE116
 C2L39    2      B CAP_A_0402V-0.01UF,25V,10%,X7RA   I221 @BASEBOARD_FAB2_LIB.BASEBOARD_FAB2(SCH_1):PAGE173

SATA6G_PCH_PCIE_UP_SATA_TXP<1> @BASEBOARD_FAB2_LIB.BASEBOARD_FAB2(SCH_1):SATA6G_PCH_PCIE_UP_SATA_TXP(1)
  U7C1  V72 PCIE13_UP1_SATA1_TXP LBG_CORE_QAT_EXT_D_BGA1-IC,H91A   I220 @BASEBOARD_FAB2_LIB.BASEBOARD_FAB2(SCH_1):PAGE116
 C2L43    2      B CAP_A_0402V-0.01UF,25V,10%,X7RA   I222 @BASEBOARD_FAB2_LIB.BASEBOARD_FAB2(SCH_1):PAGE173

SATA6G_PCH_PCIE_UP_SATA_TXP<2> @BASEBOARD_FAB2_LIB.BASEBOARD_FAB2(SCH_1):SATA6G_PCH_PCIE_UP_SATA_TXP(2)
  U7C1  T71 PCIE14_UP2_SATA2_TXP LBG_CORE_QAT_EXT_D_BGA1-IC,H91A   I220 @BASEBOARD_FAB2_LIB.BASEBOARD_FAB2(SCH_1):PAGE116
 C2L41    2      B CAP_A_0402V-0.01UF,25V,10%,X7RA   I242 @BASEBOARD_FAB2_LIB.BASEBOARD_FAB2(SCH_1):PAGE173

SATA6G_PCH_PCIE_UP_SATA_TXP<3> @BASEBOARD_FAB2_LIB.BASEBOARD_FAB2(SCH_1):SATA6G_PCH_PCIE_UP_SATA_TXP(3)
  U7C1  R72 PCIE15_UP3_SATA3_TXP LBG_CORE_QAT_EXT_D_BGA1-IC,H91A   I220 @BASEBOARD_FAB2_LIB.BASEBOARD_FAB2(SCH_1):PAGE116
 C2L23    2      B CAP_A_0402V-0.01UF,25V,10%,X7RA   I241 @BASEBOARD_FAB2_LIB.BASEBOARD_FAB2(SCH_1):PAGE173

SATA6G_PCH_PCIE_UP_SATA_TXP<4> @BASEBOARD_FAB2_LIB.BASEBOARD_FAB2(SCH_1):SATA6G_PCH_PCIE_UP_SATA_TXP(4)
  U7C1  P71 PCIE16_UP4_SATA4_TXP LBG_CORE_QAT_EXT_D_BGA1-IC,H91A   I220 @BASEBOARD_FAB2_LIB.BASEBOARD_FAB2(SCH_1):PAGE116
 C2L47    2      B CAP_A_0402V-0.01UF,25V,10%,X7RA   I239 @BASEBOARD_FAB2_LIB.BASEBOARD_FAB2(SCH_1):PAGE173

SATA6G_PCH_PCIE_UP_SATA_TXP<5> @BASEBOARD_FAB2_LIB.BASEBOARD_FAB2(SCH_1):SATA6G_PCH_PCIE_UP_SATA_TXP(5)
  U7C1  N72 PCIE17_UP5_SATA5_TXP LBG_CORE_QAT_EXT_D_BGA1-IC,H91A   I220 @BASEBOARD_FAB2_LIB.BASEBOARD_FAB2(SCH_1):PAGE116
 C2L27    2      B CAP_A_0402V-0.01UF,25V,10%,X7RA   I240 @BASEBOARD_FAB2_LIB.BASEBOARD_FAB2(SCH_1):PAGE173

SATA6G_PCH_PCIE_UP_SATA_TXP<6> @BASEBOARD_FAB2_LIB.BASEBOARD_FAB2(SCH_1):SATA6G_PCH_PCIE_UP_SATA_TXP(6)
  U7C1  M71 PCIE18_UP6_SATA6_TXP LBG_CORE_QAT_EXT_D_BGA1-IC,H91A   I220 @BASEBOARD_FAB2_LIB.BASEBOARD_FAB2(SCH_1):PAGE116
 C2L48    2      B CAP_A_0402V-0.01UF,25V,10%,X7RA   I257 @BASEBOARD_FAB2_LIB.BASEBOARD_FAB2(SCH_1):PAGE173

SATA6G_PCH_PCIE_UP_SATA_TXP<7> @BASEBOARD_FAB2_LIB.BASEBOARD_FAB2(SCH_1):SATA6G_PCH_PCIE_UP_SATA_TXP(7)
  U7C1  L72 PCIE19_UP7_SATA7_TXP LBG_CORE_QAT_EXT_D_BGA1-IC,H91A   I220 @BASEBOARD_FAB2_LIB.BASEBOARD_FAB2(SCH_1):PAGE116
 C2L24    2      B CAP_A_0402V-0.01UF,25V,10%,X7RA   I258 @BASEBOARD_FAB2_LIB.BASEBOARD_FAB2(SCH_1):PAGE173

SATA6G_RX_DN<0> @BASEBOARD_FAB2_LIB.BASEBOARD_FAB2(SCH_1):SATA6G_RX_DN(0)
  U7C1 BA65 PCIE8_SSATA2_GBE_RXN LBG_CORE_QAT_EXT_D_BGA1-IC,H91A   I220 @BASEBOARD_FAB2_LIB.BASEBOARD_FAB2(SCH_1):PAGE116
 C2L31    1      A CAP_A_0402V-0.01UF,25V,10%,X7RA    I29 @BASEBOARD_FAB2_LIB.BASEBOARD_FAB2(SCH_1):PAGE174

SATA6G_RX_DN<1> @BASEBOARD_FAB2_LIB.BASEBOARD_FAB2(SCH_1):SATA6G_RX_DN(1)
  U7C1 AW65 PCIE9_SSATA3_RXN LBG_CORE_QAT_EXT_D_BGA1-IC,H91A   I220 @BASEBOARD_FAB2_LIB.BASEBOARD_FAB2(SCH_1):PAGE116
 C2L29    1      A CAP_A_0402V-0.01UF,25V,10%,X7RA    I32 @BASEBOARD_FAB2_LIB.BASEBOARD_FAB2(SCH_1):PAGE174

SATA6G_RX_DN<2> @BASEBOARD_FAB2_LIB.BASEBOARD_FAB2(SCH_1):SATA6G_RX_DN(2)
  U7C1 AV63 PCIE10_SSATA4_RXN LBG_CORE_QAT_EXT_D_BGA1-IC,H91A   I220 @BASEBOARD_FAB2_LIB.BASEBOARD_FAB2(SCH_1):PAGE116
 C2L36    1      A CAP_A_0402V-0.01UF,25V,10%,X7RA    I39 @BASEBOARD_FAB2_LIB.BASEBOARD_FAB2(SCH_1):PAGE174

SATA6G_RX_DN<3> @BASEBOARD_FAB2_LIB.BASEBOARD_FAB2(SCH_1):SATA6G_RX_DN(3)
  U7C1 AT66 PCIE11_SSATA5_GBE_RXN LBG_CORE_QAT_EXT_D_BGA1-IC,H91A   I220 @BASEBOARD_FAB2_LIB.BASEBOARD_FAB2(SCH_1):PAGE116
 C2L34    1      A CAP_A_0402V-0.01UF,25V,10%,X7RA    I41 @BASEBOARD_FAB2_LIB.BASEBOARD_FAB2(SCH_1):PAGE174

SATA6G_RX_DP<0> @BASEBOARD_FAB2_LIB.BASEBOARD_FAB2(SCH_1):SATA6G_RX_DP(0)
  U7C1 BD65 PCIE8_SSATA2_GBE_RXP LBG_CORE_QAT_EXT_D_BGA1-IC,H91A   I220 @BASEBOARD_FAB2_LIB.BASEBOARD_FAB2(SCH_1):PAGE116
 C2L30    1      A CAP_A_0402V-0.01UF,25V,10%,X7RA    I28 @BASEBOARD_FAB2_LIB.BASEBOARD_FAB2(SCH_1):PAGE174

SATA6G_RX_DP<1> @BASEBOARD_FAB2_LIB.BASEBOARD_FAB2(SCH_1):SATA6G_RX_DP(1)
  U7C1 AY66 PCIE9_SSATA3_RXP LBG_CORE_QAT_EXT_D_BGA1-IC,H91A   I220 @BASEBOARD_FAB2_LIB.BASEBOARD_FAB2(SCH_1):PAGE116
 C2L28    1      A CAP_A_0402V-0.01UF,25V,10%,X7RA    I30 @BASEBOARD_FAB2_LIB.BASEBOARD_FAB2(SCH_1):PAGE174

SATA6G_RX_DP<2> @BASEBOARD_FAB2_LIB.BASEBOARD_FAB2(SCH_1):SATA6G_RX_DP(2)
  U7C1 AU65 PCIE10_SSATA4_RXP LBG_CORE_QAT_EXT_D_BGA1-IC,H91A   I220 @BASEBOARD_FAB2_LIB.BASEBOARD_FAB2(SCH_1):PAGE116
 C2L35    1      A CAP_A_0402V-0.01UF,25V,10%,X7RA    I31 @BASEBOARD_FAB2_LIB.BASEBOARD_FAB2(SCH_1):PAGE174

SATA6G_RX_DP<3> @BASEBOARD_FAB2_LIB.BASEBOARD_FAB2(SCH_1):SATA6G_RX_DP(3)
  U7C1 AV66 PCIE11_SSATA5_GBE_RXP LBG_CORE_QAT_EXT_D_BGA1-IC,H91A   I220 @BASEBOARD_FAB2_LIB.BASEBOARD_FAB2(SCH_1):PAGE116
 C2L33    1      A CAP_A_0402V-0.01UF,25V,10%,X7RA    I40 @BASEBOARD_FAB2_LIB.BASEBOARD_FAB2(SCH_1):PAGE174

SATA6G_S0_RX_DN @BASEBOARD_FAB2_LIB.BASEBOARD_FAB2(SCH_1):SATA6G_S0_RX_DN
  U7C1 BB63 PCIE6_SSATA0_RXN LBG_CORE_QAT_EXT_D_BGA1-IC,H91A   I220 @BASEBOARD_FAB2_LIB.BASEBOARD_FAB2(SCH_1):PAGE116
 C8F15    1      A CAP_A_0402V-0.01UF,25V,10%,EMPA    I90 @BASEBOARD_FAB2_LIB.BASEBOARD_FAB2(SCH_1):PAGE185

SATA6G_S0_RX_DP @BASEBOARD_FAB2_LIB.BASEBOARD_FAB2(SCH_1):SATA6G_S0_RX_DP
  U7C1 BD61 PCIE6_SSATA0_RXP LBG_CORE_QAT_EXT_D_BGA1-IC,H91A   I220 @BASEBOARD_FAB2_LIB.BASEBOARD_FAB2(SCH_1):PAGE116
 C8F13    1      A CAP_A_0402V-0.01UF,25V,10%,EMPA    I99 @BASEBOARD_FAB2_LIB.BASEBOARD_FAB2(SCH_1):PAGE185

SATA6G_S0_TX_DN @BASEBOARD_FAB2_LIB.BASEBOARD_FAB2(SCH_1):SATA6G_S0_TX_DN
  U7C1 AJ70 PCIE6_SSATA0_TXN LBG_CORE_QAT_EXT_D_BGA1-IC,H91A   I220 @BASEBOARD_FAB2_LIB.BASEBOARD_FAB2(SCH_1):PAGE116
 C8F11    1      A CAP_A_0402V-0.01UF,25V,10%,EMPA    I97 @BASEBOARD_FAB2_LIB.BASEBOARD_FAB2(SCH_1):PAGE185

SATA6G_S0_TX_DP @BASEBOARD_FAB2_LIB.BASEBOARD_FAB2(SCH_1):SATA6G_S0_TX_DP
  U7C1 AJ72 PCIE6_SSATA0_TXP LBG_CORE_QAT_EXT_D_BGA1-IC,H91A   I220 @BASEBOARD_FAB2_LIB.BASEBOARD_FAB2(SCH_1):PAGE116
  C8F6    1      A CAP_A_0402V-0.01UF,25V,10%,EMPA    I95 @BASEBOARD_FAB2_LIB.BASEBOARD_FAB2(SCH_1):PAGE185

SATA6G_S1_RX_C_DN @BASEBOARD_FAB2_LIB.BASEBOARD_FAB2(SCH_1):SATA6G_S1_RX_C_DN
 C2L50    1      A CAP_A_0402V-0.01UF,25V,10%,X7RA     I7 @BASEBOARD_FAB2_LIB.BASEBOARD_FAB2(SCH_1):PAGE172
  J8A3    5 SATA_RXN CONN7_E82125014_PIP_TH-EMPTY,EA    I17 @BASEBOARD_FAB2_LIB.BASEBOARD_FAB2(SCH_1):PAGE172
  J2M1    5 SATA_RXN CONN7_E82125014_PIP_TH-CONN,E8A    I52 @BASEBOARD_FAB2_LIB.BASEBOARD_FAB2(SCH_1):PAGE172

SATA6G_S1_RX_C_DP @BASEBOARD_FAB2_LIB.BASEBOARD_FAB2(SCH_1):SATA6G_S1_RX_C_DP
 C2L49    1      A CAP_A_0402V-0.01UF,25V,10%,X7RA     I5 @BASEBOARD_FAB2_LIB.BASEBOARD_FAB2(SCH_1):PAGE172
  J8A3    6 SATA_RXP CONN7_E82125014_PIP_TH-EMPTY,EA    I17 @BASEBOARD_FAB2_LIB.BASEBOARD_FAB2(SCH_1):PAGE172
  J2M1    6 SATA_RXP CONN7_E82125014_PIP_TH-CONN,E8A    I52 @BASEBOARD_FAB2_LIB.BASEBOARD_FAB2(SCH_1):PAGE172

SATA6G_S1_RX_DN @BASEBOARD_FAB2_LIB.BASEBOARD_FAB2(SCH_1):SATA6G_S1_RX_DN
  U7C1 AY59 PCIE7_SSATA1_RXN LBG_CORE_QAT_EXT_D_BGA1-IC,H91A   I220 @BASEBOARD_FAB2_LIB.BASEBOARD_FAB2(SCH_1):PAGE116
 C2L50    2      B CAP_A_0402V-0.01UF,25V,10%,X7RA     I7 @BASEBOARD_FAB2_LIB.BASEBOARD_FAB2(SCH_1):PAGE172

SATA6G_S1_RX_DP @BASEBOARD_FAB2_LIB.BASEBOARD_FAB2(SCH_1):SATA6G_S1_RX_DP
  U7C1 BA61 PCIE7_SSATA1_RXP LBG_CORE_QAT_EXT_D_BGA1-IC,H91A   I220 @BASEBOARD_FAB2_LIB.BASEBOARD_FAB2(SCH_1):PAGE116
 C2L49    2      B CAP_A_0402V-0.01UF,25V,10%,X7RA     I5 @BASEBOARD_FAB2_LIB.BASEBOARD_FAB2(SCH_1):PAGE172

SATA6G_S1_TX_C_DN @BASEBOARD_FAB2_LIB.BASEBOARD_FAB2(SCH_1):SATA6G_S1_TX_C_DN
 C2L51    1      A CAP_A_0402V-0.01UF,25V,10%,X7RA     I8 @BASEBOARD_FAB2_LIB.BASEBOARD_FAB2(SCH_1):PAGE172
  J8A3    3 SATA_TXN CONN7_E82125014_PIP_TH-EMPTY,EA    I17 @BASEBOARD_FAB2_LIB.BASEBOARD_FAB2(SCH_1):PAGE172
  J2M1    3 SATA_TXN CONN7_E82125014_PIP_TH-CONN,E8A    I52 @BASEBOARD_FAB2_LIB.BASEBOARD_FAB2(SCH_1):PAGE172

SATA6G_S1_TX_C_DP @BASEBOARD_FAB2_LIB.BASEBOARD_FAB2(SCH_1):SATA6G_S1_TX_C_DP
 C2L52    1      A CAP_A_0402V-0.01UF,25V,10%,X7RA     I6 @BASEBOARD_FAB2_LIB.BASEBOARD_FAB2(SCH_1):PAGE172
  J8A3    2 SATA_TXP CONN7_E82125014_PIP_TH-EMPTY,EA    I17 @BASEBOARD_FAB2_LIB.BASEBOARD_FAB2(SCH_1):PAGE172
  J2M1    2 SATA_TXP CONN7_E82125014_PIP_TH-CONN,E8A    I52 @BASEBOARD_FAB2_LIB.BASEBOARD_FAB2(SCH_1):PAGE172

SATA6G_S1_TX_DN @BASEBOARD_FAB2_LIB.BASEBOARD_FAB2(SCH_1):SATA6G_S1_TX_DN
  U7C1 AH69 PCIE7_SSATA1_TXN LBG_CORE_QAT_EXT_D_BGA1-IC,H91A   I220 @BASEBOARD_FAB2_LIB.BASEBOARD_FAB2(SCH_1):PAGE116
 C2L51    2      B CAP_A_0402V-0.01UF,25V,10%,X7RA     I8 @BASEBOARD_FAB2_LIB.BASEBOARD_FAB2(SCH_1):PAGE172

SATA6G_S1_TX_DP @BASEBOARD_FAB2_LIB.BASEBOARD_FAB2(SCH_1):SATA6G_S1_TX_DP
  U7C1 AH71 PCIE7_SSATA1_TXP LBG_CORE_QAT_EXT_D_BGA1-IC,H91A   I220 @BASEBOARD_FAB2_LIB.BASEBOARD_FAB2(SCH_1):PAGE116
 C2L52    2      B CAP_A_0402V-0.01UF,25V,10%,X7RA     I6 @BASEBOARD_FAB2_LIB.BASEBOARD_FAB2(SCH_1):PAGE172

SATA6G_TX_DN<0> @BASEBOARD_FAB2_LIB.BASEBOARD_FAB2(SCH_1):SATA6G_TX_DN(0)
  U7C1 AF70 PCIE8_SSATA2_GBE_TXN LBG_CORE_QAT_EXT_D_BGA1-IC,H91A   I220 @BASEBOARD_FAB2_LIB.BASEBOARD_FAB2(SCH_1):PAGE116
  C1L3    2      B CAP_A_0402V-0.01UF,25V,10%,X7RA     I8 @BASEBOARD_FAB2_LIB.BASEBOARD_FAB2(SCH_1):PAGE174

SATA6G_TX_DN<1> @BASEBOARD_FAB2_LIB.BASEBOARD_FAB2(SCH_1):SATA6G_TX_DN(1)
  U7C1 AE69 PCIE9_SSATA3_TXN LBG_CORE_QAT_EXT_D_BGA1-IC,H91A   I220 @BASEBOARD_FAB2_LIB.BASEBOARD_FAB2(SCH_1):PAGE116
  C1L7    2      B CAP_A_0402V-0.01UF,25V,10%,X7RA    I12 @BASEBOARD_FAB2_LIB.BASEBOARD_FAB2(SCH_1):PAGE174

SATA6G_TX_DN<2> @BASEBOARD_FAB2_LIB.BASEBOARD_FAB2(SCH_1):SATA6G_TX_DN(2)
  U7C1 AD70 PCIE10_SSATA4_TXN LBG_CORE_QAT_EXT_D_BGA1-IC,H91A   I220 @BASEBOARD_FAB2_LIB.BASEBOARD_FAB2(SCH_1):PAGE116
 C1L13    2      B CAP_A_0402V-0.01UF,25V,10%,X7RA    I14 @BASEBOARD_FAB2_LIB.BASEBOARD_FAB2(SCH_1):PAGE174

SATA6G_TX_DN<3> @BASEBOARD_FAB2_LIB.BASEBOARD_FAB2(SCH_1):SATA6G_TX_DN(3)
  U7C1 AC69 PCIE11_SSATA5_GBE_TXN LBG_CORE_QAT_EXT_D_BGA1-IC,H91A   I220 @BASEBOARD_FAB2_LIB.BASEBOARD_FAB2(SCH_1):PAGE116
 C1L15    2      B CAP_A_0402V-0.01UF,25V,10%,X7RA    I18 @BASEBOARD_FAB2_LIB.BASEBOARD_FAB2(SCH_1):PAGE174

SATA6G_TX_DP<0> @BASEBOARD_FAB2_LIB.BASEBOARD_FAB2(SCH_1):SATA6G_TX_DP(0)
  U7C1 AF72 PCIE8_SSATA2_GBE_TXP LBG_CORE_QAT_EXT_D_BGA1-IC,H91A   I220 @BASEBOARD_FAB2_LIB.BASEBOARD_FAB2(SCH_1):PAGE116
  C1L2    2      B CAP_A_0402V-0.01UF,25V,10%,X7RA     I9 @BASEBOARD_FAB2_LIB.BASEBOARD_FAB2(SCH_1):PAGE174

SATA6G_TX_DP<1> @BASEBOARD_FAB2_LIB.BASEBOARD_FAB2(SCH_1):SATA6G_TX_DP(1)
  U7C1 AE71 PCIE9_SSATA3_TXP LBG_CORE_QAT_EXT_D_BGA1-IC,H91A   I220 @BASEBOARD_FAB2_LIB.BASEBOARD_FAB2(SCH_1):PAGE116
  C1L6    2      B CAP_A_0402V-0.01UF,25V,10%,X7RA    I13 @BASEBOARD_FAB2_LIB.BASEBOARD_FAB2(SCH_1):PAGE174

SATA6G_TX_DP<2> @BASEBOARD_FAB2_LIB.BASEBOARD_FAB2(SCH_1):SATA6G_TX_DP(2)
  U7C1 AD72 PCIE10_SSATA4_TXP LBG_CORE_QAT_EXT_D_BGA1-IC,H91A   I220 @BASEBOARD_FAB2_LIB.BASEBOARD_FAB2(SCH_1):PAGE116
 C1L12    2      B CAP_A_0402V-0.01UF,25V,10%,X7RA    I19 @BASEBOARD_FAB2_LIB.BASEBOARD_FAB2(SCH_1):PAGE174

SATA6G_TX_DP<3> @BASEBOARD_FAB2_LIB.BASEBOARD_FAB2(SCH_1):SATA6G_TX_DP(3)
  U7C1 AC71 PCIE11_SSATA5_GBE_TXP LBG_CORE_QAT_EXT_D_BGA1-IC,H91A   I220 @BASEBOARD_FAB2_LIB.BASEBOARD_FAB2(SCH_1):PAGE116
 C1L14    2      B CAP_A_0402V-0.01UF,25V,10%,X7RA    I20 @BASEBOARD_FAB2_LIB.BASEBOARD_FAB2(SCH_1):PAGE174

SGPIO_BMC_CLK @BASEBOARD_FAB2_LIB.BASEBOARD_FAB2(SCH_1):SGPIO_BMC_CLK
  U8D7   J1 PL7C_PCLKT4_0 LCMXO2_A_256BGA-IC,H63395-001   I179 @BASEBOARD_FAB2_LIB.BASEBOARD_FAB2(SCH_1):PAGE190
 R1U14    2      B RES_0402-51,5.0%,1/16W,CHIP,G2A    I57 @BASEBOARD_FAB2_LIB.BASEBOARD_FAB2(SCH_1):PAGE144

SGPIO_BMC_CLK_R @BASEBOARD_FAB2_LIB.BASEBOARD_FAB2(SCH_1):SGPIO_BMC_CLK_R
 R1U14    1      A RES_0402-51,5.0%,1/16W,CHIP,G2A    I57 @BASEBOARD_FAB2_LIB.BASEBOARD_FAB2(SCH_1):PAGE144
 U25W4   R2 GPIOJ0_SGPMCK AST2520A1-GP-GP_ASIC2-GB1-AST2A    I95 @BASEBOARD_FAB2_LIB.BASEBOARD_FAB2(SCH_1):PAGE144

SGPIO_BMC_DIN @BASEBOARD_FAB2_LIB.BASEBOARD_FAB2(SCH_1):SGPIO_BMC_DIN
  R2R6    2      B RES_0402-51,5.0%,1/16W,CHIP,G2A   I166 @BASEBOARD_FAB2_LIB.BASEBOARD_FAB2(SCH_1):PAGE191
 U25W4   N4 GPIOJ3_SGPMI AST2520A1-GP-GP_ASIC2-GB1-AST2A    I95 @BASEBOARD_FAB2_LIB.BASEBOARD_FAB2(SCH_1):PAGE144

SGPIO_BMC_DIN_R @BASEBOARD_FAB2_LIB.BASEBOARD_FAB2(SCH_1):SGPIO_BMC_DIN_R
  U8D7   F8  PT18A LCMXO2_A_256BGA-IC,H63395-001    I59 @BASEBOARD_FAB2_LIB.BASEBOARD_FAB2(SCH_1):PAGE191
  R2R6    1      A RES_0402-51,5.0%,1/16W,CHIP,G2A   I166 @BASEBOARD_FAB2_LIB.BASEBOARD_FAB2(SCH_1):PAGE191

SGPIO_BMC_DOUT @BASEBOARD_FAB2_LIB.BASEBOARD_FAB2(SCH_1):SGPIO_BMC_DOUT
  U8D7   J2   PL9A LCMXO2_A_256BGA-IC,H63395-001   I179 @BASEBOARD_FAB2_LIB.BASEBOARD_FAB2(SCH_1):PAGE190
 R1U13    2      B RES_0402-51,5.0%,1/16W,CHIP,G2A    I58 @BASEBOARD_FAB2_LIB.BASEBOARD_FAB2(SCH_1):PAGE144

SGPIO_BMC_DOUT_R @BASEBOARD_FAB2_LIB.BASEBOARD_FAB2(SCH_1):SGPIO_BMC_DOUT_R
 R1U13    1      A RES_0402-51,5.0%,1/16W,CHIP,G2A    I58 @BASEBOARD_FAB2_LIB.BASEBOARD_FAB2(SCH_1):PAGE144
 U25W4   N3 GPIOJ2_SGPMO AST2520A1-GP-GP_ASIC2-GB1-AST2A    I95 @BASEBOARD_FAB2_LIB.BASEBOARD_FAB2(SCH_1):PAGE144

SGPIO_BMC_LD_N @BASEBOARD_FAB2_LIB.BASEBOARD_FAB2(SCH_1):SGPIO_BMC_LD_N
  U8D7   K4  PL11C LCMXO2_A_256BGA-IC,H63395-001   I179 @BASEBOARD_FAB2_LIB.BASEBOARD_FAB2(SCH_1):PAGE190
 R1U12    2      B RES_0402-51,5.0%,1/16W,CHIP,G2A    I59 @BASEBOARD_FAB2_LIB.BASEBOARD_FAB2(SCH_1):PAGE144

SGPIO_BMC_LD_R_N @BASEBOARD_FAB2_LIB.BASEBOARD_FAB2(SCH_1):SGPIO_BMC_LD_R_N
 R1U12    1      A RES_0402-51,5.0%,1/16W,CHIP,G2A    I59 @BASEBOARD_FAB2_LIB.BASEBOARD_FAB2(SCH_1):PAGE144
 U25W4   L2 GPIOJ1_SGPMLD AST2520A1-GP-GP_ASIC2-GB1-AST2A    I95 @BASEBOARD_FAB2_LIB.BASEBOARD_FAB2(SCH_1):PAGE144

SGPIO_PCH_SATA_CLOCK @BASEBOARD_FAB2_LIB.BASEBOARD_FAB2(SCH_1):SGPIO_PCH_SATA_CLOCK
  U7C1  AL7 GPP_F10_SATA_SCLOCK LBG_CORE_QAT_EXT_D_BGA1-IC,H91A   I147 @BASEBOARD_FAB2_LIB.BASEBOARD_FAB2(SCH_1):PAGE120
 R2N31    1      A RES_0402-49.9,1%,1/16W,CHIP,G2A    I11 @BASEBOARD_FAB2_LIB.BASEBOARD_FAB2(SCH_1):PAGE178

SGPIO_PCH_SATA_CLOCK_R @BASEBOARD_FAB2_LIB.BASEBOARD_FAB2(SCH_1):SGPIO_PCH_SATA_CLOCK_R
  J8A1  1A2 SIDEBANDA_0 CONN72_G97614002_A_CP-CONN,G97A   I163 @BASEBOARD_FAB2_LIB.BASEBOARD_FAB2(SCH_1):PAGE173
 R2N31    2      B RES_0402-49.9,1%,1/16W,CHIP,G2A    I11 @BASEBOARD_FAB2_LIB.BASEBOARD_FAB2(SCH_1):PAGE178
 R2L11    2      B RES_0402-2.0K,1%,1/16W,CHIP,G2A    I13 @BASEBOARD_FAB2_LIB.BASEBOARD_FAB2(SCH_1):PAGE178

SGPIO_PCH_SATA_DOUT0 @BASEBOARD_FAB2_LIB.BASEBOARD_FAB2(SCH_1):SGPIO_PCH_SATA_DOUT0
  U7C1 AP11 GPP_F13_SATA_SDATAOUT0 LBG_CORE_QAT_EXT_D_BGA1-IC,H91A   I147 @BASEBOARD_FAB2_LIB.BASEBOARD_FAB2(SCH_1):PAGE120
 R8D19    1      A RES_0402-49.9,1%,1/16W,CHIP,G2A     I8 @BASEBOARD_FAB2_LIB.BASEBOARD_FAB2(SCH_1):PAGE178

SGPIO_PCH_SATA_DOUT0_R @BASEBOARD_FAB2_LIB.BASEBOARD_FAB2(SCH_1):SGPIO_PCH_SATA_DOUT0_R
  J8A1  1C1 SIDEBANDA_4 CONN72_G97614002_A_CP-CONN,G97A   I163 @BASEBOARD_FAB2_LIB.BASEBOARD_FAB2(SCH_1):PAGE173
 R8D19    2      B RES_0402-49.9,1%,1/16W,CHIP,G2A     I8 @BASEBOARD_FAB2_LIB.BASEBOARD_FAB2(SCH_1):PAGE178
 R2L15    2      B RES_0402-2.0K,1%,1/16W,CHIP,G2A    I12 @BASEBOARD_FAB2_LIB.BASEBOARD_FAB2(SCH_1):PAGE178

SGPIO_PCH_SATA_LOAD @BASEBOARD_FAB2_LIB.BASEBOARD_FAB2(SCH_1):SGPIO_PCH_SATA_LOAD
  U7C1  AR9 GPP_F11_SATA_SLOAD LBG_CORE_QAT_EXT_D_BGA1-IC,H91A   I147 @BASEBOARD_FAB2_LIB.BASEBOARD_FAB2(SCH_1):PAGE120
 R8D20    1      A RES_0402-49.9,1%,1/16W,CHIP,G2A     I1 @BASEBOARD_FAB2_LIB.BASEBOARD_FAB2(SCH_1):PAGE178

SGPIO_PCH_SATA_LOAD_R @BASEBOARD_FAB2_LIB.BASEBOARD_FAB2(SCH_1):SGPIO_PCH_SATA_LOAD_R
  J8A1  1B2 SIDEBANDA_1 CONN72_G97614002_A_CP-CONN,G97A   I163 @BASEBOARD_FAB2_LIB.BASEBOARD_FAB2(SCH_1):PAGE173
 R8D20    2      B RES_0402-49.9,1%,1/16W,CHIP,G2A     I1 @BASEBOARD_FAB2_LIB.BASEBOARD_FAB2(SCH_1):PAGE178
 R2L12    2      B RES_0402-2.0K,1%,1/16W,CHIP,G2A     I2 @BASEBOARD_FAB2_LIB.BASEBOARD_FAB2(SCH_1):PAGE178

SGPIO_PCH_SSATA_CLOCK @BASEBOARD_FAB2_LIB.BASEBOARD_FAB2(SCH_1):SGPIO_PCH_SSATA_CLOCK
  U7C1 AP18 GPP_F22_SSATA_SCLOCK LBG_CORE_QAT_EXT_D_BGA1-IC,H91A   I147 @BASEBOARD_FAB2_LIB.BASEBOARD_FAB2(SCH_1):PAGE120
 R2N22    1      A RES_0402-49.9,1%,1/16W,CHIP,G2A    I23 @BASEBOARD_FAB2_LIB.BASEBOARD_FAB2(SCH_1):PAGE178

SGPIO_PCH_SSATA_CLOCK_R @BASEBOARD_FAB2_LIB.BASEBOARD_FAB2(SCH_1):SGPIO_PCH_SSATA_CLOCK_R
  J8A2   A2 SIDEBAND0 CONN36_G97614001_CP-CONN,G9761A    I26 @BASEBOARD_FAB2_LIB.BASEBOARD_FAB2(SCH_1):PAGE174
  R2L6    2      B RES_0402-2.0K,1%,1/16W,CHIP,G2A    I17 @BASEBOARD_FAB2_LIB.BASEBOARD_FAB2(SCH_1):PAGE178
 R2N22    2      B RES_0402-49.9,1%,1/16W,CHIP,G2A    I23 @BASEBOARD_FAB2_LIB.BASEBOARD_FAB2(SCH_1):PAGE178

SGPIO_PCH_SSATA_DOUT0 @BASEBOARD_FAB2_LIB.BASEBOARD_FAB2(SCH_1):SGPIO_PCH_SSATA_DOUT0
  U7C1 BW43 GPP_D15_SSATA_SDATAOUT0 LBG_CORE_QAT_EXT_D_BGA1-IC,H91A   I115 @BASEBOARD_FAB2_LIB.BASEBOARD_FAB2(SCH_1):PAGE119
 R8B29    1      A RES_0402-49.9,1%,1/16W,CHIP,G2A    I21 @BASEBOARD_FAB2_LIB.BASEBOARD_FAB2(SCH_1):PAGE178

SGPIO_PCH_SSATA_DOUT0_R @BASEBOARD_FAB2_LIB.BASEBOARD_FAB2(SCH_1):SGPIO_PCH_SSATA_DOUT0_R
  J8A2   C1 SIDEBAND4 CONN36_G97614001_CP-CONN,G9761A    I26 @BASEBOARD_FAB2_LIB.BASEBOARD_FAB2(SCH_1):PAGE174
  R2L4    2      B RES_0402-2.0K,1%,1/16W,CHIP,G2A    I18 @BASEBOARD_FAB2_LIB.BASEBOARD_FAB2(SCH_1):PAGE178
 R8B29    2      B RES_0402-49.9,1%,1/16W,CHIP,G2A    I21 @BASEBOARD_FAB2_LIB.BASEBOARD_FAB2(SCH_1):PAGE178

SGPIO_PCH_SSATA_LOAD @BASEBOARD_FAB2_LIB.BASEBOARD_FAB2(SCH_1):SGPIO_PCH_SSATA_LOAD
  U7C1 AU17 GPP_F23_SSATA_SLOAD LBG_CORE_QAT_EXT_D_BGA1-IC,H91A   I147 @BASEBOARD_FAB2_LIB.BASEBOARD_FAB2(SCH_1):PAGE120
 R2N19    1      A RES_0402-49.9,1%,1/16W,CHIP,G2A    I22 @BASEBOARD_FAB2_LIB.BASEBOARD_FAB2(SCH_1):PAGE178

SGPIO_PCH_SSATA_LOAD_R @BASEBOARD_FAB2_LIB.BASEBOARD_FAB2(SCH_1):SGPIO_PCH_SSATA_LOAD_R
  J8A2   B2 SIDEBAND1 CONN36_G97614001_CP-CONN,G9761A    I26 @BASEBOARD_FAB2_LIB.BASEBOARD_FAB2(SCH_1):PAGE174
  R2L5    2      B RES_0402-2.0K,1%,1/16W,CHIP,G2A    I20 @BASEBOARD_FAB2_LIB.BASEBOARD_FAB2(SCH_1):PAGE178
 R2N19    2      B RES_0402-49.9,1%,1/16W,CHIP,G2A    I22 @BASEBOARD_FAB2_LIB.BASEBOARD_FAB2(SCH_1):PAGE178

SMB_3V3SB_HSC_SCL_R @BASEBOARD_FAB2_LIB.BASEBOARD_FAB2(SCH_1):SMB_3V3SB_HSC_SCL_R
 EU1D2   16    SCL ADM1278_SM-IC,G99251-001    I10 @BASEBOARD_FAB2_LIB.BASEBOARD_FAB2(SCH_1):PAGE199
 R1D24    2      B RES_0402-0.0,5%,1/16W,CHIP,G21A    I27 @BASEBOARD_FAB2_LIB.BASEBOARD_FAB2(SCH_1):PAGE199

SMB_3V3SB_HSC_SDA_R @BASEBOARD_FAB2_LIB.BASEBOARD_FAB2(SCH_1):SMB_3V3SB_HSC_SDA_R
 EU1D2   15    SDA ADM1278_SM-IC,G99251-001    I10 @BASEBOARD_FAB2_LIB.BASEBOARD_FAB2(SCH_1):PAGE199
 R1D25    2      B RES_0402-0.0,5%,1/16W,CHIP,G21A    I28 @BASEBOARD_FAB2_LIB.BASEBOARD_FAB2(SCH_1):PAGE199

SMB_BMC_PMBUS_STBY_LVC3_SCL @BASEBOARD_FAB2_LIB.BASEBOARD_FAB2(SCH_1):SMB_BMC_PMBUS_STBY_LVC3_SCL
 R2T54    2      B RES_0402-665,1.0%,1/16W,CHIP,GA    I84 @BASEBOARD_FAB2_LIB.BASEBOARD_FAB2(SCH_1):PAGE138
 R2T56    2      B RES_0402-20.0,1%,1/16W,CHIP,G2A   I160 @BASEBOARD_FAB2_LIB.BASEBOARD_FAB2(SCH_1):PAGE138
  R2U1    2      B RES_0402-20.0,1%,1/16W,CHIP,G2A   I218 @BASEBOARD_FAB2_LIB.BASEBOARD_FAB2(SCH_1):PAGE159
  J1F1   C6   IOC6 CONN76_H22707001_THMT1-CONN,H2A   I111 @BASEBOARD_FAB2_LIB.BASEBOARD_FAB2(SCH_1):PAGE181
  J1F3    7    IO7 CONN8_H62179001_PIP-CONN,H6217A   I189 @BASEBOARD_FAB2_LIB.BASEBOARD_FAB2(SCH_1):PAGE181
 R1D24    1      A RES_0402-0.0,5%,1/16W,CHIP,G21A    I27 @BASEBOARD_FAB2_LIB.BASEBOARD_FAB2(SCH_1):PAGE199
  U6W2    7   SCL1 PCA9515ADGKR-1-GP_DISCRET-G5-PA    I77 @BASEBOARD_FAB2_LIB.BASEBOARD_FAB2(SCH_1):PAGE247

SMB_BMC_PMBUS_STBY_LVC3_SCL_R @BASEBOARD_FAB2_LIB.BASEBOARD_FAB2(SCH_1):SMB_BMC_PMBUS_STBY_LVC3_SCL_R
  R2U1    1      A RES_0402-20.0,1%,1/16W,CHIP,G2A   I218 @BASEBOARD_FAB2_LIB.BASEBOARD_FAB2(SCH_1):PAGE159
 U25W4   P2 GPIOK6_SCL8 AST2520A1-GP-GP_ASIC2-GB1-AST2A    I95 @BASEBOARD_FAB2_LIB.BASEBOARD_FAB2(SCH_1):PAGE144

SMB_BMC_PMBUS_STBY_LVC3_SDA @BASEBOARD_FAB2_LIB.BASEBOARD_FAB2(SCH_1):SMB_BMC_PMBUS_STBY_LVC3_SDA
 R2T53    2      B RES_0402-665,1.0%,1/16W,CHIP,GA    I83 @BASEBOARD_FAB2_LIB.BASEBOARD_FAB2(SCH_1):PAGE138
 R2T55    2      B RES_0402-20.0,1%,1/16W,CHIP,G2A   I116 @BASEBOARD_FAB2_LIB.BASEBOARD_FAB2(SCH_1):PAGE138
 R2T49    2      B RES_0402-20.0,1%,1/16W,CHIP,G2A   I219 @BASEBOARD_FAB2_LIB.BASEBOARD_FAB2(SCH_1):PAGE159
  J1F1   B6   IOB6 CONN76_H22707001_THMT1-CONN,H2A   I111 @BASEBOARD_FAB2_LIB.BASEBOARD_FAB2(SCH_1):PAGE181
  J1F3    6    IO6 CONN8_H62179001_PIP-CONN,H6217A   I189 @BASEBOARD_FAB2_LIB.BASEBOARD_FAB2(SCH_1):PAGE181
 R1D25    1      A RES_0402-0.0,5%,1/16W,CHIP,G21A    I28 @BASEBOARD_FAB2_LIB.BASEBOARD_FAB2(SCH_1):PAGE199
  U6W2    6   SDA1 PCA9515ADGKR-1-GP_DISCRET-G5-PA    I77 @BASEBOARD_FAB2_LIB.BASEBOARD_FAB2(SCH_1):PAGE247

SMB_BMC_PMBUS_STBY_LVC3_SDA_R @BASEBOARD_FAB2_LIB.BASEBOARD_FAB2(SCH_1):SMB_BMC_PMBUS_STBY_LVC3_SDA_R
 R2T49    1      A RES_0402-20.0,1%,1/16W,CHIP,G2A   I219 @BASEBOARD_FAB2_LIB.BASEBOARD_FAB2(SCH_1):PAGE159
 U25W4   R1 GPIOK7_SDA8 AST2520A1-GP-GP_ASIC2-GB1-AST2A    I95 @BASEBOARD_FAB2_LIB.BASEBOARD_FAB2(SCH_1):PAGE144

SMB_CPU1_PE_HP_GTL_R_SCL @BASEBOARD_FAB2_LIB.BASEBOARD_FAB2(SCH_1):SMB_CPU1_PE_HP_GTL_R_SCL
  U1B2    2   SCLA PCA9517_SM-IC,G77073-001-GND=GA     I1 @BASEBOARD_FAB2_LIB.BASEBOARD_FAB2(SCH_1):PAGE163
  R6N8    2      B RES_0402-10.0,1%,1/16W,CHIP,G2A     I2 @BASEBOARD_FAB2_LIB.BASEBOARD_FAB2(SCH_1):PAGE163
 R9M19    2      B RES_0402-240,1.0%,1/16W,CHIP,GA     I7 @BASEBOARD_FAB2_LIB.BASEBOARD_FAB2(SCH_1):PAGE163

SMB_CPU1_PE_HP_GTL_R_SDA @BASEBOARD_FAB2_LIB.BASEBOARD_FAB2(SCH_1):SMB_CPU1_PE_HP_GTL_R_SDA
  U1B2    3   SDAA PCA9517_SM-IC,G77073-001-GND=GA     I1 @BASEBOARD_FAB2_LIB.BASEBOARD_FAB2(SCH_1):PAGE163
  R6N9    2      B RES_0402-10.0,1%,1/16W,CHIP,G2A     I3 @BASEBOARD_FAB2_LIB.BASEBOARD_FAB2(SCH_1):PAGE163
 R9M18    2      B RES_0402-240,1.0%,1/16W,CHIP,GA     I6 @BASEBOARD_FAB2_LIB.BASEBOARD_FAB2(SCH_1):PAGE163

SMB_CPU1_PE_HP_GTL_SCL @BASEBOARD_FAB2_LIB.BASEBOARD_FAB2(SCH_1):SMB_CPU1_PE_HP_GTL_SCL
  U2D1 AM19 PE_HP_SCL SKX_EXT_B_BGA1-IC,TBD   I172 @BASEBOARD_FAB2_LIB.BASEBOARD_FAB2(SCH_1):PAGE55
  R6N8    1      A RES_0402-10.0,1%,1/16W,CHIP,G2A     I2 @BASEBOARD_FAB2_LIB.BASEBOARD_FAB2(SCH_1):PAGE163

SMB_CPU1_PE_HP_GTL_SDA @BASEBOARD_FAB2_LIB.BASEBOARD_FAB2(SCH_1):SMB_CPU1_PE_HP_GTL_SDA
  U2D1 AL18 PE_HP_SDA SKX_EXT_B_BGA1-IC,TBD   I172 @BASEBOARD_FAB2_LIB.BASEBOARD_FAB2(SCH_1):PAGE55
  R6N9    1      A RES_0402-10.0,1%,1/16W,CHIP,G2A     I3 @BASEBOARD_FAB2_LIB.BASEBOARD_FAB2(SCH_1):PAGE163

SMB_DDR_ABC_SCL_G @BASEBOARD_FAB2_LIB.BASEBOARD_FAB2(SCH_1):SMB_DDR_ABC_SCL_G
  U6F1    2   SCLA PCA9617_SSOP-IC,G81764-001-GNDA    I15 @BASEBOARD_FAB2_LIB.BASEBOARD_FAB2(SCH_1):PAGE99
  R4T5    2      B RES_0402-240,1.0%,1/16W,CHIP,GA    I19 @BASEBOARD_FAB2_LIB.BASEBOARD_FAB2(SCH_1):PAGE99
  R4T3    2      B RES_0402-10.0,1%,1/16W,CHIP,G2A    I83 @BASEBOARD_FAB2_LIB.BASEBOARD_FAB2(SCH_1):PAGE99

SMB_DDR_ABC_SCL_G_R @BASEBOARD_FAB2_LIB.BASEBOARD_FAB2(SCH_1):SMB_DDR_ABC_SCL_G_R
  U5D1 AJ18 DDR012_SPDSCL SKX_EXT_B_BGA1-IC,TBD   I259 @BASEBOARD_FAB2_LIB.BASEBOARD_FAB2(SCH_1):PAGE21
  R4T3    1      A RES_0402-10.0,1%,1/16W,CHIP,G2A    I83 @BASEBOARD_FAB2_LIB.BASEBOARD_FAB2(SCH_1):PAGE99

SMB_DDR_ABC_SDA_G @BASEBOARD_FAB2_LIB.BASEBOARD_FAB2(SCH_1):SMB_DDR_ABC_SDA_G
  U6F1    3   SDAA PCA9617_SSOP-IC,G81764-001-GNDA    I15 @BASEBOARD_FAB2_LIB.BASEBOARD_FAB2(SCH_1):PAGE99
  R4T6    2      B RES_0402-240,1.0%,1/16W,CHIP,GA    I17 @BASEBOARD_FAB2_LIB.BASEBOARD_FAB2(SCH_1):PAGE99
  R4T4    2      B RES_0402-10.0,1%,1/16W,CHIP,G2A    I20 @BASEBOARD_FAB2_LIB.BASEBOARD_FAB2(SCH_1):PAGE99

SMB_DDR_ABC_SDA_G_R @BASEBOARD_FAB2_LIB.BASEBOARD_FAB2(SCH_1):SMB_DDR_ABC_SDA_G_R
  U5D1 AF17 DDR012_SPDSDA SKX_EXT_B_BGA1-IC,TBD   I259 @BASEBOARD_FAB2_LIB.BASEBOARD_FAB2(SCH_1):PAGE21
  R4T4    1      A RES_0402-10.0,1%,1/16W,CHIP,G2A    I20 @BASEBOARD_FAB2_LIB.BASEBOARD_FAB2(SCH_1):PAGE99

SMB_DDR_ABC_VPP_SCL @BASEBOARD_FAB2_LIB.BASEBOARD_FAB2(SCH_1):SMB_DDR_ABC_VPP_SCL
  J4G1  141    SCL SCONN288_H44441004_PIP-SCONN,HA     I1 @BASEBOARD_FAB2_LIB.BASEBOARD_FAB2(SCH_1):PAGE43
  J6T1  141    SCL SCONN288_H44441003_PIP-SCONN,HA    I13 @BASEBOARD_FAB2_LIB.BASEBOARD_FAB2(SCH_1):PAGE44
  J4G2  141    SCL SCONN288_H44441004_PIP-SCONN,HA   I111 @BASEBOARD_FAB2_LIB.BASEBOARD_FAB2(SCH_1):PAGE45
  J6U1  141    SCL SCONN288_H44441003_PIP-SCONN,HA    I14 @BASEBOARD_FAB2_LIB.BASEBOARD_FAB2(SCH_1):PAGE46
  J4G3  141    SCL SCONN288_H44441004_PIP-SCONN,HA   I111 @BASEBOARD_FAB2_LIB.BASEBOARD_FAB2(SCH_1):PAGE47
  J6U2  141    SCL SCONN288_H44441003_PIP-SCONN,HA   I111 @BASEBOARD_FAB2_LIB.BASEBOARD_FAB2(SCH_1):PAGE48
  R4T9    2      B RES_0402-20.0,1%,1/16W,CHIP,G2A     I9 @BASEBOARD_FAB2_LIB.BASEBOARD_FAB2(SCH_1):PAGE99

SMB_DDR_ABC_VPP_SCL_R @BASEBOARD_FAB2_LIB.BASEBOARD_FAB2(SCH_1):SMB_DDR_ABC_VPP_SCL_R
  R4T9    1      A RES_0402-20.0,1%,1/16W,CHIP,G2A     I9 @BASEBOARD_FAB2_LIB.BASEBOARD_FAB2(SCH_1):PAGE99
  R4T7    2      B RES_0402-665,1.0%,1/16W,CHIP,GA    I13 @BASEBOARD_FAB2_LIB.BASEBOARD_FAB2(SCH_1):PAGE99
  U6F1    7   SCLB PCA9617_SSOP-IC,G81764-001-GNDA    I15 @BASEBOARD_FAB2_LIB.BASEBOARD_FAB2(SCH_1):PAGE99

SMB_DDR_ABC_VPP_SDA @BASEBOARD_FAB2_LIB.BASEBOARD_FAB2(SCH_1):SMB_DDR_ABC_VPP_SDA
  J4G1  285    SDA SCONN288_H44441004_PIP-SCONN,HA     I1 @BASEBOARD_FAB2_LIB.BASEBOARD_FAB2(SCH_1):PAGE43
  J6T1  285    SDA SCONN288_H44441003_PIP-SCONN,HA    I13 @BASEBOARD_FAB2_LIB.BASEBOARD_FAB2(SCH_1):PAGE44
  J4G2  285    SDA SCONN288_H44441004_PIP-SCONN,HA   I111 @BASEBOARD_FAB2_LIB.BASEBOARD_FAB2(SCH_1):PAGE45
  J6U1  285    SDA SCONN288_H44441003_PIP-SCONN,HA    I14 @BASEBOARD_FAB2_LIB.BASEBOARD_FAB2(SCH_1):PAGE46
  J4G3  285    SDA SCONN288_H44441004_PIP-SCONN,HA   I111 @BASEBOARD_FAB2_LIB.BASEBOARD_FAB2(SCH_1):PAGE47
  J6U2  285    SDA SCONN288_H44441003_PIP-SCONN,HA   I111 @BASEBOARD_FAB2_LIB.BASEBOARD_FAB2(SCH_1):PAGE48
 R4T10    2      B RES_0402-20.0,1%,1/16W,CHIP,G2A    I10 @BASEBOARD_FAB2_LIB.BASEBOARD_FAB2(SCH_1):PAGE99

SMB_DDR_ABC_VPP_SDA_R @BASEBOARD_FAB2_LIB.BASEBOARD_FAB2(SCH_1):SMB_DDR_ABC_VPP_SDA_R
 R4T10    1      A RES_0402-20.0,1%,1/16W,CHIP,G2A    I10 @BASEBOARD_FAB2_LIB.BASEBOARD_FAB2(SCH_1):PAGE99
  R4T8    2      B RES_0402-665,1.0%,1/16W,CHIP,GA    I11 @BASEBOARD_FAB2_LIB.BASEBOARD_FAB2(SCH_1):PAGE99
  U6F1    6   SDAB PCA9617_SSOP-IC,G81764-001-GNDA    I15 @BASEBOARD_FAB2_LIB.BASEBOARD_FAB2(SCH_1):PAGE99

SMB_DDR_DEF_SCL_G @BASEBOARD_FAB2_LIB.BASEBOARD_FAB2(SCH_1):SMB_DDR_DEF_SCL_G
  U7E1    2   SCLA PCA9617_SSOP-IC,G81764-001-GNDA    I61 @BASEBOARD_FAB2_LIB.BASEBOARD_FAB2(SCH_1):PAGE99
 R3P60    2      B RES_0402-240,1.0%,1/16W,CHIP,GA    I67 @BASEBOARD_FAB2_LIB.BASEBOARD_FAB2(SCH_1):PAGE99
  R3R7    2      B RES_0402-10.0,1%,1/16W,CHIP,G2A    I88 @BASEBOARD_FAB2_LIB.BASEBOARD_FAB2(SCH_1):PAGE99

SMB_DDR_DEF_SCL_G_R @BASEBOARD_FAB2_LIB.BASEBOARD_FAB2(SCH_1):SMB_DDR_DEF_SCL_G_R
  U5D1 AE18 DDR345_SPDSCL SKX_EXT_B_BGA1-IC,TBD   I259 @BASEBOARD_FAB2_LIB.BASEBOARD_FAB2(SCH_1):PAGE21
  R3R7    1      A RES_0402-10.0,1%,1/16W,CHIP,G2A    I88 @BASEBOARD_FAB2_LIB.BASEBOARD_FAB2(SCH_1):PAGE99

SMB_DDR_DEF_SDA_G @BASEBOARD_FAB2_LIB.BASEBOARD_FAB2(SCH_1):SMB_DDR_DEF_SDA_G
  U7E1    3   SDAA PCA9617_SSOP-IC,G81764-001-GNDA    I61 @BASEBOARD_FAB2_LIB.BASEBOARD_FAB2(SCH_1):PAGE99
 R3R13    2      B RES_0402-240,1.0%,1/16W,CHIP,GA    I65 @BASEBOARD_FAB2_LIB.BASEBOARD_FAB2(SCH_1):PAGE99
 R3R14    2      B RES_0402-10.0,1%,1/16W,CHIP,G2A   I110 @BASEBOARD_FAB2_LIB.BASEBOARD_FAB2(SCH_1):PAGE99

SMB_DDR_DEF_SDA_G_R @BASEBOARD_FAB2_LIB.BASEBOARD_FAB2(SCH_1):SMB_DDR_DEF_SDA_G_R
  U5D1 AD17 DDR345_SPDSDA SKX_EXT_B_BGA1-IC,TBD   I259 @BASEBOARD_FAB2_LIB.BASEBOARD_FAB2(SCH_1):PAGE21
 R3R14    1      A RES_0402-10.0,1%,1/16W,CHIP,G2A   I110 @BASEBOARD_FAB2_LIB.BASEBOARD_FAB2(SCH_1):PAGE99

SMB_DDR_DEF_VPP_SCL @BASEBOARD_FAB2_LIB.BASEBOARD_FAB2(SCH_1):SMB_DDR_DEF_VPP_SCL
  J4B1  141    SCL SCONN288_H44441004_PIP-SCONN,HA   I111 @BASEBOARD_FAB2_LIB.BASEBOARD_FAB2(SCH_1):PAGE49
  J6M1  141    SCL SCONN288_H44441003_PIP-SCONN,HA   I158 @BASEBOARD_FAB2_LIB.BASEBOARD_FAB2(SCH_1):PAGE50
  J4A2  141    SCL SCONN288_H44441004_PIP-SCONN,HA   I111 @BASEBOARD_FAB2_LIB.BASEBOARD_FAB2(SCH_1):PAGE51
  J6L2  141    SCL SCONN288_H44441003_PIP-SCONN,HA    I12 @BASEBOARD_FAB2_LIB.BASEBOARD_FAB2(SCH_1):PAGE52
  J4A1  141    SCL SCONN288_H44441004_PIP-SCONN,HA   I111 @BASEBOARD_FAB2_LIB.BASEBOARD_FAB2(SCH_1):PAGE53
  J6L1  141    SCL SCONN288_H44441003_PIP-SCONN,HA   I111 @BASEBOARD_FAB2_LIB.BASEBOARD_FAB2(SCH_1):PAGE54
  R3R8    2      B RES_0402-20.0,1%,1/16W,CHIP,G2A    I35 @BASEBOARD_FAB2_LIB.BASEBOARD_FAB2(SCH_1):PAGE99

SMB_DDR_DEF_VPP_SCL_R @BASEBOARD_FAB2_LIB.BASEBOARD_FAB2(SCH_1):SMB_DDR_DEF_VPP_SCL_R
  R3R8    1      A RES_0402-20.0,1%,1/16W,CHIP,G2A    I35 @BASEBOARD_FAB2_LIB.BASEBOARD_FAB2(SCH_1):PAGE99
  U7E1    7   SCLB PCA9617_SSOP-IC,G81764-001-GNDA    I61 @BASEBOARD_FAB2_LIB.BASEBOARD_FAB2(SCH_1):PAGE99
  R3R5    2      B RES_0402-665,1.0%,1/16W,CHIP,GA   I103 @BASEBOARD_FAB2_LIB.BASEBOARD_FAB2(SCH_1):PAGE99

SMB_DDR_DEF_VPP_SDA @BASEBOARD_FAB2_LIB.BASEBOARD_FAB2(SCH_1):SMB_DDR_DEF_VPP_SDA
  J4B1  285    SDA SCONN288_H44441004_PIP-SCONN,HA   I111 @BASEBOARD_FAB2_LIB.BASEBOARD_FAB2(SCH_1):PAGE49
  J6M1  285    SDA SCONN288_H44441003_PIP-SCONN,HA   I158 @BASEBOARD_FAB2_LIB.BASEBOARD_FAB2(SCH_1):PAGE50
  J4A2  285    SDA SCONN288_H44441004_PIP-SCONN,HA   I111 @BASEBOARD_FAB2_LIB.BASEBOARD_FAB2(SCH_1):PAGE51
  J6L2  285    SDA SCONN288_H44441003_PIP-SCONN,HA    I12 @BASEBOARD_FAB2_LIB.BASEBOARD_FAB2(SCH_1):PAGE52
  J4A1  285    SDA SCONN288_H44441004_PIP-SCONN,HA   I111 @BASEBOARD_FAB2_LIB.BASEBOARD_FAB2(SCH_1):PAGE53
  J6L1  285    SDA SCONN288_H44441003_PIP-SCONN,HA   I111 @BASEBOARD_FAB2_LIB.BASEBOARD_FAB2(SCH_1):PAGE54
  R3R9    2      B RES_0402-20.0,1%,1/16W,CHIP,G2A    I34 @BASEBOARD_FAB2_LIB.BASEBOARD_FAB2(SCH_1):PAGE99

SMB_DDR_DEF_VPP_SDA_R @BASEBOARD_FAB2_LIB.BASEBOARD_FAB2(SCH_1):SMB_DDR_DEF_VPP_SDA_R
  R3R9    1      A RES_0402-20.0,1%,1/16W,CHIP,G2A    I34 @BASEBOARD_FAB2_LIB.BASEBOARD_FAB2(SCH_1):PAGE99
  U7E1    6   SDAB PCA9617_SSOP-IC,G81764-001-GNDA    I61 @BASEBOARD_FAB2_LIB.BASEBOARD_FAB2(SCH_1):PAGE99
 R3R12    2      B RES_0402-665,1.0%,1/16W,CHIP,GA   I101 @BASEBOARD_FAB2_LIB.BASEBOARD_FAB2(SCH_1):PAGE99

SMB_DDR_GHJ_SCL_G @BASEBOARD_FAB2_LIB.BASEBOARD_FAB2(SCH_1):SMB_DDR_GHJ_SCL_G
  U4G1    2   SCLA PCA9617_SSOP-IC,G81764-001-GNDA    I63 @BASEBOARD_FAB2_LIB.BASEBOARD_FAB2(SCH_1):PAGE99
  R6T2    2      B RES_0402-240,1.0%,1/16W,CHIP,GA    I72 @BASEBOARD_FAB2_LIB.BASEBOARD_FAB2(SCH_1):PAGE99
  R6T3    2      B RES_0402-10.0,1%,1/16W,CHIP,G2A    I92 @BASEBOARD_FAB2_LIB.BASEBOARD_FAB2(SCH_1):PAGE99

SMB_DDR_GHJ_SCL_G_R @BASEBOARD_FAB2_LIB.BASEBOARD_FAB2(SCH_1):SMB_DDR_GHJ_SCL_G_R
  U2D1 AJ18 DDR012_SPDSCL SKX_EXT_B_BGA1-IC,TBD   I172 @BASEBOARD_FAB2_LIB.BASEBOARD_FAB2(SCH_1):PAGE55
  R6T3    1      A RES_0402-10.0,1%,1/16W,CHIP,G2A    I92 @BASEBOARD_FAB2_LIB.BASEBOARD_FAB2(SCH_1):PAGE99

SMB_DDR_GHJ_SDA_G @BASEBOARD_FAB2_LIB.BASEBOARD_FAB2(SCH_1):SMB_DDR_GHJ_SDA_G
  U4G1    3   SDAA PCA9617_SSOP-IC,G81764-001-GNDA    I63 @BASEBOARD_FAB2_LIB.BASEBOARD_FAB2(SCH_1):PAGE99
  R6T1    2      B RES_0402-240,1.0%,1/16W,CHIP,GA    I70 @BASEBOARD_FAB2_LIB.BASEBOARD_FAB2(SCH_1):PAGE99
  R6T4    2      B RES_0402-10.0,1%,1/16W,CHIP,G2A   I111 @BASEBOARD_FAB2_LIB.BASEBOARD_FAB2(SCH_1):PAGE99

SMB_DDR_GHJ_SDA_G_R @BASEBOARD_FAB2_LIB.BASEBOARD_FAB2(SCH_1):SMB_DDR_GHJ_SDA_G_R
  U2D1 AF17 DDR012_SPDSDA SKX_EXT_B_BGA1-IC,TBD   I172 @BASEBOARD_FAB2_LIB.BASEBOARD_FAB2(SCH_1):PAGE55
  R6T4    1      A RES_0402-10.0,1%,1/16W,CHIP,G2A   I111 @BASEBOARD_FAB2_LIB.BASEBOARD_FAB2(SCH_1):PAGE99

SMB_DDR_GHJ_VPP_SCL @BASEBOARD_FAB2_LIB.BASEBOARD_FAB2(SCH_1):SMB_DDR_GHJ_VPP_SCL
  J1G1  141    SCL SCONN288_H44441004_PIP-SCONN,HA   I111 @BASEBOARD_FAB2_LIB.BASEBOARD_FAB2(SCH_1):PAGE77
  J9T1  141    SCL SCONN288_H44441003_PIP-SCONN,HA    I13 @BASEBOARD_FAB2_LIB.BASEBOARD_FAB2(SCH_1):PAGE78
  J1G2  141    SCL SCONN288_H44441004_PIP-SCONN,HA   I111 @BASEBOARD_FAB2_LIB.BASEBOARD_FAB2(SCH_1):PAGE79
  J9U1  141    SCL SCONN288_H44441003_PIP-SCONN,HA    I24 @BASEBOARD_FAB2_LIB.BASEBOARD_FAB2(SCH_1):PAGE80
  J1G3  141    SCL SCONN288_H44441004_PIP-SCONN,HA   I186 @BASEBOARD_FAB2_LIB.BASEBOARD_FAB2(SCH_1):PAGE81
  J9U2  141    SCL SCONN288_H44441003_PIP-SCONN,HA   I187 @BASEBOARD_FAB2_LIB.BASEBOARD_FAB2(SCH_1):PAGE82
 R6U13    2      B RES_0402-20.0,1%,1/16W,CHIP,G2A    I42 @BASEBOARD_FAB2_LIB.BASEBOARD_FAB2(SCH_1):PAGE99

SMB_DDR_GHJ_VPP_SCL_R @BASEBOARD_FAB2_LIB.BASEBOARD_FAB2(SCH_1):SMB_DDR_GHJ_VPP_SCL_R
 R6U13    1      A RES_0402-20.0,1%,1/16W,CHIP,G2A    I42 @BASEBOARD_FAB2_LIB.BASEBOARD_FAB2(SCH_1):PAGE99
  U4G1    7   SCLB PCA9617_SSOP-IC,G81764-001-GNDA    I63 @BASEBOARD_FAB2_LIB.BASEBOARD_FAB2(SCH_1):PAGE99
 R6U17    2      B RES_0402-665,1.0%,1/16W,CHIP,GA   I106 @BASEBOARD_FAB2_LIB.BASEBOARD_FAB2(SCH_1):PAGE99

SMB_DDR_GHJ_VPP_SDA @BASEBOARD_FAB2_LIB.BASEBOARD_FAB2(SCH_1):SMB_DDR_GHJ_VPP_SDA
  J1G1  285    SDA SCONN288_H44441004_PIP-SCONN,HA   I111 @BASEBOARD_FAB2_LIB.BASEBOARD_FAB2(SCH_1):PAGE77
  J9T1  285    SDA SCONN288_H44441003_PIP-SCONN,HA    I13 @BASEBOARD_FAB2_LIB.BASEBOARD_FAB2(SCH_1):PAGE78
  J1G2  285    SDA SCONN288_H44441004_PIP-SCONN,HA   I111 @BASEBOARD_FAB2_LIB.BASEBOARD_FAB2(SCH_1):PAGE79
  J9U1  285    SDA SCONN288_H44441003_PIP-SCONN,HA    I24 @BASEBOARD_FAB2_LIB.BASEBOARD_FAB2(SCH_1):PAGE80
  J1G3  285    SDA SCONN288_H44441004_PIP-SCONN,HA   I186 @BASEBOARD_FAB2_LIB.BASEBOARD_FAB2(SCH_1):PAGE81
  J9U2  285    SDA SCONN288_H44441003_PIP-SCONN,HA   I187 @BASEBOARD_FAB2_LIB.BASEBOARD_FAB2(SCH_1):PAGE82
 R6U14    2      B RES_0402-20.0,1%,1/16W,CHIP,G2A    I43 @BASEBOARD_FAB2_LIB.BASEBOARD_FAB2(SCH_1):PAGE99

SMB_DDR_GHJ_VPP_SDA_R @BASEBOARD_FAB2_LIB.BASEBOARD_FAB2(SCH_1):SMB_DDR_GHJ_VPP_SDA_R
 R6U14    1      A RES_0402-20.0,1%,1/16W,CHIP,G2A    I43 @BASEBOARD_FAB2_LIB.BASEBOARD_FAB2(SCH_1):PAGE99
  U4G1    6   SDAB PCA9617_SSOP-IC,G81764-001-GNDA    I63 @BASEBOARD_FAB2_LIB.BASEBOARD_FAB2(SCH_1):PAGE99
 R6U18    2      B RES_0402-665,1.0%,1/16W,CHIP,GA   I104 @BASEBOARD_FAB2_LIB.BASEBOARD_FAB2(SCH_1):PAGE99

SMB_DDR_KLM_SCL_G @BASEBOARD_FAB2_LIB.BASEBOARD_FAB2(SCH_1):SMB_DDR_KLM_SCL_G
  U3B1    2   SCLA PCA9617_SSOP-IC,G81764-001-GNDA    I75 @BASEBOARD_FAB2_LIB.BASEBOARD_FAB2(SCH_1):PAGE99
  R7M2    2      B RES_0402-240,1.0%,1/16W,CHIP,GA    I79 @BASEBOARD_FAB2_LIB.BASEBOARD_FAB2(SCH_1):PAGE99
  R7M3    2      B RES_0402-10.0,1%,1/16W,CHIP,G2A    I98 @BASEBOARD_FAB2_LIB.BASEBOARD_FAB2(SCH_1):PAGE99

SMB_DDR_KLM_SCL_G_R @BASEBOARD_FAB2_LIB.BASEBOARD_FAB2(SCH_1):SMB_DDR_KLM_SCL_G_R
  U2D1 AE18 DDR345_SPDSCL SKX_EXT_B_BGA1-IC,TBD   I172 @BASEBOARD_FAB2_LIB.BASEBOARD_FAB2(SCH_1):PAGE55
  R7M3    1      A RES_0402-10.0,1%,1/16W,CHIP,G2A    I98 @BASEBOARD_FAB2_LIB.BASEBOARD_FAB2(SCH_1):PAGE99

SMB_DDR_KLM_SDA_G @BASEBOARD_FAB2_LIB.BASEBOARD_FAB2(SCH_1):SMB_DDR_KLM_SDA_G
  U3B1    3   SDAA PCA9617_SSOP-IC,G81764-001-GNDA    I75 @BASEBOARD_FAB2_LIB.BASEBOARD_FAB2(SCH_1):PAGE99
  R7M7    2      B RES_0402-240,1.0%,1/16W,CHIP,GA    I77 @BASEBOARD_FAB2_LIB.BASEBOARD_FAB2(SCH_1):PAGE99
  R7M8    2      B RES_0402-10.0,1%,1/16W,CHIP,G2A   I112 @BASEBOARD_FAB2_LIB.BASEBOARD_FAB2(SCH_1):PAGE99

SMB_DDR_KLM_SDA_G_R @BASEBOARD_FAB2_LIB.BASEBOARD_FAB2(SCH_1):SMB_DDR_KLM_SDA_G_R
  U2D1 AD17 DDR345_SPDSDA SKX_EXT_B_BGA1-IC,TBD   I172 @BASEBOARD_FAB2_LIB.BASEBOARD_FAB2(SCH_1):PAGE55
  R7M8    1      A RES_0402-10.0,1%,1/16W,CHIP,G2A   I112 @BASEBOARD_FAB2_LIB.BASEBOARD_FAB2(SCH_1):PAGE99

SMB_DDR_KLM_VPP_SCL @BASEBOARD_FAB2_LIB.BASEBOARD_FAB2(SCH_1):SMB_DDR_KLM_VPP_SCL
  J1B1  141    SCL SCONN288_H44441004_PIP-SCONN,HA   I111 @BASEBOARD_FAB2_LIB.BASEBOARD_FAB2(SCH_1):PAGE83
  J9M1  141    SCL SCONN288_H44441003_PIP-SCONN,HA    I14 @BASEBOARD_FAB2_LIB.BASEBOARD_FAB2(SCH_1):PAGE84
  J1A2  141    SCL SCONN288_H44441004_PIP-SCONN,HA   I111 @BASEBOARD_FAB2_LIB.BASEBOARD_FAB2(SCH_1):PAGE85
  J9L2  141    SCL SCONN288_H44441003_PIP-SCONN,HA    I12 @BASEBOARD_FAB2_LIB.BASEBOARD_FAB2(SCH_1):PAGE86
  J1A1  141    SCL SCONN288_H44441004_PIP-SCONN,HA   I186 @BASEBOARD_FAB2_LIB.BASEBOARD_FAB2(SCH_1):PAGE87
  J9L1  141    SCL SCONN288_H44441003_PIP-SCONN,HA   I111 @BASEBOARD_FAB2_LIB.BASEBOARD_FAB2(SCH_1):PAGE88
  R7M4    2      B RES_0402-20.0,1%,1/16W,CHIP,G2A    I56 @BASEBOARD_FAB2_LIB.BASEBOARD_FAB2(SCH_1):PAGE99

SMB_DDR_KLM_VPP_SCL_R @BASEBOARD_FAB2_LIB.BASEBOARD_FAB2(SCH_1):SMB_DDR_KLM_VPP_SCL_R
  R7M4    1      A RES_0402-20.0,1%,1/16W,CHIP,G2A    I56 @BASEBOARD_FAB2_LIB.BASEBOARD_FAB2(SCH_1):PAGE99
  U3B1    7   SCLB PCA9617_SSOP-IC,G81764-001-GNDA    I75 @BASEBOARD_FAB2_LIB.BASEBOARD_FAB2(SCH_1):PAGE99
  R7M1    2      B RES_0402-665,1.0%,1/16W,CHIP,GA   I109 @BASEBOARD_FAB2_LIB.BASEBOARD_FAB2(SCH_1):PAGE99

SMB_DDR_KLM_VPP_SDA @BASEBOARD_FAB2_LIB.BASEBOARD_FAB2(SCH_1):SMB_DDR_KLM_VPP_SDA
  J1B1  285    SDA SCONN288_H44441004_PIP-SCONN,HA   I111 @BASEBOARD_FAB2_LIB.BASEBOARD_FAB2(SCH_1):PAGE83
  J9M1  285    SDA SCONN288_H44441003_PIP-SCONN,HA    I14 @BASEBOARD_FAB2_LIB.BASEBOARD_FAB2(SCH_1):PAGE84
  J1A2  285    SDA SCONN288_H44441004_PIP-SCONN,HA   I111 @BASEBOARD_FAB2_LIB.BASEBOARD_FAB2(SCH_1):PAGE85
  J9L2  285    SDA SCONN288_H44441003_PIP-SCONN,HA    I12 @BASEBOARD_FAB2_LIB.BASEBOARD_FAB2(SCH_1):PAGE86
  J1A1  285    SDA SCONN288_H44441004_PIP-SCONN,HA   I186 @BASEBOARD_FAB2_LIB.BASEBOARD_FAB2(SCH_1):PAGE87
  J9L1  285    SDA SCONN288_H44441003_PIP-SCONN,HA   I111 @BASEBOARD_FAB2_LIB.BASEBOARD_FAB2(SCH_1):PAGE88
  R7M5    2      B RES_0402-20.0,1%,1/16W,CHIP,G2A    I55 @BASEBOARD_FAB2_LIB.BASEBOARD_FAB2(SCH_1):PAGE99

SMB_DDR_KLM_VPP_SDA_R @BASEBOARD_FAB2_LIB.BASEBOARD_FAB2(SCH_1):SMB_DDR_KLM_VPP_SDA_R
  R7M5    1      A RES_0402-20.0,1%,1/16W,CHIP,G2A    I55 @BASEBOARD_FAB2_LIB.BASEBOARD_FAB2(SCH_1):PAGE99
  U3B1    6   SDAB PCA9617_SSOP-IC,G81764-001-GNDA    I75 @BASEBOARD_FAB2_LIB.BASEBOARD_FAB2(SCH_1):PAGE99
  R7M6    2      B RES_0402-665,1.0%,1/16W,CHIP,GA   I107 @BASEBOARD_FAB2_LIB.BASEBOARD_FAB2(SCH_1):PAGE99

SMB_HFI0_CPU0_LVC2_SCL @BASEBOARD_FAB2_LIB.BASEBOARD_FAB2(SCH_1):SMB_HFI0_CPU0_LVC2_SCL
  U5D1 BN22 CD_HFI0_I2CCLK SKX_EXT_B_BGA1-IC,TBD    I61 @BASEBOARD_FAB2_LIB.BASEBOARD_FAB2(SCH_1):PAGE29
  J8B1    2    IO2 SCONN24_H46321001_SM-SCONN,H46A     I1 @BASEBOARD_FAB2_LIB.BASEBOARD_FAB2(SCH_1):PAGE91
  R8B6    2      B RES_0402-1.8K,1%,1/16W,CHIP,G2A    I37 @BASEBOARD_FAB2_LIB.BASEBOARD_FAB2(SCH_1):PAGE91

SMB_HFI0_CPU0_LVC2_SDA @BASEBOARD_FAB2_LIB.BASEBOARD_FAB2(SCH_1):SMB_HFI0_CPU0_LVC2_SDA
  U5D1 BP23 CD_HFI0_I2CDAT SKX_EXT_B_BGA1-IC,TBD    I61 @BASEBOARD_FAB2_LIB.BASEBOARD_FAB2(SCH_1):PAGE29
  J8B1    4    IO4 SCONN24_H46321001_SM-SCONN,H46A     I1 @BASEBOARD_FAB2_LIB.BASEBOARD_FAB2(SCH_1):PAGE91
  R8B7    2      B RES_0402-1.8K,1%,1/16W,CHIP,G2A    I36 @BASEBOARD_FAB2_LIB.BASEBOARD_FAB2(SCH_1):PAGE91

SMB_HFI1_CPU0_LVC2_SCL @BASEBOARD_FAB2_LIB.BASEBOARD_FAB2(SCH_1):SMB_HFI1_CPU0_LVC2_SCL
  U5D1 BJ22 CD_HFI1_I2CCLK SKX_EXT_B_BGA1-IC,TBD    I61 @BASEBOARD_FAB2_LIB.BASEBOARD_FAB2(SCH_1):PAGE29
  J8B1   10   IO10 SCONN24_H46321001_SM-SCONN,H46A     I1 @BASEBOARD_FAB2_LIB.BASEBOARD_FAB2(SCH_1):PAGE91
 R8B11    2      B RES_0402-1.8K,1%,1/16W,CHIP,G2A    I35 @BASEBOARD_FAB2_LIB.BASEBOARD_FAB2(SCH_1):PAGE91

SMB_HFI1_CPU0_LVC2_SDA @BASEBOARD_FAB2_LIB.BASEBOARD_FAB2(SCH_1):SMB_HFI1_CPU0_LVC2_SDA
  U5D1 BH23 CD_HFI1_I2CDAT SKX_EXT_B_BGA1-IC,TBD    I61 @BASEBOARD_FAB2_LIB.BASEBOARD_FAB2(SCH_1):PAGE29
  J8B1   12   IO12 SCONN24_H46321001_SM-SCONN,H46A     I1 @BASEBOARD_FAB2_LIB.BASEBOARD_FAB2(SCH_1):PAGE91
 R8B13    2      B RES_0402-1.8K,1%,1/16W,CHIP,G2A    I34 @BASEBOARD_FAB2_LIB.BASEBOARD_FAB2(SCH_1):PAGE91

SMB_HOST_STBY_LVC3_SCL @BASEBOARD_FAB2_LIB.BASEBOARD_FAB2(SCH_1):SMB_HOST_STBY_LVC3_SCL
 EU8F2   38 SMBCLK ICS9FGP204_MLFP-IC,E95226-001    I34 @BASEBOARD_FAB2_LIB.BASEBOARD_FAB2(SCH_1):PAGE101
 R4D37    1      A RES_0402-33.2,1%,1/16W,CHIP,G2A    I87 @BASEBOARD_FAB2_LIB.BASEBOARD_FAB2(SCH_1):PAGE102
  J9A3   53   IO53 SCONN60_C21100002_SMLF-CONN,C2A    I26 @BASEBOARD_FAB2_LIB.BASEBOARD_FAB2(SCH_1):PAGE111
 R8C15    2      B RES_0402-2.0K,1%,1/16W,CHIP,G2A    I92 @BASEBOARD_FAB2_LIB.BASEBOARD_FAB2(SCH_1):PAGE138
 R8C14    2      B RES_0402-20.0,1%,1/16W,CHIP,G2A   I168 @BASEBOARD_FAB2_LIB.BASEBOARD_FAB2(SCH_1):PAGE138
  J8C1    3    IO3 CONN3_C95678002_PIP-CONN,C9567A   I285 @BASEBOARD_FAB2_LIB.BASEBOARD_FAB2(SCH_1):PAGE156
 R2U34    2      B RES_0402-20.0,1%,1/16W,CHIP,G2A   I230 @BASEBOARD_FAB2_LIB.BASEBOARD_FAB2(SCH_1):PAGE159
 R6W22    1      A RES_0402-20.0,1%,1/16W,CHIP,G2A    I94 @BASEBOARD_FAB2_LIB.BASEBOARD_FAB2(SCH_1):PAGE247

SMB_HOST_STBY_LVC3_SCL_R @BASEBOARD_FAB2_LIB.BASEBOARD_FAB2(SCH_1):SMB_HOST_STBY_LVC3_SCL_R
 R2U34    1      A RES_0402-20.0,1%,1/16W,CHIP,G2A   I230 @BASEBOARD_FAB2_LIB.BASEBOARD_FAB2(SCH_1):PAGE159
 U25W4   A9 GPIOQ2_SCL4 AST2520A1-GP-GP_ASIC2-GB1-AST2A    I95 @BASEBOARD_FAB2_LIB.BASEBOARD_FAB2(SCH_1):PAGE144

SMB_HOST_STBY_LVC3_SCL_R1 @BASEBOARD_FAB2_LIB.BASEBOARD_FAB2(SCH_1):SMB_HOST_STBY_LVC3_SCL_R1
  U7C1 BW28 GPP_C0_SMBCLK LBG_CORE_QAT_EXT_D_BGA1-IC,H91A   I115 @BASEBOARD_FAB2_LIB.BASEBOARD_FAB2(SCH_1):PAGE119
 R8C14    1      A RES_0402-20.0,1%,1/16W,CHIP,G2A   I168 @BASEBOARD_FAB2_LIB.BASEBOARD_FAB2(SCH_1):PAGE138

SMB_HOST_STBY_LVC3_SCL_R2 @BASEBOARD_FAB2_LIB.BASEBOARD_FAB2(SCH_1):SMB_HOST_STBY_LVC3_SCL_R2
 EU4D2   13    SCL NB3W1200L_LCC-IC,H13585-001     I1 @BASEBOARD_FAB2_LIB.BASEBOARD_FAB2(SCH_1):PAGE102
 R4D37    2      B RES_0402-33.2,1%,1/16W,CHIP,G2A    I87 @BASEBOARD_FAB2_LIB.BASEBOARD_FAB2(SCH_1):PAGE102

SMB_HOST_STBY_LVC3_SCL_R3 @BASEBOARD_FAB2_LIB.BASEBOARD_FAB2(SCH_1):SMB_HOST_STBY_LVC3_SCL_R3
  U6W3    6    SCL AT24C64_SOICLF-IC,C47049-001-GA    I89 @BASEBOARD_FAB2_LIB.BASEBOARD_FAB2(SCH_1):PAGE247
 R6W22    2      B RES_0402-20.0,1%,1/16W,CHIP,G2A    I94 @BASEBOARD_FAB2_LIB.BASEBOARD_FAB2(SCH_1):PAGE247

SMB_HOST_STBY_LVC3_SDA @BASEBOARD_FAB2_LIB.BASEBOARD_FAB2(SCH_1):SMB_HOST_STBY_LVC3_SDA
 EU8F2   39 SMBDAT ICS9FGP204_MLFP-IC,E95226-001    I34 @BASEBOARD_FAB2_LIB.BASEBOARD_FAB2(SCH_1):PAGE101
 R4D36    1      A RES_0402-33.2,1%,1/16W,CHIP,G2A    I82 @BASEBOARD_FAB2_LIB.BASEBOARD_FAB2(SCH_1):PAGE102
  J9A3   51   IO51 SCONN60_C21100002_SMLF-CONN,C2A    I26 @BASEBOARD_FAB2_LIB.BASEBOARD_FAB2(SCH_1):PAGE111
 R8C16    2      B RES_0402-2.0K,1%,1/16W,CHIP,G2A    I91 @BASEBOARD_FAB2_LIB.BASEBOARD_FAB2(SCH_1):PAGE138
 R8C20    2      B RES_0402-20.0,1%,1/16W,CHIP,G2A   I167 @BASEBOARD_FAB2_LIB.BASEBOARD_FAB2(SCH_1):PAGE138
  J8C1    1    IO1 CONN3_C95678002_PIP-CONN,C9567A   I285 @BASEBOARD_FAB2_LIB.BASEBOARD_FAB2(SCH_1):PAGE156
 R2U33    2      B RES_0402-20.0,1%,1/16W,CHIP,G2A   I231 @BASEBOARD_FAB2_LIB.BASEBOARD_FAB2(SCH_1):PAGE159
 R6W20    2      B RES_0402-20.0,1%,1/16W,CHIP,G2A    I87 @BASEBOARD_FAB2_LIB.BASEBOARD_FAB2(SCH_1):PAGE247

SMB_HOST_STBY_LVC3_SDA_R @BASEBOARD_FAB2_LIB.BASEBOARD_FAB2(SCH_1):SMB_HOST_STBY_LVC3_SDA_R
 R2U33    1      A RES_0402-20.0,1%,1/16W,CHIP,G2A   I231 @BASEBOARD_FAB2_LIB.BASEBOARD_FAB2(SCH_1):PAGE159
 U25W4   B9 GPIOQ3_SDA4 AST2520A1-GP-GP_ASIC2-GB1-AST2A    I95 @BASEBOARD_FAB2_LIB.BASEBOARD_FAB2(SCH_1):PAGE144

SMB_HOST_STBY_LVC3_SDA_R1 @BASEBOARD_FAB2_LIB.BASEBOARD_FAB2(SCH_1):SMB_HOST_STBY_LVC3_SDA_R1
  U7C1 BV27 GPP_C1_SMBDATA LBG_CORE_QAT_EXT_D_BGA1-IC,H91A   I115 @BASEBOARD_FAB2_LIB.BASEBOARD_FAB2(SCH_1):PAGE119
 R8C20    1      A RES_0402-20.0,1%,1/16W,CHIP,G2A   I167 @BASEBOARD_FAB2_LIB.BASEBOARD_FAB2(SCH_1):PAGE138

SMB_HOST_STBY_LVC3_SDA_R2 @BASEBOARD_FAB2_LIB.BASEBOARD_FAB2(SCH_1):SMB_HOST_STBY_LVC3_SDA_R2
 EU4D2   12    SDA NB3W1200L_LCC-IC,H13585-001     I1 @BASEBOARD_FAB2_LIB.BASEBOARD_FAB2(SCH_1):PAGE102
 R4D36    2      B RES_0402-33.2,1%,1/16W,CHIP,G2A    I82 @BASEBOARD_FAB2_LIB.BASEBOARD_FAB2(SCH_1):PAGE102

SMB_HOST_STBY_LVC3_SDA_R3 @BASEBOARD_FAB2_LIB.BASEBOARD_FAB2(SCH_1):SMB_HOST_STBY_LVC3_SDA_R3
 R6W20    1      A RES_0402-20.0,1%,1/16W,CHIP,G2A    I87 @BASEBOARD_FAB2_LIB.BASEBOARD_FAB2(SCH_1):PAGE247
  U6W3    5    SDA AT24C64_SOICLF-IC,C47049-001-GA    I89 @BASEBOARD_FAB2_LIB.BASEBOARD_FAB2(SCH_1):PAGE247

SMB_IE_3V3AUX_SCL @BASEBOARD_FAB2_LIB.BASEBOARD_FAB2(SCH_1):SMB_IE_3V3AUX_SCL
 U25W4  C11 GPIOC6_SD1CD#_SCL13 AST2520A1-GP-GP_ASIC2-GB1-AST2A   I117 @BASEBOARD_FAB2_LIB.BASEBOARD_FAB2(SCH_1):PAGE145

SMB_IE_3V3AUX_SDA @BASEBOARD_FAB2_LIB.BASEBOARD_FAB2(SCH_1):SMB_IE_3V3AUX_SDA
 U25W4  B11 GPIOC7_SD1WP#_SDA13 AST2520A1-GP-GP_ASIC2-GB1-AST2A   I117 @BASEBOARD_FAB2_LIB.BASEBOARD_FAB2(SCH_1):PAGE145

SMB_IPMB_3V3AUX_SCL @BASEBOARD_FAB2_LIB.BASEBOARD_FAB2(SCH_1):SMB_IPMB_3V3AUX_SCL
  J9B1    5 STDA_SSRXN CONN9_H51826001_PIP2-CONN,H518A    I69 @BASEBOARD_FAB2_LIB.BASEBOARD_FAB2(SCH_1):PAGE176
 R6W11    2      B RES_0402-4.75K,1%,1/16W,EMPTY,A    I67 @BASEBOARD_FAB2_LIB.BASEBOARD_FAB2(SCH_1):PAGE247
 R6W17    1      A RES_0402-0.0,5%,1/16W,CHIP,G21A    I89 @BASEBOARD_FAB2_LIB.BASEBOARD_FAB2(SCH_1):PAGE144
  U6W1   22    SCL PCA9555PWRG4-GP_DISCRET-G5-PCAA    I97 @BASEBOARD_FAB2_LIB.BASEBOARD_FAB2(SCH_1):PAGE247

SMB_IPMB_3V3AUX_SCL_R @BASEBOARD_FAB2_LIB.BASEBOARD_FAB2(SCH_1):SMB_IPMB_3V3AUX_SCL_R
 R6W17    2      B RES_0402-0.0,5%,1/16W,CHIP,G21A    I89 @BASEBOARD_FAB2_LIB.BASEBOARD_FAB2(SCH_1):PAGE144
 U25W4  M18 GPIOY4_SCL1 AST2520A1-GP-GP_ASIC2-GB1-AST2A    I95 @BASEBOARD_FAB2_LIB.BASEBOARD_FAB2(SCH_1):PAGE144

SMB_IPMB_3V3AUX_SDA @BASEBOARD_FAB2_LIB.BASEBOARD_FAB2(SCH_1):SMB_IPMB_3V3AUX_SDA
  J9B1    6 STDA_SSRXP CONN9_H51826001_PIP2-CONN,H518A    I69 @BASEBOARD_FAB2_LIB.BASEBOARD_FAB2(SCH_1):PAGE176
 R6W12    2      B RES_0402-4.75K,1%,1/16W,EMPTY,A    I68 @BASEBOARD_FAB2_LIB.BASEBOARD_FAB2(SCH_1):PAGE247
 R6W18    1      A RES_0402-0.0,5%,1/16W,CHIP,G21A    I90 @BASEBOARD_FAB2_LIB.BASEBOARD_FAB2(SCH_1):PAGE144
  U6W1   23    SDA PCA9555PWRG4-GP_DISCRET-G5-PCAA    I97 @BASEBOARD_FAB2_LIB.BASEBOARD_FAB2(SCH_1):PAGE247

SMB_IPMB_3V3AUX_SDA_R @BASEBOARD_FAB2_LIB.BASEBOARD_FAB2(SCH_1):SMB_IPMB_3V3AUX_SDA_R
 R6W18    2      B RES_0402-0.0,5%,1/16W,CHIP,G21A    I90 @BASEBOARD_FAB2_LIB.BASEBOARD_FAB2(SCH_1):PAGE144
 U25W4  M19 GPIOY5_SDA1 AST2520A1-GP-GP_ASIC2-GB1-AST2A    I95 @BASEBOARD_FAB2_LIB.BASEBOARD_FAB2(SCH_1):PAGE144

SMB_LAN_STBY_LVC3_SCL @BASEBOARD_FAB2_LIB.BASEBOARD_FAB2(SCH_1):SMB_LAN_STBY_LVC3_SCL
  R2U3    2      B RES_0402-665,1.0%,1/16W,CHIP,GA    I98 @BASEBOARD_FAB2_LIB.BASEBOARD_FAB2(SCH_1):PAGE138
  R2U8    1      A RES_0402-20.0,1%,1/16W,EMPTY,GA   I158 @BASEBOARD_FAB2_LIB.BASEBOARD_FAB2(SCH_1):PAGE138
  R2U6    2      B RES_0402-20.0,1%,1/16W,CHIP,G2A   I166 @BASEBOARD_FAB2_LIB.BASEBOARD_FAB2(SCH_1):PAGE138
 R2N21    2      B RES_0402-0.0,5%,1/16W,CHIP,G21A   I175 @BASEBOARD_FAB2_LIB.BASEBOARD_FAB2(SCH_1):PAGE138
 R9M20    1      A RES_0402-0.0,5%,1/16W,CHIP,G21A   I323 @BASEBOARD_FAB2_LIB.BASEBOARD_FAB2(SCH_1):PAGE156
  R4A9    1      A RES_0402-0.0,5%,1/16W,CHIP,G21A   I324 @BASEBOARD_FAB2_LIB.BASEBOARD_FAB2(SCH_1):PAGE156
 R9F22    2      B RES_0402-20.0,1%,1/16W,CHIP,G2A    I52 @BASEBOARD_FAB2_LIB.BASEBOARD_FAB2(SCH_1):PAGE160
  J1C1   E5   IOE5 CONN76_H22707001_THMT1-CONN,H2A    I18 @BASEBOARD_FAB2_LIB.BASEBOARD_FAB2(SCH_1):PAGE182
 R1C11    1      A RES_0402-0.0,5%,1/16W,EMPTY,G2A    I97 @BASEBOARD_FAB2_LIB.BASEBOARD_FAB2(SCH_1):PAGE182

SMB_LAN_STBY_LVC3_SCL_R @BASEBOARD_FAB2_LIB.BASEBOARD_FAB2(SCH_1):SMB_LAN_STBY_LVC3_SCL_R
 R9F22    1      A RES_0402-20.0,1%,1/16W,CHIP,G2A    I52 @BASEBOARD_FAB2_LIB.BASEBOARD_FAB2(SCH_1):PAGE160
 U25W4  D10 GPIOC4_SD1DAT2_SCL12 AST2520A1-GP-GP_ASIC2-GB1-AST2A   I117 @BASEBOARD_FAB2_LIB.BASEBOARD_FAB2(SCH_1):PAGE145

SMB_LAN_STBY_LVC3_SCL_R1 @BASEBOARD_FAB2_LIB.BASEBOARD_FAB2(SCH_1):SMB_LAN_STBY_LVC3_SCL_R1
  U7C1  BF1 GPP_H16_SML4CLK_IE LBG_CORE_QAT_EXT_D_BGA1-IC,H91A   I147 @BASEBOARD_FAB2_LIB.BASEBOARD_FAB2(SCH_1):PAGE120
  R2U6    1      A RES_0402-20.0,1%,1/16W,CHIP,G2A   I166 @BASEBOARD_FAB2_LIB.BASEBOARD_FAB2(SCH_1):PAGE138

SMB_LAN_STBY_LVC3_SCL_R2 @BASEBOARD_FAB2_LIB.BASEBOARD_FAB2(SCH_1):SMB_LAN_STBY_LVC3_SCL_R2
  U7C1  AU9 GPP_F19_LAN_SMBCLK LBG_CORE_QAT_EXT_D_BGA1-IC,H91A   I147 @BASEBOARD_FAB2_LIB.BASEBOARD_FAB2(SCH_1):PAGE120
 R2N21    1      A RES_0402-0.0,5%,1/16W,CHIP,G21A   I175 @BASEBOARD_FAB2_LIB.BASEBOARD_FAB2(SCH_1):PAGE138

SMB_LAN_STBY_LVC3_SDA @BASEBOARD_FAB2_LIB.BASEBOARD_FAB2(SCH_1):SMB_LAN_STBY_LVC3_SDA
 R2U11    2      B RES_0402-665,1.0%,1/16W,CHIP,GA    I97 @BASEBOARD_FAB2_LIB.BASEBOARD_FAB2(SCH_1):PAGE138
 R2U12    1      A RES_0402-20.0,1%,1/16W,EMPTY,GA   I159 @BASEBOARD_FAB2_LIB.BASEBOARD_FAB2(SCH_1):PAGE138
  R2U9    2      B RES_0402-20.0,1%,1/16W,CHIP,G2A   I165 @BASEBOARD_FAB2_LIB.BASEBOARD_FAB2(SCH_1):PAGE138
 R2N20    2      B RES_0402-0.0,5%,1/16W,CHIP,G21A   I171 @BASEBOARD_FAB2_LIB.BASEBOARD_FAB2(SCH_1):PAGE138
 R9M21    1      A RES_0402-0.0,5%,1/16W,CHIP,G21A   I321 @BASEBOARD_FAB2_LIB.BASEBOARD_FAB2(SCH_1):PAGE156
  R4A8    1      A RES_0402-0.0,5%,1/16W,CHIP,G21A   I322 @BASEBOARD_FAB2_LIB.BASEBOARD_FAB2(SCH_1):PAGE156
 R9F23    2      B RES_0402-20.0,1%,1/16W,CHIP,G2A    I51 @BASEBOARD_FAB2_LIB.BASEBOARD_FAB2(SCH_1):PAGE160
  J1C1   D5   IOD5 CONN76_H22707001_THMT1-CONN,H2A    I18 @BASEBOARD_FAB2_LIB.BASEBOARD_FAB2(SCH_1):PAGE182
 R1C10    1      A RES_0402-0.0,5%,1/16W,EMPTY,G2A   I101 @BASEBOARD_FAB2_LIB.BASEBOARD_FAB2(SCH_1):PAGE182

SMB_LAN_STBY_LVC3_SDA_R @BASEBOARD_FAB2_LIB.BASEBOARD_FAB2(SCH_1):SMB_LAN_STBY_LVC3_SDA_R
 R9F23    1      A RES_0402-20.0,1%,1/16W,CHIP,G2A    I51 @BASEBOARD_FAB2_LIB.BASEBOARD_FAB2(SCH_1):PAGE160
 U25W4  E12 GPIOC5_SD1DAT3_SDA12 AST2520A1-GP-GP_ASIC2-GB1-AST2A   I117 @BASEBOARD_FAB2_LIB.BASEBOARD_FAB2(SCH_1):PAGE145

SMB_LAN_STBY_LVC3_SDA_R1 @BASEBOARD_FAB2_LIB.BASEBOARD_FAB2(SCH_1):SMB_LAN_STBY_LVC3_SDA_R1
  U7C1  BE4 GPP_H17_SML4DATA_IE LBG_CORE_QAT_EXT_D_BGA1-IC,H91A   I147 @BASEBOARD_FAB2_LIB.BASEBOARD_FAB2(SCH_1):PAGE120
  R2U9    1      A RES_0402-20.0,1%,1/16W,CHIP,G2A   I165 @BASEBOARD_FAB2_LIB.BASEBOARD_FAB2(SCH_1):PAGE138

SMB_LAN_STBY_LVC3_SDA_R2 @BASEBOARD_FAB2_LIB.BASEBOARD_FAB2(SCH_1):SMB_LAN_STBY_LVC3_SDA_R2
  U7C1 AU20 GPP_F20_LAN_SMBDATA LBG_CORE_QAT_EXT_D_BGA1-IC,H91A   I147 @BASEBOARD_FAB2_LIB.BASEBOARD_FAB2(SCH_1):PAGE120
 R2N20    1      A RES_0402-0.0,5%,1/16W,CHIP,G21A   I171 @BASEBOARD_FAB2_LIB.BASEBOARD_FAB2(SCH_1):PAGE138

SMB_OCP_FRU_STBY_LVC3_SCL @BASEBOARD_FAB2_LIB.BASEBOARD_FAB2(SCH_1):SMB_OCP_FRU_STBY_LVC3_SCL
  J8B1   22   IO22 SCONN24_H46321001_SM-SCONN,H46A     I1 @BASEBOARD_FAB2_LIB.BASEBOARD_FAB2(SCH_1):PAGE91
  R2U8    2      B RES_0402-20.0,1%,1/16W,EMPTY,GA   I158 @BASEBOARD_FAB2_LIB.BASEBOARD_FAB2(SCH_1):PAGE138
  R2U7    2      B RES_0402-20.0,1%,1/16W,CHIP,G2A   I220 @BASEBOARD_FAB2_LIB.BASEBOARD_FAB2(SCH_1):PAGE159
  J9B3   30   IO30 SCONN120_A28699018_SM-SCONN,A2A   I336 @BASEBOARD_FAB2_LIB.BASEBOARD_FAB2(SCH_1):PAGE186
  J8E4    1    IO1 SCONN64_H87568002_A_SMT-CONN,HA    I27 @BASEBOARD_FAB2_LIB.BASEBOARD_FAB2(SCH_1):PAGE188

SMB_OCP_FRU_STBY_LVC3_SCL_R @BASEBOARD_FAB2_LIB.BASEBOARD_FAB2(SCH_1):SMB_OCP_FRU_STBY_LVC3_SCL_R
  R2U5    2      B RES_0402-2.26K,1.0%,1/16W,CHIPA   I214 @BASEBOARD_FAB2_LIB.BASEBOARD_FAB2(SCH_1):PAGE159
  R2U7    1      A RES_0402-20.0,1%,1/16W,CHIP,G2A   I220 @BASEBOARD_FAB2_LIB.BASEBOARD_FAB2(SCH_1):PAGE159
 U25W4   N1 GPIOK4_SCL7 AST2520A1-GP-GP_ASIC2-GB1-AST2A    I95 @BASEBOARD_FAB2_LIB.BASEBOARD_FAB2(SCH_1):PAGE144

SMB_OCP_FRU_STBY_LVC3_SDA @BASEBOARD_FAB2_LIB.BASEBOARD_FAB2(SCH_1):SMB_OCP_FRU_STBY_LVC3_SDA
  J8B1   24   IO24 SCONN24_H46321001_SM-SCONN,H46A     I1 @BASEBOARD_FAB2_LIB.BASEBOARD_FAB2(SCH_1):PAGE91
 R2U12    2      B RES_0402-20.0,1%,1/16W,EMPTY,GA   I159 @BASEBOARD_FAB2_LIB.BASEBOARD_FAB2(SCH_1):PAGE138
 R2U10    2      B RES_0402-20.0,1%,1/16W,CHIP,G2A   I221 @BASEBOARD_FAB2_LIB.BASEBOARD_FAB2(SCH_1):PAGE159
  J9B3   32   IO32 SCONN120_A28699018_SM-SCONN,A2A   I336 @BASEBOARD_FAB2_LIB.BASEBOARD_FAB2(SCH_1):PAGE186
  J8E4    2    IO2 SCONN64_H87568002_A_SMT-CONN,HA    I27 @BASEBOARD_FAB2_LIB.BASEBOARD_FAB2(SCH_1):PAGE188

SMB_OCP_FRU_STBY_LVC3_SDA_R @BASEBOARD_FAB2_LIB.BASEBOARD_FAB2(SCH_1):SMB_OCP_FRU_STBY_LVC3_SDA_R
 R2U13    2      B RES_0402-2.26K,1.0%,1/16W,CHIPA   I216 @BASEBOARD_FAB2_LIB.BASEBOARD_FAB2(SCH_1):PAGE159
 R2U10    1      A RES_0402-20.0,1%,1/16W,CHIP,G2A   I221 @BASEBOARD_FAB2_LIB.BASEBOARD_FAB2(SCH_1):PAGE159
 U25W4   P1 GPIOK5_SDA7 AST2520A1-GP-GP_ASIC2-GB1-AST2A    I95 @BASEBOARD_FAB2_LIB.BASEBOARD_FAB2(SCH_1):PAGE144

SMB_OCP_LAN_STBY_LVC3_SCL @BASEBOARD_FAB2_LIB.BASEBOARD_FAB2(SCH_1):SMB_OCP_LAN_STBY_LVC3_SCL
 R9G13    1      A RES_0402-20.0,1%,1/16W,CHIP,G2A   I227 @BASEBOARD_FAB2_LIB.BASEBOARD_FAB2(SCH_1):PAGE159
  R8G4    2      B RES_0402-20.0,1%,1/16W,CHIP,G2A   I229 @BASEBOARD_FAB2_LIB.BASEBOARD_FAB2(SCH_1):PAGE159
  J9B3   35   IO35 SCONN120_A28699018_SM-SCONN,A2A   I336 @BASEBOARD_FAB2_LIB.BASEBOARD_FAB2(SCH_1):PAGE186

SMB_OCP_LAN_STBY_LVC3_SCL_R @BASEBOARD_FAB2_LIB.BASEBOARD_FAB2(SCH_1):SMB_OCP_LAN_STBY_LVC3_SCL_R
  R8G3    2      B RES_0402-2.26K,1.0%,1/16W,EMPTA   I210 @BASEBOARD_FAB2_LIB.BASEBOARD_FAB2(SCH_1):PAGE159
  R8G4    1      A RES_0402-20.0,1%,1/16W,CHIP,G2A   I229 @BASEBOARD_FAB2_LIB.BASEBOARD_FAB2(SCH_1):PAGE159
 U25W4  N21 GPIOQ4_SCL14 AST2520A1-GP-GP_ASIC2-GB1-AST2A    I95 @BASEBOARD_FAB2_LIB.BASEBOARD_FAB2(SCH_1):PAGE144

SMB_OCP_LAN_STBY_LVC3_SDA @BASEBOARD_FAB2_LIB.BASEBOARD_FAB2(SCH_1):SMB_OCP_LAN_STBY_LVC3_SDA
 R9G12    1      A RES_0402-20.0,1%,1/16W,CHIP,G2A   I224 @BASEBOARD_FAB2_LIB.BASEBOARD_FAB2(SCH_1):PAGE159
  R8G5    2      B RES_0402-20.0,1%,1/16W,CHIP,G2A   I228 @BASEBOARD_FAB2_LIB.BASEBOARD_FAB2(SCH_1):PAGE159
  J9B3   37   IO37 SCONN120_A28699018_SM-SCONN,A2A   I336 @BASEBOARD_FAB2_LIB.BASEBOARD_FAB2(SCH_1):PAGE186

SMB_OCP_LAN_STBY_LVC3_SDA_R @BASEBOARD_FAB2_LIB.BASEBOARD_FAB2(SCH_1):SMB_OCP_LAN_STBY_LVC3_SDA_R
  R8G6    2      B RES_0402-2.26K,1.0%,1/16W,EMPTA   I212 @BASEBOARD_FAB2_LIB.BASEBOARD_FAB2(SCH_1):PAGE159
  R8G5    1      A RES_0402-20.0,1%,1/16W,CHIP,G2A   I228 @BASEBOARD_FAB2_LIB.BASEBOARD_FAB2(SCH_1):PAGE159
 U25W4  N22 GPIOQ5_SDA14 AST2520A1-GP-GP_ASIC2-GB1-AST2A    I95 @BASEBOARD_FAB2_LIB.BASEBOARD_FAB2(SCH_1):PAGE144

SMB_PCH_MEZZ_LOM0_SCL @BASEBOARD_FAB2_LIB.BASEBOARD_FAB2(SCH_1):SMB_PCH_MEZZ_LOM0_SCL
  U7C1  BM4 GPP_J8_LAN_I2C_SCL_MDC_P0 LBG_CORE_QAT_EXT_D_BGA1-IC,H91A   I147 @BASEBOARD_FAB2_LIB.BASEBOARD_FAB2(SCH_1):PAGE120
  J8E4   20   IO20 SCONN64_H87568002_A_SMT-CONN,HA    I27 @BASEBOARD_FAB2_LIB.BASEBOARD_FAB2(SCH_1):PAGE188
 R1R18    2      B RES_0402-2.21K,1%,1/16W,CHIP,GA    I88 @BASEBOARD_FAB2_LIB.BASEBOARD_FAB2(SCH_1):PAGE188

SMB_PCH_MEZZ_LOM0_SDA @BASEBOARD_FAB2_LIB.BASEBOARD_FAB2(SCH_1):SMB_PCH_MEZZ_LOM0_SDA
  U7C1  BN3 GPP_J9_LAN_I2C_SDA_MDIO_P0 LBG_CORE_QAT_EXT_D_BGA1-IC,H91A   I147 @BASEBOARD_FAB2_LIB.BASEBOARD_FAB2(SCH_1):PAGE120
  J8E4   21   IO21 SCONN64_H87568002_A_SMT-CONN,HA    I27 @BASEBOARD_FAB2_LIB.BASEBOARD_FAB2(SCH_1):PAGE188
 R1R19    2      B RES_0402-2.21K,1%,1/16W,CHIP,GA    I89 @BASEBOARD_FAB2_LIB.BASEBOARD_FAB2(SCH_1):PAGE188

SMB_PCH_MEZZ_LOM1_SCL @BASEBOARD_FAB2_LIB.BASEBOARD_FAB2(SCH_1):SMB_PCH_MEZZ_LOM1_SCL
  U7C1  BW5 GPP_J10_LAN_I2C_SCL_MDC_P1 LBG_CORE_QAT_EXT_D_BGA1-IC,H91A   I147 @BASEBOARD_FAB2_LIB.BASEBOARD_FAB2(SCH_1):PAGE120
  J8E4   26   IO26 SCONN64_H87568002_A_SMT-CONN,HA    I27 @BASEBOARD_FAB2_LIB.BASEBOARD_FAB2(SCH_1):PAGE188
 R1R20    2      B RES_0402-2.21K,1%,1/16W,CHIP,GA    I91 @BASEBOARD_FAB2_LIB.BASEBOARD_FAB2(SCH_1):PAGE188

SMB_PCH_MEZZ_LOM1_SDA @BASEBOARD_FAB2_LIB.BASEBOARD_FAB2(SCH_1):SMB_PCH_MEZZ_LOM1_SDA
  U7C1  BV8 GPP_J11_LAN_I2C_SDA_MDIO_P1 LBG_CORE_QAT_EXT_D_BGA1-IC,H91A   I147 @BASEBOARD_FAB2_LIB.BASEBOARD_FAB2(SCH_1):PAGE120
  J8E4   27   IO27 SCONN64_H87568002_A_SMT-CONN,HA    I27 @BASEBOARD_FAB2_LIB.BASEBOARD_FAB2(SCH_1):PAGE188
 R1R21    2      B RES_0402-2.21K,1%,1/16W,CHIP,GA    I90 @BASEBOARD_FAB2_LIB.BASEBOARD_FAB2(SCH_1):PAGE188

SMB_PCH_MEZZ_LOM2_SCL @BASEBOARD_FAB2_LIB.BASEBOARD_FAB2(SCH_1):SMB_PCH_MEZZ_LOM2_SCL
  U7C1  BT5 GPP_J12_LAN_I2C_SCL_MDC_P2 LBG_CORE_QAT_EXT_D_BGA1-IC,H91A   I147 @BASEBOARD_FAB2_LIB.BASEBOARD_FAB2(SCH_1):PAGE120
  J8E4   61   IO61 SCONN64_H87568002_A_SMT-CONN,HA    I27 @BASEBOARD_FAB2_LIB.BASEBOARD_FAB2(SCH_1):PAGE188
 R1R16    2      B RES_0402-2.21K,1%,1/16W,CHIP,GA    I93 @BASEBOARD_FAB2_LIB.BASEBOARD_FAB2(SCH_1):PAGE188

SMB_PCH_MEZZ_LOM2_SDA @BASEBOARD_FAB2_LIB.BASEBOARD_FAB2(SCH_1):SMB_PCH_MEZZ_LOM2_SDA
  U7C1 BW11 GPP_J13_LAN_I2C_SDA_MDIO_P2 LBG_CORE_QAT_EXT_D_BGA1-IC,H91A   I147 @BASEBOARD_FAB2_LIB.BASEBOARD_FAB2(SCH_1):PAGE120
  J8E4   62   IO62 SCONN64_H87568002_A_SMT-CONN,HA    I27 @BASEBOARD_FAB2_LIB.BASEBOARD_FAB2(SCH_1):PAGE188
 R1R17    2      B RES_0402-2.21K,1%,1/16W,CHIP,GA    I94 @BASEBOARD_FAB2_LIB.BASEBOARD_FAB2(SCH_1):PAGE188

SMB_PCH_MEZZ_LOM3_SCL @BASEBOARD_FAB2_LIB.BASEBOARD_FAB2(SCH_1):SMB_PCH_MEZZ_LOM3_SCL
  U7C1  BW6 GPP_J14_LAN_I2C_SCL_MDC_P3 LBG_CORE_QAT_EXT_D_BGA1-IC,H91A   I147 @BASEBOARD_FAB2_LIB.BASEBOARD_FAB2(SCH_1):PAGE120
  J8E4   29   IO29 SCONN64_H87568002_A_SMT-CONN,HA    I27 @BASEBOARD_FAB2_LIB.BASEBOARD_FAB2(SCH_1):PAGE188
 R1R23    2      B RES_0402-2.21K,1%,1/16W,CHIP,GA    I95 @BASEBOARD_FAB2_LIB.BASEBOARD_FAB2(SCH_1):PAGE188

SMB_PCH_MEZZ_LOM3_SDA @BASEBOARD_FAB2_LIB.BASEBOARD_FAB2(SCH_1):SMB_PCH_MEZZ_LOM3_SDA
  U7C1  BW9 GPP_J15_LAN_I2C_SDA_MDIO_P3 LBG_CORE_QAT_EXT_D_BGA1-IC,H91A   I147 @BASEBOARD_FAB2_LIB.BASEBOARD_FAB2(SCH_1):PAGE120
  J8E4   30   IO30 SCONN64_H87568002_A_SMT-CONN,HA    I27 @BASEBOARD_FAB2_LIB.BASEBOARD_FAB2(SCH_1):PAGE188
 R1R22    2      B RES_0402-2.21K,1%,1/16W,CHIP,GA    I92 @BASEBOARD_FAB2_LIB.BASEBOARD_FAB2(SCH_1):PAGE188

SMB_PCIE_SSD_3V3AUX_SCL @BASEBOARD_FAB2_LIB.BASEBOARD_FAB2(SCH_1):SMB_PCIE_SSD_3V3AUX_SCL
 U25W4  C12 GPIOC0_SD1CLK_SCL10 AST2520A1-GP-GP_ASIC2-GB1-AST2A   I117 @BASEBOARD_FAB2_LIB.BASEBOARD_FAB2(SCH_1):PAGE145

SMB_PCIE_SSD_3V3AUX_SDA @BASEBOARD_FAB2_LIB.BASEBOARD_FAB2(SCH_1):SMB_PCIE_SSD_3V3AUX_SDA
 U25W4  A12 GPIOC1_SD1CMD_SDA10 AST2520A1-GP-GP_ASIC2-GB1-AST2A   I117 @BASEBOARD_FAB2_LIB.BASEBOARD_FAB2(SCH_1):PAGE145

SMB_PEHPCPU1_STBY_LVC3_R_SCL @BASEBOARD_FAB2_LIB.BASEBOARD_FAB2(SCH_1):SMB_PEHPCPU1_STBY_LVC3_R_SCL
  U1B2    7   SCLB PCA9517_SM-IC,G77073-001-GND=GA     I1 @BASEBOARD_FAB2_LIB.BASEBOARD_FAB2(SCH_1):PAGE163
 R9M17    2      B RES_0402-2.0K,1%,1/16W,CHIP,G2A    I15 @BASEBOARD_FAB2_LIB.BASEBOARD_FAB2(SCH_1):PAGE163
 R9M14    1      A RES_0402-20.0,1%,1/16W,CHIP,G2A    I20 @BASEBOARD_FAB2_LIB.BASEBOARD_FAB2(SCH_1):PAGE163
 R9M15    1      A RES_0402-20.0,1%,1/16W,CHIP,G2A    I25 @BASEBOARD_FAB2_LIB.BASEBOARD_FAB2(SCH_1):PAGE163

SMB_PEHPCPU1_STBY_LVC3_R_SDA @BASEBOARD_FAB2_LIB.BASEBOARD_FAB2(SCH_1):SMB_PEHPCPU1_STBY_LVC3_R_SDA
  U1B2    6   SDAB PCA9517_SM-IC,G77073-001-GND=GA     I1 @BASEBOARD_FAB2_LIB.BASEBOARD_FAB2(SCH_1):PAGE163
 R9M16    2      B RES_0402-2.0K,1%,1/16W,CHIP,G2A    I16 @BASEBOARD_FAB2_LIB.BASEBOARD_FAB2(SCH_1):PAGE163
 R9M13    1      A RES_0402-20.0,1%,1/16W,CHIP,G2A    I21 @BASEBOARD_FAB2_LIB.BASEBOARD_FAB2(SCH_1):PAGE163
 R9M12    1      A RES_0402-20.0,1%,1/16W,CHIP,G2A    I24 @BASEBOARD_FAB2_LIB.BASEBOARD_FAB2(SCH_1):PAGE163

SMB_PEHPCPU1_STBY_LVC3_SCL @BASEBOARD_FAB2_LIB.BASEBOARD_FAB2(SCH_1):SMB_PEHPCPU1_STBY_LVC3_SCL
 R9M14    2      B RES_0402-20.0,1%,1/16W,CHIP,G2A    I20 @BASEBOARD_FAB2_LIB.BASEBOARD_FAB2(SCH_1):PAGE163
  J1C1   C6   IOC6 CONN76_H22707001_THMT1-CONN,H2A    I18 @BASEBOARD_FAB2_LIB.BASEBOARD_FAB2(SCH_1):PAGE182

SMB_PEHPCPU1_STBY_LVC3_SDA @BASEBOARD_FAB2_LIB.BASEBOARD_FAB2(SCH_1):SMB_PEHPCPU1_STBY_LVC3_SDA
 R9M13    2      B RES_0402-20.0,1%,1/16W,CHIP,G2A    I21 @BASEBOARD_FAB2_LIB.BASEBOARD_FAB2(SCH_1):PAGE163
  J1C1   B6   IOB6 CONN76_H22707001_THMT1-CONN,H2A    I18 @BASEBOARD_FAB2_LIB.BASEBOARD_FAB2(SCH_1):PAGE182

SMB_PIROM_CPU0_SCL @BASEBOARD_FAB2_LIB.BASEBOARD_FAB2(SCH_1):SMB_PIROM_CPU0_SCL
  U5D1 CT59 SMBCLK SKX_EXT_B_BGA1-IC,TBD   I259 @BASEBOARD_FAB2_LIB.BASEBOARD_FAB2(SCH_1):PAGE21
  R4A9    2      B RES_0402-0.0,5%,1/16W,CHIP,G21A   I324 @BASEBOARD_FAB2_LIB.BASEBOARD_FAB2(SCH_1):PAGE156

SMB_PIROM_CPU0_SDA @BASEBOARD_FAB2_LIB.BASEBOARD_FAB2(SCH_1):SMB_PIROM_CPU0_SDA
  U5D1 CW58 SMBDAT SKX_EXT_B_BGA1-IC,TBD   I259 @BASEBOARD_FAB2_LIB.BASEBOARD_FAB2(SCH_1):PAGE21
  R4A8    2      B RES_0402-0.0,5%,1/16W,CHIP,G21A   I322 @BASEBOARD_FAB2_LIB.BASEBOARD_FAB2(SCH_1):PAGE156

SMB_PIROM_CPU1_SCL @BASEBOARD_FAB2_LIB.BASEBOARD_FAB2(SCH_1):SMB_PIROM_CPU1_SCL
  U2D1 CT59 SMBCLK SKX_EXT_B_BGA1-IC,TBD   I172 @BASEBOARD_FAB2_LIB.BASEBOARD_FAB2(SCH_1):PAGE55
 R9M20    2      B RES_0402-0.0,5%,1/16W,CHIP,G21A   I323 @BASEBOARD_FAB2_LIB.BASEBOARD_FAB2(SCH_1):PAGE156

SMB_PIROM_CPU1_SDA @BASEBOARD_FAB2_LIB.BASEBOARD_FAB2(SCH_1):SMB_PIROM_CPU1_SDA
  U2D1 CW58 SMBDAT SKX_EXT_B_BGA1-IC,TBD   I172 @BASEBOARD_FAB2_LIB.BASEBOARD_FAB2(SCH_1):PAGE55
 R9M21    2      B RES_0402-0.0,5%,1/16W,CHIP,G21A   I321 @BASEBOARD_FAB2_LIB.BASEBOARD_FAB2(SCH_1):PAGE156

SMB_PMBUS_BMC_STBY_LVC3_SCL_R1 @BASEBOARD_FAB2_LIB.BASEBOARD_FAB2(SCH_1):SMB_PMBUS_BMC_STBY_LVC3_SCL_R1
  U7C1 CA28 GPP_C6_SML1CLK_IE LBG_CORE_QAT_EXT_D_BGA1-IC,H91A   I115 @BASEBOARD_FAB2_LIB.BASEBOARD_FAB2(SCH_1):PAGE119
 R2T56    1      A RES_0402-20.0,1%,1/16W,CHIP,G2A   I160 @BASEBOARD_FAB2_LIB.BASEBOARD_FAB2(SCH_1):PAGE138
  U6W2    2   SCL0 PCA9515ADGKR-1-GP_DISCRET-G5-PA    I77 @BASEBOARD_FAB2_LIB.BASEBOARD_FAB2(SCH_1):PAGE247

SMB_PMBUS_BMC_STBY_LVC3_SDA_R1 @BASEBOARD_FAB2_LIB.BASEBOARD_FAB2(SCH_1):SMB_PMBUS_BMC_STBY_LVC3_SDA_R1
  U7C1 BV35 GPP_C7_SML1DATA_IE LBG_CORE_QAT_EXT_D_BGA1-IC,H91A   I115 @BASEBOARD_FAB2_LIB.BASEBOARD_FAB2(SCH_1):PAGE119
 R2T55    1      A RES_0402-20.0,1%,1/16W,CHIP,G2A   I116 @BASEBOARD_FAB2_LIB.BASEBOARD_FAB2(SCH_1):PAGE138
  U6W2    3   SDA0 PCA9515ADGKR-1-GP_DISCRET-G5-PA    I77 @BASEBOARD_FAB2_LIB.BASEBOARD_FAB2(SCH_1):PAGE247

SMB_SENSOR_BMC_STBY_LVC3_SCL @BASEBOARD_FAB2_LIB.BASEBOARD_FAB2(SCH_1):SMB_SENSOR_BMC_STBY_LVC3_SCL
 R9G14    1      A RES_0402-20.0,1%,1/16W,CHIP,G2A    I77 @BASEBOARD_FAB2_LIB.BASEBOARD_FAB2(SCH_1):PAGE167
 U25W4   L3 GPIOK0_SCL5 AST2520A1-GP-GP_ASIC2-GB1-AST2A    I95 @BASEBOARD_FAB2_LIB.BASEBOARD_FAB2(SCH_1):PAGE144

SMB_SENSOR_BMC_STBY_LVC3_SDA @BASEBOARD_FAB2_LIB.BASEBOARD_FAB2(SCH_1):SMB_SENSOR_BMC_STBY_LVC3_SDA
 R9G15    1      A RES_0402-20.0,1%,1/16W,CHIP,G2A    I58 @BASEBOARD_FAB2_LIB.BASEBOARD_FAB2(SCH_1):PAGE167
 U25W4   L4 GPIOK1_SDA5 AST2520A1-GP-GP_ASIC2-GB1-AST2A    I95 @BASEBOARD_FAB2_LIB.BASEBOARD_FAB2(SCH_1):PAGE144

SMB_SENSOR_PCH_STBY_LVC3_SCL @BASEBOARD_FAB2_LIB.BASEBOARD_FAB2(SCH_1):SMB_SENSOR_PCH_STBY_LVC3_SCL
  R8D3    2      B RES_0402-20.0,1%,1/16W,CHIP,G2A   I161 @BASEBOARD_FAB2_LIB.BASEBOARD_FAB2(SCH_1):PAGE138
 EU9G1    3    SCL ADC128D818_SM-IC,H63642-001    I52 @BASEBOARD_FAB2_LIB.BASEBOARD_FAB2(SCH_1):PAGE165
 R1U25    1      A RES_0402-20.0,1%,1/16W,CHIP,G2A    I79 @BASEBOARD_FAB2_LIB.BASEBOARD_FAB2(SCH_1):PAGE167

SMB_SENSOR_PCH_STBY_LVC3_SDA @BASEBOARD_FAB2_LIB.BASEBOARD_FAB2(SCH_1):SMB_SENSOR_PCH_STBY_LVC3_SDA
  R8D6    2      B RES_0402-20.0,1%,1/16W,CHIP,G2A   I162 @BASEBOARD_FAB2_LIB.BASEBOARD_FAB2(SCH_1):PAGE138
 EU9G1    2    SDA ADC128D818_SM-IC,H63642-001    I52 @BASEBOARD_FAB2_LIB.BASEBOARD_FAB2(SCH_1):PAGE165
 R1U31    1      A RES_0402-20.0,1%,1/16W,CHIP,G2A    I78 @BASEBOARD_FAB2_LIB.BASEBOARD_FAB2(SCH_1):PAGE167

SMB_SENSOR_STBY_LVC3_SCL @BASEBOARD_FAB2_LIB.BASEBOARD_FAB2(SCH_1):SMB_SENSOR_STBY_LVC3_SCL
  R1M8    2      B RES_0402-20.0,1%,1/16W,CHIP,G2A    I74 @BASEBOARD_FAB2_LIB.BASEBOARD_FAB2(SCH_1):PAGE167
  R9R7    2      B RES_0402-20.0,1%,1/16W,CHIP,G2A    I75 @BASEBOARD_FAB2_LIB.BASEBOARD_FAB2(SCH_1):PAGE167
 R9G14    2      B RES_0402-20.0,1%,1/16W,CHIP,G2A    I77 @BASEBOARD_FAB2_LIB.BASEBOARD_FAB2(SCH_1):PAGE167
 R1U25    2      B RES_0402-20.0,1%,1/16W,CHIP,G2A    I79 @BASEBOARD_FAB2_LIB.BASEBOARD_FAB2(SCH_1):PAGE167
 R2U38    2      B RES_0402-665,1.0%,1/16W,CHIP,GA    I80 @BASEBOARD_FAB2_LIB.BASEBOARD_FAB2(SCH_1):PAGE167
 R8D24    1      A RES_0402-20.0,1%,1/16W,CHIP,G2A    I84 @BASEBOARD_FAB2_LIB.BASEBOARD_FAB2(SCH_1):PAGE167
  J8E1   10   IO10 SCONN11_H67026001_SM-CONN,H670A    I87 @BASEBOARD_FAB2_LIB.BASEBOARD_FAB2(SCH_1):PAGE184
  U8D7   A9 PT18C_SCL_PCLKT0_0 LCMXO2_A_256BGA-IC,H63395-001    I59 @BASEBOARD_FAB2_LIB.BASEBOARD_FAB2(SCH_1):PAGE191

SMB_SENSOR_STBY_LVC3_SCL_R1 @BASEBOARD_FAB2_LIB.BASEBOARD_FAB2(SCH_1):SMB_SENSOR_STBY_LVC3_SCL_R1
  U7C1  AY1 GPP_H13_SML3CLK_IE LBG_CORE_QAT_EXT_D_BGA1-IC,H91A   I147 @BASEBOARD_FAB2_LIB.BASEBOARD_FAB2(SCH_1):PAGE120
  R8D3    1      A RES_0402-20.0,1%,1/16W,CHIP,G2A   I161 @BASEBOARD_FAB2_LIB.BASEBOARD_FAB2(SCH_1):PAGE138

SMB_SENSOR_STBY_LVC3_SCL_R2 @BASEBOARD_FAB2_LIB.BASEBOARD_FAB2(SCH_1):SMB_SENSOR_STBY_LVC3_SCL_R2
  U8D4    6    SCL AT24C64_SOICLF-IC,C47049-001-GA    I49 @BASEBOARD_FAB2_LIB.BASEBOARD_FAB2(SCH_1):PAGE167
 R8D24    2      B RES_0402-20.0,1%,1/16W,CHIP,G2A    I84 @BASEBOARD_FAB2_LIB.BASEBOARD_FAB2(SCH_1):PAGE167

SMB_SENSOR_STBY_LVC3_SDA @BASEBOARD_FAB2_LIB.BASEBOARD_FAB2(SCH_1):SMB_SENSOR_STBY_LVC3_SDA
  R1M9    2      B RES_0402-20.0,1%,1/16W,CHIP,G2A     I8 @BASEBOARD_FAB2_LIB.BASEBOARD_FAB2(SCH_1):PAGE167
 R9G15    2      B RES_0402-20.0,1%,1/16W,CHIP,G2A    I58 @BASEBOARD_FAB2_LIB.BASEBOARD_FAB2(SCH_1):PAGE167
  R9R8    2      B RES_0402-20.0,1%,1/16W,CHIP,G2A    I76 @BASEBOARD_FAB2_LIB.BASEBOARD_FAB2(SCH_1):PAGE167
 R1U31    2      B RES_0402-20.0,1%,1/16W,CHIP,G2A    I78 @BASEBOARD_FAB2_LIB.BASEBOARD_FAB2(SCH_1):PAGE167
 R2U39    2      B RES_0402-665,1.0%,1/16W,CHIP,GA    I83 @BASEBOARD_FAB2_LIB.BASEBOARD_FAB2(SCH_1):PAGE167
 R8D23    2      B RES_0402-20.0,1%,1/16W,CHIP,G2A    I85 @BASEBOARD_FAB2_LIB.BASEBOARD_FAB2(SCH_1):PAGE167
  J8E1    6    IO6 SCONN11_H67026001_SM-CONN,H670A    I87 @BASEBOARD_FAB2_LIB.BASEBOARD_FAB2(SCH_1):PAGE184
  U8D7   C9 PT18D_SDA_PCLKC0_0 LCMXO2_A_256BGA-IC,H63395-001    I59 @BASEBOARD_FAB2_LIB.BASEBOARD_FAB2(SCH_1):PAGE191

SMB_SENSOR_STBY_LVC3_SDA_R1 @BASEBOARD_FAB2_LIB.BASEBOARD_FAB2(SCH_1):SMB_SENSOR_STBY_LVC3_SDA_R1
  U7C1  BC2 GPP_H14_SML3DATA_IE LBG_CORE_QAT_EXT_D_BGA1-IC,H91A   I147 @BASEBOARD_FAB2_LIB.BASEBOARD_FAB2(SCH_1):PAGE120
  R8D6    1      A RES_0402-20.0,1%,1/16W,CHIP,G2A   I162 @BASEBOARD_FAB2_LIB.BASEBOARD_FAB2(SCH_1):PAGE138

SMB_SENSOR_STBY_LVC3_SDA_R2 @BASEBOARD_FAB2_LIB.BASEBOARD_FAB2(SCH_1):SMB_SENSOR_STBY_LVC3_SDA_R2
  U8D4    5    SDA AT24C64_SOICLF-IC,C47049-001-GA    I49 @BASEBOARD_FAB2_LIB.BASEBOARD_FAB2(SCH_1):PAGE167
 R8D23    1      A RES_0402-20.0,1%,1/16W,CHIP,G2A    I85 @BASEBOARD_FAB2_LIB.BASEBOARD_FAB2(SCH_1):PAGE167

SMB_SENSOR_TMP421_1_SCL @BASEBOARD_FAB2_LIB.BASEBOARD_FAB2(SCH_1):SMB_SENSOR_TMP421_1_SCL
  U9B4    7    SCL TMP421_TSSOP-IC,G62962-001     I1 @BASEBOARD_FAB2_LIB.BASEBOARD_FAB2(SCH_1):PAGE167
  R1M8    1      A RES_0402-20.0,1%,1/16W,CHIP,G2A    I74 @BASEBOARD_FAB2_LIB.BASEBOARD_FAB2(SCH_1):PAGE167

SMB_SENSOR_TMP421_1_SDA @BASEBOARD_FAB2_LIB.BASEBOARD_FAB2(SCH_1):SMB_SENSOR_TMP421_1_SDA
  U9B4    6    SDA TMP421_TSSOP-IC,G62962-001     I1 @BASEBOARD_FAB2_LIB.BASEBOARD_FAB2(SCH_1):PAGE167
  R1M9    1      A RES_0402-20.0,1%,1/16W,CHIP,G2A     I8 @BASEBOARD_FAB2_LIB.BASEBOARD_FAB2(SCH_1):PAGE167

SMB_SENSOR_TMP421_2_SCL @BASEBOARD_FAB2_LIB.BASEBOARD_FAB2(SCH_1):SMB_SENSOR_TMP421_2_SCL
  U1E1    7    SCL TMP421_TSSOP-IC,G62962-001    I30 @BASEBOARD_FAB2_LIB.BASEBOARD_FAB2(SCH_1):PAGE167
  R9R7    1      A RES_0402-20.0,1%,1/16W,CHIP,G2A    I75 @BASEBOARD_FAB2_LIB.BASEBOARD_FAB2(SCH_1):PAGE167

SMB_SENSOR_TMP421_2_SDA @BASEBOARD_FAB2_LIB.BASEBOARD_FAB2(SCH_1):SMB_SENSOR_TMP421_2_SDA
  U1E1    6    SDA TMP421_TSSOP-IC,G62962-001    I30 @BASEBOARD_FAB2_LIB.BASEBOARD_FAB2(SCH_1):PAGE167
  R9R8    1      A RES_0402-20.0,1%,1/16W,CHIP,G2A    I76 @BASEBOARD_FAB2_LIB.BASEBOARD_FAB2(SCH_1):PAGE167

SMB_SLOTX24_BMC_STBY_LVC3_SCL @BASEBOARD_FAB2_LIB.BASEBOARD_FAB2(SCH_1):SMB_SLOTX24_BMC_STBY_LVC3_SCL
 R2U32    1      A RES_0402-20.0,1%,1/16W,CHIP,G2A   I339 @BASEBOARD_FAB2_LIB.BASEBOARD_FAB2(SCH_1):PAGE108
  R1T7    2      B RES_0402-20.0,1%,1/16W,CHIP,G2A    I50 @BASEBOARD_FAB2_LIB.BASEBOARD_FAB2(SCH_1):PAGE160
 R9M15    2      B RES_0402-20.0,1%,1/16W,CHIP,G2A    I25 @BASEBOARD_FAB2_LIB.BASEBOARD_FAB2(SCH_1):PAGE163

SMB_SLOTX24_BMC_STBY_LVC3_SDA @BASEBOARD_FAB2_LIB.BASEBOARD_FAB2(SCH_1):SMB_SLOTX24_BMC_STBY_LVC3_SDA
 R2U31    1      A RES_0402-20.0,1%,1/16W,CHIP,G2A   I330 @BASEBOARD_FAB2_LIB.BASEBOARD_FAB2(SCH_1):PAGE108
  R1T8    2      B RES_0402-20.0,1%,1/16W,CHIP,G2A     I4 @BASEBOARD_FAB2_LIB.BASEBOARD_FAB2(SCH_1):PAGE160
 R9M12    2      B RES_0402-20.0,1%,1/16W,CHIP,G2A    I24 @BASEBOARD_FAB2_LIB.BASEBOARD_FAB2(SCH_1):PAGE163

SMB_SLOTX24_PCH_STBY_LVC3_SCL @BASEBOARD_FAB2_LIB.BASEBOARD_FAB2(SCH_1):SMB_SLOTX24_PCH_STBY_LVC3_SCL
 R2U36    1      A RES_0402-20.0,1%,1/16W,EMPTY,GA   I340 @BASEBOARD_FAB2_LIB.BASEBOARD_FAB2(SCH_1):PAGE108
 R8B26    2      B RES_0402-3.3K,5%,1/16W,CHIP,G2A    I96 @BASEBOARD_FAB2_LIB.BASEBOARD_FAB2(SCH_1):PAGE138
 R8B28    2      B RES_0402-20.0,1%,1/16W,CHIP,G2A   I174 @BASEBOARD_FAB2_LIB.BASEBOARD_FAB2(SCH_1):PAGE138
 EU9F3   17    SCL PI7C9X1172_QFN-IC,H66899-001     I1 @BASEBOARD_FAB2_LIB.BASEBOARD_FAB2(SCH_1):PAGE183
  U8D7   H5   PL9C LCMXO2_A_256BGA-IC,H63395-001   I179 @BASEBOARD_FAB2_LIB.BASEBOARD_FAB2(SCH_1):PAGE190

SMB_SLOTX24_PCH_STBY_LVC3_SDA @BASEBOARD_FAB2_LIB.BASEBOARD_FAB2(SCH_1):SMB_SLOTX24_PCH_STBY_LVC3_SDA
 R2U35    1      A RES_0402-20.0,1%,1/16W,EMPTY,GA   I320 @BASEBOARD_FAB2_LIB.BASEBOARD_FAB2(SCH_1):PAGE108
 R8B24    2      B RES_0402-3.3K,5%,1/16W,CHIP,G2A    I95 @BASEBOARD_FAB2_LIB.BASEBOARD_FAB2(SCH_1):PAGE138
 R8B27    2      B RES_0402-20.0,1%,1/16W,CHIP,G2A   I173 @BASEBOARD_FAB2_LIB.BASEBOARD_FAB2(SCH_1):PAGE138
 EU9F3    3    SDA PI7C9X1172_QFN-IC,H66899-001     I1 @BASEBOARD_FAB2_LIB.BASEBOARD_FAB2(SCH_1):PAGE183
  U8D7   J4   PL9D LCMXO2_A_256BGA-IC,H63395-001   I179 @BASEBOARD_FAB2_LIB.BASEBOARD_FAB2(SCH_1):PAGE190

SMB_SLOTX24_STBY_LVC3_SCL_R @BASEBOARD_FAB2_LIB.BASEBOARD_FAB2(SCH_1):SMB_SLOTX24_STBY_LVC3_SCL_R
  R1T2    2      B RES_0402-665,1.0%,1/16W,CHIP,GA    I49 @BASEBOARD_FAB2_LIB.BASEBOARD_FAB2(SCH_1):PAGE160
  R1T7    1      A RES_0402-20.0,1%,1/16W,CHIP,G2A    I50 @BASEBOARD_FAB2_LIB.BASEBOARD_FAB2(SCH_1):PAGE160
 U25W4  C14 GPIOA4_TIMER5_SCL9 AST2520A1-GP-GP_ASIC2-GB1-AST2A    I95 @BASEBOARD_FAB2_LIB.BASEBOARD_FAB2(SCH_1):PAGE144

SMB_SLOTX24_STBY_LVC3_SCL_R1 @BASEBOARD_FAB2_LIB.BASEBOARD_FAB2(SCH_1):SMB_SLOTX24_STBY_LVC3_SCL_R1
  U7C1 BY44 GPP_D13_SML0BCLK_IE LBG_CORE_QAT_EXT_D_BGA1-IC,H91A   I115 @BASEBOARD_FAB2_LIB.BASEBOARD_FAB2(SCH_1):PAGE119
 R8B28    1      A RES_0402-20.0,1%,1/16W,CHIP,G2A   I174 @BASEBOARD_FAB2_LIB.BASEBOARD_FAB2(SCH_1):PAGE138

SMB_SLOTX24_STBY_LVC3_SCL_R2 @BASEBOARD_FAB2_LIB.BASEBOARD_FAB2(SCH_1):SMB_SLOTX24_STBY_LVC3_SCL_R2
  J8G1   17   IO17 SCONN200_H68296001_SM-CONN,H68A   I258 @BASEBOARD_FAB2_LIB.BASEBOARD_FAB2(SCH_1):PAGE108
 R2U32    2      B RES_0402-20.0,1%,1/16W,CHIP,G2A   I339 @BASEBOARD_FAB2_LIB.BASEBOARD_FAB2(SCH_1):PAGE108
 R2U36    2      B RES_0402-20.0,1%,1/16W,EMPTY,GA   I340 @BASEBOARD_FAB2_LIB.BASEBOARD_FAB2(SCH_1):PAGE108

SMB_SLOTX24_STBY_LVC3_SDA_R @BASEBOARD_FAB2_LIB.BASEBOARD_FAB2(SCH_1):SMB_SLOTX24_STBY_LVC3_SDA_R
  R1T8    1      A RES_0402-20.0,1%,1/16W,CHIP,G2A     I4 @BASEBOARD_FAB2_LIB.BASEBOARD_FAB2(SCH_1):PAGE160
  R1T3    2      B RES_0402-665,1.0%,1/16W,CHIP,GA    I46 @BASEBOARD_FAB2_LIB.BASEBOARD_FAB2(SCH_1):PAGE160
 U25W4  A13 GPIOA5_TIMER6_SDA9 AST2520A1-GP-GP_ASIC2-GB1-AST2A    I95 @BASEBOARD_FAB2_LIB.BASEBOARD_FAB2(SCH_1):PAGE144

SMB_SLOTX24_STBY_LVC3_SDA_R1 @BASEBOARD_FAB2_LIB.BASEBOARD_FAB2(SCH_1):SMB_SLOTX24_STBY_LVC3_SDA_R1
  U7C1 BL44 GPP_D14_SML0BDATA_IE LBG_CORE_QAT_EXT_D_BGA1-IC,H91A   I115 @BASEBOARD_FAB2_LIB.BASEBOARD_FAB2(SCH_1):PAGE119
 R8B27    1      A RES_0402-20.0,1%,1/16W,CHIP,G2A   I173 @BASEBOARD_FAB2_LIB.BASEBOARD_FAB2(SCH_1):PAGE138

SMB_SLOTX24_STBY_LVC3_SDA_R2 @BASEBOARD_FAB2_LIB.BASEBOARD_FAB2(SCH_1):SMB_SLOTX24_STBY_LVC3_SDA_R2
  J8G1   15   IO15 SCONN200_H68296001_SM-CONN,H68A   I258 @BASEBOARD_FAB2_LIB.BASEBOARD_FAB2(SCH_1):PAGE108
 R2U35    2      B RES_0402-20.0,1%,1/16W,EMPTY,GA   I320 @BASEBOARD_FAB2_LIB.BASEBOARD_FAB2(SCH_1):PAGE108
 R2U31    2      B RES_0402-20.0,1%,1/16W,CHIP,G2A   I330 @BASEBOARD_FAB2_LIB.BASEBOARD_FAB2(SCH_1):PAGE108

SMB_SMLINK0_STBY_LVC3_SCL @BASEBOARD_FAB2_LIB.BASEBOARD_FAB2(SCH_1):SMB_SMLINK0_STBY_LVC3_SCL
  R2N5    2      B RES_0402-665,1.0%,1/16W,CHIP,GA    I90 @BASEBOARD_FAB2_LIB.BASEBOARD_FAB2(SCH_1):PAGE138
 R8C12    2      B RES_0402-20.0,1%,1/16W,CHIP,G2A   I170 @BASEBOARD_FAB2_LIB.BASEBOARD_FAB2(SCH_1):PAGE138
  J9B2    3    IO3 CONN3_C95678002_PIP-CONN,C9567A   I281 @BASEBOARD_FAB2_LIB.BASEBOARD_FAB2(SCH_1):PAGE156
 R1U19    1      A RES_0402-20.0,1%,1/16W,CHIP,G2A   I226 @BASEBOARD_FAB2_LIB.BASEBOARD_FAB2(SCH_1):PAGE159
  R1U9    2      B RES_0402-20.0,1%,1/16W,CHIP,G2A   I232 @BASEBOARD_FAB2_LIB.BASEBOARD_FAB2(SCH_1):PAGE159

SMB_SMLINK0_STBY_LVC3_SCL_R @BASEBOARD_FAB2_LIB.BASEBOARD_FAB2(SCH_1):SMB_SMLINK0_STBY_LVC3_SCL_R
  R1U9    1      A RES_0402-20.0,1%,1/16W,CHIP,G2A   I232 @BASEBOARD_FAB2_LIB.BASEBOARD_FAB2(SCH_1):PAGE159
 U25W4   L1 GPIOK2_SCL6 AST2520A1-GP-GP_ASIC2-GB1-AST2A    I95 @BASEBOARD_FAB2_LIB.BASEBOARD_FAB2(SCH_1):PAGE144

SMB_SMLINK0_STBY_LVC3_SCL_R1 @BASEBOARD_FAB2_LIB.BASEBOARD_FAB2(SCH_1):SMB_SMLINK0_STBY_LVC3_SCL_R1
  U7C1 BV29 GPP_C3_SML0CLK_IE LBG_CORE_QAT_EXT_D_BGA1-IC,H91A   I115 @BASEBOARD_FAB2_LIB.BASEBOARD_FAB2(SCH_1):PAGE119
 R8C12    1      A RES_0402-20.0,1%,1/16W,CHIP,G2A   I170 @BASEBOARD_FAB2_LIB.BASEBOARD_FAB2(SCH_1):PAGE138

SMB_SMLINK0_STBY_LVC3_SDA @BASEBOARD_FAB2_LIB.BASEBOARD_FAB2(SCH_1):SMB_SMLINK0_STBY_LVC3_SDA
  R2N8    2      B RES_0402-665,1.0%,1/16W,CHIP,GA    I89 @BASEBOARD_FAB2_LIB.BASEBOARD_FAB2(SCH_1):PAGE138
 R8C11    2      B RES_0402-20.0,1%,1/16W,CHIP,G2A   I169 @BASEBOARD_FAB2_LIB.BASEBOARD_FAB2(SCH_1):PAGE138
  J9B2    1    IO1 CONN3_C95678002_PIP-CONN,C9567A   I281 @BASEBOARD_FAB2_LIB.BASEBOARD_FAB2(SCH_1):PAGE156
 R1U20    1      A RES_0402-20.0,1%,1/16W,CHIP,G2A   I225 @BASEBOARD_FAB2_LIB.BASEBOARD_FAB2(SCH_1):PAGE159
 R1U10    2      B RES_0402-20.0,1%,1/16W,CHIP,G2A   I233 @BASEBOARD_FAB2_LIB.BASEBOARD_FAB2(SCH_1):PAGE159

SMB_SMLINK0_STBY_LVC3_SDA_R @BASEBOARD_FAB2_LIB.BASEBOARD_FAB2(SCH_1):SMB_SMLINK0_STBY_LVC3_SDA_R
 R1U10    1      A RES_0402-20.0,1%,1/16W,CHIP,G2A   I233 @BASEBOARD_FAB2_LIB.BASEBOARD_FAB2(SCH_1):PAGE159
 U25W4   N2 GPIOK3_SDA6 AST2520A1-GP-GP_ASIC2-GB1-AST2A    I95 @BASEBOARD_FAB2_LIB.BASEBOARD_FAB2(SCH_1):PAGE144

SMB_SMLINK0_STBY_LVC3_SDA_R1 @BASEBOARD_FAB2_LIB.BASEBOARD_FAB2(SCH_1):SMB_SMLINK0_STBY_LVC3_SDA_R1
  U7C1 BW30 GPP_C4_SML0DATA_IE LBG_CORE_QAT_EXT_D_BGA1-IC,H91A   I115 @BASEBOARD_FAB2_LIB.BASEBOARD_FAB2(SCH_1):PAGE119
 R8C11    1      A RES_0402-20.0,1%,1/16W,CHIP,G2A   I169 @BASEBOARD_FAB2_LIB.BASEBOARD_FAB2(SCH_1):PAGE138

SMB_SPRINGVILLE_STBY_LVC3_SCL @BASEBOARD_FAB2_LIB.BASEBOARD_FAB2(SCH_1):SMB_SPRINGVILLE_STBY_LVC3_SCL
 EU9E1   34 SMB_CLK SPRINGVILLE_SM1-IC,G47144-004    I72 @BASEBOARD_FAB2_LIB.BASEBOARD_FAB2(SCH_1):PAGE139
 R1U19    2      B RES_0402-20.0,1%,1/16W,CHIP,G2A   I226 @BASEBOARD_FAB2_LIB.BASEBOARD_FAB2(SCH_1):PAGE159
 R9G13    2      B RES_0402-20.0,1%,1/16W,CHIP,G2A   I227 @BASEBOARD_FAB2_LIB.BASEBOARD_FAB2(SCH_1):PAGE159

SMB_SPRINGVILLE_STBY_LVC3_SDA @BASEBOARD_FAB2_LIB.BASEBOARD_FAB2(SCH_1):SMB_SPRINGVILLE_STBY_LVC3_SDA
 EU9E1   36 SMB_DATA SPRINGVILLE_SM1-IC,G47144-004    I72 @BASEBOARD_FAB2_LIB.BASEBOARD_FAB2(SCH_1):PAGE139
 R9G12    2      B RES_0402-20.0,1%,1/16W,CHIP,G2A   I224 @BASEBOARD_FAB2_LIB.BASEBOARD_FAB2(SCH_1):PAGE159
 R1U20    2      B RES_0402-20.0,1%,1/16W,CHIP,G2A   I225 @BASEBOARD_FAB2_LIB.BASEBOARD_FAB2(SCH_1):PAGE159

SMB_VR_SCL_PVCCIO_CPU0 @BASEBOARD_FAB2_LIB.BASEBOARD_FAB2(SCH_1):SMB_VR_SCL_PVCCIO_CPU0
 R3P24    2      B RES_0402-20.0,1%,1/16W,CHIP,G2A    I46 @BASEBOARD_FAB2_LIB.BASEBOARD_FAB2(SCH_1):PAGE211
 EU3P1    7    SCL PXE1110B_QFN-IC,H89187-001    I93 @BASEBOARD_FAB2_LIB.BASEBOARD_FAB2(SCH_1):PAGE211

SMB_VR_SCL_PVCCIO_CPU1 @BASEBOARD_FAB2_LIB.BASEBOARD_FAB2(SCH_1):SMB_VR_SCL_PVCCIO_CPU1
 R4D43    2      B RES_0402-20.0,1%,1/16W,CHIP,G2A    I39 @BASEBOARD_FAB2_LIB.BASEBOARD_FAB2(SCH_1):PAGE213
 EU4D5    7    SCL PXE1110B_QFN-IC,H89187-001    I96 @BASEBOARD_FAB2_LIB.BASEBOARD_FAB2(SCH_1):PAGE213

SMB_VR_SCL_PVNN_PCH @BASEBOARD_FAB2_LIB.BASEBOARD_FAB2(SCH_1):SMB_VR_SCL_PVNN_PCH
  R8A9    2      B RES_0402-20.0,1%,1/16W,CHIP,G2A   I173 @BASEBOARD_FAB2_LIB.BASEBOARD_FAB2(SCH_1):PAGE235
 EU8A1    7    SCL PXE1110B_QFN-IC,H89187-001   I229 @BASEBOARD_FAB2_LIB.BASEBOARD_FAB2(SCH_1):PAGE235

SMB_VR_SCL_R @BASEBOARD_FAB2_LIB.BASEBOARD_FAB2(SCH_1):SMB_VR_SCL_R
 R4D53    1      A RES_0402-0.0,5%,1/16W,CHIP,G21A    I31 @BASEBOARD_FAB2_LIB.BASEBOARD_FAB2(SCH_1):PAGE201
 EU4D4    9    SCL PXE1610B_QFN-IC,H79206-001   I155 @BASEBOARD_FAB2_LIB.BASEBOARD_FAB2(SCH_1):PAGE201

SMB_VR_SCL_R1 @BASEBOARD_FAB2_LIB.BASEBOARD_FAB2(SCH_1):SMB_VR_SCL_R1
 R1C25    1      A RES_0402-0.0,5%,1/16W,CHIP,G21A    I28 @BASEBOARD_FAB2_LIB.BASEBOARD_FAB2(SCH_1):PAGE206
 EU1C2    9    SCL PXE1610B_QFN-IC,H79206-001   I130 @BASEBOARD_FAB2_LIB.BASEBOARD_FAB2(SCH_1):PAGE206

SMB_VR_SCL_VDDQ_ABC @BASEBOARD_FAB2_LIB.BASEBOARD_FAB2(SCH_1):SMB_VR_SCL_VDDQ_ABC
 R7F25    1      A RES_0402-20.0,1%,1/16W,CHIP,G2A   I298 @BASEBOARD_FAB2_LIB.BASEBOARD_FAB2(SCH_1):PAGE215
 EU7G1    7    SCL PXM1310B_QFN-IC,H89186-001   I358 @BASEBOARD_FAB2_LIB.BASEBOARD_FAB2(SCH_1):PAGE215

SMB_VR_SCL_VDDQ_DEF @BASEBOARD_FAB2_LIB.BASEBOARD_FAB2(SCH_1):SMB_VR_SCL_VDDQ_DEF
  R7B3    1      A RES_0402-20.0,1%,1/16W,CHIP,G2A    I21 @BASEBOARD_FAB2_LIB.BASEBOARD_FAB2(SCH_1):PAGE218
 EU7A5    7    SCL PXM1310B_QFN-IC,H89186-001    I75 @BASEBOARD_FAB2_LIB.BASEBOARD_FAB2(SCH_1):PAGE218

SMB_VR_SCL_VDDQ_GHJ @BASEBOARD_FAB2_LIB.BASEBOARD_FAB2(SCH_1):SMB_VR_SCL_VDDQ_GHJ
 R1G19    1      A RES_0402-0.0,5%,1/16W,CHIP,G21A    I21 @BASEBOARD_FAB2_LIB.BASEBOARD_FAB2(SCH_1):PAGE223
 EU1G2    7    SCL PXM1310B_QFN-IC,H89186-001    I90 @BASEBOARD_FAB2_LIB.BASEBOARD_FAB2(SCH_1):PAGE223

SMB_VR_SCL_VDDQ_KLM @BASEBOARD_FAB2_LIB.BASEBOARD_FAB2(SCH_1):SMB_VR_SCL_VDDQ_KLM
  R1B6    1      A RES_0402-20.0,1%,1/16W,CHIP,G2A    I21 @BASEBOARD_FAB2_LIB.BASEBOARD_FAB2(SCH_1):PAGE226
 EU1B1    7    SCL PXM1310B_QFN-IC,H89186-001    I90 @BASEBOARD_FAB2_LIB.BASEBOARD_FAB2(SCH_1):PAGE226

SMB_VR_SDA_PVCCIO_CPU0 @BASEBOARD_FAB2_LIB.BASEBOARD_FAB2(SCH_1):SMB_VR_SDA_PVCCIO_CPU0
 R3P23    2      B RES_0402-20.0,1%,1/16W,CHIP,G2A    I47 @BASEBOARD_FAB2_LIB.BASEBOARD_FAB2(SCH_1):PAGE211
 EU3P1    6    SDA PXE1110B_QFN-IC,H89187-001    I93 @BASEBOARD_FAB2_LIB.BASEBOARD_FAB2(SCH_1):PAGE211

SMB_VR_SDA_PVCCIO_CPU1 @BASEBOARD_FAB2_LIB.BASEBOARD_FAB2(SCH_1):SMB_VR_SDA_PVCCIO_CPU1
 R4D44    2      B RES_0402-20.0,1%,1/16W,CHIP,G2A    I38 @BASEBOARD_FAB2_LIB.BASEBOARD_FAB2(SCH_1):PAGE213
 EU4D5    6    SDA PXE1110B_QFN-IC,H89187-001    I96 @BASEBOARD_FAB2_LIB.BASEBOARD_FAB2(SCH_1):PAGE213

SMB_VR_SDA_PVNN_PCH @BASEBOARD_FAB2_LIB.BASEBOARD_FAB2(SCH_1):SMB_VR_SDA_PVNN_PCH
  R8A8    2      B RES_0402-20.0,1%,1/16W,CHIP,G2A   I172 @BASEBOARD_FAB2_LIB.BASEBOARD_FAB2(SCH_1):PAGE235
 EU8A1    6    SDA PXE1110B_QFN-IC,H89187-001   I229 @BASEBOARD_FAB2_LIB.BASEBOARD_FAB2(SCH_1):PAGE235

SMB_VR_SDA_R @BASEBOARD_FAB2_LIB.BASEBOARD_FAB2(SCH_1):SMB_VR_SDA_R
 R4D50    1      A RES_0402-0.0,5%,1/16W,CHIP,G21A    I28 @BASEBOARD_FAB2_LIB.BASEBOARD_FAB2(SCH_1):PAGE201
 EU4D4    8    SDA PXE1610B_QFN-IC,H79206-001   I155 @BASEBOARD_FAB2_LIB.BASEBOARD_FAB2(SCH_1):PAGE201

SMB_VR_SDA_R1 @BASEBOARD_FAB2_LIB.BASEBOARD_FAB2(SCH_1):SMB_VR_SDA_R1
 R1C23    1      A RES_0402-0.0,5%,1/16W,CHIP,G21A    I27 @BASEBOARD_FAB2_LIB.BASEBOARD_FAB2(SCH_1):PAGE206
 EU1C2    8    SDA PXE1610B_QFN-IC,H79206-001   I130 @BASEBOARD_FAB2_LIB.BASEBOARD_FAB2(SCH_1):PAGE206

SMB_VR_SDA_VDDQ_ABC @BASEBOARD_FAB2_LIB.BASEBOARD_FAB2(SCH_1):SMB_VR_SDA_VDDQ_ABC
 R7F26    1      A RES_0402-20.0,1%,1/16W,CHIP,G2A   I304 @BASEBOARD_FAB2_LIB.BASEBOARD_FAB2(SCH_1):PAGE215
 EU7G1    6    SDA PXM1310B_QFN-IC,H89186-001   I358 @BASEBOARD_FAB2_LIB.BASEBOARD_FAB2(SCH_1):PAGE215

SMB_VR_SDA_VDDQ_DEF @BASEBOARD_FAB2_LIB.BASEBOARD_FAB2(SCH_1):SMB_VR_SDA_VDDQ_DEF
  R7B2    1      A RES_0402-20.0,1%,1/16W,CHIP,G2A    I24 @BASEBOARD_FAB2_LIB.BASEBOARD_FAB2(SCH_1):PAGE218
 EU7A5    6    SDA PXM1310B_QFN-IC,H89186-001    I75 @BASEBOARD_FAB2_LIB.BASEBOARD_FAB2(SCH_1):PAGE218

SMB_VR_SDA_VDDQ_GHJ @BASEBOARD_FAB2_LIB.BASEBOARD_FAB2(SCH_1):SMB_VR_SDA_VDDQ_GHJ
 R1G21    1      A RES_0402-0.0,5%,1/16W,CHIP,G21A    I22 @BASEBOARD_FAB2_LIB.BASEBOARD_FAB2(SCH_1):PAGE223
 EU1G2    6    SDA PXM1310B_QFN-IC,H89186-001    I90 @BASEBOARD_FAB2_LIB.BASEBOARD_FAB2(SCH_1):PAGE223

SMB_VR_SDA_VDDQ_KLM @BASEBOARD_FAB2_LIB.BASEBOARD_FAB2(SCH_1):SMB_VR_SDA_VDDQ_KLM
  R1B7    1      A RES_0402-20.0,1%,1/16W,CHIP,G2A    I22 @BASEBOARD_FAB2_LIB.BASEBOARD_FAB2(SCH_1):PAGE226
 EU1B1    6    SDA PXM1310B_QFN-IC,H89186-001    I90 @BASEBOARD_FAB2_LIB.BASEBOARD_FAB2(SCH_1):PAGE226

SMB_VR_STBY_LVC3_SCL @BASEBOARD_FAB2_LIB.BASEBOARD_FAB2(SCH_1):SMB_VR_STBY_LVC3_SCL
 R8D15    2      B RES_0402-1.37K,1%,1/16W,CHIP,GA    I88 @BASEBOARD_FAB2_LIB.BASEBOARD_FAB2(SCH_1):PAGE138
  R8D4    2      B RES_0402-20.0,1%,1/16W,CHIP,G2A   I164 @BASEBOARD_FAB2_LIB.BASEBOARD_FAB2(SCH_1):PAGE138
 R1U11    2      B RES_0402-0.0,5%,1/16W,CHIP,G21A   I222 @BASEBOARD_FAB2_LIB.BASEBOARD_FAB2(SCH_1):PAGE159
  J4B2  A18  IOA18 SCONN120_H61426002_SM-CONN,H61A    I46 @BASEBOARD_FAB2_LIB.BASEBOARD_FAB2(SCH_1):PAGE193
  J6B1  A18  IOA18 SCONN120_H61426002_SM-CONN,H61A    I56 @BASEBOARD_FAB2_LIB.BASEBOARD_FAB2(SCH_1):PAGE194
 R4D53    2      B RES_0402-0.0,5%,1/16W,CHIP,G21A    I31 @BASEBOARD_FAB2_LIB.BASEBOARD_FAB2(SCH_1):PAGE201
 R6P37    2      B RES_0402-2.0K,1%,1/16W,EMPTY,GA   I103 @BASEBOARD_FAB2_LIB.BASEBOARD_FAB2(SCH_1):PAGE201
  J8D4    3    IO3 CONN3_C95678002_PIP-CONN,C9567A   I122 @BASEBOARD_FAB2_LIB.BASEBOARD_FAB2(SCH_1):PAGE201
 R1C25    2      B RES_0402-0.0,5%,1/16W,CHIP,G21A    I28 @BASEBOARD_FAB2_LIB.BASEBOARD_FAB2(SCH_1):PAGE206
 R3P24    1      A RES_0402-20.0,1%,1/16W,CHIP,G2A    I46 @BASEBOARD_FAB2_LIB.BASEBOARD_FAB2(SCH_1):PAGE211
 R4D43    1      A RES_0402-20.0,1%,1/16W,CHIP,G2A    I39 @BASEBOARD_FAB2_LIB.BASEBOARD_FAB2(SCH_1):PAGE213
 R7F25    2      B RES_0402-20.0,1%,1/16W,CHIP,G2A   I298 @BASEBOARD_FAB2_LIB.BASEBOARD_FAB2(SCH_1):PAGE215
  R7B3    2      B RES_0402-20.0,1%,1/16W,CHIP,G2A    I21 @BASEBOARD_FAB2_LIB.BASEBOARD_FAB2(SCH_1):PAGE218
 R1G19    2      B RES_0402-0.0,5%,1/16W,CHIP,G21A    I21 @BASEBOARD_FAB2_LIB.BASEBOARD_FAB2(SCH_1):PAGE223
  R1B6    2      B RES_0402-20.0,1%,1/16W,CHIP,G2A    I21 @BASEBOARD_FAB2_LIB.BASEBOARD_FAB2(SCH_1):PAGE226
  R8A9    1      A RES_0402-20.0,1%,1/16W,CHIP,G2A   I173 @BASEBOARD_FAB2_LIB.BASEBOARD_FAB2(SCH_1):PAGE235

SMB_VR_STBY_LVC3_SCL_R @BASEBOARD_FAB2_LIB.BASEBOARD_FAB2(SCH_1):SMB_VR_STBY_LVC3_SCL_R
 R1U11    1      A RES_0402-0.0,5%,1/16W,CHIP,G21A   I222 @BASEBOARD_FAB2_LIB.BASEBOARD_FAB2(SCH_1):PAGE159
 U25W4  A11 GPIOQ0_SCL3 AST2520A1-GP-GP_ASIC2-GB1-AST2A    I95 @BASEBOARD_FAB2_LIB.BASEBOARD_FAB2(SCH_1):PAGE144

SMB_VR_STBY_LVC3_SCL_R1 @BASEBOARD_FAB2_LIB.BASEBOARD_FAB2(SCH_1):SMB_VR_STBY_LVC3_SCL_R1
  U7C1  BA4 GPP_H10_SML2CLK_IE LBG_CORE_QAT_EXT_D_BGA1-IC,H91A   I147 @BASEBOARD_FAB2_LIB.BASEBOARD_FAB2(SCH_1):PAGE120
  R8D4    1      A RES_0402-20.0,1%,1/16W,CHIP,G2A   I164 @BASEBOARD_FAB2_LIB.BASEBOARD_FAB2(SCH_1):PAGE138

SMB_VR_STBY_LVC3_SDA @BASEBOARD_FAB2_LIB.BASEBOARD_FAB2(SCH_1):SMB_VR_STBY_LVC3_SDA
 R8D17    2      B RES_0402-1.37K,1%,1/16W,CHIP,GA    I87 @BASEBOARD_FAB2_LIB.BASEBOARD_FAB2(SCH_1):PAGE138
  R8D7    2      B RES_0402-20.0,1%,1/16W,CHIP,G2A   I163 @BASEBOARD_FAB2_LIB.BASEBOARD_FAB2(SCH_1):PAGE138
  R1U8    2      B RES_0402-0.0,5%,1/16W,CHIP,G21A   I223 @BASEBOARD_FAB2_LIB.BASEBOARD_FAB2(SCH_1):PAGE159
  J4B2  B18  IOB18 SCONN120_H61426002_SM-CONN,H61A    I46 @BASEBOARD_FAB2_LIB.BASEBOARD_FAB2(SCH_1):PAGE193
  J6B1  B18  IOB18 SCONN120_H61426002_SM-CONN,H61A    I56 @BASEBOARD_FAB2_LIB.BASEBOARD_FAB2(SCH_1):PAGE194
 R4D50    2      B RES_0402-0.0,5%,1/16W,CHIP,G21A    I28 @BASEBOARD_FAB2_LIB.BASEBOARD_FAB2(SCH_1):PAGE201
 R6P32    2      B RES_0402-2.0K,1%,1/16W,EMPTY,GA   I102 @BASEBOARD_FAB2_LIB.BASEBOARD_FAB2(SCH_1):PAGE201
  J8D4    1    IO1 CONN3_C95678002_PIP-CONN,C9567A   I122 @BASEBOARD_FAB2_LIB.BASEBOARD_FAB2(SCH_1):PAGE201
 R1C23    2      B RES_0402-0.0,5%,1/16W,CHIP,G21A    I27 @BASEBOARD_FAB2_LIB.BASEBOARD_FAB2(SCH_1):PAGE206
 R3P23    1      A RES_0402-20.0,1%,1/16W,CHIP,G2A    I47 @BASEBOARD_FAB2_LIB.BASEBOARD_FAB2(SCH_1):PAGE211
 R4D44    1      A RES_0402-20.0,1%,1/16W,CHIP,G2A    I38 @BASEBOARD_FAB2_LIB.BASEBOARD_FAB2(SCH_1):PAGE213
 R7F26    2      B RES_0402-20.0,1%,1/16W,CHIP,G2A   I304 @BASEBOARD_FAB2_LIB.BASEBOARD_FAB2(SCH_1):PAGE215
  R7B2    2      B RES_0402-20.0,1%,1/16W,CHIP,G2A    I24 @BASEBOARD_FAB2_LIB.BASEBOARD_FAB2(SCH_1):PAGE218
 R1G21    2      B RES_0402-0.0,5%,1/16W,CHIP,G21A    I22 @BASEBOARD_FAB2_LIB.BASEBOARD_FAB2(SCH_1):PAGE223
  R1B7    2      B RES_0402-20.0,1%,1/16W,CHIP,G2A    I22 @BASEBOARD_FAB2_LIB.BASEBOARD_FAB2(SCH_1):PAGE226
  R8A8    1      A RES_0402-20.0,1%,1/16W,CHIP,G2A   I172 @BASEBOARD_FAB2_LIB.BASEBOARD_FAB2(SCH_1):PAGE235

SMB_VR_STBY_LVC3_SDA_R @BASEBOARD_FAB2_LIB.BASEBOARD_FAB2(SCH_1):SMB_VR_STBY_LVC3_SDA_R
  R1U8    1      A RES_0402-0.0,5%,1/16W,CHIP,G21A   I223 @BASEBOARD_FAB2_LIB.BASEBOARD_FAB2(SCH_1):PAGE159
 U25W4  A10 GPIOQ1_SDA3 AST2520A1-GP-GP_ASIC2-GB1-AST2A    I95 @BASEBOARD_FAB2_LIB.BASEBOARD_FAB2(SCH_1):PAGE144

SMB_VR_STBY_LVC3_SDA_R1 @BASEBOARD_FAB2_LIB.BASEBOARD_FAB2(SCH_1):SMB_VR_STBY_LVC3_SDA_R1
  U7C1  BD1 GPP_H11_SML2DATA_IE LBG_CORE_QAT_EXT_D_BGA1-IC,H91A   I147 @BASEBOARD_FAB2_LIB.BASEBOARD_FAB2(SCH_1):PAGE120
  R8D7    1      A RES_0402-20.0,1%,1/16W,CHIP,G2A   I163 @BASEBOARD_FAB2_LIB.BASEBOARD_FAB2(SCH_1):PAGE138

SP1_BMC_HOST_UART_RX @BASEBOARD_FAB2_LIB.BASEBOARD_FAB2(SCH_1):SP1_BMC_HOST_UART_RX
  U9F1    3     B2 FSA3357_SM-IC,C63273-001    I75 @BASEBOARD_FAB2_LIB.BASEBOARD_FAB2(SCH_1):PAGE158
 R9F54    1      A RES_0402-0.0,5%,1/16W,CHIP,G21A    I52 @BASEBOARD_FAB2_LIB.BASEBOARD_FAB2(SCH_1):PAGE183
  U8D7   K3  PL10A LCMXO2_A_256BGA-IC,H63395-001   I179 @BASEBOARD_FAB2_LIB.BASEBOARD_FAB2(SCH_1):PAGE190
 U25W4   W1 GPIOL7_RXD1 AST2520A1-GP-GP_ASIC2-GB1-AST2A   I117 @BASEBOARD_FAB2_LIB.BASEBOARD_FAB2(SCH_1):PAGE145

SP1_BMC_HOST_UART_TX @BASEBOARD_FAB2_LIB.BASEBOARD_FAB2(SCH_1):SP1_BMC_HOST_UART_TX
  U9F2    3     B2 FSA3357_SM-IC,C63273-001    I74 @BASEBOARD_FAB2_LIB.BASEBOARD_FAB2(SCH_1):PAGE158
 R9F56    2      B RES_0402-0.0,5%,1/16W,CHIP,G21A    I49 @BASEBOARD_FAB2_LIB.BASEBOARD_FAB2(SCH_1):PAGE183
  U8D7   K2  PL10B LCMXO2_A_256BGA-IC,H63395-001   I179 @BASEBOARD_FAB2_LIB.BASEBOARD_FAB2(SCH_1):PAGE190
 U25W4   V1 GPIOL6_TXD1 AST2520A1-GP-GP_ASIC2-GB1-AST2A   I117 @BASEBOARD_FAB2_LIB.BASEBOARD_FAB2(SCH_1):PAGE145

SP1_HOST_BRIDGE_UART_RX @BASEBOARD_FAB2_LIB.BASEBOARD_FAB2(SCH_1):SP1_HOST_BRIDGE_UART_RX
 EU9F3    5    RXA PI7C9X1172_QFN-IC,H66899-001     I1 @BASEBOARD_FAB2_LIB.BASEBOARD_FAB2(SCH_1):PAGE183
 R9F54    2      B RES_0402-0.0,5%,1/16W,CHIP,G21A    I52 @BASEBOARD_FAB2_LIB.BASEBOARD_FAB2(SCH_1):PAGE183

SP1_HOST_BRIDGE_UART_TX @BASEBOARD_FAB2_LIB.BASEBOARD_FAB2(SCH_1):SP1_HOST_BRIDGE_UART_TX
 EU9F3    6    TXA PI7C9X1172_QFN-IC,H66899-001     I1 @BASEBOARD_FAB2_LIB.BASEBOARD_FAB2(SCH_1):PAGE183
 R9F56    1      A RES_0402-0.0,5%,1/16W,CHIP,G21A    I49 @BASEBOARD_FAB2_LIB.BASEBOARD_FAB2(SCH_1):PAGE183

SP2_BMC_CM_UART_RX @BASEBOARD_FAB2_LIB.BASEBOARD_FAB2(SCH_1):SP2_BMC_CM_UART_RX
  U7C1 BV44 GPP_D21_IE_UART_RX LBG_CORE_QAT_EXT_D_BGA1-IC,H91A   I115 @BASEBOARD_FAB2_LIB.BASEBOARD_FAB2(SCH_1):PAGE119
 R9F24    2      B RES_0402-0.0,5%,1/16W,EMPTY,G2A   I100 @BASEBOARD_FAB2_LIB.BASEBOARD_FAB2(SCH_1):PAGE158
 R9F68    2      B RES_0402-0.0,5%,1/16W,EMPTY,G2A   I149 @BASEBOARD_FAB2_LIB.BASEBOARD_FAB2(SCH_1):PAGE158
 U25W4   T5 GPIOM7_RXD2_VPIB9 AST2520A1-GP-GP_ASIC2-GB1-AST2A   I117 @BASEBOARD_FAB2_LIB.BASEBOARD_FAB2(SCH_1):PAGE145

SP2_BMC_CM_UART_RX_R @BASEBOARD_FAB2_LIB.BASEBOARD_FAB2(SCH_1):SP2_BMC_CM_UART_RX_R
  U9F1    1     B0 FSA3357_SM-IC,C63273-001    I75 @BASEBOARD_FAB2_LIB.BASEBOARD_FAB2(SCH_1):PAGE158
 R9F68    1      A RES_0402-0.0,5%,1/16W,EMPTY,G2A   I149 @BASEBOARD_FAB2_LIB.BASEBOARD_FAB2(SCH_1):PAGE158
 R9F69    1      A RES_0402-0.0,5%,1/16W,CHIP,G21A   I150 @BASEBOARD_FAB2_LIB.BASEBOARD_FAB2(SCH_1):PAGE158

SP2_BMC_CM_UART_RX_R1 @BASEBOARD_FAB2_LIB.BASEBOARD_FAB2(SCH_1):SP2_BMC_CM_UART_RX_R1
 R9F67    1      A RES_0402-0.0,5%,1/16W,CHIP,G21A   I279 @BASEBOARD_FAB2_LIB.BASEBOARD_FAB2(SCH_1):PAGE181
 R9F69    2      B RES_0402-0.0,5%,1/16W,CHIP,G21A   I150 @BASEBOARD_FAB2_LIB.BASEBOARD_FAB2(SCH_1):PAGE158

SP2_BMC_CM_UART_TX @BASEBOARD_FAB2_LIB.BASEBOARD_FAB2(SCH_1):SP2_BMC_CM_UART_TX
  U7C1 BR46 GPP_D22_IE_UART_TX LBG_CORE_QAT_EXT_D_BGA1-IC,H91A   I115 @BASEBOARD_FAB2_LIB.BASEBOARD_FAB2(SCH_1):PAGE119
 R9F26    1      A RES_0402-0.0,5%,1/16W,EMPTY,G2A    I99 @BASEBOARD_FAB2_LIB.BASEBOARD_FAB2(SCH_1):PAGE158
 R9F66    1      A RES_0402-0.0,5%,1/16W,EMPTY,G2A   I152 @BASEBOARD_FAB2_LIB.BASEBOARD_FAB2(SCH_1):PAGE158
 U25W4   R5 GPIOM6_TXD2_VPIB8 AST2520A1-GP-GP_ASIC2-GB1-AST2A   I117 @BASEBOARD_FAB2_LIB.BASEBOARD_FAB2(SCH_1):PAGE145

SP2_BMC_CM_UART_TX_R @BASEBOARD_FAB2_LIB.BASEBOARD_FAB2(SCH_1):SP2_BMC_CM_UART_TX_R
  U9F2    1     B0 FSA3357_SM-IC,C63273-001    I74 @BASEBOARD_FAB2_LIB.BASEBOARD_FAB2(SCH_1):PAGE158
 R9F65    2      B RES_0402-0.0,5%,1/16W,CHIP,G21A   I148 @BASEBOARD_FAB2_LIB.BASEBOARD_FAB2(SCH_1):PAGE158
 R9F66    2      B RES_0402-0.0,5%,1/16W,EMPTY,G2A   I152 @BASEBOARD_FAB2_LIB.BASEBOARD_FAB2(SCH_1):PAGE158

SP2_BMC_CM_UART_TX_R1 @BASEBOARD_FAB2_LIB.BASEBOARD_FAB2(SCH_1):SP2_BMC_CM_UART_TX_R1
 R9F65    1      A RES_0402-0.0,5%,1/16W,CHIP,G21A   I148 @BASEBOARD_FAB2_LIB.BASEBOARD_FAB2(SCH_1):PAGE158
 R9F64    1      A RES_0402-0.0,5%,1/16W,CHIP,G21A   I281 @BASEBOARD_FAB2_LIB.BASEBOARD_FAB2(SCH_1):PAGE181

SPA_5V_SIN_SW @BASEBOARD_FAB2_LIB.BASEBOARD_FAB2(SCH_1):SPA_5V_SIN_SW
  J9A2   10   IO10 CONN14_H54902001_PIP-CONN,H549A   I171 @BASEBOARD_FAB2_LIB.BASEBOARD_FAB2(SCH_1):PAGE155
  U9A1    2      A TTL1G07_A_SOP-74LVC1G07,IC,C88B   I178 @BASEBOARD_FAB2_LIB.BASEBOARD_FAB2(SCH_1):PAGE155
  R9A6    2      B RES_0402-20.0K,1%,1/16W,EMPTY,A   I191 @BASEBOARD_FAB2_LIB.BASEBOARD_FAB2(SCH_1):PAGE155
 R6W19    1      A RES_0402-0.0,5%,1/16W,CHIP,G21A   I196 @BASEBOARD_FAB2_LIB.BASEBOARD_FAB2(SCH_1):PAGE155

SPA_MID_DBG1__RX @BASEBOARD_FAB2_LIB.BASEBOARD_FAB2(SCH_1):SPA_MID_DBG1__RX
  R9A8    2      B RES_0402-0.0,5%,1/16W,CHIP,G21A    I53 @BASEBOARD_FAB2_LIB.BASEBOARD_FAB2(SCH_1):PAGE155
 U6W10    1   A<0> TTL1G08_SOTLF-NC7SZ08,IC,D1032B   I122 @BASEBOARD_FAB2_LIB.BASEBOARD_FAB2(SCH_1):PAGE176

SPA_MID_DBG2_RX @BASEBOARD_FAB2_LIB.BASEBOARD_FAB2(SCH_1):SPA_MID_DBG2_RX
  J9B1    9 STDA_SSTXP CONN9_H51826001_PIP2-CONN,H518A    I69 @BASEBOARD_FAB2_LIB.BASEBOARD_FAB2(SCH_1):PAGE176
 U6W10    2   B<0> TTL1G08_SOTLF-NC7SZ08,IC,D1032B   I122 @BASEBOARD_FAB2_LIB.BASEBOARD_FAB2(SCH_1):PAGE176

SPA_MID_DBG_RX @BASEBOARD_FAB2_LIB.BASEBOARD_FAB2(SCH_1):SPA_MID_DBG_RX
 R9F25    1      A RES_0402-100.0,1%,1/16W,CHIP,GA    I86 @BASEBOARD_FAB2_LIB.BASEBOARD_FAB2(SCH_1):PAGE158
 R9F24    1      A RES_0402-0.0,5%,1/16W,EMPTY,G2A   I100 @BASEBOARD_FAB2_LIB.BASEBOARD_FAB2(SCH_1):PAGE158
 U6W10    4   Y<0> TTL1G08_SOTLF-NC7SZ08,IC,D1032B   I122 @BASEBOARD_FAB2_LIB.BASEBOARD_FAB2(SCH_1):PAGE176
 R9F63    1      A RES_0402-0.0,5%,1/16W,EMPTY,G2A   I282 @BASEBOARD_FAB2_LIB.BASEBOARD_FAB2(SCH_1):PAGE181

SPA_MID_DBG_RX_R @BASEBOARD_FAB2_LIB.BASEBOARD_FAB2(SCH_1):SPA_MID_DBG_RX_R
  J1F1   H3   IOH3 CONN76_H22707001_THMT1-CONN,H2A   I111 @BASEBOARD_FAB2_LIB.BASEBOARD_FAB2(SCH_1):PAGE181
 R9F64    2      B RES_0402-0.0,5%,1/16W,CHIP,G21A   I281 @BASEBOARD_FAB2_LIB.BASEBOARD_FAB2(SCH_1):PAGE181
 R9F63    2      B RES_0402-0.0,5%,1/16W,EMPTY,G2A   I282 @BASEBOARD_FAB2_LIB.BASEBOARD_FAB2(SCH_1):PAGE181

SPA_MID_DBG_TX @BASEBOARD_FAB2_LIB.BASEBOARD_FAB2(SCH_1):SPA_MID_DBG_TX
  J9A2    9    IO9 CONN14_H54902001_PIP-CONN,H549A   I171 @BASEBOARD_FAB2_LIB.BASEBOARD_FAB2(SCH_1):PAGE155
 R9F27    2      B RES_0402-0.0,5%,1/16W,CHIP,G21A    I91 @BASEBOARD_FAB2_LIB.BASEBOARD_FAB2(SCH_1):PAGE158
 R9F26    2      B RES_0402-0.0,5%,1/16W,EMPTY,G2A    I99 @BASEBOARD_FAB2_LIB.BASEBOARD_FAB2(SCH_1):PAGE158
  J9B1    8 STDA_SSTXN CONN9_H51826001_PIP2-CONN,H518A    I69 @BASEBOARD_FAB2_LIB.BASEBOARD_FAB2(SCH_1):PAGE176
 R9F70    1      A RES_0402-0.0,5%,1/16W,EMPTY,G2A   I280 @BASEBOARD_FAB2_LIB.BASEBOARD_FAB2(SCH_1):PAGE181

SPA_MID_DBG_TX_R @BASEBOARD_FAB2_LIB.BASEBOARD_FAB2(SCH_1):SPA_MID_DBG_TX_R
  J1F1   G3   IOG3 CONN76_H22707001_THMT1-CONN,H2A   I111 @BASEBOARD_FAB2_LIB.BASEBOARD_FAB2(SCH_1):PAGE181
 R9F67    2      B RES_0402-0.0,5%,1/16W,CHIP,G21A   I279 @BASEBOARD_FAB2_LIB.BASEBOARD_FAB2(SCH_1):PAGE181
 R9F70    2      B RES_0402-0.0,5%,1/16W,EMPTY,G2A   I280 @BASEBOARD_FAB2_LIB.BASEBOARD_FAB2(SCH_1):PAGE181

SPA_SIN_SW_R @BASEBOARD_FAB2_LIB.BASEBOARD_FAB2(SCH_1):SPA_SIN_SW_R
  R9A8    1      A RES_0402-0.0,5%,1/16W,CHIP,G21A    I53 @BASEBOARD_FAB2_LIB.BASEBOARD_FAB2(SCH_1):PAGE155
  R9A7    2      B RES_0402-2.21K,1%,1/16W,CHIP,GA    I80 @BASEBOARD_FAB2_LIB.BASEBOARD_FAB2(SCH_1):PAGE155
  U9A1    4      Y TTL1G07_A_SOP-74LVC1G07,IC,C88B   I178 @BASEBOARD_FAB2_LIB.BASEBOARD_FAB2(SCH_1):PAGE155
 R6W19    2      B RES_0402-0.0,5%,1/16W,CHIP,G21A   I196 @BASEBOARD_FAB2_LIB.BASEBOARD_FAB2(SCH_1):PAGE155

SPI_BIOS_SOCKET_IO2 @BASEBOARD_FAB2_LIB.BASEBOARD_FAB2(SCH_1):SPI_BIOS_SOCKET_IO2
 R7F37    1      A RES_0402-33.2,1%,1/16W,CHIP,G2A   I108 @BASEBOARD_FAB2_LIB.BASEBOARD_FAB2(SCH_1):PAGE153
  R3U1    1      A RES_0402-33.2,1%,1/16W,CHIP,G2A   I156 @BASEBOARD_FAB2_LIB.BASEBOARD_FAB2(SCH_1):PAGE153
  U2T1    4     YA PI3B3257A_TSSOPLF-IC,E16801-001    I75 @BASEBOARD_FAB2_LIB.BASEBOARD_FAB2(SCH_1):PAGE154

SPI_BIOS_SOCKET_IO3 @BASEBOARD_FAB2_LIB.BASEBOARD_FAB2(SCH_1):SPI_BIOS_SOCKET_IO3
  R7F3    1      A RES_0402-33.2,1%,1/16W,CHIP,G2A   I109 @BASEBOARD_FAB2_LIB.BASEBOARD_FAB2(SCH_1):PAGE153
  R3T1    1      A RES_0402-33.2,1%,1/16W,CHIP,G2A   I157 @BASEBOARD_FAB2_LIB.BASEBOARD_FAB2(SCH_1):PAGE153
  U2T1    7     YB PI3B3257A_TSSOPLF-IC,E16801-001    I75 @BASEBOARD_FAB2_LIB.BASEBOARD_FAB2(SCH_1):PAGE154

SPI_BMC_BT_CLK @BASEBOARD_FAB2_LIB.BASEBOARD_FAB2(SCH_1):SPI_BMC_BT_CLK
  U8F2   16    CLK W25Q128_SKT16-IC,H12709-001    I32 @BASEBOARD_FAB2_LIB.BASEBOARD_FAB2(SCH_1):PAGE162
 UN8F2   16    CLK W25Q256_XSOI-IC,H25002-001    I17 @BASEBOARD_FAB2_LIB.BASEBOARD_FAB2(SCH_1):PAGE246
R25W95    2      B RES_0402-4.75K,1%,1/16W,CHIP,GA     I2 @BASEBOARD_FAB2_LIB.BASEBOARD_FAB2(SCH_1):PAGE151
R25W81    1      A RES_0402-33.2,1%,1/16W,CHIP,G2A    I67 @BASEBOARD_FAB2_LIB.BASEBOARD_FAB2(SCH_1):PAGE146

SPI_BMC_BT_CLK_R @BASEBOARD_FAB2_LIB.BASEBOARD_FAB2(SCH_1):SPI_BMC_BT_CLK_R
R25W81    2      B RES_0402-33.2,1%,1/16W,CHIP,G2A    I67 @BASEBOARD_FAB2_LIB.BASEBOARD_FAB2(SCH_1):PAGE146
 U25W4 AA18 FWSPICK AST2520A1-GP-GP_ASIC2-GB1-AST2A   I105 @BASEBOARD_FAB2_LIB.BASEBOARD_FAB2(SCH_1):PAGE146

SPI_BMC_BT_CS1_N @BASEBOARD_FAB2_LIB.BASEBOARD_FAB2(SCH_1):SPI_BMC_BT_CS1_N
 RN8F1    2      B RES_0402-4.75K,1%,1/16W,CHIP,GA     I5 @BASEBOARD_FAB2_LIB.BASEBOARD_FAB2(SCH_1):PAGE246
 UN8F2    7   CS_N W25Q256_XSOI-IC,H25002-001    I17 @BASEBOARD_FAB2_LIB.BASEBOARD_FAB2(SCH_1):PAGE246
 U25W4 AA19 GPIOR0_FWSPICS1# AST2520A1-GP-GP_ASIC2-GB1-AST2A   I105 @BASEBOARD_FAB2_LIB.BASEBOARD_FAB2(SCH_1):PAGE146

SPI_BMC_BT_CS_N @BASEBOARD_FAB2_LIB.BASEBOARD_FAB2(SCH_1):SPI_BMC_BT_CS_N
 R8F13    2      B RES_0402-4.75K,1%,1/16W,CHIP,GA    I23 @BASEBOARD_FAB2_LIB.BASEBOARD_FAB2(SCH_1):PAGE162
  U8F2    7   CS_N W25Q128_SKT16-IC,H12709-001    I32 @BASEBOARD_FAB2_LIB.BASEBOARD_FAB2(SCH_1):PAGE162
R25W94    2      B RES_0402-4.75K,1%,1/16W,CHIP,GA     I9 @BASEBOARD_FAB2_LIB.BASEBOARD_FAB2(SCH_1):PAGE151
R25W78    1      A RES_0402-22.1,1.0%,1/16W,CHIP,A    I69 @BASEBOARD_FAB2_LIB.BASEBOARD_FAB2(SCH_1):PAGE146

SPI_BMC_BT_CS_R_N @BASEBOARD_FAB2_LIB.BASEBOARD_FAB2(SCH_1):SPI_BMC_BT_CS_R_N
R25W78    2      B RES_0402-22.1,1.0%,1/16W,CHIP,A    I69 @BASEBOARD_FAB2_LIB.BASEBOARD_FAB2(SCH_1):PAGE146
 U25W4 AB19 FWSPICS0# AST2520A1-GP-GP_ASIC2-GB1-AST2A   I105 @BASEBOARD_FAB2_LIB.BASEBOARD_FAB2(SCH_1):PAGE146

SPI_BMC_BT_DI @BASEBOARD_FAB2_LIB.BASEBOARD_FAB2(SCH_1):SPI_BMC_BT_DI
 R8F12    1      A RES_0402-33.2,1%,1/16W,CHIP,G2A    I13 @BASEBOARD_FAB2_LIB.BASEBOARD_FAB2(SCH_1):PAGE162
 RN8F5    1      A RES_0402-33.2,1%,1/16W,CHIP,G2A     I9 @BASEBOARD_FAB2_LIB.BASEBOARD_FAB2(SCH_1):PAGE246
R25W97    2      B RES_0402-4.75K,1%,1/16W,EMPTY,A    I11 @BASEBOARD_FAB2_LIB.BASEBOARD_FAB2(SCH_1):PAGE151
 U25W4  T18 FWSPIMISO AST2520A1-GP-GP_ASIC2-GB1-AST2A   I105 @BASEBOARD_FAB2_LIB.BASEBOARD_FAB2(SCH_1):PAGE146

SPI_BMC_BT_DI_R @BASEBOARD_FAB2_LIB.BASEBOARD_FAB2(SCH_1):SPI_BMC_BT_DI_R
 R8F12    2      B RES_0402-33.2,1%,1/16W,CHIP,G2A    I13 @BASEBOARD_FAB2_LIB.BASEBOARD_FAB2(SCH_1):PAGE162
  U8F2    8 DO_IO<1> W25Q128_SKT16-IC,H12709-001    I32 @BASEBOARD_FAB2_LIB.BASEBOARD_FAB2(SCH_1):PAGE162

SPI_BMC_BT_DO @BASEBOARD_FAB2_LIB.BASEBOARD_FAB2(SCH_1):SPI_BMC_BT_DO
  U8F2   15 DI_IO<0> W25Q128_SKT16-IC,H12709-001    I32 @BASEBOARD_FAB2_LIB.BASEBOARD_FAB2(SCH_1):PAGE162
 UN8F2   15 DI_IO<0> W25Q256_XSOI-IC,H25002-001    I17 @BASEBOARD_FAB2_LIB.BASEBOARD_FAB2(SCH_1):PAGE246
R25W96    2      B RES_0402-4.75K,1%,1/16W,CHIP,GA    I10 @BASEBOARD_FAB2_LIB.BASEBOARD_FAB2(SCH_1):PAGE151
R25W82    1      A RES_0402-33.2,1%,1/16W,CHIP,G2A    I68 @BASEBOARD_FAB2_LIB.BASEBOARD_FAB2(SCH_1):PAGE146

SPI_BMC_BT_DO_R @BASEBOARD_FAB2_LIB.BASEBOARD_FAB2(SCH_1):SPI_BMC_BT_DO_R
R25W82    2      B RES_0402-33.2,1%,1/16W,CHIP,G2A    I68 @BASEBOARD_FAB2_LIB.BASEBOARD_FAB2(SCH_1):PAGE146
 U25W4  U17 FWSPIMOSI AST2520A1-GP-GP_ASIC2-GB1-AST2A   I105 @BASEBOARD_FAB2_LIB.BASEBOARD_FAB2(SCH_1):PAGE146

SPI_BMC_CLK @BASEBOARD_FAB2_LIB.BASEBOARD_FAB2(SCH_1):SPI_BMC_CLK
  U8F1    3    IA1 PI3B3257A_TSSOPLF-IC,E16801-001    I74 @BASEBOARD_FAB2_LIB.BASEBOARD_FAB2(SCH_1):PAGE154
 U25W4  Y19 GPIOR3_SPI2CK AST2520A1-GP-GP_ASIC2-GB1-AST2A   I105 @BASEBOARD_FAB2_LIB.BASEBOARD_FAB2(SCH_1):PAGE146

SPI_BMC_CS0_N @BASEBOARD_FAB2_LIB.BASEBOARD_FAB2(SCH_1):SPI_BMC_CS0_N
  U8F1   10    IC1 PI3B3257A_TSSOPLF-IC,E16801-001    I74 @BASEBOARD_FAB2_LIB.BASEBOARD_FAB2(SCH_1):PAGE154
 U25W4  T17 GPIOR2_SPI2CS0# AST2520A1-GP-GP_ASIC2-GB1-AST2A   I105 @BASEBOARD_FAB2_LIB.BASEBOARD_FAB2(SCH_1):PAGE146

SPI_BMC_DI @BASEBOARD_FAB2_LIB.BASEBOARD_FAB2(SCH_1):SPI_BMC_DI
  U8F1   13    ID1 PI3B3257A_TSSOPLF-IC,E16801-001    I74 @BASEBOARD_FAB2_LIB.BASEBOARD_FAB2(SCH_1):PAGE154
 U25W4  V19 GPIOR5_SPI2MISO AST2520A1-GP-GP_ASIC2-GB1-AST2A   I105 @BASEBOARD_FAB2_LIB.BASEBOARD_FAB2(SCH_1):PAGE146

SPI_BMC_DO @BASEBOARD_FAB2_LIB.BASEBOARD_FAB2(SCH_1):SPI_BMC_DO
  U8F1    6    IB1 PI3B3257A_TSSOPLF-IC,E16801-001    I74 @BASEBOARD_FAB2_LIB.BASEBOARD_FAB2(SCH_1):PAGE154
 U25W4  W19 GPIOR4_SPI2MOSI AST2520A1-GP-GP_ASIC2-GB1-AST2A   I105 @BASEBOARD_FAB2_LIB.BASEBOARD_FAB2(SCH_1):PAGE146

SPI_CLK_R0 @BASEBOARD_FAB2_LIB.BASEBOARD_FAB2(SCH_1):SPI_CLK_R0
  U7F1   16    CLK W25Q256_XSOI-IC,H25002-001   I146 @BASEBOARD_FAB2_LIB.BASEBOARD_FAB2(SCH_1):PAGE153
  R8F8    2      B RES_0402-33.2,1%,1/16W,CHIP,G2A   I166 @BASEBOARD_FAB2_LIB.BASEBOARD_FAB2(SCH_1):PAGE153

SPI_CLK_R1 @BASEBOARD_FAB2_LIB.BASEBOARD_FAB2(SCH_1):SPI_CLK_R1
  U3T1   16    CLK W25Q256_XSOI-IC,H25002-001   I165 @BASEBOARD_FAB2_LIB.BASEBOARD_FAB2(SCH_1):PAGE153
  R8F7    2      B RES_0402-33.2,1%,1/16W,CHIP,G2A   I167 @BASEBOARD_FAB2_LIB.BASEBOARD_FAB2(SCH_1):PAGE153

SPI_CS0_PRIMARY_N @BASEBOARD_FAB2_LIB.BASEBOARD_FAB2(SCH_1):SPI_CS0_PRIMARY_N
  U2T3    4      Y TTL1G32_A_SOT-74LVC1G32,IC,E60B    I99 @BASEBOARD_FAB2_LIB.BASEBOARD_FAB2(SCH_1):PAGE154
 R2T13    1      A RES_0402-200.0,1%,1/16W,CHIP,GA   I101 @BASEBOARD_FAB2_LIB.BASEBOARD_FAB2(SCH_1):PAGE154

SPI_CS0_PRIMARY_R_N @BASEBOARD_FAB2_LIB.BASEBOARD_FAB2(SCH_1):SPI_CS0_PRIMARY_R_N
  R7F5    2      B RES_0402-4.75K,1%,1/16W,CHIP,GA    I94 @BASEBOARD_FAB2_LIB.BASEBOARD_FAB2(SCH_1):PAGE153
  U7F1    7   CS_N W25Q256_XSOI-IC,H25002-001   I146 @BASEBOARD_FAB2_LIB.BASEBOARD_FAB2(SCH_1):PAGE153
 R2T13    2      B RES_0402-200.0,1%,1/16W,CHIP,GA   I101 @BASEBOARD_FAB2_LIB.BASEBOARD_FAB2(SCH_1):PAGE154

SPI_CS0_SECONDARY_N @BASEBOARD_FAB2_LIB.BASEBOARD_FAB2(SCH_1):SPI_CS0_SECONDARY_N
  R2T9    1      A RES_0402-75,1.0%,1/16W,CHIP,G2A    I62 @BASEBOARD_FAB2_LIB.BASEBOARD_FAB2(SCH_1):PAGE154
  U2T2    4      Y TTL1G32_A_SOT-74LVC1G32,IC,E60B   I100 @BASEBOARD_FAB2_LIB.BASEBOARD_FAB2(SCH_1):PAGE154

SPI_CS0_SECONDARY_R_N @BASEBOARD_FAB2_LIB.BASEBOARD_FAB2(SCH_1):SPI_CS0_SECONDARY_R_N
  R3T5    2      B RES_0402-4.75K,1%,1/16W,CHIP,GA   I152 @BASEBOARD_FAB2_LIB.BASEBOARD_FAB2(SCH_1):PAGE153
  U3T1    7   CS_N W25Q256_XSOI-IC,H25002-001   I165 @BASEBOARD_FAB2_LIB.BASEBOARD_FAB2(SCH_1):PAGE153
  R2T9    2      B RES_0402-75,1.0%,1/16W,CHIP,G2A    I62 @BASEBOARD_FAB2_LIB.BASEBOARD_FAB2(SCH_1):PAGE154

SPI_MISO_R0 @BASEBOARD_FAB2_LIB.BASEBOARD_FAB2(SCH_1):SPI_MISO_R0
  R7F4    2      B RES_0402-33.2,1%,1/16W,CHIP,G2A    I98 @BASEBOARD_FAB2_LIB.BASEBOARD_FAB2(SCH_1):PAGE153
  U7F1    8 DO_IO<1> W25Q256_XSOI-IC,H25002-001   I146 @BASEBOARD_FAB2_LIB.BASEBOARD_FAB2(SCH_1):PAGE153

SPI_MISO_R1 @BASEBOARD_FAB2_LIB.BASEBOARD_FAB2(SCH_1):SPI_MISO_R1
  R3T2    2      B RES_0402-33.2,1%,1/16W,CHIP,G2A   I155 @BASEBOARD_FAB2_LIB.BASEBOARD_FAB2(SCH_1):PAGE153
  U3T1    8 DO_IO<1> W25Q256_XSOI-IC,H25002-001   I165 @BASEBOARD_FAB2_LIB.BASEBOARD_FAB2(SCH_1):PAGE153

SPI_NIC_CS_N @BASEBOARD_FAB2_LIB.BASEBOARD_FAB2(SCH_1):SPI_NIC_CS_N
  R9E5    2      B RES_0402-33.2,1%,1/16W,CHIP,G2A   I129 @BASEBOARD_FAB2_LIB.BASEBOARD_FAB2(SCH_1):PAGE139
  U9E1    1    S_N M25PE16_SM-IC,H77797-001     I1 @BASEBOARD_FAB2_LIB.BASEBOARD_FAB2(SCH_1):PAGE140

SPI_NIC_CS_R_N @BASEBOARD_FAB2_LIB.BASEBOARD_FAB2(SCH_1):SPI_NIC_CS_R_N
 EU9E1   15 NVM_CS_N SPRINGVILLE_SM1-IC,G47144-004    I72 @BASEBOARD_FAB2_LIB.BASEBOARD_FAB2(SCH_1):PAGE139
  R9E5    1      A RES_0402-33.2,1%,1/16W,CHIP,G2A   I129 @BASEBOARD_FAB2_LIB.BASEBOARD_FAB2(SCH_1):PAGE139

SPI_NIC_MISO @BASEBOARD_FAB2_LIB.BASEBOARD_FAB2(SCH_1):SPI_NIC_MISO
 EU9E1   14 NVM_SO SPRINGVILLE_SM1-IC,G47144-004    I72 @BASEBOARD_FAB2_LIB.BASEBOARD_FAB2(SCH_1):PAGE139
  R9E6    2      B RES_0402-33.2,1%,1/16W,CHIP,G2A    I17 @BASEBOARD_FAB2_LIB.BASEBOARD_FAB2(SCH_1):PAGE140

SPI_NIC_MISO_R @BASEBOARD_FAB2_LIB.BASEBOARD_FAB2(SCH_1):SPI_NIC_MISO_R
  U9E1    2    DQ1 M25PE16_SM-IC,H77797-001     I1 @BASEBOARD_FAB2_LIB.BASEBOARD_FAB2(SCH_1):PAGE140
  R9E6    1      A RES_0402-33.2,1%,1/16W,CHIP,G2A    I17 @BASEBOARD_FAB2_LIB.BASEBOARD_FAB2(SCH_1):PAGE140

SPI_NIC_MOSI @BASEBOARD_FAB2_LIB.BASEBOARD_FAB2(SCH_1):SPI_NIC_MOSI
  R9E9    2      B RES_0402-33.2,1%,1/16W,CHIP,G2A   I128 @BASEBOARD_FAB2_LIB.BASEBOARD_FAB2(SCH_1):PAGE139
  U9E1    5    DQ0 M25PE16_SM-IC,H77797-001     I1 @BASEBOARD_FAB2_LIB.BASEBOARD_FAB2(SCH_1):PAGE140
  R1R7    2      B RES_0402-20.0K,1%,1/16W,CHIP,GA    I12 @BASEBOARD_FAB2_LIB.BASEBOARD_FAB2(SCH_1):PAGE140
  R1R6    1      A RES_0402-3.32K,1%,1/16W,EMPTY,A    I14 @BASEBOARD_FAB2_LIB.BASEBOARD_FAB2(SCH_1):PAGE140

SPI_NIC_MOSI_R @BASEBOARD_FAB2_LIB.BASEBOARD_FAB2(SCH_1):SPI_NIC_MOSI_R
 EU9E1   12 NVM_SI SPRINGVILLE_SM1-IC,G47144-004    I72 @BASEBOARD_FAB2_LIB.BASEBOARD_FAB2(SCH_1):PAGE139
  R9E9    1      A RES_0402-33.2,1%,1/16W,CHIP,G2A   I128 @BASEBOARD_FAB2_LIB.BASEBOARD_FAB2(SCH_1):PAGE139

SPI_NIC_SCLK @BASEBOARD_FAB2_LIB.BASEBOARD_FAB2(SCH_1):SPI_NIC_SCLK
  R9E8    2      B RES_0402-33.2,1%,1/16W,CHIP,G2A   I130 @BASEBOARD_FAB2_LIB.BASEBOARD_FAB2(SCH_1):PAGE139
  U9E1    6      C M25PE16_SM-IC,H77797-001     I1 @BASEBOARD_FAB2_LIB.BASEBOARD_FAB2(SCH_1):PAGE140

SPI_NIC_SCLK_R @BASEBOARD_FAB2_LIB.BASEBOARD_FAB2(SCH_1):SPI_NIC_SCLK_R
 EU9E1   13 NVM_SK SPRINGVILLE_SM1-IC,G47144-004    I72 @BASEBOARD_FAB2_LIB.BASEBOARD_FAB2(SCH_1):PAGE139
  R9E8    1      A RES_0402-33.2,1%,1/16W,CHIP,G2A   I130 @BASEBOARD_FAB2_LIB.BASEBOARD_FAB2(SCH_1):PAGE139

SPI_PCH_CLK @BASEBOARD_FAB2_LIB.BASEBOARD_FAB2(SCH_1):SPI_PCH_CLK
  U7C1   K2 SPI0_CLK LBG_CORE_QAT_EXT_D_BGA1-IC,H91A    I34 @BASEBOARD_FAB2_LIB.BASEBOARD_FAB2(SCH_1):PAGE121
  U8F1    2    IA0 PI3B3257A_TSSOPLF-IC,E16801-001    I74 @BASEBOARD_FAB2_LIB.BASEBOARD_FAB2(SCH_1):PAGE154
  R8E9    1      A RES_0402-33.2,1%,1/16W,CHIP,G2A    I88 @BASEBOARD_FAB2_LIB.BASEBOARD_FAB2(SCH_1):PAGE184

SPI_PCH_CS0_N @BASEBOARD_FAB2_LIB.BASEBOARD_FAB2(SCH_1):SPI_PCH_CS0_N
 R7C16    2      B RES_0402-33.2,1%,1/16W,CHIP,G2A    I33 @BASEBOARD_FAB2_LIB.BASEBOARD_FAB2(SCH_1):PAGE121
  U8F1   11    IC0 PI3B3257A_TSSOPLF-IC,E16801-001    I74 @BASEBOARD_FAB2_LIB.BASEBOARD_FAB2(SCH_1):PAGE154

SPI_PCH_CS0_R_N @BASEBOARD_FAB2_LIB.BASEBOARD_FAB2(SCH_1):SPI_PCH_CS0_R_N
 R7C16    1      A RES_0402-33.2,1%,1/16W,CHIP,G2A    I33 @BASEBOARD_FAB2_LIB.BASEBOARD_FAB2(SCH_1):PAGE121
  U7C1   J3 SPI0_FLASH_CS0_N LBG_CORE_QAT_EXT_D_BGA1-IC,H91A    I34 @BASEBOARD_FAB2_LIB.BASEBOARD_FAB2(SCH_1):PAGE121

SPI_PCH_IO2 @BASEBOARD_FAB2_LIB.BASEBOARD_FAB2(SCH_1):SPI_PCH_IO2
  R2P2    1      A RES_0402-1.00K,1%,1/16W,CHIP,GA    I37 @BASEBOARD_FAB2_LIB.BASEBOARD_FAB2(SCH_1):PAGE111
  U7C1   F5 SPI0_IO2 LBG_CORE_QAT_EXT_D_BGA1-IC,H91A    I34 @BASEBOARD_FAB2_LIB.BASEBOARD_FAB2(SCH_1):PAGE121
 R2R11    1      A RES_0402-1.00K,1%,1/16W,EMPTY,A    I11 @BASEBOARD_FAB2_LIB.BASEBOARD_FAB2(SCH_1):PAGE125
 R2R12    1      A RES_0402-0.0,5%,1/16W,CHIP,G21A    I93 @BASEBOARD_FAB2_LIB.BASEBOARD_FAB2(SCH_1):PAGE154

SPI_PCH_IO2_R1 @BASEBOARD_FAB2_LIB.BASEBOARD_FAB2(SCH_1):SPI_PCH_IO2_R1
  U2T1    2    IA0 PI3B3257A_TSSOPLF-IC,E16801-001    I75 @BASEBOARD_FAB2_LIB.BASEBOARD_FAB2(SCH_1):PAGE154
 R2R12    2      B RES_0402-0.0,5%,1/16W,CHIP,G21A    I93 @BASEBOARD_FAB2_LIB.BASEBOARD_FAB2(SCH_1):PAGE154

SPI_PCH_IO3 @BASEBOARD_FAB2_LIB.BASEBOARD_FAB2(SCH_1):SPI_PCH_IO3
  U7C1   L1 SPI0_IO3 LBG_CORE_QAT_EXT_D_BGA1-IC,H91A    I34 @BASEBOARD_FAB2_LIB.BASEBOARD_FAB2(SCH_1):PAGE121
  R2T1    1      A RES_0402-1.00K,1%,1/16W,CHIP,GA    I15 @BASEBOARD_FAB2_LIB.BASEBOARD_FAB2(SCH_1):PAGE125
 R3N17    2      B RES_0402-1.00K,1%,1/16W,EMPTY,A    I78 @BASEBOARD_FAB2_LIB.BASEBOARD_FAB2(SCH_1):PAGE125
  R2T2    1      A RES_0402-0.0,5%,1/16W,CHIP,G21A    I92 @BASEBOARD_FAB2_LIB.BASEBOARD_FAB2(SCH_1):PAGE154

SPI_PCH_IO3_R1 @BASEBOARD_FAB2_LIB.BASEBOARD_FAB2(SCH_1):SPI_PCH_IO3_R1
  U2T1    5    IB0 PI3B3257A_TSSOPLF-IC,E16801-001    I75 @BASEBOARD_FAB2_LIB.BASEBOARD_FAB2(SCH_1):PAGE154
  R2T2    2      B RES_0402-0.0,5%,1/16W,CHIP,G21A    I92 @BASEBOARD_FAB2_LIB.BASEBOARD_FAB2(SCH_1):PAGE154

SPI_PCH_MISO @BASEBOARD_FAB2_LIB.BASEBOARD_FAB2(SCH_1):SPI_PCH_MISO
  U7C1   L3 SPI0_MISO_IO1 LBG_CORE_QAT_EXT_D_BGA1-IC,H91A    I34 @BASEBOARD_FAB2_LIB.BASEBOARD_FAB2(SCH_1):PAGE121
  R8F6    1      A RES_0402-0.0,5%,1/16W,CHIP,G21A   I119 @BASEBOARD_FAB2_LIB.BASEBOARD_FAB2(SCH_1):PAGE154
 R8E13    1      A RES_0402-33.2,1%,1/16W,CHIP,G2A    I93 @BASEBOARD_FAB2_LIB.BASEBOARD_FAB2(SCH_1):PAGE184

SPI_PCH_MISO_R @BASEBOARD_FAB2_LIB.BASEBOARD_FAB2(SCH_1):SPI_PCH_MISO_R
  U8F1   14    ID0 PI3B3257A_TSSOPLF-IC,E16801-001    I74 @BASEBOARD_FAB2_LIB.BASEBOARD_FAB2(SCH_1):PAGE154
  R8F6    2      B RES_0402-0.0,5%,1/16W,CHIP,G21A   I119 @BASEBOARD_FAB2_LIB.BASEBOARD_FAB2(SCH_1):PAGE154

SPI_PCH_MOSI @BASEBOARD_FAB2_LIB.BASEBOARD_FAB2(SCH_1):SPI_PCH_MOSI
  R8E2    2      B RES_0402-1.00K,1%,1/16W,CHIP,GA    I89 @BASEBOARD_FAB2_LIB.BASEBOARD_FAB2(SCH_1):PAGE111
 R7C15    2      B RES_0402-0.0,5%,1/16W,CHIP,G21A    I31 @BASEBOARD_FAB2_LIB.BASEBOARD_FAB2(SCH_1):PAGE121
  R8E6    2      B RES_0402-1.00K,1%,1/16W,EMPTY,A    I21 @BASEBOARD_FAB2_LIB.BASEBOARD_FAB2(SCH_1):PAGE125
  R8E4    1      A RES_0402-1.00K,1%,1/16W,EMPTY,A    I24 @BASEBOARD_FAB2_LIB.BASEBOARD_FAB2(SCH_1):PAGE125
  U8F1    5    IB0 PI3B3257A_TSSOPLF-IC,E16801-001    I74 @BASEBOARD_FAB2_LIB.BASEBOARD_FAB2(SCH_1):PAGE154
 R8E10    1      A RES_0402-33.2,1%,1/16W,CHIP,G2A    I95 @BASEBOARD_FAB2_LIB.BASEBOARD_FAB2(SCH_1):PAGE184

SPI_PCH_MOSI_R @BASEBOARD_FAB2_LIB.BASEBOARD_FAB2(SCH_1):SPI_PCH_MOSI_R
 R7C15    1      A RES_0402-0.0,5%,1/16W,CHIP,G21A    I31 @BASEBOARD_FAB2_LIB.BASEBOARD_FAB2(SCH_1):PAGE121
  U7C1   H4 SPI0_MOSI_IO0 LBG_CORE_QAT_EXT_D_BGA1-IC,H91A    I34 @BASEBOARD_FAB2_LIB.BASEBOARD_FAB2(SCH_1):PAGE121

SPI_PCH_TPM_CLK_R @BASEBOARD_FAB2_LIB.BASEBOARD_FAB2(SCH_1):SPI_PCH_TPM_CLK_R
  J8E1    1    IO1 SCONN11_H67026001_SM-CONN,H670A    I87 @BASEBOARD_FAB2_LIB.BASEBOARD_FAB2(SCH_1):PAGE184
  R8E9    2      B RES_0402-33.2,1%,1/16W,CHIP,G2A    I88 @BASEBOARD_FAB2_LIB.BASEBOARD_FAB2(SCH_1):PAGE184

SPI_PCH_TPM_CS_N @BASEBOARD_FAB2_LIB.BASEBOARD_FAB2(SCH_1):SPI_PCH_TPM_CS_N
  U7C1   K4 SPI0_TPM_CS_N LBG_CORE_QAT_EXT_D_BGA1-IC,H91A    I34 @BASEBOARD_FAB2_LIB.BASEBOARD_FAB2(SCH_1):PAGE121
 R8D35    1      A RES_0402-0.0,5%,1/16W,CHIP,G21A    I92 @BASEBOARD_FAB2_LIB.BASEBOARD_FAB2(SCH_1):PAGE184

SPI_PCH_TPM_CS_R_N @BASEBOARD_FAB2_LIB.BASEBOARD_FAB2(SCH_1):SPI_PCH_TPM_CS_R_N
  J8E1    5    IO5 SCONN11_H67026001_SM-CONN,H670A    I87 @BASEBOARD_FAB2_LIB.BASEBOARD_FAB2(SCH_1):PAGE184
 R8D35    2      B RES_0402-0.0,5%,1/16W,CHIP,G21A    I92 @BASEBOARD_FAB2_LIB.BASEBOARD_FAB2(SCH_1):PAGE184

SPI_PCH_TPM_MISO_R @BASEBOARD_FAB2_LIB.BASEBOARD_FAB2(SCH_1):SPI_PCH_TPM_MISO_R
  J8E1    4    IO4 SCONN11_H67026001_SM-CONN,H670A    I87 @BASEBOARD_FAB2_LIB.BASEBOARD_FAB2(SCH_1):PAGE184
 R8E13    2      B RES_0402-33.2,1%,1/16W,CHIP,G2A    I93 @BASEBOARD_FAB2_LIB.BASEBOARD_FAB2(SCH_1):PAGE184

SPI_PCH_TPM_MOSI_R @BASEBOARD_FAB2_LIB.BASEBOARD_FAB2(SCH_1):SPI_PCH_TPM_MOSI_R
  J8E1    3    IO3 SCONN11_H67026001_SM-CONN,H670A    I87 @BASEBOARD_FAB2_LIB.BASEBOARD_FAB2(SCH_1):PAGE184
 R8E10    2      B RES_0402-33.2,1%,1/16W,CHIP,G2A    I95 @BASEBOARD_FAB2_LIB.BASEBOARD_FAB2(SCH_1):PAGE184

SPI_SWITCH_CLK @BASEBOARD_FAB2_LIB.BASEBOARD_FAB2(SCH_1):SPI_SWITCH_CLK
  R8F8    1      A RES_0402-33.2,1%,1/16W,CHIP,G2A   I166 @BASEBOARD_FAB2_LIB.BASEBOARD_FAB2(SCH_1):PAGE153
  R8F7    1      A RES_0402-33.2,1%,1/16W,CHIP,G2A   I167 @BASEBOARD_FAB2_LIB.BASEBOARD_FAB2(SCH_1):PAGE153
  U8F1    4     YA PI3B3257A_TSSOPLF-IC,E16801-001    I74 @BASEBOARD_FAB2_LIB.BASEBOARD_FAB2(SCH_1):PAGE154

SPI_SWITCH_CS0_N @BASEBOARD_FAB2_LIB.BASEBOARD_FAB2(SCH_1):SPI_SWITCH_CS0_N
  U8F1    9     YC PI3B3257A_TSSOPLF-IC,E16801-001    I74 @BASEBOARD_FAB2_LIB.BASEBOARD_FAB2(SCH_1):PAGE154
  U2T3    2      B TTL1G32_A_SOT-74LVC1G32,IC,E60B    I99 @BASEBOARD_FAB2_LIB.BASEBOARD_FAB2(SCH_1):PAGE154
  U2T2    2      B TTL1G32_A_SOT-74LVC1G32,IC,E60B   I100 @BASEBOARD_FAB2_LIB.BASEBOARD_FAB2(SCH_1):PAGE154
  R2T8    2      B RES_0402-10.0K,1%,1/16W,CHIP,GA   I106 @BASEBOARD_FAB2_LIB.BASEBOARD_FAB2(SCH_1):PAGE154

SPI_SWITCH_MISO @BASEBOARD_FAB2_LIB.BASEBOARD_FAB2(SCH_1):SPI_SWITCH_MISO
  R7F4    1      A RES_0402-33.2,1%,1/16W,CHIP,G2A    I98 @BASEBOARD_FAB2_LIB.BASEBOARD_FAB2(SCH_1):PAGE153
  R3T2    1      A RES_0402-33.2,1%,1/16W,CHIP,G2A   I155 @BASEBOARD_FAB2_LIB.BASEBOARD_FAB2(SCH_1):PAGE153
  U8F1   12     YD PI3B3257A_TSSOPLF-IC,E16801-001    I74 @BASEBOARD_FAB2_LIB.BASEBOARD_FAB2(SCH_1):PAGE154

SPI_SWITCH_MOSI @BASEBOARD_FAB2_LIB.BASEBOARD_FAB2(SCH_1):SPI_SWITCH_MOSI
 R7F29    1      A RES_0402-33.2,1%,1/16W,CHIP,G2A   I181 @BASEBOARD_FAB2_LIB.BASEBOARD_FAB2(SCH_1):PAGE153
 R3T10    1      A RES_0402-33.2,1%,1/16W,CHIP,G2A   I184 @BASEBOARD_FAB2_LIB.BASEBOARD_FAB2(SCH_1):PAGE153
  U8F1    7     YB PI3B3257A_TSSOPLF-IC,E16801-001    I74 @BASEBOARD_FAB2_LIB.BASEBOARD_FAB2(SCH_1):PAGE154

SPI_SWITCH_MOSI_R0 @BASEBOARD_FAB2_LIB.BASEBOARD_FAB2(SCH_1):SPI_SWITCH_MOSI_R0
  U7F1   15 DI_IO<0> W25Q256_XSOI-IC,H25002-001   I146 @BASEBOARD_FAB2_LIB.BASEBOARD_FAB2(SCH_1):PAGE153
 R7F29    2      B RES_0402-33.2,1%,1/16W,CHIP,G2A   I181 @BASEBOARD_FAB2_LIB.BASEBOARD_FAB2(SCH_1):PAGE153

SPI_SWITCH_MOSI_R1 @BASEBOARD_FAB2_LIB.BASEBOARD_FAB2(SCH_1):SPI_SWITCH_MOSI_R1
  U3T1   15 DI_IO<0> W25Q256_XSOI-IC,H25002-001   I165 @BASEBOARD_FAB2_LIB.BASEBOARD_FAB2(SCH_1):PAGE153
 R3T10    2      B RES_0402-33.2,1%,1/16W,CHIP,G2A   I184 @BASEBOARD_FAB2_LIB.BASEBOARD_FAB2(SCH_1):PAGE153

SPI_TPM_BMC_DI_R_ @BASEBOARD_FAB2_LIB.BASEBOARD_FAB2(SCH_1):SPI_TPM_BMC_DI_R_
 RN8F5    2      B RES_0402-33.2,1%,1/16W,CHIP,G2A     I9 @BASEBOARD_FAB2_LIB.BASEBOARD_FAB2(SCH_1):PAGE246
 UN8F2    8 DO_IO<1> W25Q256_XSOI-IC,H25002-001    I17 @BASEBOARD_FAB2_LIB.BASEBOARD_FAB2(SCH_1):PAGE246

SVID_ALERT0_CPU0_N @BASEBOARD_FAB2_LIB.BASEBOARD_FAB2(SCH_1):SVID_ALERT0_CPU0_N
 R6N10    1      A RES_0402-221,1.0%,1/16W,CHIP,GA   I149 @BASEBOARD_FAB2_LIB.BASEBOARD_FAB2(SCH_1):PAGE21
  U5D1 DE44 SVIDALERT_N<0> SKX_EXT_B_BGA1-IC,TBD   I259 @BASEBOARD_FAB2_LIB.BASEBOARD_FAB2(SCH_1):PAGE21

SVID_ALERT0_CPU0_R_N @BASEBOARD_FAB2_LIB.BASEBOARD_FAB2(SCH_1):SVID_ALERT0_CPU0_R_N
 R6N10    2      B RES_0402-221,1.0%,1/16W,CHIP,GA   I149 @BASEBOARD_FAB2_LIB.BASEBOARD_FAB2(SCH_1):PAGE21
  R6N1    1      A RES_0402-49.9,1%,1/16W,CHIP,G2A   I164 @BASEBOARD_FAB2_LIB.BASEBOARD_FAB2(SCH_1):PAGE21
  J6B1  A19  IOA19 SCONN120_H61426002_SM-CONN,H61A    I56 @BASEBOARD_FAB2_LIB.BASEBOARD_FAB2(SCH_1):PAGE194
 R4D67    2      B RES_0402-0.0,5%,1/16W,CHIP,G21A    I26 @BASEBOARD_FAB2_LIB.BASEBOARD_FAB2(SCH_1):PAGE201
  R3P1    2      B RES_0402-0.0,5%,1/16W,CHIP,G21A    I61 @BASEBOARD_FAB2_LIB.BASEBOARD_FAB2(SCH_1):PAGE211

SVID_ALERT0_CPU1_N @BASEBOARD_FAB2_LIB.BASEBOARD_FAB2(SCH_1):SVID_ALERT0_CPU1_N
  R3B1    1      A RES_0402-221,1.0%,1/16W,CHIP,GA    I27 @BASEBOARD_FAB2_LIB.BASEBOARD_FAB2(SCH_1):PAGE55
  U2D1 DE44 SVIDALERT_N<0> SKX_EXT_B_BGA1-IC,TBD   I172 @BASEBOARD_FAB2_LIB.BASEBOARD_FAB2(SCH_1):PAGE55

SVID_ALERT0_CPU1_R_N @BASEBOARD_FAB2_LIB.BASEBOARD_FAB2(SCH_1):SVID_ALERT0_CPU1_R_N
  R3B2    1      A RES_0402-49.9,1%,1/16W,CHIP,G2A    I19 @BASEBOARD_FAB2_LIB.BASEBOARD_FAB2(SCH_1):PAGE55
  R3B1    2      B RES_0402-221,1.0%,1/16W,CHIP,GA    I27 @BASEBOARD_FAB2_LIB.BASEBOARD_FAB2(SCH_1):PAGE55
  J4B2  A19  IOA19 SCONN120_H61426002_SM-CONN,H61A    I46 @BASEBOARD_FAB2_LIB.BASEBOARD_FAB2(SCH_1):PAGE193
  R1D3    2      B RES_0402-0.0,5%,1/16W,CHIP,G21A    I37 @BASEBOARD_FAB2_LIB.BASEBOARD_FAB2(SCH_1):PAGE206
 R4D56    2      B RES_0402-0.0,5%,1/16W,CHIP,G21A    I16 @BASEBOARD_FAB2_LIB.BASEBOARD_FAB2(SCH_1):PAGE213

SVID_ALERT1_CPU0_N @BASEBOARD_FAB2_LIB.BASEBOARD_FAB2(SCH_1):SVID_ALERT1_CPU0_N
  R6B3    1      A RES_0402-221,1.0%,1/16W,CHIP,GA   I152 @BASEBOARD_FAB2_LIB.BASEBOARD_FAB2(SCH_1):PAGE21
  U5D1 DL44 SVIDALERT_N<1> SKX_EXT_B_BGA1-IC,TBD   I259 @BASEBOARD_FAB2_LIB.BASEBOARD_FAB2(SCH_1):PAGE21

SVID_ALERT1_CPU0_R_N @BASEBOARD_FAB2_LIB.BASEBOARD_FAB2(SCH_1):SVID_ALERT1_CPU0_R_N
  R6B3    2      B RES_0402-221,1.0%,1/16W,CHIP,GA   I152 @BASEBOARD_FAB2_LIB.BASEBOARD_FAB2(SCH_1):PAGE21
  R6B1    2      B RES_0402-49.9,1%,1/16W,CHIP,G2A   I161 @BASEBOARD_FAB2_LIB.BASEBOARD_FAB2(SCH_1):PAGE21
  J6B1  B19  IOB19 SCONN120_H61426002_SM-CONN,H61A    I56 @BASEBOARD_FAB2_LIB.BASEBOARD_FAB2(SCH_1):PAGE194
  R7G4    2      B RES_0402-0.0,5%,1/16W,CHIP,G21A   I302 @BASEBOARD_FAB2_LIB.BASEBOARD_FAB2(SCH_1):PAGE215
 R7A11    2      B RES_0402-0.0,5%,1/16W,CHIP,G21A    I15 @BASEBOARD_FAB2_LIB.BASEBOARD_FAB2(SCH_1):PAGE218

SVID_ALERT1_CPU1_N @BASEBOARD_FAB2_LIB.BASEBOARD_FAB2(SCH_1):SVID_ALERT1_CPU1_N
  R1C1    1      A RES_0402-221,1.0%,1/16W,CHIP,GA    I26 @BASEBOARD_FAB2_LIB.BASEBOARD_FAB2(SCH_1):PAGE55
  U2D1 DL44 SVIDALERT_N<1> SKX_EXT_B_BGA1-IC,TBD   I172 @BASEBOARD_FAB2_LIB.BASEBOARD_FAB2(SCH_1):PAGE55

SVID_ALERT1_CPU1_R_N @BASEBOARD_FAB2_LIB.BASEBOARD_FAB2(SCH_1):SVID_ALERT1_CPU1_R_N
  R9N1    2      B RES_0402-49.9,1%,1/16W,CHIP,G2A     I4 @BASEBOARD_FAB2_LIB.BASEBOARD_FAB2(SCH_1):PAGE55
  R1C1    2      B RES_0402-221,1.0%,1/16W,CHIP,GA    I26 @BASEBOARD_FAB2_LIB.BASEBOARD_FAB2(SCH_1):PAGE55
  J4B2  B19  IOB19 SCONN120_H61426002_SM-CONN,H61A    I46 @BASEBOARD_FAB2_LIB.BASEBOARD_FAB2(SCH_1):PAGE193
  R1G9    2      B RES_0402-0.0,5%,1/16W,CHIP,G21A    I16 @BASEBOARD_FAB2_LIB.BASEBOARD_FAB2(SCH_1):PAGE223
 R1B11    2      B RES_0402-0.0,5%,1/16W,CHIP,G21A    I16 @BASEBOARD_FAB2_LIB.BASEBOARD_FAB2(SCH_1):PAGE226

SVID_ALERT_PVCCIO_CPU0 @BASEBOARD_FAB2_LIB.BASEBOARD_FAB2(SCH_1):SVID_ALERT_PVCCIO_CPU0
  R3P1    1      A RES_0402-0.0,5%,1/16W,CHIP,G21A    I61 @BASEBOARD_FAB2_LIB.BASEBOARD_FAB2(SCH_1):PAGE211
 EU3P1   17 VALRT_N PXE1110B_QFN-IC,H89187-001    I93 @BASEBOARD_FAB2_LIB.BASEBOARD_FAB2(SCH_1):PAGE211

SVID_ALERT_PVCCIO_CPU1 @BASEBOARD_FAB2_LIB.BASEBOARD_FAB2(SCH_1):SVID_ALERT_PVCCIO_CPU1
 R4D56    1      A RES_0402-0.0,5%,1/16W,CHIP,G21A    I16 @BASEBOARD_FAB2_LIB.BASEBOARD_FAB2(SCH_1):PAGE213
 EU4D5   17 VALRT_N PXE1110B_QFN-IC,H89187-001    I96 @BASEBOARD_FAB2_LIB.BASEBOARD_FAB2(SCH_1):PAGE213

SVID_ALERT_PVDDQ_ABC @BASEBOARD_FAB2_LIB.BASEBOARD_FAB2(SCH_1):SVID_ALERT_PVDDQ_ABC
  R7G4    1      A RES_0402-0.0,5%,1/16W,CHIP,G21A   I302 @BASEBOARD_FAB2_LIB.BASEBOARD_FAB2(SCH_1):PAGE215
 EU7G1   17 VALRT_N PXM1310B_QFN-IC,H89186-001   I358 @BASEBOARD_FAB2_LIB.BASEBOARD_FAB2(SCH_1):PAGE215

SVID_ALERT_PVDDQ_DEF @BASEBOARD_FAB2_LIB.BASEBOARD_FAB2(SCH_1):SVID_ALERT_PVDDQ_DEF
 R7A11    1      A RES_0402-0.0,5%,1/16W,CHIP,G21A    I15 @BASEBOARD_FAB2_LIB.BASEBOARD_FAB2(SCH_1):PAGE218
 EU7A5   17 VALRT_N PXM1310B_QFN-IC,H89186-001    I75 @BASEBOARD_FAB2_LIB.BASEBOARD_FAB2(SCH_1):PAGE218

SVID_ALERT_PVDDQ_GHJ @BASEBOARD_FAB2_LIB.BASEBOARD_FAB2(SCH_1):SVID_ALERT_PVDDQ_GHJ
  R1G9    1      A RES_0402-0.0,5%,1/16W,CHIP,G21A    I16 @BASEBOARD_FAB2_LIB.BASEBOARD_FAB2(SCH_1):PAGE223
 EU1G2   17 VALRT_N PXM1310B_QFN-IC,H89186-001    I90 @BASEBOARD_FAB2_LIB.BASEBOARD_FAB2(SCH_1):PAGE223

SVID_ALERT_PVDDQ_KLM @BASEBOARD_FAB2_LIB.BASEBOARD_FAB2(SCH_1):SVID_ALERT_PVDDQ_KLM
 R1B11    1      A RES_0402-0.0,5%,1/16W,CHIP,G21A    I16 @BASEBOARD_FAB2_LIB.BASEBOARD_FAB2(SCH_1):PAGE226
 EU1B1   17 VALRT_N PXM1310B_QFN-IC,H89186-001    I90 @BASEBOARD_FAB2_LIB.BASEBOARD_FAB2(SCH_1):PAGE226

SVID_CLK0_CPU0 @BASEBOARD_FAB2_LIB.BASEBOARD_FAB2(SCH_1):SVID_CLK0_CPU0
 R6N12    1      A RES_0402-0.0,5%,1/16W,CHIP,G21A   I150 @BASEBOARD_FAB2_LIB.BASEBOARD_FAB2(SCH_1):PAGE21
  U5D1 DC44 SVIDCLK<0> SKX_EXT_B_BGA1-IC,TBD   I259 @BASEBOARD_FAB2_LIB.BASEBOARD_FAB2(SCH_1):PAGE21

SVID_CLK0_CPU0_R @BASEBOARD_FAB2_LIB.BASEBOARD_FAB2(SCH_1):SVID_CLK0_CPU0_R
 R6N12    2      B RES_0402-0.0,5%,1/16W,CHIP,G21A   I150 @BASEBOARD_FAB2_LIB.BASEBOARD_FAB2(SCH_1):PAGE21
  J6B1  A20  IOA20 SCONN120_H61426002_SM-CONN,H61A    I56 @BASEBOARD_FAB2_LIB.BASEBOARD_FAB2(SCH_1):PAGE194
  R4E9    2      B RES_0402-49.9,1%,1/16W,CHIP,G2A    I52 @BASEBOARD_FAB2_LIB.BASEBOARD_FAB2(SCH_1):PAGE201
  R4E6    1      A RES_0402-150.0,1%,1/16W,CHIP,GA    I56 @BASEBOARD_FAB2_LIB.BASEBOARD_FAB2(SCH_1):PAGE201
 R3P17    2      B RES_0402-49.9,1%,1/16W,EMPTY,GA    I28 @BASEBOARD_FAB2_LIB.BASEBOARD_FAB2(SCH_1):PAGE211
 R3P15    1      A RES_0402-150.0,1%,1/16W,CHIP,GA    I29 @BASEBOARD_FAB2_LIB.BASEBOARD_FAB2(SCH_1):PAGE211

SVID_CLK0_CPU1 @BASEBOARD_FAB2_LIB.BASEBOARD_FAB2(SCH_1):SVID_CLK0_CPU1
  R3B5    1      A RES_0402-0.0,5%,1/16W,CHIP,G21A    I28 @BASEBOARD_FAB2_LIB.BASEBOARD_FAB2(SCH_1):PAGE55
  U2D1 DC44 SVIDCLK<0> SKX_EXT_B_BGA1-IC,TBD   I172 @BASEBOARD_FAB2_LIB.BASEBOARD_FAB2(SCH_1):PAGE55

SVID_CLK0_CPU1_R @BASEBOARD_FAB2_LIB.BASEBOARD_FAB2(SCH_1):SVID_CLK0_CPU1_R
  R3B5    2      B RES_0402-0.0,5%,1/16W,CHIP,G21A    I28 @BASEBOARD_FAB2_LIB.BASEBOARD_FAB2(SCH_1):PAGE55
  J4B2  A20  IOA20 SCONN120_H61426002_SM-CONN,H61A    I46 @BASEBOARD_FAB2_LIB.BASEBOARD_FAB2(SCH_1):PAGE193
  R9P2    2      B RES_0402-49.9,1%,1/16W,CHIP,G2A    I53 @BASEBOARD_FAB2_LIB.BASEBOARD_FAB2(SCH_1):PAGE206
  R1D9    1      A RES_0402-150.0,1%,1/16W,CHIP,GA    I54 @BASEBOARD_FAB2_LIB.BASEBOARD_FAB2(SCH_1):PAGE206
 R6P33    2      B RES_0402-110,1%,1/16W,EMPTY,G2A    I30 @BASEBOARD_FAB2_LIB.BASEBOARD_FAB2(SCH_1):PAGE213
 R4D51    1      A RES_0402-150.0,1%,1/16W,CHIP,GA    I46 @BASEBOARD_FAB2_LIB.BASEBOARD_FAB2(SCH_1):PAGE213

SVID_CLK1_CPU0 @BASEBOARD_FAB2_LIB.BASEBOARD_FAB2(SCH_1):SVID_CLK1_CPU0
  R6B5    1      A RES_0402-0.0,5%,1/16W,CHIP,G21A   I153 @BASEBOARD_FAB2_LIB.BASEBOARD_FAB2(SCH_1):PAGE21
  U5D1 DG44 SVIDCLK<1> SKX_EXT_B_BGA1-IC,TBD   I259 @BASEBOARD_FAB2_LIB.BASEBOARD_FAB2(SCH_1):PAGE21

SVID_CLK1_CPU0_R @BASEBOARD_FAB2_LIB.BASEBOARD_FAB2(SCH_1):SVID_CLK1_CPU0_R
  R6B5    2      B RES_0402-0.0,5%,1/16W,CHIP,G21A   I153 @BASEBOARD_FAB2_LIB.BASEBOARD_FAB2(SCH_1):PAGE21
  J6B1  E20  IOE20 SCONN120_H61426002_SM-CONN,H61A    I56 @BASEBOARD_FAB2_LIB.BASEBOARD_FAB2(SCH_1):PAGE194
 R3T11    2      B RES_0402-49.9,1%,1/16W,EMPTY,GA   I330 @BASEBOARD_FAB2_LIB.BASEBOARD_FAB2(SCH_1):PAGE215
 R7G24    1      A RES_0402-150.0,1%,1/16W,CHIP,GA   I331 @BASEBOARD_FAB2_LIB.BASEBOARD_FAB2(SCH_1):PAGE215
 R3L13    2      B RES_0402-49.9,1%,1/16W,CHIP,G2A    I47 @BASEBOARD_FAB2_LIB.BASEBOARD_FAB2(SCH_1):PAGE218
 R7A17    1      A RES_0402-150.0,1%,1/16W,CHIP,GA    I48 @BASEBOARD_FAB2_LIB.BASEBOARD_FAB2(SCH_1):PAGE218

SVID_CLK1_CPU1 @BASEBOARD_FAB2_LIB.BASEBOARD_FAB2(SCH_1):SVID_CLK1_CPU1
  R1C3    1      A RES_0402-0.0,5%,1/16W,CHIP,G21A    I25 @BASEBOARD_FAB2_LIB.BASEBOARD_FAB2(SCH_1):PAGE55
  U2D1 DG44 SVIDCLK<1> SKX_EXT_B_BGA1-IC,TBD   I172 @BASEBOARD_FAB2_LIB.BASEBOARD_FAB2(SCH_1):PAGE55

SVID_CLK1_CPU1_R @BASEBOARD_FAB2_LIB.BASEBOARD_FAB2(SCH_1):SVID_CLK1_CPU1_R
  R1C3    2      B RES_0402-0.0,5%,1/16W,CHIP,G21A    I25 @BASEBOARD_FAB2_LIB.BASEBOARD_FAB2(SCH_1):PAGE55
  J4B2  E20  IOE20 SCONN120_H61426002_SM-CONN,H61A    I46 @BASEBOARD_FAB2_LIB.BASEBOARD_FAB2(SCH_1):PAGE193
  R9U4    2      B RES_0402-49.9,1%,1/16W,EMPTY,GA    I50 @BASEBOARD_FAB2_LIB.BASEBOARD_FAB2(SCH_1):PAGE223
  R1G7    1      A RES_0402-150.0,1%,1/16W,CHIP,GA    I53 @BASEBOARD_FAB2_LIB.BASEBOARD_FAB2(SCH_1):PAGE223
  R9M6    2      B RES_0402-49.9,1%,1/16W,CHIP,G2A    I50 @BASEBOARD_FAB2_LIB.BASEBOARD_FAB2(SCH_1):PAGE226
  R1B8    1      A RES_0402-150.0,1%,1/16W,CHIP,GA    I53 @BASEBOARD_FAB2_LIB.BASEBOARD_FAB2(SCH_1):PAGE226

SVID_CLK_PVCCIO_CPU0 @BASEBOARD_FAB2_LIB.BASEBOARD_FAB2(SCH_1):SVID_CLK_PVCCIO_CPU0
 R3P15    2      B RES_0402-150.0,1%,1/16W,CHIP,GA    I29 @BASEBOARD_FAB2_LIB.BASEBOARD_FAB2(SCH_1):PAGE211
 EU3P1   15   VCLK PXE1110B_QFN-IC,H89187-001    I93 @BASEBOARD_FAB2_LIB.BASEBOARD_FAB2(SCH_1):PAGE211

SVID_CLK_PVCCIO_CPU1 @BASEBOARD_FAB2_LIB.BASEBOARD_FAB2(SCH_1):SVID_CLK_PVCCIO_CPU1
 R4D51    2      B RES_0402-150.0,1%,1/16W,CHIP,GA    I46 @BASEBOARD_FAB2_LIB.BASEBOARD_FAB2(SCH_1):PAGE213
 EU4D5   15   VCLK PXE1110B_QFN-IC,H89187-001    I96 @BASEBOARD_FAB2_LIB.BASEBOARD_FAB2(SCH_1):PAGE213

SVID_CLK_PVDDQ_ABC @BASEBOARD_FAB2_LIB.BASEBOARD_FAB2(SCH_1):SVID_CLK_PVDDQ_ABC
 R7G24    2      B RES_0402-150.0,1%,1/16W,CHIP,GA   I331 @BASEBOARD_FAB2_LIB.BASEBOARD_FAB2(SCH_1):PAGE215
 EU7G1   15   VCLK PXM1310B_QFN-IC,H89186-001   I358 @BASEBOARD_FAB2_LIB.BASEBOARD_FAB2(SCH_1):PAGE215

SVID_CLK_PVDDQ_DEF @BASEBOARD_FAB2_LIB.BASEBOARD_FAB2(SCH_1):SVID_CLK_PVDDQ_DEF
 R7A17    2      B RES_0402-150.0,1%,1/16W,CHIP,GA    I48 @BASEBOARD_FAB2_LIB.BASEBOARD_FAB2(SCH_1):PAGE218
 EU7A5   15   VCLK PXM1310B_QFN-IC,H89186-001    I75 @BASEBOARD_FAB2_LIB.BASEBOARD_FAB2(SCH_1):PAGE218

SVID_CLK_PVDDQ_GHJ @BASEBOARD_FAB2_LIB.BASEBOARD_FAB2(SCH_1):SVID_CLK_PVDDQ_GHJ
  R1G7    2      B RES_0402-150.0,1%,1/16W,CHIP,GA    I53 @BASEBOARD_FAB2_LIB.BASEBOARD_FAB2(SCH_1):PAGE223
 EU1G2   15   VCLK PXM1310B_QFN-IC,H89186-001    I90 @BASEBOARD_FAB2_LIB.BASEBOARD_FAB2(SCH_1):PAGE223

SVID_CLK_PVDDQ_KLM @BASEBOARD_FAB2_LIB.BASEBOARD_FAB2(SCH_1):SVID_CLK_PVDDQ_KLM
  R1B8    2      B RES_0402-150.0,1%,1/16W,CHIP,GA    I53 @BASEBOARD_FAB2_LIB.BASEBOARD_FAB2(SCH_1):PAGE226
 EU1B1   15   VCLK PXM1310B_QFN-IC,H89186-001    I90 @BASEBOARD_FAB2_LIB.BASEBOARD_FAB2(SCH_1):PAGE226

SVID_DIO0_CPU0 @BASEBOARD_FAB2_LIB.BASEBOARD_FAB2(SCH_1):SVID_DIO0_CPU0
 R6N11    1      A RES_0402-0.0,5%,1/16W,CHIP,G21A   I151 @BASEBOARD_FAB2_LIB.BASEBOARD_FAB2(SCH_1):PAGE21
  U5D1 DB45 SVIDDATA<0> SKX_EXT_B_BGA1-IC,TBD   I259 @BASEBOARD_FAB2_LIB.BASEBOARD_FAB2(SCH_1):PAGE21

SVID_DIO0_CPU0_R @BASEBOARD_FAB2_LIB.BASEBOARD_FAB2(SCH_1):SVID_DIO0_CPU0_R
 R6N11    2      B RES_0402-0.0,5%,1/16W,CHIP,G21A   I151 @BASEBOARD_FAB2_LIB.BASEBOARD_FAB2(SCH_1):PAGE21
  R6N2    1      A RES_0402-100.0,1%,1/16W,CHIP,GA   I163 @BASEBOARD_FAB2_LIB.BASEBOARD_FAB2(SCH_1):PAGE21
  J6B1  B20  IOB20 SCONN120_H61426002_SM-CONN,H61A    I56 @BASEBOARD_FAB2_LIB.BASEBOARD_FAB2(SCH_1):PAGE194
 R4E10    2      B RES_0402-100.0,1%,1/16W,CHIP,GA    I20 @BASEBOARD_FAB2_LIB.BASEBOARD_FAB2(SCH_1):PAGE201
 R4D66    2      B RES_0402-0.0,5%,1/16W,CHIP,G21A    I98 @BASEBOARD_FAB2_LIB.BASEBOARD_FAB2(SCH_1):PAGE201
 R3P11    1      A RES_0402-0.0,5%,1/16W,CHIP,G21A    I16 @BASEBOARD_FAB2_LIB.BASEBOARD_FAB2(SCH_1):PAGE211
 R3P13    2      B RES_0402-100.0,1%,1/16W,EMPTY,A    I17 @BASEBOARD_FAB2_LIB.BASEBOARD_FAB2(SCH_1):PAGE211

SVID_DIO0_CPU1 @BASEBOARD_FAB2_LIB.BASEBOARD_FAB2(SCH_1):SVID_DIO0_CPU1
  R3B3    1      A RES_0402-0.0,5%,1/16W,CHIP,G21A    I29 @BASEBOARD_FAB2_LIB.BASEBOARD_FAB2(SCH_1):PAGE55
  U2D1 DB45 SVIDDATA<0> SKX_EXT_B_BGA1-IC,TBD   I172 @BASEBOARD_FAB2_LIB.BASEBOARD_FAB2(SCH_1):PAGE55

SVID_DIO0_CPU1_R @BASEBOARD_FAB2_LIB.BASEBOARD_FAB2(SCH_1):SVID_DIO0_CPU1_R
  R3B4    1      A RES_0402-100.0,1%,1/16W,CHIP,GA    I21 @BASEBOARD_FAB2_LIB.BASEBOARD_FAB2(SCH_1):PAGE55
  R3B3    2      B RES_0402-0.0,5%,1/16W,CHIP,G21A    I29 @BASEBOARD_FAB2_LIB.BASEBOARD_FAB2(SCH_1):PAGE55
  J4B2  B20  IOB20 SCONN120_H61426002_SM-CONN,H61A    I46 @BASEBOARD_FAB2_LIB.BASEBOARD_FAB2(SCH_1):PAGE193
  R9P1    2      B RES_0402-100.0,1%,1/16W,CHIP,GA     I4 @BASEBOARD_FAB2_LIB.BASEBOARD_FAB2(SCH_1):PAGE206
  R1D2    2      B RES_0402-0.0,5%,1/16W,CHIP,G21A    I38 @BASEBOARD_FAB2_LIB.BASEBOARD_FAB2(SCH_1):PAGE206
 R6P35    2      B RES_0402-100.0,1%,1/16W,EMPTY,A    I27 @BASEBOARD_FAB2_LIB.BASEBOARD_FAB2(SCH_1):PAGE213
 R4D54    1      A RES_0402-0.0,5%,1/16W,CHIP,G21A    I37 @BASEBOARD_FAB2_LIB.BASEBOARD_FAB2(SCH_1):PAGE213

SVID_DIO1_CPU0 @BASEBOARD_FAB2_LIB.BASEBOARD_FAB2(SCH_1):SVID_DIO1_CPU0
  R6B4    1      A RES_0402-0.0,5%,1/16W,CHIP,G21A   I154 @BASEBOARD_FAB2_LIB.BASEBOARD_FAB2(SCH_1):PAGE21
  U5D1 DJ44 SVIDDATA<1> SKX_EXT_B_BGA1-IC,TBD   I259 @BASEBOARD_FAB2_LIB.BASEBOARD_FAB2(SCH_1):PAGE21

SVID_DIO1_CPU0_R @BASEBOARD_FAB2_LIB.BASEBOARD_FAB2(SCH_1):SVID_DIO1_CPU0_R
  R6B4    2      B RES_0402-0.0,5%,1/16W,CHIP,G21A   I154 @BASEBOARD_FAB2_LIB.BASEBOARD_FAB2(SCH_1):PAGE21
  R6B2    2      B RES_0402-100.0,1%,1/16W,CHIP,GA   I159 @BASEBOARD_FAB2_LIB.BASEBOARD_FAB2(SCH_1):PAGE21
  J6B1  F20  IOF20 SCONN120_H61426002_SM-CONN,H61A    I56 @BASEBOARD_FAB2_LIB.BASEBOARD_FAB2(SCH_1):PAGE194
  R3U2    2      B RES_0402-100.0,1%,1/16W,CHIP,GA   I295 @BASEBOARD_FAB2_LIB.BASEBOARD_FAB2(SCH_1):PAGE215
  R7G2    2      B RES_0402-0.0,5%,1/16W,CHIP,G21A   I307 @BASEBOARD_FAB2_LIB.BASEBOARD_FAB2(SCH_1):PAGE215
 R3L11    2      B RES_0402-100.0,1%,1/16W,EMPTY,A     I7 @BASEBOARD_FAB2_LIB.BASEBOARD_FAB2(SCH_1):PAGE218
 R7A12    2      B RES_0402-0.0,5%,1/16W,CHIP,G21A    I25 @BASEBOARD_FAB2_LIB.BASEBOARD_FAB2(SCH_1):PAGE218

SVID_DIO1_CPU1 @BASEBOARD_FAB2_LIB.BASEBOARD_FAB2(SCH_1):SVID_DIO1_CPU1
  R1C2    1      A RES_0402-0.0,5%,1/16W,CHIP,G21A    I24 @BASEBOARD_FAB2_LIB.BASEBOARD_FAB2(SCH_1):PAGE55
  U2D1 DJ44 SVIDDATA<1> SKX_EXT_B_BGA1-IC,TBD   I172 @BASEBOARD_FAB2_LIB.BASEBOARD_FAB2(SCH_1):PAGE55

SVID_DIO1_CPU1_R @BASEBOARD_FAB2_LIB.BASEBOARD_FAB2(SCH_1):SVID_DIO1_CPU1_R
  R9N2    2      B RES_0402-100.0,1%,1/16W,CHIP,GA     I7 @BASEBOARD_FAB2_LIB.BASEBOARD_FAB2(SCH_1):PAGE55
  R1C2    2      B RES_0402-0.0,5%,1/16W,CHIP,G21A    I24 @BASEBOARD_FAB2_LIB.BASEBOARD_FAB2(SCH_1):PAGE55
  J4B2  F20  IOF20 SCONN120_H61426002_SM-CONN,H61A    I46 @BASEBOARD_FAB2_LIB.BASEBOARD_FAB2(SCH_1):PAGE193
  R9U3    2      B RES_0402-100.0,1%,1/16W,CHIP,GA     I8 @BASEBOARD_FAB2_LIB.BASEBOARD_FAB2(SCH_1):PAGE223
 R1G10    2      B RES_0402-0.0,5%,1/16W,CHIP,G21A    I23 @BASEBOARD_FAB2_LIB.BASEBOARD_FAB2(SCH_1):PAGE223
  R9M7    2      B RES_0402-100.0,1%,1/16W,EMPTY,A     I8 @BASEBOARD_FAB2_LIB.BASEBOARD_FAB2(SCH_1):PAGE226
 R1B10    2      B RES_0402-0.0,5%,1/16W,CHIP,G21A    I23 @BASEBOARD_FAB2_LIB.BASEBOARD_FAB2(SCH_1):PAGE226

SVID_VALERT_VCCIN_CPU0 @BASEBOARD_FAB2_LIB.BASEBOARD_FAB2(SCH_1):SVID_VALERT_VCCIN_CPU0
 R4D67    1      A RES_0402-0.0,5%,1/16W,CHIP,G21A    I26 @BASEBOARD_FAB2_LIB.BASEBOARD_FAB2(SCH_1):PAGE201
 EU4D4   19 VALRT_N PXE1610B_QFN-IC,H79206-001   I155 @BASEBOARD_FAB2_LIB.BASEBOARD_FAB2(SCH_1):PAGE201

SVID_VALERT_VCCIN_CPU1 @BASEBOARD_FAB2_LIB.BASEBOARD_FAB2(SCH_1):SVID_VALERT_VCCIN_CPU1
  R1D3    1      A RES_0402-0.0,5%,1/16W,CHIP,G21A    I37 @BASEBOARD_FAB2_LIB.BASEBOARD_FAB2(SCH_1):PAGE206
 EU1C2   19 VALRT_N PXE1610B_QFN-IC,H79206-001   I130 @BASEBOARD_FAB2_LIB.BASEBOARD_FAB2(SCH_1):PAGE206

SVID_VCLK_PVCCIN_CPU0 @BASEBOARD_FAB2_LIB.BASEBOARD_FAB2(SCH_1):SVID_VCLK_PVCCIN_CPU0
  R4E6    2      B RES_0402-150.0,1%,1/16W,CHIP,GA    I56 @BASEBOARD_FAB2_LIB.BASEBOARD_FAB2(SCH_1):PAGE201
 EU4D4   17   VCLK PXE1610B_QFN-IC,H79206-001   I155 @BASEBOARD_FAB2_LIB.BASEBOARD_FAB2(SCH_1):PAGE201

SVID_VCLK_PVCCIN_CPU1 @BASEBOARD_FAB2_LIB.BASEBOARD_FAB2(SCH_1):SVID_VCLK_PVCCIN_CPU1
  R1D9    2      B RES_0402-150.0,1%,1/16W,CHIP,GA    I54 @BASEBOARD_FAB2_LIB.BASEBOARD_FAB2(SCH_1):PAGE206
 EU1C2   17   VCLK PXE1610B_QFN-IC,H79206-001   I130 @BASEBOARD_FAB2_LIB.BASEBOARD_FAB2(SCH_1):PAGE206

SVID_VDIO_PVCCIN_CPU0 @BASEBOARD_FAB2_LIB.BASEBOARD_FAB2(SCH_1):SVID_VDIO_PVCCIN_CPU0
 R4D66    1      A RES_0402-0.0,5%,1/16W,CHIP,G21A    I98 @BASEBOARD_FAB2_LIB.BASEBOARD_FAB2(SCH_1):PAGE201
 EU4D4   18   VDIO PXE1610B_QFN-IC,H79206-001   I155 @BASEBOARD_FAB2_LIB.BASEBOARD_FAB2(SCH_1):PAGE201

SVID_VDIO_PVCCIN_CPU1 @BASEBOARD_FAB2_LIB.BASEBOARD_FAB2(SCH_1):SVID_VDIO_PVCCIN_CPU1
  R1D2    1      A RES_0402-0.0,5%,1/16W,CHIP,G21A    I38 @BASEBOARD_FAB2_LIB.BASEBOARD_FAB2(SCH_1):PAGE206
 EU1C2   18   VDIO PXE1610B_QFN-IC,H79206-001   I130 @BASEBOARD_FAB2_LIB.BASEBOARD_FAB2(SCH_1):PAGE206

SVID_VDIO_PVCCIO_CPU0 @BASEBOARD_FAB2_LIB.BASEBOARD_FAB2(SCH_1):SVID_VDIO_PVCCIO_CPU0
 R3P11    2      B RES_0402-0.0,5%,1/16W,CHIP,G21A    I16 @BASEBOARD_FAB2_LIB.BASEBOARD_FAB2(SCH_1):PAGE211
 EU3P1   16   VDIO PXE1110B_QFN-IC,H89187-001    I93 @BASEBOARD_FAB2_LIB.BASEBOARD_FAB2(SCH_1):PAGE211

SVID_VDIO_PVCCIO_CPU1 @BASEBOARD_FAB2_LIB.BASEBOARD_FAB2(SCH_1):SVID_VDIO_PVCCIO_CPU1
 R4D54    2      B RES_0402-0.0,5%,1/16W,CHIP,G21A    I37 @BASEBOARD_FAB2_LIB.BASEBOARD_FAB2(SCH_1):PAGE213
 EU4D5   16   VDIO PXE1110B_QFN-IC,H89187-001    I96 @BASEBOARD_FAB2_LIB.BASEBOARD_FAB2(SCH_1):PAGE213

SVID_VDIO_PVDDQ_ABC @BASEBOARD_FAB2_LIB.BASEBOARD_FAB2(SCH_1):SVID_VDIO_PVDDQ_ABC
  R7G2    1      A RES_0402-0.0,5%,1/16W,CHIP,G21A   I307 @BASEBOARD_FAB2_LIB.BASEBOARD_FAB2(SCH_1):PAGE215
 EU7G1   16   VDIO PXM1310B_QFN-IC,H89186-001   I358 @BASEBOARD_FAB2_LIB.BASEBOARD_FAB2(SCH_1):PAGE215

SVID_VDIO_PVDDQ_DEF @BASEBOARD_FAB2_LIB.BASEBOARD_FAB2(SCH_1):SVID_VDIO_PVDDQ_DEF
 R7A12    1      A RES_0402-0.0,5%,1/16W,CHIP,G21A    I25 @BASEBOARD_FAB2_LIB.BASEBOARD_FAB2(SCH_1):PAGE218
 EU7A5   16   VDIO PXM1310B_QFN-IC,H89186-001    I75 @BASEBOARD_FAB2_LIB.BASEBOARD_FAB2(SCH_1):PAGE218

SVID_VDIO_PVDDQ_GHJ @BASEBOARD_FAB2_LIB.BASEBOARD_FAB2(SCH_1):SVID_VDIO_PVDDQ_GHJ
 R1G10    1      A RES_0402-0.0,5%,1/16W,CHIP,G21A    I23 @BASEBOARD_FAB2_LIB.BASEBOARD_FAB2(SCH_1):PAGE223
 EU1G2   16   VDIO PXM1310B_QFN-IC,H89186-001    I90 @BASEBOARD_FAB2_LIB.BASEBOARD_FAB2(SCH_1):PAGE223

SVID_VDIO_PVDDQ_KLM @BASEBOARD_FAB2_LIB.BASEBOARD_FAB2(SCH_1):SVID_VDIO_PVDDQ_KLM
 R1B10    1      A RES_0402-0.0,5%,1/16W,CHIP,G21A    I23 @BASEBOARD_FAB2_LIB.BASEBOARD_FAB2(SCH_1):PAGE226
 EU1B1   16   VDIO PXM1310B_QFN-IC,H89186-001    I90 @BASEBOARD_FAB2_LIB.BASEBOARD_FAB2(SCH_1):PAGE226

TP_10GBE_KR0_MON_DN @BASEBOARD_FAB2_LIB.BASEBOARD_FAB2(SCH_1):TP_10GBE_KR0_MON_DN
  U7C1 BL26 RSVD<39> LBG_CORE_QAT_EXT_D_BGA1-IC,H91A    I73 @BASEBOARD_FAB2_LIB.BASEBOARD_FAB2(SCH_1):PAGE118

TP_10GBE_KR0_MON_DP @BASEBOARD_FAB2_LIB.BASEBOARD_FAB2(SCH_1):TP_10GBE_KR0_MON_DP
  U7C1 BN26 RSVD<40> LBG_CORE_QAT_EXT_D_BGA1-IC,H91A    I73 @BASEBOARD_FAB2_LIB.BASEBOARD_FAB2(SCH_1):PAGE118

TP_10GBE_KR1_MON_DN @BASEBOARD_FAB2_LIB.BASEBOARD_FAB2(SCH_1):TP_10GBE_KR1_MON_DN
  U7C1 BL33 RSVD<43> LBG_CORE_QAT_EXT_D_BGA1-IC,H91A    I73 @BASEBOARD_FAB2_LIB.BASEBOARD_FAB2(SCH_1):PAGE118

TP_10GBE_KR1_MON_DP @BASEBOARD_FAB2_LIB.BASEBOARD_FAB2(SCH_1):TP_10GBE_KR1_MON_DP
  U7C1 BN33 RSVD<44> LBG_CORE_QAT_EXT_D_BGA1-IC,H91A    I73 @BASEBOARD_FAB2_LIB.BASEBOARD_FAB2(SCH_1):PAGE118

TP_33P_33M_SMBADR @BASEBOARD_FAB2_LIB.BASEBOARD_FAB2(SCH_1):TP_33P_33M_SMBADR
 EU8F2   22 33MHZ_SMBADR ICS9FGP204_MLFP-IC,E95226-001    I34 @BASEBOARD_FAB2_LIB.BASEBOARD_FAB2(SCH_1):PAGE101

TP_ADC128_VREF @BASEBOARD_FAB2_LIB.BASEBOARD_FAB2(SCH_1):TP_ADC128_VREF
 EU9G1    1   VREF ADC128D818_SM-IC,H63642-001    I52 @BASEBOARD_FAB2_LIB.BASEBOARD_FAB2(SCH_1):PAGE165

TP_BIOS_RECOVER_BOOT @BASEBOARD_FAB2_LIB.BASEBOARD_FAB2(SCH_1):TP_BIOS_RECOVER_BOOT
  J7G3    8    IO8 CONN12_C73564003_PIP-CONN,C735A   I174 @BASEBOARD_FAB2_LIB.BASEBOARD_FAB2(SCH_1):PAGE136

TP_BIOS_USB_RECOVERY @BASEBOARD_FAB2_LIB.BASEBOARD_FAB2(SCH_1):TP_BIOS_USB_RECOVERY
  J7G3    2    IO2 CONN12_C73564003_PIP-CONN,C735A   I174 @BASEBOARD_FAB2_LIB.BASEBOARD_FAB2(SCH_1):PAGE136

TP_BMC_DISABLE @BASEBOARD_FAB2_LIB.BASEBOARD_FAB2(SCH_1):TP_BMC_DISABLE
  J9G1    1    IO1 CONN12_C73564003_PIP-CONN,C735A   I128 @BASEBOARD_FAB2_LIB.BASEBOARD_FAB2(SCH_1):PAGE137

TP_BMC_M_A15 @BASEBOARD_FAB2_LIB.BASEBOARD_FAB2(SCH_1):TP_BMC_M_A15
 U25W4  U15   MA15 AST2520A1-GP-GP_ASIC2-GB1-AST2A    I63 @BASEBOARD_FAB2_LIB.BASEBOARD_FAB2(SCH_1):PAGE143

TP_CD_HFI1_CPU1_I2CDAT @BASEBOARD_FAB2_LIB.BASEBOARD_FAB2(SCH_1):TP_CD_HFI1_CPU1_I2CDAT
  U2D1 BH23 CD_HFI1_I2CDAT SKX_EXT_B_BGA1-IC,TBD    I23 @BASEBOARD_FAB2_LIB.BASEBOARD_FAB2(SCH_1):PAGE63

TP_CD_HFI1_CPU1_I2CLK @BASEBOARD_FAB2_LIB.BASEBOARD_FAB2(SCH_1):TP_CD_HFI1_CPU1_I2CLK
  U2D1 BJ22 CD_HFI1_I2CCLK SKX_EXT_B_BGA1-IC,TBD    I23 @BASEBOARD_FAB2_LIB.BASEBOARD_FAB2(SCH_1):PAGE63

TP_CD_HFI1_CPU1_INT_N @BASEBOARD_FAB2_LIB.BASEBOARD_FAB2(SCH_1):TP_CD_HFI1_CPU1_INT_N
  U2D1 BM21 CD_HFI1_INT_N SKX_EXT_B_BGA1-IC,TBD    I23 @BASEBOARD_FAB2_LIB.BASEBOARD_FAB2(SCH_1):PAGE63

TP_CD_HFI1_CPU1_LED_N @BASEBOARD_FAB2_LIB.BASEBOARD_FAB2(SCH_1):TP_CD_HFI1_CPU1_LED_N
  U2D1 BM23 CD_HFI1_LED_N SKX_EXT_B_BGA1-IC,TBD    I23 @BASEBOARD_FAB2_LIB.BASEBOARD_FAB2(SCH_1):PAGE63

TP_CD_HFI1_CPU1_MODPRST_N @BASEBOARD_FAB2_LIB.BASEBOARD_FAB2(SCH_1):TP_CD_HFI1_CPU1_MODPRST_N
  U2D1 BT19 CD_HFI1_MODPRST_N SKX_EXT_B_BGA1-IC,TBD    I23 @BASEBOARD_FAB2_LIB.BASEBOARD_FAB2(SCH_1):PAGE63

TP_CD_HFI1_CPU1_RESET_N @BASEBOARD_FAB2_LIB.BASEBOARD_FAB2(SCH_1):TP_CD_HFI1_CPU1_RESET_N
  U2D1 BK23 CD_HFI1_RESET_N SKX_EXT_B_BGA1-IC,TBD    I23 @BASEBOARD_FAB2_LIB.BASEBOARD_FAB2(SCH_1):PAGE63

TP_CH_A_DIMM_A0_RFU_0 @BASEBOARD_FAB2_LIB.BASEBOARD_FAB2(SCH_1):TP_CH_A_DIMM_A0_RFU_0
  J4G1  205 RFU<0> SCONN288_H44441004_PIP-SCONN,HA     I1 @BASEBOARD_FAB2_LIB.BASEBOARD_FAB2(SCH_1):PAGE43

TP_CH_A_DIMM_A0_RFU_1 @BASEBOARD_FAB2_LIB.BASEBOARD_FAB2(SCH_1):TP_CH_A_DIMM_A0_RFU_1
  J4G1  227 RFU<1> SCONN288_H44441004_PIP-SCONN,HA     I1 @BASEBOARD_FAB2_LIB.BASEBOARD_FAB2(SCH_1):PAGE43

TP_CH_A_DIMM_A0_RFU_2 @BASEBOARD_FAB2_LIB.BASEBOARD_FAB2(SCH_1):TP_CH_A_DIMM_A0_RFU_2
  J4G1  144 RFU<2> SCONN288_H44441004_PIP-SCONN,HA     I1 @BASEBOARD_FAB2_LIB.BASEBOARD_FAB2(SCH_1):PAGE43

TP_CH_A_DIMM_A1_RFU_0 @BASEBOARD_FAB2_LIB.BASEBOARD_FAB2(SCH_1):TP_CH_A_DIMM_A1_RFU_0
  J6T1  205 RFU<0> SCONN288_H44441003_PIP-SCONN,HA    I13 @BASEBOARD_FAB2_LIB.BASEBOARD_FAB2(SCH_1):PAGE44

TP_CH_A_DIMM_A1_RFU_1 @BASEBOARD_FAB2_LIB.BASEBOARD_FAB2(SCH_1):TP_CH_A_DIMM_A1_RFU_1
  J6T1  227 RFU<1> SCONN288_H44441003_PIP-SCONN,HA    I13 @BASEBOARD_FAB2_LIB.BASEBOARD_FAB2(SCH_1):PAGE44

TP_CH_A_DIMM_A1_RFU_2 @BASEBOARD_FAB2_LIB.BASEBOARD_FAB2(SCH_1):TP_CH_A_DIMM_A1_RFU_2
  J6T1  144 RFU<2> SCONN288_H44441003_PIP-SCONN,HA    I13 @BASEBOARD_FAB2_LIB.BASEBOARD_FAB2(SCH_1):PAGE44

TP_CH_B_DIMM_B0_RFU_0 @BASEBOARD_FAB2_LIB.BASEBOARD_FAB2(SCH_1):TP_CH_B_DIMM_B0_RFU_0
  J4G2  205 RFU<0> SCONN288_H44441004_PIP-SCONN,HA   I111 @BASEBOARD_FAB2_LIB.BASEBOARD_FAB2(SCH_1):PAGE45

TP_CH_B_DIMM_B0_RFU_1 @BASEBOARD_FAB2_LIB.BASEBOARD_FAB2(SCH_1):TP_CH_B_DIMM_B0_RFU_1
  J4G2  227 RFU<1> SCONN288_H44441004_PIP-SCONN,HA   I111 @BASEBOARD_FAB2_LIB.BASEBOARD_FAB2(SCH_1):PAGE45

TP_CH_B_DIMM_B0_RFU_2 @BASEBOARD_FAB2_LIB.BASEBOARD_FAB2(SCH_1):TP_CH_B_DIMM_B0_RFU_2
  J4G2  144 RFU<2> SCONN288_H44441004_PIP-SCONN,HA   I111 @BASEBOARD_FAB2_LIB.BASEBOARD_FAB2(SCH_1):PAGE45

TP_CH_B_DIMM_B1_RFU_0 @BASEBOARD_FAB2_LIB.BASEBOARD_FAB2(SCH_1):TP_CH_B_DIMM_B1_RFU_0
  J6U1  205 RFU<0> SCONN288_H44441003_PIP-SCONN,HA    I14 @BASEBOARD_FAB2_LIB.BASEBOARD_FAB2(SCH_1):PAGE46

TP_CH_B_DIMM_B1_RFU_1 @BASEBOARD_FAB2_LIB.BASEBOARD_FAB2(SCH_1):TP_CH_B_DIMM_B1_RFU_1
  J6U1  227 RFU<1> SCONN288_H44441003_PIP-SCONN,HA    I14 @BASEBOARD_FAB2_LIB.BASEBOARD_FAB2(SCH_1):PAGE46

TP_CH_B_DIMM_B1_RFU_2 @BASEBOARD_FAB2_LIB.BASEBOARD_FAB2(SCH_1):TP_CH_B_DIMM_B1_RFU_2
  J6U1  144 RFU<2> SCONN288_H44441003_PIP-SCONN,HA    I14 @BASEBOARD_FAB2_LIB.BASEBOARD_FAB2(SCH_1):PAGE46

TP_CH_C_DIMM_C0_RFU_0 @BASEBOARD_FAB2_LIB.BASEBOARD_FAB2(SCH_1):TP_CH_C_DIMM_C0_RFU_0
  J4G3  205 RFU<0> SCONN288_H44441004_PIP-SCONN,HA   I111 @BASEBOARD_FAB2_LIB.BASEBOARD_FAB2(SCH_1):PAGE47

TP_CH_C_DIMM_C0_RFU_1 @BASEBOARD_FAB2_LIB.BASEBOARD_FAB2(SCH_1):TP_CH_C_DIMM_C0_RFU_1
  J4G3  227 RFU<1> SCONN288_H44441004_PIP-SCONN,HA   I111 @BASEBOARD_FAB2_LIB.BASEBOARD_FAB2(SCH_1):PAGE47

TP_CH_C_DIMM_C0_RFU_2 @BASEBOARD_FAB2_LIB.BASEBOARD_FAB2(SCH_1):TP_CH_C_DIMM_C0_RFU_2
  J4G3  144 RFU<2> SCONN288_H44441004_PIP-SCONN,HA   I111 @BASEBOARD_FAB2_LIB.BASEBOARD_FAB2(SCH_1):PAGE47

TP_CH_C_DIMM_C1_RFU_0 @BASEBOARD_FAB2_LIB.BASEBOARD_FAB2(SCH_1):TP_CH_C_DIMM_C1_RFU_0
  J6U2  205 RFU<0> SCONN288_H44441003_PIP-SCONN,HA   I111 @BASEBOARD_FAB2_LIB.BASEBOARD_FAB2(SCH_1):PAGE48

TP_CH_C_DIMM_C1_RFU_1 @BASEBOARD_FAB2_LIB.BASEBOARD_FAB2(SCH_1):TP_CH_C_DIMM_C1_RFU_1
  J6U2  227 RFU<1> SCONN288_H44441003_PIP-SCONN,HA   I111 @BASEBOARD_FAB2_LIB.BASEBOARD_FAB2(SCH_1):PAGE48

TP_CH_C_DIMM_C1_RFU_2 @BASEBOARD_FAB2_LIB.BASEBOARD_FAB2(SCH_1):TP_CH_C_DIMM_C1_RFU_2
  J6U2  144 RFU<2> SCONN288_H44441003_PIP-SCONN,HA   I111 @BASEBOARD_FAB2_LIB.BASEBOARD_FAB2(SCH_1):PAGE48

TP_CH_D_DIMM_D0_RFU_0 @BASEBOARD_FAB2_LIB.BASEBOARD_FAB2(SCH_1):TP_CH_D_DIMM_D0_RFU_0
  J4B1  205 RFU<0> SCONN288_H44441004_PIP-SCONN,HA   I111 @BASEBOARD_FAB2_LIB.BASEBOARD_FAB2(SCH_1):PAGE49

TP_CH_D_DIMM_D0_RFU_1 @BASEBOARD_FAB2_LIB.BASEBOARD_FAB2(SCH_1):TP_CH_D_DIMM_D0_RFU_1
  J4B1  227 RFU<1> SCONN288_H44441004_PIP-SCONN,HA   I111 @BASEBOARD_FAB2_LIB.BASEBOARD_FAB2(SCH_1):PAGE49

TP_CH_D_DIMM_D0_RFU_2 @BASEBOARD_FAB2_LIB.BASEBOARD_FAB2(SCH_1):TP_CH_D_DIMM_D0_RFU_2
  J4B1  144 RFU<2> SCONN288_H44441004_PIP-SCONN,HA   I111 @BASEBOARD_FAB2_LIB.BASEBOARD_FAB2(SCH_1):PAGE49

TP_CH_D_DIMM_D1_RFU_0 @BASEBOARD_FAB2_LIB.BASEBOARD_FAB2(SCH_1):TP_CH_D_DIMM_D1_RFU_0
  J6M1  205 RFU<0> SCONN288_H44441003_PIP-SCONN,HA   I158 @BASEBOARD_FAB2_LIB.BASEBOARD_FAB2(SCH_1):PAGE50

TP_CH_D_DIMM_D1_RFU_1 @BASEBOARD_FAB2_LIB.BASEBOARD_FAB2(SCH_1):TP_CH_D_DIMM_D1_RFU_1
  J6M1  227 RFU<1> SCONN288_H44441003_PIP-SCONN,HA   I158 @BASEBOARD_FAB2_LIB.BASEBOARD_FAB2(SCH_1):PAGE50

TP_CH_D_DIMM_D1_RFU_2 @BASEBOARD_FAB2_LIB.BASEBOARD_FAB2(SCH_1):TP_CH_D_DIMM_D1_RFU_2
  J6M1  144 RFU<2> SCONN288_H44441003_PIP-SCONN,HA   I158 @BASEBOARD_FAB2_LIB.BASEBOARD_FAB2(SCH_1):PAGE50

TP_CH_E_DIMM_E0_RFU_0 @BASEBOARD_FAB2_LIB.BASEBOARD_FAB2(SCH_1):TP_CH_E_DIMM_E0_RFU_0
  J4A2  205 RFU<0> SCONN288_H44441004_PIP-SCONN,HA   I111 @BASEBOARD_FAB2_LIB.BASEBOARD_FAB2(SCH_1):PAGE51

TP_CH_E_DIMM_E0_RFU_1 @BASEBOARD_FAB2_LIB.BASEBOARD_FAB2(SCH_1):TP_CH_E_DIMM_E0_RFU_1
  J4A2  227 RFU<1> SCONN288_H44441004_PIP-SCONN,HA   I111 @BASEBOARD_FAB2_LIB.BASEBOARD_FAB2(SCH_1):PAGE51

TP_CH_E_DIMM_E0_RFU_2 @BASEBOARD_FAB2_LIB.BASEBOARD_FAB2(SCH_1):TP_CH_E_DIMM_E0_RFU_2
  J4A2  144 RFU<2> SCONN288_H44441004_PIP-SCONN,HA   I111 @BASEBOARD_FAB2_LIB.BASEBOARD_FAB2(SCH_1):PAGE51

TP_CH_E_DIMM_E1_RFU_0 @BASEBOARD_FAB2_LIB.BASEBOARD_FAB2(SCH_1):TP_CH_E_DIMM_E1_RFU_0
  J6L2  205 RFU<0> SCONN288_H44441003_PIP-SCONN,HA    I12 @BASEBOARD_FAB2_LIB.BASEBOARD_FAB2(SCH_1):PAGE52

TP_CH_E_DIMM_E1_RFU_1 @BASEBOARD_FAB2_LIB.BASEBOARD_FAB2(SCH_1):TP_CH_E_DIMM_E1_RFU_1
  J6L2  227 RFU<1> SCONN288_H44441003_PIP-SCONN,HA    I12 @BASEBOARD_FAB2_LIB.BASEBOARD_FAB2(SCH_1):PAGE52

TP_CH_E_DIMM_E1_RFU_2 @BASEBOARD_FAB2_LIB.BASEBOARD_FAB2(SCH_1):TP_CH_E_DIMM_E1_RFU_2
  J6L2  144 RFU<2> SCONN288_H44441003_PIP-SCONN,HA    I12 @BASEBOARD_FAB2_LIB.BASEBOARD_FAB2(SCH_1):PAGE52

TP_CH_F_DIMM_F0_RFU_0 @BASEBOARD_FAB2_LIB.BASEBOARD_FAB2(SCH_1):TP_CH_F_DIMM_F0_RFU_0
  J4A1  205 RFU<0> SCONN288_H44441004_PIP-SCONN,HA   I111 @BASEBOARD_FAB2_LIB.BASEBOARD_FAB2(SCH_1):PAGE53

TP_CH_F_DIMM_F0_RFU_1 @BASEBOARD_FAB2_LIB.BASEBOARD_FAB2(SCH_1):TP_CH_F_DIMM_F0_RFU_1
  J4A1  227 RFU<1> SCONN288_H44441004_PIP-SCONN,HA   I111 @BASEBOARD_FAB2_LIB.BASEBOARD_FAB2(SCH_1):PAGE53

TP_CH_F_DIMM_F0_RFU_2 @BASEBOARD_FAB2_LIB.BASEBOARD_FAB2(SCH_1):TP_CH_F_DIMM_F0_RFU_2
  J4A1  144 RFU<2> SCONN288_H44441004_PIP-SCONN,HA   I111 @BASEBOARD_FAB2_LIB.BASEBOARD_FAB2(SCH_1):PAGE53

TP_CH_F_DIMM_F1_RFU_0 @BASEBOARD_FAB2_LIB.BASEBOARD_FAB2(SCH_1):TP_CH_F_DIMM_F1_RFU_0
  J6L1  205 RFU<0> SCONN288_H44441003_PIP-SCONN,HA   I111 @BASEBOARD_FAB2_LIB.BASEBOARD_FAB2(SCH_1):PAGE54

TP_CH_F_DIMM_F1_RFU_1 @BASEBOARD_FAB2_LIB.BASEBOARD_FAB2(SCH_1):TP_CH_F_DIMM_F1_RFU_1
  J6L1  227 RFU<1> SCONN288_H44441003_PIP-SCONN,HA   I111 @BASEBOARD_FAB2_LIB.BASEBOARD_FAB2(SCH_1):PAGE54

TP_CH_F_DIMM_F1_RFU_2 @BASEBOARD_FAB2_LIB.BASEBOARD_FAB2(SCH_1):TP_CH_F_DIMM_F1_RFU_2
  J6L1  144 RFU<2> SCONN288_H44441003_PIP-SCONN,HA   I111 @BASEBOARD_FAB2_LIB.BASEBOARD_FAB2(SCH_1):PAGE54

TP_CH_G_DIMM0_RFU_0 @BASEBOARD_FAB2_LIB.BASEBOARD_FAB2(SCH_1):TP_CH_G_DIMM0_RFU_0
  J9T1  205 RFU<0> SCONN288_H44441003_PIP-SCONN,HA    I13 @BASEBOARD_FAB2_LIB.BASEBOARD_FAB2(SCH_1):PAGE78

TP_CH_G_DIMM0_RFU_1 @BASEBOARD_FAB2_LIB.BASEBOARD_FAB2(SCH_1):TP_CH_G_DIMM0_RFU_1
  J9T1  227 RFU<1> SCONN288_H44441003_PIP-SCONN,HA    I13 @BASEBOARD_FAB2_LIB.BASEBOARD_FAB2(SCH_1):PAGE78

TP_CH_G_DIMM0_RFU_2 @BASEBOARD_FAB2_LIB.BASEBOARD_FAB2(SCH_1):TP_CH_G_DIMM0_RFU_2
  J9T1  144 RFU<2> SCONN288_H44441003_PIP-SCONN,HA    I13 @BASEBOARD_FAB2_LIB.BASEBOARD_FAB2(SCH_1):PAGE78

TP_CH_G_DIMM_G0_RFU_0 @BASEBOARD_FAB2_LIB.BASEBOARD_FAB2(SCH_1):TP_CH_G_DIMM_G0_RFU_0
  J1G1  205 RFU<0> SCONN288_H44441004_PIP-SCONN,HA   I111 @BASEBOARD_FAB2_LIB.BASEBOARD_FAB2(SCH_1):PAGE77

TP_CH_G_DIMM_G0_RFU_1 @BASEBOARD_FAB2_LIB.BASEBOARD_FAB2(SCH_1):TP_CH_G_DIMM_G0_RFU_1
  J1G1  227 RFU<1> SCONN288_H44441004_PIP-SCONN,HA   I111 @BASEBOARD_FAB2_LIB.BASEBOARD_FAB2(SCH_1):PAGE77

TP_CH_G_DIMM_G0_RFU_2 @BASEBOARD_FAB2_LIB.BASEBOARD_FAB2(SCH_1):TP_CH_G_DIMM_G0_RFU_2
  J1G1  144 RFU<2> SCONN288_H44441004_PIP-SCONN,HA   I111 @BASEBOARD_FAB2_LIB.BASEBOARD_FAB2(SCH_1):PAGE77

TP_CH_H_DIMM0_RFU_0 @BASEBOARD_FAB2_LIB.BASEBOARD_FAB2(SCH_1):TP_CH_H_DIMM0_RFU_0
  J9U1  205 RFU<0> SCONN288_H44441003_PIP-SCONN,HA    I24 @BASEBOARD_FAB2_LIB.BASEBOARD_FAB2(SCH_1):PAGE80

TP_CH_H_DIMM0_RFU_1 @BASEBOARD_FAB2_LIB.BASEBOARD_FAB2(SCH_1):TP_CH_H_DIMM0_RFU_1
  J9U1  227 RFU<1> SCONN288_H44441003_PIP-SCONN,HA    I24 @BASEBOARD_FAB2_LIB.BASEBOARD_FAB2(SCH_1):PAGE80

TP_CH_H_DIMM0_RFU_2 @BASEBOARD_FAB2_LIB.BASEBOARD_FAB2(SCH_1):TP_CH_H_DIMM0_RFU_2
  J9U1  144 RFU<2> SCONN288_H44441003_PIP-SCONN,HA    I24 @BASEBOARD_FAB2_LIB.BASEBOARD_FAB2(SCH_1):PAGE80

TP_CH_H_DIMM_H0_RFU_0 @BASEBOARD_FAB2_LIB.BASEBOARD_FAB2(SCH_1):TP_CH_H_DIMM_H0_RFU_0
  J1G2  205 RFU<0> SCONN288_H44441004_PIP-SCONN,HA   I111 @BASEBOARD_FAB2_LIB.BASEBOARD_FAB2(SCH_1):PAGE79

TP_CH_H_DIMM_H0_RFU_1 @BASEBOARD_FAB2_LIB.BASEBOARD_FAB2(SCH_1):TP_CH_H_DIMM_H0_RFU_1
  J1G2  227 RFU<1> SCONN288_H44441004_PIP-SCONN,HA   I111 @BASEBOARD_FAB2_LIB.BASEBOARD_FAB2(SCH_1):PAGE79

TP_CH_H_DIMM_H0_RFU_2 @BASEBOARD_FAB2_LIB.BASEBOARD_FAB2(SCH_1):TP_CH_H_DIMM_H0_RFU_2
  J1G2  144 RFU<2> SCONN288_H44441004_PIP-SCONN,HA   I111 @BASEBOARD_FAB2_LIB.BASEBOARD_FAB2(SCH_1):PAGE79

TP_CH_J_DIMM_J0_RFU_0 @BASEBOARD_FAB2_LIB.BASEBOARD_FAB2(SCH_1):TP_CH_J_DIMM_J0_RFU_0
  J1G3  205 RFU<0> SCONN288_H44441004_PIP-SCONN,HA   I186 @BASEBOARD_FAB2_LIB.BASEBOARD_FAB2(SCH_1):PAGE81

TP_CH_J_DIMM_J0_RFU_1 @BASEBOARD_FAB2_LIB.BASEBOARD_FAB2(SCH_1):TP_CH_J_DIMM_J0_RFU_1
  J1G3  227 RFU<1> SCONN288_H44441004_PIP-SCONN,HA   I186 @BASEBOARD_FAB2_LIB.BASEBOARD_FAB2(SCH_1):PAGE81

TP_CH_J_DIMM_J0_RFU_2 @BASEBOARD_FAB2_LIB.BASEBOARD_FAB2(SCH_1):TP_CH_J_DIMM_J0_RFU_2
  J1G3  144 RFU<2> SCONN288_H44441004_PIP-SCONN,HA   I186 @BASEBOARD_FAB2_LIB.BASEBOARD_FAB2(SCH_1):PAGE81

TP_CH_J_DIMM_J1_RFU_0 @BASEBOARD_FAB2_LIB.BASEBOARD_FAB2(SCH_1):TP_CH_J_DIMM_J1_RFU_0
  J9U2  205 RFU<0> SCONN288_H44441003_PIP-SCONN,HA   I187 @BASEBOARD_FAB2_LIB.BASEBOARD_FAB2(SCH_1):PAGE82

TP_CH_J_DIMM_J1_RFU_1 @BASEBOARD_FAB2_LIB.BASEBOARD_FAB2(SCH_1):TP_CH_J_DIMM_J1_RFU_1
  J9U2  227 RFU<1> SCONN288_H44441003_PIP-SCONN,HA   I187 @BASEBOARD_FAB2_LIB.BASEBOARD_FAB2(SCH_1):PAGE82

TP_CH_J_DIMM_J1_RFU_2 @BASEBOARD_FAB2_LIB.BASEBOARD_FAB2(SCH_1):TP_CH_J_DIMM_J1_RFU_2
  J9U2  144 RFU<2> SCONN288_H44441003_PIP-SCONN,HA   I187 @BASEBOARD_FAB2_LIB.BASEBOARD_FAB2(SCH_1):PAGE82

TP_CH_K_DIMM0_RFU_0 @BASEBOARD_FAB2_LIB.BASEBOARD_FAB2(SCH_1):TP_CH_K_DIMM0_RFU_0
  J9M1  205 RFU<0> SCONN288_H44441003_PIP-SCONN,HA    I14 @BASEBOARD_FAB2_LIB.BASEBOARD_FAB2(SCH_1):PAGE84

TP_CH_K_DIMM0_RFU_1 @BASEBOARD_FAB2_LIB.BASEBOARD_FAB2(SCH_1):TP_CH_K_DIMM0_RFU_1
  J9M1  227 RFU<1> SCONN288_H44441003_PIP-SCONN,HA    I14 @BASEBOARD_FAB2_LIB.BASEBOARD_FAB2(SCH_1):PAGE84

TP_CH_K_DIMM0_RFU_2 @BASEBOARD_FAB2_LIB.BASEBOARD_FAB2(SCH_1):TP_CH_K_DIMM0_RFU_2
  J9M1  144 RFU<2> SCONN288_H44441003_PIP-SCONN,HA    I14 @BASEBOARD_FAB2_LIB.BASEBOARD_FAB2(SCH_1):PAGE84

TP_CH_K_DIMM_K0_RFU_0 @BASEBOARD_FAB2_LIB.BASEBOARD_FAB2(SCH_1):TP_CH_K_DIMM_K0_RFU_0
  J1B1  205 RFU<0> SCONN288_H44441004_PIP-SCONN,HA   I111 @BASEBOARD_FAB2_LIB.BASEBOARD_FAB2(SCH_1):PAGE83

TP_CH_K_DIMM_K0_RFU_1 @BASEBOARD_FAB2_LIB.BASEBOARD_FAB2(SCH_1):TP_CH_K_DIMM_K0_RFU_1
  J1B1  227 RFU<1> SCONN288_H44441004_PIP-SCONN,HA   I111 @BASEBOARD_FAB2_LIB.BASEBOARD_FAB2(SCH_1):PAGE83

TP_CH_K_DIMM_K0_RFU_2 @BASEBOARD_FAB2_LIB.BASEBOARD_FAB2(SCH_1):TP_CH_K_DIMM_K0_RFU_2
  J1B1  144 RFU<2> SCONN288_H44441004_PIP-SCONN,HA   I111 @BASEBOARD_FAB2_LIB.BASEBOARD_FAB2(SCH_1):PAGE83

TP_CH_L_DIMM0_RFU_0 @BASEBOARD_FAB2_LIB.BASEBOARD_FAB2(SCH_1):TP_CH_L_DIMM0_RFU_0
  J9L2  205 RFU<0> SCONN288_H44441003_PIP-SCONN,HA    I12 @BASEBOARD_FAB2_LIB.BASEBOARD_FAB2(SCH_1):PAGE86

TP_CH_L_DIMM0_RFU_1 @BASEBOARD_FAB2_LIB.BASEBOARD_FAB2(SCH_1):TP_CH_L_DIMM0_RFU_1
  J9L2  227 RFU<1> SCONN288_H44441003_PIP-SCONN,HA    I12 @BASEBOARD_FAB2_LIB.BASEBOARD_FAB2(SCH_1):PAGE86

TP_CH_L_DIMM0_RFU_2 @BASEBOARD_FAB2_LIB.BASEBOARD_FAB2(SCH_1):TP_CH_L_DIMM0_RFU_2
  J9L2  144 RFU<2> SCONN288_H44441003_PIP-SCONN,HA    I12 @BASEBOARD_FAB2_LIB.BASEBOARD_FAB2(SCH_1):PAGE86

TP_CH_L_DIMM_L0_RFU_0 @BASEBOARD_FAB2_LIB.BASEBOARD_FAB2(SCH_1):TP_CH_L_DIMM_L0_RFU_0
  J1A2  205 RFU<0> SCONN288_H44441004_PIP-SCONN,HA   I111 @BASEBOARD_FAB2_LIB.BASEBOARD_FAB2(SCH_1):PAGE85

TP_CH_L_DIMM_L0_RFU_1 @BASEBOARD_FAB2_LIB.BASEBOARD_FAB2(SCH_1):TP_CH_L_DIMM_L0_RFU_1
  J1A2  227 RFU<1> SCONN288_H44441004_PIP-SCONN,HA   I111 @BASEBOARD_FAB2_LIB.BASEBOARD_FAB2(SCH_1):PAGE85

TP_CH_L_DIMM_L0_RFU_2 @BASEBOARD_FAB2_LIB.BASEBOARD_FAB2(SCH_1):TP_CH_L_DIMM_L0_RFU_2
  J1A2  144 RFU<2> SCONN288_H44441004_PIP-SCONN,HA   I111 @BASEBOARD_FAB2_LIB.BASEBOARD_FAB2(SCH_1):PAGE85

TP_CH_M_DIMM_M0_RFU_0 @BASEBOARD_FAB2_LIB.BASEBOARD_FAB2(SCH_1):TP_CH_M_DIMM_M0_RFU_0
  J1A1  205 RFU<0> SCONN288_H44441004_PIP-SCONN,HA   I186 @BASEBOARD_FAB2_LIB.BASEBOARD_FAB2(SCH_1):PAGE87

TP_CH_M_DIMM_M0_RFU_1 @BASEBOARD_FAB2_LIB.BASEBOARD_FAB2(SCH_1):TP_CH_M_DIMM_M0_RFU_1
  J1A1  227 RFU<1> SCONN288_H44441004_PIP-SCONN,HA   I186 @BASEBOARD_FAB2_LIB.BASEBOARD_FAB2(SCH_1):PAGE87

TP_CH_M_DIMM_M0_RFU_2 @BASEBOARD_FAB2_LIB.BASEBOARD_FAB2(SCH_1):TP_CH_M_DIMM_M0_RFU_2
  J1A1  144 RFU<2> SCONN288_H44441004_PIP-SCONN,HA   I186 @BASEBOARD_FAB2_LIB.BASEBOARD_FAB2(SCH_1):PAGE87

TP_CH_M_DIMM_M1_RFU_0 @BASEBOARD_FAB2_LIB.BASEBOARD_FAB2(SCH_1):TP_CH_M_DIMM_M1_RFU_0
  J9L1  205 RFU<0> SCONN288_H44441003_PIP-SCONN,HA   I111 @BASEBOARD_FAB2_LIB.BASEBOARD_FAB2(SCH_1):PAGE88

TP_CH_M_DIMM_M1_RFU_1 @BASEBOARD_FAB2_LIB.BASEBOARD_FAB2(SCH_1):TP_CH_M_DIMM_M1_RFU_1
  J9L1  227 RFU<1> SCONN288_H44441003_PIP-SCONN,HA   I111 @BASEBOARD_FAB2_LIB.BASEBOARD_FAB2(SCH_1):PAGE88

TP_CH_M_DIMM_M1_RFU_2 @BASEBOARD_FAB2_LIB.BASEBOARD_FAB2(SCH_1):TP_CH_M_DIMM_M1_RFU_2
  J9L1  144 RFU<2> SCONN288_H44441003_PIP-SCONN,HA   I111 @BASEBOARD_FAB2_LIB.BASEBOARD_FAB2(SCH_1):PAGE88

TP_CLK5_50M_CKMNG @BASEBOARD_FAB2_LIB.BASEBOARD_FAB2(SCH_1):TP_CLK5_50M_CKMNG
 EU8F2   24 RMII<5> ICS9FGP204_MLFP-IC,E95226-001    I34 @BASEBOARD_FAB2_LIB.BASEBOARD_FAB2(SCH_1):PAGE101

TP_CLK_100M_NSSCC0_DN @BASEBOARD_FAB2_LIB.BASEBOARD_FAB2(SCH_1):TP_CLK_100M_NSSCC0_DN
  U7C1  A32 CLKOUT_NSSCCAP0N LBG_CORE_QAT_EXT_D_BGA1-IC,H91A    I40 @BASEBOARD_FAB2_LIB.BASEBOARD_FAB2(SCH_1):PAGE114

TP_CLK_100M_NSSCC0_DP @BASEBOARD_FAB2_LIB.BASEBOARD_FAB2(SCH_1):TP_CLK_100M_NSSCC0_DP
  U7C1  C32 CLKOUT_NSSCCAP0P LBG_CORE_QAT_EXT_D_BGA1-IC,H91A    I40 @BASEBOARD_FAB2_LIB.BASEBOARD_FAB2(SCH_1):PAGE114

TP_CLK_100M_NSSCC1_DN @BASEBOARD_FAB2_LIB.BASEBOARD_FAB2(SCH_1):TP_CLK_100M_NSSCC1_DN
  U7C1  B38 CLKOUT_NSSCCAP1N LBG_CORE_QAT_EXT_D_BGA1-IC,H91A    I40 @BASEBOARD_FAB2_LIB.BASEBOARD_FAB2(SCH_1):PAGE114

TP_CLK_100M_NSSCC1_DP @BASEBOARD_FAB2_LIB.BASEBOARD_FAB2(SCH_1):TP_CLK_100M_NSSCC1_DP
  U7C1  D38 CLKOUT_NSSCCAP1P LBG_CORE_QAT_EXT_D_BGA1-IC,H91A    I40 @BASEBOARD_FAB2_LIB.BASEBOARD_FAB2(SCH_1):PAGE114

TP_CLK_100M_PLAT1_DN @BASEBOARD_FAB2_LIB.BASEBOARD_FAB2(SCH_1):TP_CLK_100M_PLAT1_DN
  U7C1  B40 CLKOUT_PLAT1N LBG_CORE_QAT_EXT_D_BGA1-IC,H91A    I40 @BASEBOARD_FAB2_LIB.BASEBOARD_FAB2(SCH_1):PAGE114

TP_CLK_100M_PLAT1_DP @BASEBOARD_FAB2_LIB.BASEBOARD_FAB2(SCH_1):TP_CLK_100M_PLAT1_DP
  U7C1  D40 CLKOUT_PLAT1P LBG_CORE_QAT_EXT_D_BGA1-IC,H91A    I40 @BASEBOARD_FAB2_LIB.BASEBOARD_FAB2(SCH_1):PAGE114

TP_CLK_100M_R_DN @BASEBOARD_FAB2_LIB.BASEBOARD_FAB2(SCH_1):TP_CLK_100M_R_DN
 EU8F2    8 CPUCLKC0 ICS9FGP204_MLFP-IC,E95226-001    I34 @BASEBOARD_FAB2_LIB.BASEBOARD_FAB2(SCH_1):PAGE101

TP_CLK_100M_R_DP @BASEBOARD_FAB2_LIB.BASEBOARD_FAB2(SCH_1):TP_CLK_100M_R_DP
 EU8F2    7 CPUCLKT0 ICS9FGP204_MLFP-IC,E95226-001    I34 @BASEBOARD_FAB2_LIB.BASEBOARD_FAB2(SCH_1):PAGE101

TP_CLK_125M @BASEBOARD_FAB2_LIB.BASEBOARD_FAB2(SCH_1):TP_CLK_125M
 EU8F2   36 RGMII<1> ICS9FGP204_MLFP-IC,E95226-001    I34 @BASEBOARD_FAB2_LIB.BASEBOARD_FAB2(SCH_1):PAGE101

TP_CLK_125M_BMCA @BASEBOARD_FAB2_LIB.BASEBOARD_FAB2(SCH_1):TP_CLK_125M_BMCA
 EU8F2   37 RGMII<0> ICS9FGP204_MLFP-IC,E95226-001    I34 @BASEBOARD_FAB2_LIB.BASEBOARD_FAB2(SCH_1):PAGE101

TP_CLK_24M_PMSYNC2 @BASEBOARD_FAB2_LIB.BASEBOARD_FAB2(SCH_1):TP_CLK_24M_PMSYNC2
  U7C1 BV51 CLOCKSE_PMSYNCCLK2 LBG_CORE_QAT_EXT_D_BGA1-IC,H91A    I40 @BASEBOARD_FAB2_LIB.BASEBOARD_FAB2(SCH_1):PAGE114

TP_CLK_96M_CKMNG_N @BASEBOARD_FAB2_LIB.BASEBOARD_FAB2(SCH_1):TP_CLK_96M_CKMNG_N
 EU8F2    4 DOT96SSC ICS9FGP204_MLFP-IC,E95226-001    I34 @BASEBOARD_FAB2_LIB.BASEBOARD_FAB2(SCH_1):PAGE101

TP_CLK_96M_CKMNG_P @BASEBOARD_FAB2_LIB.BASEBOARD_FAB2(SCH_1):TP_CLK_96M_CKMNG_P
 EU8F2    3 DOT96SST ICS9FGP204_MLFP-IC,E95226-001    I34 @BASEBOARD_FAB2_LIB.BASEBOARD_FAB2(SCH_1):PAGE101

TP_CPLD1_PB11B_PCLKC2_0 @BASEBOARD_FAB2_LIB.BASEBOARD_FAB2(SCH_1):TP_CPLD1_PB11B_PCLKC2_0
  U8D7   R8 PB11B_PCLKC2_0 LCMXO2_A_256BGA-IC,H63395-001   I179 @BASEBOARD_FAB2_LIB.BASEBOARD_FAB2(SCH_1):PAGE190

TP_CPLD1_PB16A_PCLKT2_1 @BASEBOARD_FAB2_LIB.BASEBOARD_FAB2(SCH_1):TP_CPLD1_PB16A_PCLKT2_1
  U8D7   T9 PB16A_PCLKT2_1 LCMXO2_A_256BGA-IC,H63395-001   I179 @BASEBOARD_FAB2_LIB.BASEBOARD_FAB2(SCH_1):PAGE190

TP_CPLD1_PB16B_PCLKC2_1 @BASEBOARD_FAB2_LIB.BASEBOARD_FAB2(SCH_1):TP_CPLD1_PB16B_PCLKC2_1
  U8D7   P9 PB16B_PCLKC2_1 LCMXO2_A_256BGA-IC,H63395-001   I179 @BASEBOARD_FAB2_LIB.BASEBOARD_FAB2(SCH_1):PAGE190

TP_CPLD1_PB25B_SI_SISPI @BASEBOARD_FAB2_LIB.BASEBOARD_FAB2(SCH_1):TP_CPLD1_PB25B_SI_SISPI
  U8D7  P13 PB25B_SI_SISPI LCMXO2_A_256BGA-IC,H63395-001   I179 @BASEBOARD_FAB2_LIB.BASEBOARD_FAB2(SCH_1):PAGE190

TP_CPLD1_PB5A_CSSPIN @BASEBOARD_FAB2_LIB.BASEBOARD_FAB2(SCH_1):TP_CPLD1_PB5A_CSSPIN
  U8D7   R5 PB5A_CSSPIN LCMXO2_A_256BGA-IC,H63395-001   I179 @BASEBOARD_FAB2_LIB.BASEBOARD_FAB2(SCH_1):PAGE190

TP_CPLD1_PB8A_MCLK_CCLK @BASEBOARD_FAB2_LIB.BASEBOARD_FAB2(SCH_1):TP_CPLD1_PB8A_MCLK_CCLK
  U8D7   P6 PB8A_MCLK_CCLK LCMXO2_A_256BGA-IC,H63395-001   I179 @BASEBOARD_FAB2_LIB.BASEBOARD_FAB2(SCH_1):PAGE190

TP_CPLD1_PB8B_SO_SPISO @BASEBOARD_FAB2_LIB.BASEBOARD_FAB2(SCH_1):TP_CPLD1_PB8B_SO_SPISO
  U8D7   T6 PB8B_SO_SPISO LCMXO2_A_256BGA-IC,H63395-001   I179 @BASEBOARD_FAB2_LIB.BASEBOARD_FAB2(SCH_1):PAGE190

TP_CPLD1_PB8D @BASEBOARD_FAB2_LIB.BASEBOARD_FAB2(SCH_1):TP_CPLD1_PB8D
  U8D7   L7   PB8D LCMXO2_A_256BGA-IC,H63395-001   I179 @BASEBOARD_FAB2_LIB.BASEBOARD_FAB2(SCH_1):PAGE190

TP_CPLD1_PL11A @BASEBOARD_FAB2_LIB.BASEBOARD_FAB2(SCH_1):TP_CPLD1_PL11A
  U8D7   L3  PL11B LCMXO2_A_256BGA-IC,H63395-001   I179 @BASEBOARD_FAB2_LIB.BASEBOARD_FAB2(SCH_1):PAGE190

TP_CPLD1_PL1A_L_GPLLT_FB @BASEBOARD_FAB2_LIB.BASEBOARD_FAB2(SCH_1):TP_CPLD1_PL1A_L_GPLLT_FB
  U8D7   D3 PL1A_L_GPLLT_FB LCMXO2_A_256BGA-IC,H63395-001   I179 @BASEBOARD_FAB2_LIB.BASEBOARD_FAB2(SCH_1):PAGE190

TP_CPLD1_PL1B_L_GPLLC_FB @BASEBOARD_FAB2_LIB.BASEBOARD_FAB2(SCH_1):TP_CPLD1_PL1B_L_GPLLC_FB
  U8D7   D1 PL1B_L_GPLLC_FB LCMXO2_A_256BGA-IC,H63395-001   I179 @BASEBOARD_FAB2_LIB.BASEBOARD_FAB2(SCH_1):PAGE190

TP_CPLD1_PL2B_L_GPLLC_IN @BASEBOARD_FAB2_LIB.BASEBOARD_FAB2(SCH_1):TP_CPLD1_PL2B_L_GPLLC_IN
  U8D7   E3 PL2B_L_GPLLC_IN LCMXO2_A_256BGA-IC,H63395-001   I179 @BASEBOARD_FAB2_LIB.BASEBOARD_FAB2(SCH_1):PAGE190

TP_CPLD1_PL7D_PCLKT4_0 @BASEBOARD_FAB2_LIB.BASEBOARD_FAB2(SCH_1):TP_CPLD1_PL7D_PCLKT4_0
  U8D7   J3 PL7D_PCLKC4_0 LCMXO2_A_256BGA-IC,H63395-001   I179 @BASEBOARD_FAB2_LIB.BASEBOARD_FAB2(SCH_1):PAGE190

TP_CPLD1_PR10C @BASEBOARD_FAB2_LIB.BASEBOARD_FAB2(SCH_1):TP_CPLD1_PR10C
  U8D7  J11  PR10C LCMXO2_A_256BGA-IC,H63395-001    I59 @BASEBOARD_FAB2_LIB.BASEBOARD_FAB2(SCH_1):PAGE191

TP_CPLD1_PR11B @BASEBOARD_FAB2_LIB.BASEBOARD_FAB2(SCH_1):TP_CPLD1_PR11B
  U8D7  L14  PR11B LCMXO2_A_256BGA-IC,H63395-001    I59 @BASEBOARD_FAB2_LIB.BASEBOARD_FAB2(SCH_1):PAGE191

TP_CPLD1_PR12D @BASEBOARD_FAB2_LIB.BASEBOARD_FAB2(SCH_1):TP_CPLD1_PR12D
  U8D7  L13  PR12D LCMXO2_A_256BGA-IC,H63395-001    I59 @BASEBOARD_FAB2_LIB.BASEBOARD_FAB2(SCH_1):PAGE191

TP_CPLD1_PR7A_PCLKT1_0 @BASEBOARD_FAB2_LIB.BASEBOARD_FAB2(SCH_1):TP_CPLD1_PR7A_PCLKT1_0
  U8D7  H14 PR7A_PCLKT1_0 LCMXO2_A_256BGA-IC,H63395-001    I59 @BASEBOARD_FAB2_LIB.BASEBOARD_FAB2(SCH_1):PAGE191

TP_CPLD1_PR7B_PCLKC1_0 @BASEBOARD_FAB2_LIB.BASEBOARD_FAB2(SCH_1):TP_CPLD1_PR7B_PCLKC1_0
  U8D7  H16 PR7B_PCLKC1_0 LCMXO2_A_256BGA-IC,H63395-001    I59 @BASEBOARD_FAB2_LIB.BASEBOARD_FAB2(SCH_1):PAGE191

TP_CPLD1_PR7C @BASEBOARD_FAB2_LIB.BASEBOARD_FAB2(SCH_1):TP_CPLD1_PR7C
  U8D7  J16   PR7C LCMXO2_A_256BGA-IC,H63395-001    I59 @BASEBOARD_FAB2_LIB.BASEBOARD_FAB2(SCH_1):PAGE191

TP_CPLD1_PR7D @BASEBOARD_FAB2_LIB.BASEBOARD_FAB2(SCH_1):TP_CPLD1_PR7D
  U8D7  J14   PR7D LCMXO2_A_256BGA-IC,H63395-001    I59 @BASEBOARD_FAB2_LIB.BASEBOARD_FAB2(SCH_1):PAGE191

TP_CPLD1_PR9A @BASEBOARD_FAB2_LIB.BASEBOARD_FAB2(SCH_1):TP_CPLD1_PR9A
  U8D7  J15   PR9A LCMXO2_A_256BGA-IC,H63395-001    I59 @BASEBOARD_FAB2_LIB.BASEBOARD_FAB2(SCH_1):PAGE191

TP_CPLD1_PR9C @BASEBOARD_FAB2_LIB.BASEBOARD_FAB2(SCH_1):TP_CPLD1_PR9C
  U8D7  H11   PR9C LCMXO2_A_256BGA-IC,H63395-001    I59 @BASEBOARD_FAB2_LIB.BASEBOARD_FAB2(SCH_1):PAGE191

TP_CPLD1_PR9D @BASEBOARD_FAB2_LIB.BASEBOARD_FAB2(SCH_1):TP_CPLD1_PR9D
  U8D7  J13   PR9D LCMXO2_A_256BGA-IC,H63395-001    I59 @BASEBOARD_FAB2_LIB.BASEBOARD_FAB2(SCH_1):PAGE191

TP_CPLD1_PT11A @BASEBOARD_FAB2_LIB.BASEBOARD_FAB2(SCH_1):TP_CPLD1_PT11A
  U8D7   A5  PT11A LCMXO2_A_256BGA-IC,H63395-001    I59 @BASEBOARD_FAB2_LIB.BASEBOARD_FAB2(SCH_1):PAGE191

TP_CPLD1_PT11B @BASEBOARD_FAB2_LIB.BASEBOARD_FAB2(SCH_1):TP_CPLD1_PT11B
  U8D7   B6  PT11B LCMXO2_A_256BGA-IC,H63395-001    I59 @BASEBOARD_FAB2_LIB.BASEBOARD_FAB2(SCH_1):PAGE191

TP_CPLD1_PT13A @BASEBOARD_FAB2_LIB.BASEBOARD_FAB2(SCH_1):TP_CPLD1_PT13A
  U8D7   B7  PT13A LCMXO2_A_256BGA-IC,H63395-001    I59 @BASEBOARD_FAB2_LIB.BASEBOARD_FAB2(SCH_1):PAGE191

TP_CPLD1_PT16B @BASEBOARD_FAB2_LIB.BASEBOARD_FAB2(SCH_1):TP_CPLD1_PT16B
  U8D7   E8  PT16B LCMXO2_A_256BGA-IC,H63395-001    I59 @BASEBOARD_FAB2_LIB.BASEBOARD_FAB2(SCH_1):PAGE191

TP_CPLD1_PT17B_PCLKC0_1 @BASEBOARD_FAB2_LIB.BASEBOARD_FAB2(SCH_1):TP_CPLD1_PT17B_PCLKC0_1
  U8D7   A8 PT17B_PCLKC0_1 LCMXO2_A_256BGA-IC,H63395-001    I59 @BASEBOARD_FAB2_LIB.BASEBOARD_FAB2(SCH_1):PAGE191

TP_CPLD1_PT17C @BASEBOARD_FAB2_LIB.BASEBOARD_FAB2(SCH_1):TP_CPLD1_PT17C
  U8D7   D8  PT17C LCMXO2_A_256BGA-IC,H63395-001    I59 @BASEBOARD_FAB2_LIB.BASEBOARD_FAB2(SCH_1):PAGE191

TP_CPLD1_PT19D @BASEBOARD_FAB2_LIB.BASEBOARD_FAB2(SCH_1):TP_CPLD1_PT19D
  U8D7  E11  PT19D LCMXO2_A_256BGA-IC,H63395-001    I59 @BASEBOARD_FAB2_LIB.BASEBOARD_FAB2(SCH_1):PAGE191

TP_CPLD1_PT20A @BASEBOARD_FAB2_LIB.BASEBOARD_FAB2(SCH_1):TP_CPLD1_PT20A
  U8D7  D10  PT20A LCMXO2_A_256BGA-IC,H63395-001    I59 @BASEBOARD_FAB2_LIB.BASEBOARD_FAB2(SCH_1):PAGE191

TP_CPLD1_PT20B @BASEBOARD_FAB2_LIB.BASEBOARD_FAB2(SCH_1):TP_CPLD1_PT20B
  U8D7  E10  PT20B LCMXO2_A_256BGA-IC,H63395-001    I59 @BASEBOARD_FAB2_LIB.BASEBOARD_FAB2(SCH_1):PAGE191

TP_CPLD1_PT20D_PROGRAMN @BASEBOARD_FAB2_LIB.BASEBOARD_FAB2(SCH_1):TP_CPLD1_PT20D_PROGRAMN
  U8D7  B10 PT20D_PROGRAMN LCMXO2_A_256BGA-IC,H63395-001    I59 @BASEBOARD_FAB2_LIB.BASEBOARD_FAB2(SCH_1):PAGE191

TP_CPLD1_PT22C @BASEBOARD_FAB2_LIB.BASEBOARD_FAB2(SCH_1):TP_CPLD1_PT22C
  U8D7  B13  PT22C LCMXO2_A_256BGA-IC,H63395-001    I59 @BASEBOARD_FAB2_LIB.BASEBOARD_FAB2(SCH_1):PAGE191

TP_CPLD1_PT22D @BASEBOARD_FAB2_LIB.BASEBOARD_FAB2(SCH_1):TP_CPLD1_PT22D
  U8D7  A14  PT22D LCMXO2_A_256BGA-IC,H63395-001    I59 @BASEBOARD_FAB2_LIB.BASEBOARD_FAB2(SCH_1):PAGE191

TP_CPLD1_PT24B @BASEBOARD_FAB2_LIB.BASEBOARD_FAB2(SCH_1):TP_CPLD1_PT24B
  U8D7  A15  PT24B LCMXO2_A_256BGA-IC,H63395-001    I59 @BASEBOARD_FAB2_LIB.BASEBOARD_FAB2(SCH_1):PAGE191

TP_CPLD1_PT24C_INITN @BASEBOARD_FAB2_LIB.BASEBOARD_FAB2(SCH_1):TP_CPLD1_PT24C_INITN
  U8D7  A13 PT24C_INITN LCMXO2_A_256BGA-IC,H63395-001    I59 @BASEBOARD_FAB2_LIB.BASEBOARD_FAB2(SCH_1):PAGE191

TP_CPLD1_PT24D_DONE @BASEBOARD_FAB2_LIB.BASEBOARD_FAB2(SCH_1):TP_CPLD1_PT24D_DONE
  U8D7  C13 PT24D_DONE LCMXO2_A_256BGA-IC,H63395-001    I59 @BASEBOARD_FAB2_LIB.BASEBOARD_FAB2(SCH_1):PAGE191

TP_CPU0_KTI2_AMONV @BASEBOARD_FAB2_LIB.BASEBOARD_FAB2(SCH_1):TP_CPU0_KTI2_AMONV
  U5D1 CN22 RSVD<77> SKX_EXT_B_BGA1-IC,TBD   I127 @BASEBOARD_FAB2_LIB.BASEBOARD_FAB2(SCH_1):PAGE39

TP_CPU0_KTI2_DFX_DN @BASEBOARD_FAB2_LIB.BASEBOARD_FAB2(SCH_1):TP_CPU0_KTI2_DFX_DN
  U5D1 CW22 RSVD<63> SKX_EXT_B_BGA1-IC,TBD   I127 @BASEBOARD_FAB2_LIB.BASEBOARD_FAB2(SCH_1):PAGE39

TP_CPU0_PE_HP_SCL @BASEBOARD_FAB2_LIB.BASEBOARD_FAB2(SCH_1):TP_CPU0_PE_HP_SCL
  U5D1 AM19 PE_HP_SCL SKX_EXT_B_BGA1-IC,TBD   I259 @BASEBOARD_FAB2_LIB.BASEBOARD_FAB2(SCH_1):PAGE21

TP_CPU0_PE_HP_SDA @BASEBOARD_FAB2_LIB.BASEBOARD_FAB2(SCH_1):TP_CPU0_PE_HP_SDA
  U5D1 AL18 PE_HP_SDA SKX_EXT_B_BGA1-IC,TBD   I259 @BASEBOARD_FAB2_LIB.BASEBOARD_FAB2(SCH_1):PAGE21

TP_CPU0_PROCDIS_G_N @BASEBOARD_FAB2_LIB.BASEBOARD_FAB2(SCH_1):TP_CPU0_PROCDIS_G_N
  U5D1 AB17 PROCDIS_N SKX_EXT_B_BGA1-IC,TBD   I259 @BASEBOARD_FAB2_LIB.BASEBOARD_FAB2(SCH_1):PAGE21

TP_CPU0_RSVD_0 @BASEBOARD_FAB2_LIB.BASEBOARD_FAB2(SCH_1):TP_CPU0_RSVD_0
  U5D1 EF83 RSVD<0> SKX_EXT_B_BGA1-IC,TBD   I127 @BASEBOARD_FAB2_LIB.BASEBOARD_FAB2(SCH_1):PAGE39

TP_CPU0_RSVD_1 @BASEBOARD_FAB2_LIB.BASEBOARD_FAB2(SCH_1):TP_CPU0_RSVD_1
  U5D1 EF81 RSVD<1> SKX_EXT_B_BGA1-IC,TBD   I127 @BASEBOARD_FAB2_LIB.BASEBOARD_FAB2(SCH_1):PAGE39

TP_CPU0_RSVD_10 @BASEBOARD_FAB2_LIB.BASEBOARD_FAB2(SCH_1):TP_CPU0_RSVD_10
  U5D1  ED5 RSVD<10> SKX_EXT_B_BGA1-IC,TBD   I127 @BASEBOARD_FAB2_LIB.BASEBOARD_FAB2(SCH_1):PAGE39

TP_CPU0_RSVD_100 @BASEBOARD_FAB2_LIB.BASEBOARD_FAB2(SCH_1):TP_CPU0_RSVD_100
  U5D1 CF81 RSVD<100> SKX_EXT_B_BGA1-IC,TBD    I15 @BASEBOARD_FAB2_LIB.BASEBOARD_FAB2(SCH_1):PAGE36

TP_CPU0_RSVD_101 @BASEBOARD_FAB2_LIB.BASEBOARD_FAB2(SCH_1):TP_CPU0_RSVD_101
  U5D1 CF79 RSVD<101> SKX_EXT_B_BGA1-IC,TBD    I15 @BASEBOARD_FAB2_LIB.BASEBOARD_FAB2(SCH_1):PAGE36

TP_CPU0_RSVD_105 @BASEBOARD_FAB2_LIB.BASEBOARD_FAB2(SCH_1):TP_CPU0_RSVD_105
  U5D1 CE80 RSVD<105> SKX_EXT_B_BGA1-IC,TBD    I15 @BASEBOARD_FAB2_LIB.BASEBOARD_FAB2(SCH_1):PAGE36

TP_CPU0_RSVD_106 @BASEBOARD_FAB2_LIB.BASEBOARD_FAB2(SCH_1):TP_CPU0_RSVD_106
  U5D1 CE78 RSVD<106> SKX_EXT_B_BGA1-IC,TBD    I15 @BASEBOARD_FAB2_LIB.BASEBOARD_FAB2(SCH_1):PAGE36

TP_CPU0_RSVD_108 @BASEBOARD_FAB2_LIB.BASEBOARD_FAB2(SCH_1):TP_CPU0_RSVD_108
  U5D1 CD25 RSVD<108> SKX_EXT_B_BGA1-IC,TBD    I15 @BASEBOARD_FAB2_LIB.BASEBOARD_FAB2(SCH_1):PAGE36

TP_CPU0_RSVD_11 @BASEBOARD_FAB2_LIB.BASEBOARD_FAB2(SCH_1):TP_CPU0_RSVD_11
  U5D1 ED45 RSVD<11> SKX_EXT_B_BGA1-IC,TBD   I127 @BASEBOARD_FAB2_LIB.BASEBOARD_FAB2(SCH_1):PAGE39

TP_CPU0_RSVD_111 @BASEBOARD_FAB2_LIB.BASEBOARD_FAB2(SCH_1):TP_CPU0_RSVD_111
  U5D1  CC6 RSVD<111> SKX_EXT_B_BGA1-IC,TBD    I15 @BASEBOARD_FAB2_LIB.BASEBOARD_FAB2(SCH_1):PAGE36

TP_CPU0_RSVD_113 @BASEBOARD_FAB2_LIB.BASEBOARD_FAB2(SCH_1):TP_CPU0_RSVD_113
  U5D1  CB5 RSVD<113> SKX_EXT_B_BGA1-IC,TBD    I15 @BASEBOARD_FAB2_LIB.BASEBOARD_FAB2(SCH_1):PAGE36

TP_CPU0_RSVD_114 @BASEBOARD_FAB2_LIB.BASEBOARD_FAB2(SCH_1):TP_CPU0_RSVD_114
  U5D1 CB25 RSVD<114> SKX_EXT_B_BGA1-IC,TBD    I15 @BASEBOARD_FAB2_LIB.BASEBOARD_FAB2(SCH_1):PAGE36

TP_CPU0_RSVD_117 @BASEBOARD_FAB2_LIB.BASEBOARD_FAB2(SCH_1):TP_CPU0_RSVD_117
  U5D1 CA24 RSVD<117> SKX_EXT_B_BGA1-IC,TBD    I15 @BASEBOARD_FAB2_LIB.BASEBOARD_FAB2(SCH_1):PAGE36

TP_CPU0_RSVD_119 @BASEBOARD_FAB2_LIB.BASEBOARD_FAB2(SCH_1):TP_CPU0_RSVD_119
  U5D1 BY25 RSVD<119> SKX_EXT_B_BGA1-IC,TBD    I15 @BASEBOARD_FAB2_LIB.BASEBOARD_FAB2(SCH_1):PAGE36

TP_CPU0_RSVD_12 @BASEBOARD_FAB2_LIB.BASEBOARD_FAB2(SCH_1):TP_CPU0_RSVD_12
  U5D1 EC84 RSVD<12> SKX_EXT_B_BGA1-IC,TBD   I127 @BASEBOARD_FAB2_LIB.BASEBOARD_FAB2(SCH_1):PAGE39

TP_CPU0_RSVD_121 @BASEBOARD_FAB2_LIB.BASEBOARD_FAB2(SCH_1):TP_CPU0_RSVD_121
  U5D1 BW22 RSVD<121> SKX_EXT_B_BGA1-IC,TBD    I15 @BASEBOARD_FAB2_LIB.BASEBOARD_FAB2(SCH_1):PAGE36

TP_CPU0_RSVD_123 @BASEBOARD_FAB2_LIB.BASEBOARD_FAB2(SCH_1):TP_CPU0_RSVD_123
  U5D1 BW10 RSVD<123> SKX_EXT_B_BGA1-IC,TBD    I15 @BASEBOARD_FAB2_LIB.BASEBOARD_FAB2(SCH_1):PAGE36

TP_CPU0_RSVD_124 @BASEBOARD_FAB2_LIB.BASEBOARD_FAB2(SCH_1):TP_CPU0_RSVD_124
  U5D1 BV23 RSVD<124> SKX_EXT_B_BGA1-IC,TBD    I15 @BASEBOARD_FAB2_LIB.BASEBOARD_FAB2(SCH_1):PAGE36

TP_CPU0_RSVD_13 @BASEBOARD_FAB2_LIB.BASEBOARD_FAB2(SCH_1):TP_CPU0_RSVD_13
  U5D1 EC44 RSVD<13> SKX_EXT_B_BGA1-IC,TBD   I127 @BASEBOARD_FAB2_LIB.BASEBOARD_FAB2(SCH_1):PAGE39

TP_CPU0_RSVD_14 @BASEBOARD_FAB2_LIB.BASEBOARD_FAB2(SCH_1):TP_CPU0_RSVD_14
  U5D1  EC4 RSVD<14> SKX_EXT_B_BGA1-IC,TBD   I127 @BASEBOARD_FAB2_LIB.BASEBOARD_FAB2(SCH_1):PAGE39

TP_CPU0_RSVD_144 @BASEBOARD_FAB2_LIB.BASEBOARD_FAB2(SCH_1):TP_CPU0_RSVD_144
  U5D1 BG20 RSVD<144> SKX_EXT_B_BGA1-IC,TBD    I15 @BASEBOARD_FAB2_LIB.BASEBOARD_FAB2(SCH_1):PAGE36

TP_CPU0_RSVD_145 @BASEBOARD_FAB2_LIB.BASEBOARD_FAB2(SCH_1):TP_CPU0_RSVD_145
  U5D1 BG18 RSVD<145> SKX_EXT_B_BGA1-IC,TBD    I15 @BASEBOARD_FAB2_LIB.BASEBOARD_FAB2(SCH_1):PAGE36

TP_CPU0_RSVD_146 @BASEBOARD_FAB2_LIB.BASEBOARD_FAB2(SCH_1):TP_CPU0_RSVD_146
  U5D1 BF21 RSVD<146> SKX_EXT_B_BGA1-IC,TBD    I15 @BASEBOARD_FAB2_LIB.BASEBOARD_FAB2(SCH_1):PAGE36

TP_CPU0_RSVD_147 @BASEBOARD_FAB2_LIB.BASEBOARD_FAB2(SCH_1):TP_CPU0_RSVD_147
  U5D1 BE22 RSVD<147> SKX_EXT_B_BGA1-IC,TBD    I15 @BASEBOARD_FAB2_LIB.BASEBOARD_FAB2(SCH_1):PAGE36

TP_CPU0_RSVD_148 @BASEBOARD_FAB2_LIB.BASEBOARD_FAB2(SCH_1):TP_CPU0_RSVD_148
  U5D1 BE20 RSVD<148> SKX_EXT_B_BGA1-IC,TBD    I15 @BASEBOARD_FAB2_LIB.BASEBOARD_FAB2(SCH_1):PAGE36

TP_CPU0_RSVD_149 @BASEBOARD_FAB2_LIB.BASEBOARD_FAB2(SCH_1):TP_CPU0_RSVD_149
  U5D1 BE18 RSVD<149> SKX_EXT_B_BGA1-IC,TBD    I15 @BASEBOARD_FAB2_LIB.BASEBOARD_FAB2(SCH_1):PAGE36

TP_CPU0_RSVD_15 @BASEBOARD_FAB2_LIB.BASEBOARD_FAB2(SCH_1):TP_CPU0_RSVD_15
  U5D1 EC16 RSVD<15> SKX_EXT_B_BGA1-IC,TBD   I127 @BASEBOARD_FAB2_LIB.BASEBOARD_FAB2(SCH_1):PAGE39

TP_CPU0_RSVD_150 @BASEBOARD_FAB2_LIB.BASEBOARD_FAB2(SCH_1):TP_CPU0_RSVD_150
  U5D1 BD69 RSVD<150> SKX_EXT_B_BGA1-IC,TBD    I15 @BASEBOARD_FAB2_LIB.BASEBOARD_FAB2(SCH_1):PAGE36

TP_CPU0_RSVD_151 @BASEBOARD_FAB2_LIB.BASEBOARD_FAB2(SCH_1):TP_CPU0_RSVD_151
  U5D1 BD67 RSVD<151> SKX_EXT_B_BGA1-IC,TBD    I15 @BASEBOARD_FAB2_LIB.BASEBOARD_FAB2(SCH_1):PAGE36

TP_CPU0_RSVD_152 @BASEBOARD_FAB2_LIB.BASEBOARD_FAB2(SCH_1):TP_CPU0_RSVD_152
  U5D1 BD65 RSVD<152> SKX_EXT_B_BGA1-IC,TBD    I15 @BASEBOARD_FAB2_LIB.BASEBOARD_FAB2(SCH_1):PAGE36

TP_CPU0_RSVD_154 @BASEBOARD_FAB2_LIB.BASEBOARD_FAB2(SCH_1):TP_CPU0_RSVD_154
  U5D1 BD19 RSVD<154> SKX_EXT_B_BGA1-IC,TBD    I15 @BASEBOARD_FAB2_LIB.BASEBOARD_FAB2(SCH_1):PAGE36

TP_CPU0_RSVD_155 @BASEBOARD_FAB2_LIB.BASEBOARD_FAB2(SCH_1):TP_CPU0_RSVD_155
  U5D1 BD17 RSVD<155> SKX_EXT_B_BGA1-IC,TBD    I15 @BASEBOARD_FAB2_LIB.BASEBOARD_FAB2(SCH_1):PAGE36

TP_CPU0_RSVD_156 @BASEBOARD_FAB2_LIB.BASEBOARD_FAB2(SCH_1):TP_CPU0_RSVD_156
  U5D1 BC68 RSVD<156> SKX_EXT_B_BGA1-IC,TBD    I15 @BASEBOARD_FAB2_LIB.BASEBOARD_FAB2(SCH_1):PAGE36

TP_CPU0_RSVD_157 @BASEBOARD_FAB2_LIB.BASEBOARD_FAB2(SCH_1):TP_CPU0_RSVD_157
  U5D1 BC66 RSVD<157> SKX_EXT_B_BGA1-IC,TBD    I15 @BASEBOARD_FAB2_LIB.BASEBOARD_FAB2(SCH_1):PAGE36

TP_CPU0_RSVD_158 @BASEBOARD_FAB2_LIB.BASEBOARD_FAB2(SCH_1):TP_CPU0_RSVD_158
  U5D1 BC64 RSVD<158> SKX_EXT_B_BGA1-IC,TBD    I15 @BASEBOARD_FAB2_LIB.BASEBOARD_FAB2(SCH_1):PAGE36

TP_CPU0_RSVD_159 @BASEBOARD_FAB2_LIB.BASEBOARD_FAB2(SCH_1):TP_CPU0_RSVD_159
  U5D1 BC22 RSVD<159> SKX_EXT_B_BGA1-IC,TBD    I15 @BASEBOARD_FAB2_LIB.BASEBOARD_FAB2(SCH_1):PAGE36

TP_CPU0_RSVD_16 @BASEBOARD_FAB2_LIB.BASEBOARD_FAB2(SCH_1):TP_CPU0_RSVD_16
  U5D1 EB85 RSVD<16> SKX_EXT_B_BGA1-IC,TBD   I127 @BASEBOARD_FAB2_LIB.BASEBOARD_FAB2(SCH_1):PAGE39

TP_CPU0_RSVD_160 @BASEBOARD_FAB2_LIB.BASEBOARD_FAB2(SCH_1):TP_CPU0_RSVD_160
  U5D1 BC20 RSVD<160> SKX_EXT_B_BGA1-IC,TBD    I15 @BASEBOARD_FAB2_LIB.BASEBOARD_FAB2(SCH_1):PAGE36

TP_CPU0_RSVD_161 @BASEBOARD_FAB2_LIB.BASEBOARD_FAB2(SCH_1):TP_CPU0_RSVD_161
  U5D1 BC18 RSVD<161> SKX_EXT_B_BGA1-IC,TBD    I15 @BASEBOARD_FAB2_LIB.BASEBOARD_FAB2(SCH_1):PAGE36

TP_CPU0_RSVD_162 @BASEBOARD_FAB2_LIB.BASEBOARD_FAB2(SCH_1):TP_CPU0_RSVD_162
  U5D1 BC14 RSVD<162> SKX_EXT_B_BGA1-IC,TBD    I15 @BASEBOARD_FAB2_LIB.BASEBOARD_FAB2(SCH_1):PAGE36

TP_CPU0_RSVD_163 @BASEBOARD_FAB2_LIB.BASEBOARD_FAB2(SCH_1):TP_CPU0_RSVD_163
  U5D1 BB67 RSVD<163> SKX_EXT_B_BGA1-IC,TBD    I15 @BASEBOARD_FAB2_LIB.BASEBOARD_FAB2(SCH_1):PAGE36

TP_CPU0_RSVD_164 @BASEBOARD_FAB2_LIB.BASEBOARD_FAB2(SCH_1):TP_CPU0_RSVD_164
  U5D1 BB65 RSVD<164> SKX_EXT_B_BGA1-IC,TBD    I15 @BASEBOARD_FAB2_LIB.BASEBOARD_FAB2(SCH_1):PAGE36

TP_CPU0_RSVD_166 @BASEBOARD_FAB2_LIB.BASEBOARD_FAB2(SCH_1):TP_CPU0_RSVD_166
  U5D1 BB21 RSVD<166> SKX_EXT_B_BGA1-IC,TBD    I15 @BASEBOARD_FAB2_LIB.BASEBOARD_FAB2(SCH_1):PAGE36

TP_CPU0_RSVD_167 @BASEBOARD_FAB2_LIB.BASEBOARD_FAB2(SCH_1):TP_CPU0_RSVD_167
  U5D1 BB17 RSVD<167> SKX_EXT_B_BGA1-IC,TBD    I15 @BASEBOARD_FAB2_LIB.BASEBOARD_FAB2(SCH_1):PAGE36

TP_CPU0_RSVD_168 @BASEBOARD_FAB2_LIB.BASEBOARD_FAB2(SCH_1):TP_CPU0_RSVD_168
  U5D1 BB15 RSVD<168> SKX_EXT_B_BGA1-IC,TBD    I15 @BASEBOARD_FAB2_LIB.BASEBOARD_FAB2(SCH_1):PAGE36

TP_CPU0_RSVD_169 @BASEBOARD_FAB2_LIB.BASEBOARD_FAB2(SCH_1):TP_CPU0_RSVD_169
  U5D1 BB13 RSVD<169> SKX_EXT_B_BGA1-IC,TBD    I15 @BASEBOARD_FAB2_LIB.BASEBOARD_FAB2(SCH_1):PAGE36

TP_CPU0_RSVD_17 @BASEBOARD_FAB2_LIB.BASEBOARD_FAB2(SCH_1):TP_CPU0_RSVD_17
  U5D1  EB5 RSVD<17> SKX_EXT_B_BGA1-IC,TBD   I127 @BASEBOARD_FAB2_LIB.BASEBOARD_FAB2(SCH_1):PAGE39

TP_CPU0_RSVD_170 @BASEBOARD_FAB2_LIB.BASEBOARD_FAB2(SCH_1):TP_CPU0_RSVD_170
  U5D1 BA82 RSVD<170> SKX_EXT_B_BGA1-IC,TBD    I15 @BASEBOARD_FAB2_LIB.BASEBOARD_FAB2(SCH_1):PAGE36

TP_CPU0_RSVD_171 @BASEBOARD_FAB2_LIB.BASEBOARD_FAB2(SCH_1):TP_CPU0_RSVD_171
  U5D1 BA78 RSVD<171> SKX_EXT_B_BGA1-IC,TBD    I15 @BASEBOARD_FAB2_LIB.BASEBOARD_FAB2(SCH_1):PAGE36

TP_CPU0_RSVD_172 @BASEBOARD_FAB2_LIB.BASEBOARD_FAB2(SCH_1):TP_CPU0_RSVD_172
  U5D1 BA76 RSVD<172> SKX_EXT_B_BGA1-IC,TBD    I61 @BASEBOARD_FAB2_LIB.BASEBOARD_FAB2(SCH_1):PAGE29

TP_CPU0_RSVD_173 @BASEBOARD_FAB2_LIB.BASEBOARD_FAB2(SCH_1):TP_CPU0_RSVD_173
  U5D1 BA66 RSVD<173> SKX_EXT_B_BGA1-IC,TBD    I61 @BASEBOARD_FAB2_LIB.BASEBOARD_FAB2(SCH_1):PAGE29

TP_CPU0_RSVD_174 @BASEBOARD_FAB2_LIB.BASEBOARD_FAB2(SCH_1):TP_CPU0_RSVD_174
  U5D1 BA64 RSVD<174> SKX_EXT_B_BGA1-IC,TBD    I61 @BASEBOARD_FAB2_LIB.BASEBOARD_FAB2(SCH_1):PAGE29

TP_CPU0_RSVD_175 @BASEBOARD_FAB2_LIB.BASEBOARD_FAB2(SCH_1):TP_CPU0_RSVD_175
  U5D1 BA22 RSVD<175> SKX_EXT_B_BGA1-IC,TBD    I61 @BASEBOARD_FAB2_LIB.BASEBOARD_FAB2(SCH_1):PAGE29

TP_CPU0_RSVD_176 @BASEBOARD_FAB2_LIB.BASEBOARD_FAB2(SCH_1):TP_CPU0_RSVD_176
  U5D1 BA18 RSVD<176> SKX_EXT_B_BGA1-IC,TBD    I61 @BASEBOARD_FAB2_LIB.BASEBOARD_FAB2(SCH_1):PAGE29

TP_CPU0_RSVD_177 @BASEBOARD_FAB2_LIB.BASEBOARD_FAB2(SCH_1):TP_CPU0_RSVD_177
  U5D1 BA16 RSVD<177> SKX_EXT_B_BGA1-IC,TBD    I61 @BASEBOARD_FAB2_LIB.BASEBOARD_FAB2(SCH_1):PAGE29

TP_CPU0_RSVD_178 @BASEBOARD_FAB2_LIB.BASEBOARD_FAB2(SCH_1):TP_CPU0_RSVD_178
  U5D1 BA14 RSVD<178> SKX_EXT_B_BGA1-IC,TBD    I61 @BASEBOARD_FAB2_LIB.BASEBOARD_FAB2(SCH_1):PAGE29

TP_CPU0_RSVD_179 @BASEBOARD_FAB2_LIB.BASEBOARD_FAB2(SCH_1):TP_CPU0_RSVD_179
  U5D1 AY77 RSVD<179> SKX_EXT_B_BGA1-IC,TBD    I61 @BASEBOARD_FAB2_LIB.BASEBOARD_FAB2(SCH_1):PAGE29

TP_CPU0_RSVD_18 @BASEBOARD_FAB2_LIB.BASEBOARD_FAB2(SCH_1):TP_CPU0_RSVD_18
  U5D1  EB3 RSVD<18> SKX_EXT_B_BGA1-IC,TBD   I127 @BASEBOARD_FAB2_LIB.BASEBOARD_FAB2(SCH_1):PAGE39

TP_CPU0_RSVD_180 @BASEBOARD_FAB2_LIB.BASEBOARD_FAB2(SCH_1):TP_CPU0_RSVD_180
  U5D1 AY75 RSVD<180> SKX_EXT_B_BGA1-IC,TBD    I61 @BASEBOARD_FAB2_LIB.BASEBOARD_FAB2(SCH_1):PAGE29

TP_CPU0_RSVD_181 @BASEBOARD_FAB2_LIB.BASEBOARD_FAB2(SCH_1):TP_CPU0_RSVD_181
  U5D1 AY67 RSVD<181> SKX_EXT_B_BGA1-IC,TBD    I61 @BASEBOARD_FAB2_LIB.BASEBOARD_FAB2(SCH_1):PAGE29

TP_CPU0_RSVD_182 @BASEBOARD_FAB2_LIB.BASEBOARD_FAB2(SCH_1):TP_CPU0_RSVD_182
  U5D1 AY65 RSVD<182> SKX_EXT_B_BGA1-IC,TBD    I61 @BASEBOARD_FAB2_LIB.BASEBOARD_FAB2(SCH_1):PAGE29

TP_CPU0_RSVD_183 @BASEBOARD_FAB2_LIB.BASEBOARD_FAB2(SCH_1):TP_CPU0_RSVD_183
  U5D1 AW76 RSVD<183> SKX_EXT_B_BGA1-IC,TBD    I61 @BASEBOARD_FAB2_LIB.BASEBOARD_FAB2(SCH_1):PAGE29

TP_CPU0_RSVD_184 @BASEBOARD_FAB2_LIB.BASEBOARD_FAB2(SCH_1):TP_CPU0_RSVD_184
  U5D1 AW64 RSVD<184> SKX_EXT_B_BGA1-IC,TBD    I61 @BASEBOARD_FAB2_LIB.BASEBOARD_FAB2(SCH_1):PAGE29

TP_CPU0_RSVD_186 @BASEBOARD_FAB2_LIB.BASEBOARD_FAB2(SCH_1):TP_CPU0_RSVD_186
  U5D1 AV77 RSVD<186> SKX_EXT_B_BGA1-IC,TBD    I61 @BASEBOARD_FAB2_LIB.BASEBOARD_FAB2(SCH_1):PAGE29

TP_CPU0_RSVD_189 @BASEBOARD_FAB2_LIB.BASEBOARD_FAB2(SCH_1):TP_CPU0_RSVD_189
  U5D1 AT13 RSVD<189> SKX_EXT_B_BGA1-IC,TBD    I61 @BASEBOARD_FAB2_LIB.BASEBOARD_FAB2(SCH_1):PAGE29

TP_CPU0_RSVD_19 @BASEBOARD_FAB2_LIB.BASEBOARD_FAB2(SCH_1):TP_CPU0_RSVD_19
  U5D1 EA44 RSVD<19> SKX_EXT_B_BGA1-IC,TBD   I127 @BASEBOARD_FAB2_LIB.BASEBOARD_FAB2(SCH_1):PAGE39

TP_CPU0_RSVD_190 @BASEBOARD_FAB2_LIB.BASEBOARD_FAB2(SCH_1):TP_CPU0_RSVD_190
  U5D1 AR62 RSVD<190> SKX_EXT_B_BGA1-IC,TBD    I61 @BASEBOARD_FAB2_LIB.BASEBOARD_FAB2(SCH_1):PAGE29

TP_CPU0_RSVD_194 @BASEBOARD_FAB2_LIB.BASEBOARD_FAB2(SCH_1):TP_CPU0_RSVD_194
  U5D1 AP61 RSVD<194> SKX_EXT_B_BGA1-IC,TBD   I204 @BASEBOARD_FAB2_LIB.BASEBOARD_FAB2(SCH_1):PAGE22

TP_CPU0_RSVD_198 @BASEBOARD_FAB2_LIB.BASEBOARD_FAB2(SCH_1):TP_CPU0_RSVD_198
  U5D1 AN62 RSVD<198> SKX_EXT_B_BGA1-IC,TBD   I204 @BASEBOARD_FAB2_LIB.BASEBOARD_FAB2(SCH_1):PAGE22

TP_CPU0_RSVD_199 @BASEBOARD_FAB2_LIB.BASEBOARD_FAB2(SCH_1):TP_CPU0_RSVD_199
  U5D1 AN60 RSVD<199> SKX_EXT_B_BGA1-IC,TBD   I204 @BASEBOARD_FAB2_LIB.BASEBOARD_FAB2(SCH_1):PAGE22

TP_CPU0_RSVD_2 @BASEBOARD_FAB2_LIB.BASEBOARD_FAB2(SCH_1):TP_CPU0_RSVD_2
  U5D1 EF77 RSVD<2> SKX_EXT_B_BGA1-IC,TBD   I127 @BASEBOARD_FAB2_LIB.BASEBOARD_FAB2(SCH_1):PAGE39

TP_CPU0_RSVD_20 @BASEBOARD_FAB2_LIB.BASEBOARD_FAB2(SCH_1):TP_CPU0_RSVD_20
  U5D1  EA4 RSVD<20> SKX_EXT_B_BGA1-IC,TBD   I127 @BASEBOARD_FAB2_LIB.BASEBOARD_FAB2(SCH_1):PAGE39

TP_CPU0_RSVD_204 @BASEBOARD_FAB2_LIB.BASEBOARD_FAB2(SCH_1):TP_CPU0_RSVD_204
  U5D1 AM61 RSVD<204> SKX_EXT_B_BGA1-IC,TBD   I204 @BASEBOARD_FAB2_LIB.BASEBOARD_FAB2(SCH_1):PAGE22

TP_CPU0_RSVD_205 @BASEBOARD_FAB2_LIB.BASEBOARD_FAB2(SCH_1):TP_CPU0_RSVD_205
  U5D1 AM59 RSVD<205> SKX_EXT_B_BGA1-IC,TBD   I204 @BASEBOARD_FAB2_LIB.BASEBOARD_FAB2(SCH_1):PAGE22

TP_CPU0_RSVD_208 @BASEBOARD_FAB2_LIB.BASEBOARD_FAB2(SCH_1):TP_CPU0_RSVD_208
  U5D1 AM23 RSVD<208> SKX_EXT_B_BGA1-IC,TBD   I204 @BASEBOARD_FAB2_LIB.BASEBOARD_FAB2(SCH_1):PAGE22

TP_CPU0_RSVD_21 @BASEBOARD_FAB2_LIB.BASEBOARD_FAB2(SCH_1):TP_CPU0_RSVD_21
  U5D1  DY3 RSVD<21> SKX_EXT_B_BGA1-IC,TBD   I127 @BASEBOARD_FAB2_LIB.BASEBOARD_FAB2(SCH_1):PAGE39

TP_CPU0_RSVD_210 @BASEBOARD_FAB2_LIB.BASEBOARD_FAB2(SCH_1):TP_CPU0_RSVD_210
  U5D1 AL62 RSVD<210> SKX_EXT_B_BGA1-IC,TBD   I204 @BASEBOARD_FAB2_LIB.BASEBOARD_FAB2(SCH_1):PAGE22

TP_CPU0_RSVD_211 @BASEBOARD_FAB2_LIB.BASEBOARD_FAB2(SCH_1):TP_CPU0_RSVD_211
  U5D1 AL60 RSVD<211> SKX_EXT_B_BGA1-IC,TBD   I204 @BASEBOARD_FAB2_LIB.BASEBOARD_FAB2(SCH_1):PAGE22

TP_CPU0_RSVD_212 @BASEBOARD_FAB2_LIB.BASEBOARD_FAB2(SCH_1):TP_CPU0_RSVD_212
  U5D1 AL58 RSVD<212> SKX_EXT_B_BGA1-IC,TBD   I204 @BASEBOARD_FAB2_LIB.BASEBOARD_FAB2(SCH_1):PAGE22

TP_CPU0_RSVD_214 @BASEBOARD_FAB2_LIB.BASEBOARD_FAB2(SCH_1):TP_CPU0_RSVD_214
  U5D1 AL22 RSVD<214> SKX_EXT_B_BGA1-IC,TBD   I204 @BASEBOARD_FAB2_LIB.BASEBOARD_FAB2(SCH_1):PAGE22

TP_CPU0_RSVD_216 @BASEBOARD_FAB2_LIB.BASEBOARD_FAB2(SCH_1):TP_CPU0_RSVD_216
  U5D1 AK69 RSVD<216> SKX_EXT_B_BGA1-IC,TBD   I204 @BASEBOARD_FAB2_LIB.BASEBOARD_FAB2(SCH_1):PAGE22

TP_CPU0_RSVD_217 @BASEBOARD_FAB2_LIB.BASEBOARD_FAB2(SCH_1):TP_CPU0_RSVD_217
  U5D1 AK61 RSVD<217> SKX_EXT_B_BGA1-IC,TBD   I204 @BASEBOARD_FAB2_LIB.BASEBOARD_FAB2(SCH_1):PAGE22

TP_CPU0_RSVD_218 @BASEBOARD_FAB2_LIB.BASEBOARD_FAB2(SCH_1):TP_CPU0_RSVD_218
  U5D1 AK59 RSVD<218> SKX_EXT_B_BGA1-IC,TBD   I204 @BASEBOARD_FAB2_LIB.BASEBOARD_FAB2(SCH_1):PAGE22

TP_CPU0_RSVD_219 @BASEBOARD_FAB2_LIB.BASEBOARD_FAB2(SCH_1):TP_CPU0_RSVD_219
  U5D1 AK57 RSVD<219> SKX_EXT_B_BGA1-IC,TBD   I204 @BASEBOARD_FAB2_LIB.BASEBOARD_FAB2(SCH_1):PAGE22

TP_CPU0_RSVD_22 @BASEBOARD_FAB2_LIB.BASEBOARD_FAB2(SCH_1):TP_CPU0_RSVD_22
  U5D1 DW46 RSVD<22> SKX_EXT_B_BGA1-IC,TBD   I127 @BASEBOARD_FAB2_LIB.BASEBOARD_FAB2(SCH_1):PAGE39

TP_CPU0_RSVD_222 @BASEBOARD_FAB2_LIB.BASEBOARD_FAB2(SCH_1):TP_CPU0_RSVD_222
  U5D1 AJ70 RSVD<222> SKX_EXT_B_BGA1-IC,TBD   I204 @BASEBOARD_FAB2_LIB.BASEBOARD_FAB2(SCH_1):PAGE22

TP_CPU0_RSVD_223 @BASEBOARD_FAB2_LIB.BASEBOARD_FAB2(SCH_1):TP_CPU0_RSVD_223
  U5D1 AJ62 RSVD<223> SKX_EXT_B_BGA1-IC,TBD   I204 @BASEBOARD_FAB2_LIB.BASEBOARD_FAB2(SCH_1):PAGE22

TP_CPU0_RSVD_224 @BASEBOARD_FAB2_LIB.BASEBOARD_FAB2(SCH_1):TP_CPU0_RSVD_224
  U5D1 AJ60 RSVD<224> SKX_EXT_B_BGA1-IC,TBD   I204 @BASEBOARD_FAB2_LIB.BASEBOARD_FAB2(SCH_1):PAGE22

TP_CPU0_RSVD_225 @BASEBOARD_FAB2_LIB.BASEBOARD_FAB2(SCH_1):TP_CPU0_RSVD_225
  U5D1 AJ58 RSVD<225> SKX_EXT_B_BGA1-IC,TBD   I204 @BASEBOARD_FAB2_LIB.BASEBOARD_FAB2(SCH_1):PAGE22

TP_CPU0_RSVD_226 @BASEBOARD_FAB2_LIB.BASEBOARD_FAB2(SCH_1):TP_CPU0_RSVD_226
  U5D1 AJ56 RSVD<226> SKX_EXT_B_BGA1-IC,TBD   I204 @BASEBOARD_FAB2_LIB.BASEBOARD_FAB2(SCH_1):PAGE22

TP_CPU0_RSVD_227 @BASEBOARD_FAB2_LIB.BASEBOARD_FAB2(SCH_1):TP_CPU0_RSVD_227
  U5D1 AJ20 RSVD<227> SKX_EXT_B_BGA1-IC,TBD   I204 @BASEBOARD_FAB2_LIB.BASEBOARD_FAB2(SCH_1):PAGE22

TP_CPU0_RSVD_228 @BASEBOARD_FAB2_LIB.BASEBOARD_FAB2(SCH_1):TP_CPU0_RSVD_228
  U5D1 AH73 RSVD<228> SKX_EXT_B_BGA1-IC,TBD   I204 @BASEBOARD_FAB2_LIB.BASEBOARD_FAB2(SCH_1):PAGE22

TP_CPU0_RSVD_229 @BASEBOARD_FAB2_LIB.BASEBOARD_FAB2(SCH_1):TP_CPU0_RSVD_229
  U5D1 AH71 RSVD<229> SKX_EXT_B_BGA1-IC,TBD   I204 @BASEBOARD_FAB2_LIB.BASEBOARD_FAB2(SCH_1):PAGE22

TP_CPU0_RSVD_23 @BASEBOARD_FAB2_LIB.BASEBOARD_FAB2(SCH_1):TP_CPU0_RSVD_23
  U5D1 DW44 RSVD<23> SKX_EXT_B_BGA1-IC,TBD   I127 @BASEBOARD_FAB2_LIB.BASEBOARD_FAB2(SCH_1):PAGE39

TP_CPU0_RSVD_230 @BASEBOARD_FAB2_LIB.BASEBOARD_FAB2(SCH_1):TP_CPU0_RSVD_230
  U5D1 AH57 RSVD<230> SKX_EXT_B_BGA1-IC,TBD   I204 @BASEBOARD_FAB2_LIB.BASEBOARD_FAB2(SCH_1):PAGE22

TP_CPU0_RSVD_231 @BASEBOARD_FAB2_LIB.BASEBOARD_FAB2(SCH_1):TP_CPU0_RSVD_231
  U5D1 AH55 RSVD<231> SKX_EXT_B_BGA1-IC,TBD   I204 @BASEBOARD_FAB2_LIB.BASEBOARD_FAB2(SCH_1):PAGE22

TP_CPU0_RSVD_232 @BASEBOARD_FAB2_LIB.BASEBOARD_FAB2(SCH_1):TP_CPU0_RSVD_232
  U5D1 AH19 RSVD<232> SKX_EXT_B_BGA1-IC,TBD   I204 @BASEBOARD_FAB2_LIB.BASEBOARD_FAB2(SCH_1):PAGE22

TP_CPU0_RSVD_233 @BASEBOARD_FAB2_LIB.BASEBOARD_FAB2(SCH_1):TP_CPU0_RSVD_233
  U5D1 AH15 RSVD<233> SKX_EXT_B_BGA1-IC,TBD   I204 @BASEBOARD_FAB2_LIB.BASEBOARD_FAB2(SCH_1):PAGE22

TP_CPU0_RSVD_234 @BASEBOARD_FAB2_LIB.BASEBOARD_FAB2(SCH_1):TP_CPU0_RSVD_234
  U5D1 AG72 RSVD<234> SKX_EXT_B_BGA1-IC,TBD   I204 @BASEBOARD_FAB2_LIB.BASEBOARD_FAB2(SCH_1):PAGE22

TP_CPU0_RSVD_235 @BASEBOARD_FAB2_LIB.BASEBOARD_FAB2(SCH_1):TP_CPU0_RSVD_235
  U5D1 AG56 RSVD<235> SKX_EXT_B_BGA1-IC,TBD   I204 @BASEBOARD_FAB2_LIB.BASEBOARD_FAB2(SCH_1):PAGE22

TP_CPU0_RSVD_236 @BASEBOARD_FAB2_LIB.BASEBOARD_FAB2(SCH_1):TP_CPU0_RSVD_236
  U5D1 AG54 RSVD<236> SKX_EXT_B_BGA1-IC,TBD   I204 @BASEBOARD_FAB2_LIB.BASEBOARD_FAB2(SCH_1):PAGE22

TP_CPU0_RSVD_237 @BASEBOARD_FAB2_LIB.BASEBOARD_FAB2(SCH_1):TP_CPU0_RSVD_237
  U5D1 AG52 RSVD<237> SKX_EXT_B_BGA1-IC,TBD   I204 @BASEBOARD_FAB2_LIB.BASEBOARD_FAB2(SCH_1):PAGE22

TP_CPU0_RSVD_238 @BASEBOARD_FAB2_LIB.BASEBOARD_FAB2(SCH_1):TP_CPU0_RSVD_238
  U5D1 AG50 RSVD<238> SKX_EXT_B_BGA1-IC,TBD   I204 @BASEBOARD_FAB2_LIB.BASEBOARD_FAB2(SCH_1):PAGE22

TP_CPU0_RSVD_239 @BASEBOARD_FAB2_LIB.BASEBOARD_FAB2(SCH_1):TP_CPU0_RSVD_239
  U5D1 AG48 RSVD<239> SKX_EXT_B_BGA1-IC,TBD   I204 @BASEBOARD_FAB2_LIB.BASEBOARD_FAB2(SCH_1):PAGE22

TP_CPU0_RSVD_24 @BASEBOARD_FAB2_LIB.BASEBOARD_FAB2(SCH_1):TP_CPU0_RSVD_24
  U5D1 DV71 RSVD<24> SKX_EXT_B_BGA1-IC,TBD   I127 @BASEBOARD_FAB2_LIB.BASEBOARD_FAB2(SCH_1):PAGE39

TP_CPU0_RSVD_240 @BASEBOARD_FAB2_LIB.BASEBOARD_FAB2(SCH_1):TP_CPU0_RSVD_240
  U5D1 AG20 RSVD<240> SKX_EXT_B_BGA1-IC,TBD   I204 @BASEBOARD_FAB2_LIB.BASEBOARD_FAB2(SCH_1):PAGE22

TP_CPU0_RSVD_241 @BASEBOARD_FAB2_LIB.BASEBOARD_FAB2(SCH_1):TP_CPU0_RSVD_241
  U5D1 AF71 RSVD<241> SKX_EXT_B_BGA1-IC,TBD   I204 @BASEBOARD_FAB2_LIB.BASEBOARD_FAB2(SCH_1):PAGE22

TP_CPU0_RSVD_242 @BASEBOARD_FAB2_LIB.BASEBOARD_FAB2(SCH_1):TP_CPU0_RSVD_242
  U5D1 AF53 RSVD<242> SKX_EXT_B_BGA1-IC,TBD   I204 @BASEBOARD_FAB2_LIB.BASEBOARD_FAB2(SCH_1):PAGE22

TP_CPU0_RSVD_243 @BASEBOARD_FAB2_LIB.BASEBOARD_FAB2(SCH_1):TP_CPU0_RSVD_243
  U5D1 AF51 RSVD<243> SKX_EXT_B_BGA1-IC,TBD   I204 @BASEBOARD_FAB2_LIB.BASEBOARD_FAB2(SCH_1):PAGE22

TP_CPU0_RSVD_244 @BASEBOARD_FAB2_LIB.BASEBOARD_FAB2(SCH_1):TP_CPU0_RSVD_244
  U5D1 AF49 RSVD<244> SKX_EXT_B_BGA1-IC,TBD   I204 @BASEBOARD_FAB2_LIB.BASEBOARD_FAB2(SCH_1):PAGE22

TP_CPU0_RSVD_245 @BASEBOARD_FAB2_LIB.BASEBOARD_FAB2(SCH_1):TP_CPU0_RSVD_245
  U5D1 AF47 RSVD<245> SKX_EXT_B_BGA1-IC,TBD   I204 @BASEBOARD_FAB2_LIB.BASEBOARD_FAB2(SCH_1):PAGE22

TP_CPU0_RSVD_246 @BASEBOARD_FAB2_LIB.BASEBOARD_FAB2(SCH_1):TP_CPU0_RSVD_246
  U5D1 AF19 RSVD<246> SKX_EXT_B_BGA1-IC,TBD   I204 @BASEBOARD_FAB2_LIB.BASEBOARD_FAB2(SCH_1):PAGE22

TP_CPU0_RSVD_247 @BASEBOARD_FAB2_LIB.BASEBOARD_FAB2(SCH_1):TP_CPU0_RSVD_247
  U5D1 AE72 RSVD<247> SKX_EXT_B_BGA1-IC,TBD   I204 @BASEBOARD_FAB2_LIB.BASEBOARD_FAB2(SCH_1):PAGE22

TP_CPU0_RSVD_248 @BASEBOARD_FAB2_LIB.BASEBOARD_FAB2(SCH_1):TP_CPU0_RSVD_248
  U5D1 AE52 RSVD<248> SKX_EXT_B_BGA1-IC,TBD   I204 @BASEBOARD_FAB2_LIB.BASEBOARD_FAB2(SCH_1):PAGE22

TP_CPU0_RSVD_249 @BASEBOARD_FAB2_LIB.BASEBOARD_FAB2(SCH_1):TP_CPU0_RSVD_249
  U5D1 AE50 RSVD<249> SKX_EXT_B_BGA1-IC,TBD   I204 @BASEBOARD_FAB2_LIB.BASEBOARD_FAB2(SCH_1):PAGE22

TP_CPU0_RSVD_25 @BASEBOARD_FAB2_LIB.BASEBOARD_FAB2(SCH_1):TP_CPU0_RSVD_25
  U5D1 DV61 RSVD<25> SKX_EXT_B_BGA1-IC,TBD   I127 @BASEBOARD_FAB2_LIB.BASEBOARD_FAB2(SCH_1):PAGE39

TP_CPU0_RSVD_250 @BASEBOARD_FAB2_LIB.BASEBOARD_FAB2(SCH_1):TP_CPU0_RSVD_250
  U5D1 AE48 RSVD<250> SKX_EXT_B_BGA1-IC,TBD   I204 @BASEBOARD_FAB2_LIB.BASEBOARD_FAB2(SCH_1):PAGE22

TP_CPU0_RSVD_251 @BASEBOARD_FAB2_LIB.BASEBOARD_FAB2(SCH_1):TP_CPU0_RSVD_251
  U5D1 AE46 RSVD<251> SKX_EXT_B_BGA1-IC,TBD   I204 @BASEBOARD_FAB2_LIB.BASEBOARD_FAB2(SCH_1):PAGE22

TP_CPU0_RSVD_252 @BASEBOARD_FAB2_LIB.BASEBOARD_FAB2(SCH_1):TP_CPU0_RSVD_252
  U5D1 AD51 RSVD<252> SKX_EXT_B_BGA1-IC,TBD   I204 @BASEBOARD_FAB2_LIB.BASEBOARD_FAB2(SCH_1):PAGE22

TP_CPU0_RSVD_253 @BASEBOARD_FAB2_LIB.BASEBOARD_FAB2(SCH_1):TP_CPU0_RSVD_253
  U5D1 AD49 RSVD<253> SKX_EXT_B_BGA1-IC,TBD   I204 @BASEBOARD_FAB2_LIB.BASEBOARD_FAB2(SCH_1):PAGE22

TP_CPU0_RSVD_254 @BASEBOARD_FAB2_LIB.BASEBOARD_FAB2(SCH_1):TP_CPU0_RSVD_254
  U5D1 AD47 RSVD<254> SKX_EXT_B_BGA1-IC,TBD   I204 @BASEBOARD_FAB2_LIB.BASEBOARD_FAB2(SCH_1):PAGE22

TP_CPU0_RSVD_255 @BASEBOARD_FAB2_LIB.BASEBOARD_FAB2(SCH_1):TP_CPU0_RSVD_255
  U5D1 AY83 RSVD<255> SKX_EXT_B_BGA1-IC,TBD    I15 @BASEBOARD_FAB2_LIB.BASEBOARD_FAB2(SCH_1):PAGE36

TP_CPU0_RSVD_256 @BASEBOARD_FAB2_LIB.BASEBOARD_FAB2(SCH_1):TP_CPU0_RSVD_256
  U5D1  Y65 RSVD<256> SKX_EXT_B_BGA1-IC,TBD   I204 @BASEBOARD_FAB2_LIB.BASEBOARD_FAB2(SCH_1):PAGE22

TP_CPU0_RSVD_258 @BASEBOARD_FAB2_LIB.BASEBOARD_FAB2(SCH_1):TP_CPU0_RSVD_258
  U5D1  W66 RSVD<258> SKX_EXT_B_BGA1-IC,TBD   I204 @BASEBOARD_FAB2_LIB.BASEBOARD_FAB2(SCH_1):PAGE22

TP_CPU0_RSVD_259 @BASEBOARD_FAB2_LIB.BASEBOARD_FAB2(SCH_1):TP_CPU0_RSVD_259
  U5D1  V67 RSVD<259> SKX_EXT_B_BGA1-IC,TBD   I204 @BASEBOARD_FAB2_LIB.BASEBOARD_FAB2(SCH_1):PAGE22

TP_CPU0_RSVD_26 @BASEBOARD_FAB2_LIB.BASEBOARD_FAB2(SCH_1):TP_CPU0_RSVD_26
  U5D1 DU44 RSVD<26> SKX_EXT_B_BGA1-IC,TBD   I127 @BASEBOARD_FAB2_LIB.BASEBOARD_FAB2(SCH_1):PAGE39

TP_CPU0_RSVD_260 @BASEBOARD_FAB2_LIB.BASEBOARD_FAB2(SCH_1):TP_CPU0_RSVD_260
  U5D1  V65 RSVD<260> SKX_EXT_B_BGA1-IC,TBD   I204 @BASEBOARD_FAB2_LIB.BASEBOARD_FAB2(SCH_1):PAGE22

TP_CPU0_RSVD_261 @BASEBOARD_FAB2_LIB.BASEBOARD_FAB2(SCH_1):TP_CPU0_RSVD_261
  U5D1  U66 RSVD<261> SKX_EXT_B_BGA1-IC,TBD   I204 @BASEBOARD_FAB2_LIB.BASEBOARD_FAB2(SCH_1):PAGE22

TP_CPU0_RSVD_262 @BASEBOARD_FAB2_LIB.BASEBOARD_FAB2(SCH_1):TP_CPU0_RSVD_262
  U5D1  T67 RSVD<262> SKX_EXT_B_BGA1-IC,TBD   I204 @BASEBOARD_FAB2_LIB.BASEBOARD_FAB2(SCH_1):PAGE22

TP_CPU0_RSVD_263 @BASEBOARD_FAB2_LIB.BASEBOARD_FAB2(SCH_1):TP_CPU0_RSVD_263
  U5D1  R66 RSVD<263> SKX_EXT_B_BGA1-IC,TBD   I204 @BASEBOARD_FAB2_LIB.BASEBOARD_FAB2(SCH_1):PAGE22

TP_CPU0_RSVD_264 @BASEBOARD_FAB2_LIB.BASEBOARD_FAB2(SCH_1):TP_CPU0_RSVD_264
  U5D1  R62 RSVD<264> SKX_EXT_B_BGA1-IC,TBD   I204 @BASEBOARD_FAB2_LIB.BASEBOARD_FAB2(SCH_1):PAGE22

TP_CPU0_RSVD_265 @BASEBOARD_FAB2_LIB.BASEBOARD_FAB2(SCH_1):TP_CPU0_RSVD_265
  U5D1  P65 RSVD<265> SKX_EXT_B_BGA1-IC,TBD   I204 @BASEBOARD_FAB2_LIB.BASEBOARD_FAB2(SCH_1):PAGE22

TP_CPU0_RSVD_266 @BASEBOARD_FAB2_LIB.BASEBOARD_FAB2(SCH_1):TP_CPU0_RSVD_266
  U5D1  M63 RSVD<266> SKX_EXT_B_BGA1-IC,TBD   I204 @BASEBOARD_FAB2_LIB.BASEBOARD_FAB2(SCH_1):PAGE22

TP_CPU0_RSVD_267 @BASEBOARD_FAB2_LIB.BASEBOARD_FAB2(SCH_1):TP_CPU0_RSVD_267
  U5D1  K61 RSVD<267> SKX_EXT_B_BGA1-IC,TBD   I204 @BASEBOARD_FAB2_LIB.BASEBOARD_FAB2(SCH_1):PAGE22

TP_CPU0_RSVD_268 @BASEBOARD_FAB2_LIB.BASEBOARD_FAB2(SCH_1):TP_CPU0_RSVD_268
  U5D1  J62 RSVD<268> SKX_EXT_B_BGA1-IC,TBD   I204 @BASEBOARD_FAB2_LIB.BASEBOARD_FAB2(SCH_1):PAGE22

TP_CPU0_RSVD_269 @BASEBOARD_FAB2_LIB.BASEBOARD_FAB2(SCH_1):TP_CPU0_RSVD_269
  U5D1  J46 RSVD<269> SKX_EXT_B_BGA1-IC,TBD   I204 @BASEBOARD_FAB2_LIB.BASEBOARD_FAB2(SCH_1):PAGE22

TP_CPU0_RSVD_27 @BASEBOARD_FAB2_LIB.BASEBOARD_FAB2(SCH_1):TP_CPU0_RSVD_27
  U5D1 DT71 RSVD<27> SKX_EXT_B_BGA1-IC,TBD   I127 @BASEBOARD_FAB2_LIB.BASEBOARD_FAB2(SCH_1):PAGE39

TP_CPU0_RSVD_270 @BASEBOARD_FAB2_LIB.BASEBOARD_FAB2(SCH_1):TP_CPU0_RSVD_270
  U5D1  H85 RSVD<270> SKX_EXT_B_BGA1-IC,TBD   I204 @BASEBOARD_FAB2_LIB.BASEBOARD_FAB2(SCH_1):PAGE22

TP_CPU0_RSVD_271 @BASEBOARD_FAB2_LIB.BASEBOARD_FAB2(SCH_1):TP_CPU0_RSVD_271
  U5D1  H83 RSVD<271> SKX_EXT_B_BGA1-IC,TBD   I204 @BASEBOARD_FAB2_LIB.BASEBOARD_FAB2(SCH_1):PAGE22

TP_CPU0_RSVD_272 @BASEBOARD_FAB2_LIB.BASEBOARD_FAB2(SCH_1):TP_CPU0_RSVD_272
  U5D1   H1 RSVD<272> SKX_EXT_B_BGA1-IC,TBD   I204 @BASEBOARD_FAB2_LIB.BASEBOARD_FAB2(SCH_1):PAGE22

TP_CPU0_RSVD_273 @BASEBOARD_FAB2_LIB.BASEBOARD_FAB2(SCH_1):TP_CPU0_RSVD_273
  U5D1  G84 RSVD<273> SKX_EXT_B_BGA1-IC,TBD   I204 @BASEBOARD_FAB2_LIB.BASEBOARD_FAB2(SCH_1):PAGE22

TP_CPU0_RSVD_274 @BASEBOARD_FAB2_LIB.BASEBOARD_FAB2(SCH_1):TP_CPU0_RSVD_274
  U5D1  G64 RSVD<274> SKX_EXT_B_BGA1-IC,TBD   I204 @BASEBOARD_FAB2_LIB.BASEBOARD_FAB2(SCH_1):PAGE22

TP_CPU0_RSVD_275 @BASEBOARD_FAB2_LIB.BASEBOARD_FAB2(SCH_1):TP_CPU0_RSVD_275
  U5D1   G2 RSVD<275> SKX_EXT_B_BGA1-IC,TBD   I204 @BASEBOARD_FAB2_LIB.BASEBOARD_FAB2(SCH_1):PAGE22

TP_CPU0_RSVD_276 @BASEBOARD_FAB2_LIB.BASEBOARD_FAB2(SCH_1):TP_CPU0_RSVD_276
  U5D1  F83 RSVD<276> SKX_EXT_B_BGA1-IC,TBD   I204 @BASEBOARD_FAB2_LIB.BASEBOARD_FAB2(SCH_1):PAGE22

TP_CPU0_RSVD_277 @BASEBOARD_FAB2_LIB.BASEBOARD_FAB2(SCH_1):TP_CPU0_RSVD_277
  U5D1  F65 RSVD<277> SKX_EXT_B_BGA1-IC,TBD   I204 @BASEBOARD_FAB2_LIB.BASEBOARD_FAB2(SCH_1):PAGE22

TP_CPU0_RSVD_278 @BASEBOARD_FAB2_LIB.BASEBOARD_FAB2(SCH_1):TP_CPU0_RSVD_278
  U5D1  F23 RSVD<278> SKX_EXT_B_BGA1-IC,TBD   I204 @BASEBOARD_FAB2_LIB.BASEBOARD_FAB2(SCH_1):PAGE22

TP_CPU0_RSVD_279 @BASEBOARD_FAB2_LIB.BASEBOARD_FAB2(SCH_1):TP_CPU0_RSVD_279
  U5D1   F3 RSVD<279> SKX_EXT_B_BGA1-IC,TBD   I204 @BASEBOARD_FAB2_LIB.BASEBOARD_FAB2(SCH_1):PAGE22

TP_CPU0_RSVD_28 @BASEBOARD_FAB2_LIB.BASEBOARD_FAB2(SCH_1):TP_CPU0_RSVD_28
  U5D1 DR44 RSVD<28> SKX_EXT_B_BGA1-IC,TBD   I127 @BASEBOARD_FAB2_LIB.BASEBOARD_FAB2(SCH_1):PAGE39

TP_CPU0_RSVD_280 @BASEBOARD_FAB2_LIB.BASEBOARD_FAB2(SCH_1):TP_CPU0_RSVD_280
  U5D1  E84 RSVD<280> SKX_EXT_B_BGA1-IC,TBD   I204 @BASEBOARD_FAB2_LIB.BASEBOARD_FAB2(SCH_1):PAGE22

TP_CPU0_RSVD_281 @BASEBOARD_FAB2_LIB.BASEBOARD_FAB2(SCH_1):TP_CPU0_RSVD_281
  U5D1  E24 RSVD<281> SKX_EXT_B_BGA1-IC,TBD   I204 @BASEBOARD_FAB2_LIB.BASEBOARD_FAB2(SCH_1):PAGE22

TP_CPU0_RSVD_282 @BASEBOARD_FAB2_LIB.BASEBOARD_FAB2(SCH_1):TP_CPU0_RSVD_282
  U5D1   E4 RSVD<282> SKX_EXT_B_BGA1-IC,TBD   I204 @BASEBOARD_FAB2_LIB.BASEBOARD_FAB2(SCH_1):PAGE22

TP_CPU0_RSVD_283 @BASEBOARD_FAB2_LIB.BASEBOARD_FAB2(SCH_1):TP_CPU0_RSVD_283
  U5D1   E2 RSVD<283> SKX_EXT_B_BGA1-IC,TBD   I204 @BASEBOARD_FAB2_LIB.BASEBOARD_FAB2(SCH_1):PAGE22

TP_CPU0_RSVD_284 @BASEBOARD_FAB2_LIB.BASEBOARD_FAB2(SCH_1):TP_CPU0_RSVD_284
  U5D1  D83 RSVD<284> SKX_EXT_B_BGA1-IC,TBD   I204 @BASEBOARD_FAB2_LIB.BASEBOARD_FAB2(SCH_1):PAGE22

TP_CPU0_RSVD_285 @BASEBOARD_FAB2_LIB.BASEBOARD_FAB2(SCH_1):TP_CPU0_RSVD_285
  U5D1  D65 RSVD<285> SKX_EXT_B_BGA1-IC,TBD   I204 @BASEBOARD_FAB2_LIB.BASEBOARD_FAB2(SCH_1):PAGE22

TP_CPU0_RSVD_286 @BASEBOARD_FAB2_LIB.BASEBOARD_FAB2(SCH_1):TP_CPU0_RSVD_286
  U5D1  D17 RSVD<286> SKX_EXT_B_BGA1-IC,TBD   I204 @BASEBOARD_FAB2_LIB.BASEBOARD_FAB2(SCH_1):PAGE22

TP_CPU0_RSVD_287 @BASEBOARD_FAB2_LIB.BASEBOARD_FAB2(SCH_1):TP_CPU0_RSVD_287
  U5D1   D5 RSVD<287> SKX_EXT_B_BGA1-IC,TBD   I204 @BASEBOARD_FAB2_LIB.BASEBOARD_FAB2(SCH_1):PAGE22

TP_CPU0_RSVD_288 @BASEBOARD_FAB2_LIB.BASEBOARD_FAB2(SCH_1):TP_CPU0_RSVD_288
  U5D1  C82 RSVD<288> SKX_EXT_B_BGA1-IC,TBD   I204 @BASEBOARD_FAB2_LIB.BASEBOARD_FAB2(SCH_1):PAGE22

TP_CPU0_RSVD_289 @BASEBOARD_FAB2_LIB.BASEBOARD_FAB2(SCH_1):TP_CPU0_RSVD_289
  U5D1  C24 RSVD<289> SKX_EXT_B_BGA1-IC,TBD   I204 @BASEBOARD_FAB2_LIB.BASEBOARD_FAB2(SCH_1):PAGE22

TP_CPU0_RSVD_29 @BASEBOARD_FAB2_LIB.BASEBOARD_FAB2(SCH_1):TP_CPU0_RSVD_29
  U5D1 DP65 RSVD<29> SKX_EXT_B_BGA1-IC,TBD   I127 @BASEBOARD_FAB2_LIB.BASEBOARD_FAB2(SCH_1):PAGE39

TP_CPU0_RSVD_290 @BASEBOARD_FAB2_LIB.BASEBOARD_FAB2(SCH_1):TP_CPU0_RSVD_290
  U5D1  C18 RSVD<290> SKX_EXT_B_BGA1-IC,TBD   I204 @BASEBOARD_FAB2_LIB.BASEBOARD_FAB2(SCH_1):PAGE22

TP_CPU0_RSVD_291 @BASEBOARD_FAB2_LIB.BASEBOARD_FAB2(SCH_1):TP_CPU0_RSVD_291
  U5D1   C6 RSVD<291> SKX_EXT_B_BGA1-IC,TBD   I204 @BASEBOARD_FAB2_LIB.BASEBOARD_FAB2(SCH_1):PAGE22

TP_CPU0_RSVD_292 @BASEBOARD_FAB2_LIB.BASEBOARD_FAB2(SCH_1):TP_CPU0_RSVD_292
  U5D1  B81 RSVD<292> SKX_EXT_B_BGA1-IC,TBD   I204 @BASEBOARD_FAB2_LIB.BASEBOARD_FAB2(SCH_1):PAGE22

TP_CPU0_RSVD_293 @BASEBOARD_FAB2_LIB.BASEBOARD_FAB2(SCH_1):TP_CPU0_RSVD_293
  U5D1  B77 RSVD<293> SKX_EXT_B_BGA1-IC,TBD   I204 @BASEBOARD_FAB2_LIB.BASEBOARD_FAB2(SCH_1):PAGE22

TP_CPU0_RSVD_298 @BASEBOARD_FAB2_LIB.BASEBOARD_FAB2(SCH_1):TP_CPU0_RSVD_298
  U5D1   B7 RSVD<298> SKX_EXT_B_BGA1-IC,TBD   I204 @BASEBOARD_FAB2_LIB.BASEBOARD_FAB2(SCH_1):PAGE22

TP_CPU0_RSVD_299 @BASEBOARD_FAB2_LIB.BASEBOARD_FAB2(SCH_1):TP_CPU0_RSVD_299
  U5D1   B3 RSVD<299> SKX_EXT_B_BGA1-IC,TBD   I204 @BASEBOARD_FAB2_LIB.BASEBOARD_FAB2(SCH_1):PAGE22

TP_CPU0_RSVD_3 @BASEBOARD_FAB2_LIB.BASEBOARD_FAB2(SCH_1):TP_CPU0_RSVD_3
  U5D1 EF47 RSVD<3> SKX_EXT_B_BGA1-IC,TBD   I127 @BASEBOARD_FAB2_LIB.BASEBOARD_FAB2(SCH_1):PAGE39

TP_CPU0_RSVD_30 @BASEBOARD_FAB2_LIB.BASEBOARD_FAB2(SCH_1):TP_CPU0_RSVD_30
  U5D1 DP17 RSVD<30> SKX_EXT_B_BGA1-IC,TBD   I127 @BASEBOARD_FAB2_LIB.BASEBOARD_FAB2(SCH_1):PAGE39

TP_CPU0_RSVD_300 @BASEBOARD_FAB2_LIB.BASEBOARD_FAB2(SCH_1):TP_CPU0_RSVD_300
  U5D1  A24 RSVD<300> SKX_EXT_B_BGA1-IC,TBD   I204 @BASEBOARD_FAB2_LIB.BASEBOARD_FAB2(SCH_1):PAGE22

TP_CPU0_RSVD_303 @BASEBOARD_FAB2_LIB.BASEBOARD_FAB2(SCH_1):TP_CPU0_RSVD_303
  U5D1   A6 RSVD<303> SKX_EXT_B_BGA1-IC,TBD   I204 @BASEBOARD_FAB2_LIB.BASEBOARD_FAB2(SCH_1):PAGE22

TP_CPU0_RSVD_304 @BASEBOARD_FAB2_LIB.BASEBOARD_FAB2(SCH_1):TP_CPU0_RSVD_304
  U5D1   A4 RSVD<304> SKX_EXT_B_BGA1-IC,TBD   I204 @BASEBOARD_FAB2_LIB.BASEBOARD_FAB2(SCH_1):PAGE22

TP_CPU0_RSVD_31 @BASEBOARD_FAB2_LIB.BASEBOARD_FAB2(SCH_1):TP_CPU0_RSVD_31
  U5D1 DN66 RSVD<31> SKX_EXT_B_BGA1-IC,TBD   I127 @BASEBOARD_FAB2_LIB.BASEBOARD_FAB2(SCH_1):PAGE39

TP_CPU0_RSVD_32 @BASEBOARD_FAB2_LIB.BASEBOARD_FAB2(SCH_1):TP_CPU0_RSVD_32
  U5D1 DN62 RSVD<32> SKX_EXT_B_BGA1-IC,TBD   I127 @BASEBOARD_FAB2_LIB.BASEBOARD_FAB2(SCH_1):PAGE39

TP_CPU0_RSVD_33 @BASEBOARD_FAB2_LIB.BASEBOARD_FAB2(SCH_1):TP_CPU0_RSVD_33
  U5D1 DM67 RSVD<33> SKX_EXT_B_BGA1-IC,TBD   I127 @BASEBOARD_FAB2_LIB.BASEBOARD_FAB2(SCH_1):PAGE39

TP_CPU0_RSVD_34 @BASEBOARD_FAB2_LIB.BASEBOARD_FAB2(SCH_1):TP_CPU0_RSVD_34
  U5D1 DL66 RSVD<34> SKX_EXT_B_BGA1-IC,TBD   I127 @BASEBOARD_FAB2_LIB.BASEBOARD_FAB2(SCH_1):PAGE39

TP_CPU0_RSVD_35 @BASEBOARD_FAB2_LIB.BASEBOARD_FAB2(SCH_1):TP_CPU0_RSVD_35
  U5D1 DL38 RSVD<35> SKX_EXT_B_BGA1-IC,TBD   I127 @BASEBOARD_FAB2_LIB.BASEBOARD_FAB2(SCH_1):PAGE39

TP_CPU0_RSVD_36 @BASEBOARD_FAB2_LIB.BASEBOARD_FAB2(SCH_1):TP_CPU0_RSVD_36
  U5D1 DK67 RSVD<36> SKX_EXT_B_BGA1-IC,TBD   I127 @BASEBOARD_FAB2_LIB.BASEBOARD_FAB2(SCH_1):PAGE39

TP_CPU0_RSVD_37 @BASEBOARD_FAB2_LIB.BASEBOARD_FAB2(SCH_1):TP_CPU0_RSVD_37
  U5D1 DK65 RSVD<37> SKX_EXT_B_BGA1-IC,TBD   I127 @BASEBOARD_FAB2_LIB.BASEBOARD_FAB2(SCH_1):PAGE39

TP_CPU0_RSVD_38 @BASEBOARD_FAB2_LIB.BASEBOARD_FAB2(SCH_1):TP_CPU0_RSVD_38
  U5D1 DK37 RSVD<38> SKX_EXT_B_BGA1-IC,TBD   I127 @BASEBOARD_FAB2_LIB.BASEBOARD_FAB2(SCH_1):PAGE39

TP_CPU0_RSVD_39 @BASEBOARD_FAB2_LIB.BASEBOARD_FAB2(SCH_1):TP_CPU0_RSVD_39
  U5D1 DK15 RSVD<39> SKX_EXT_B_BGA1-IC,TBD   I127 @BASEBOARD_FAB2_LIB.BASEBOARD_FAB2(SCH_1):PAGE39

TP_CPU0_RSVD_4 @BASEBOARD_FAB2_LIB.BASEBOARD_FAB2(SCH_1):TP_CPU0_RSVD_4
  U5D1 EE84 RSVD<4> SKX_EXT_B_BGA1-IC,TBD   I127 @BASEBOARD_FAB2_LIB.BASEBOARD_FAB2(SCH_1):PAGE39

TP_CPU0_RSVD_40 @BASEBOARD_FAB2_LIB.BASEBOARD_FAB2(SCH_1):TP_CPU0_RSVD_40
  U5D1 DJ66 RSVD<40> SKX_EXT_B_BGA1-IC,TBD   I127 @BASEBOARD_FAB2_LIB.BASEBOARD_FAB2(SCH_1):PAGE39

TP_CPU0_RSVD_41 @BASEBOARD_FAB2_LIB.BASEBOARD_FAB2(SCH_1):TP_CPU0_RSVD_41
  U5D1 DJ36 RSVD<41> SKX_EXT_B_BGA1-IC,TBD   I127 @BASEBOARD_FAB2_LIB.BASEBOARD_FAB2(SCH_1):PAGE39

TP_CPU0_RSVD_42 @BASEBOARD_FAB2_LIB.BASEBOARD_FAB2(SCH_1):TP_CPU0_RSVD_42
  U5D1 DH65 RSVD<42> SKX_EXT_B_BGA1-IC,TBD   I127 @BASEBOARD_FAB2_LIB.BASEBOARD_FAB2(SCH_1):PAGE39

TP_CPU0_RSVD_43 @BASEBOARD_FAB2_LIB.BASEBOARD_FAB2(SCH_1):TP_CPU0_RSVD_43
  U5D1 DG64 RSVD<43> SKX_EXT_B_BGA1-IC,TBD   I127 @BASEBOARD_FAB2_LIB.BASEBOARD_FAB2(SCH_1):PAGE39

TP_CPU0_RSVD_44 @BASEBOARD_FAB2_LIB.BASEBOARD_FAB2(SCH_1):TP_CPU0_RSVD_44
  U5D1 DG36 RSVD<44> SKX_EXT_B_BGA1-IC,TBD   I127 @BASEBOARD_FAB2_LIB.BASEBOARD_FAB2(SCH_1):PAGE39

TP_CPU0_RSVD_45 @BASEBOARD_FAB2_LIB.BASEBOARD_FAB2(SCH_1):TP_CPU0_RSVD_45
  U5D1 DD51 RSVD<45> SKX_EXT_B_BGA1-IC,TBD   I127 @BASEBOARD_FAB2_LIB.BASEBOARD_FAB2(SCH_1):PAGE39

TP_CPU0_RSVD_46 @BASEBOARD_FAB2_LIB.BASEBOARD_FAB2(SCH_1):TP_CPU0_RSVD_46
  U5D1 DC52 RSVD<46> SKX_EXT_B_BGA1-IC,TBD   I127 @BASEBOARD_FAB2_LIB.BASEBOARD_FAB2(SCH_1):PAGE39

TP_CPU0_RSVD_47 @BASEBOARD_FAB2_LIB.BASEBOARD_FAB2(SCH_1):TP_CPU0_RSVD_47
  U5D1 DC46 RSVD<47> SKX_EXT_B_BGA1-IC,TBD   I127 @BASEBOARD_FAB2_LIB.BASEBOARD_FAB2(SCH_1):PAGE39

TP_CPU0_RSVD_48 @BASEBOARD_FAB2_LIB.BASEBOARD_FAB2(SCH_1):TP_CPU0_RSVD_48
  U5D1 DA56 RSVD<48> SKX_EXT_B_BGA1-IC,TBD   I127 @BASEBOARD_FAB2_LIB.BASEBOARD_FAB2(SCH_1):PAGE39

TP_CPU0_RSVD_49 @BASEBOARD_FAB2_LIB.BASEBOARD_FAB2(SCH_1):TP_CPU0_RSVD_49
  U5D1 DA54 RSVD<49> SKX_EXT_B_BGA1-IC,TBD   I127 @BASEBOARD_FAB2_LIB.BASEBOARD_FAB2(SCH_1):PAGE39

TP_CPU0_RSVD_5 @BASEBOARD_FAB2_LIB.BASEBOARD_FAB2(SCH_1):TP_CPU0_RSVD_5
  U5D1 EE82 RSVD<5> SKX_EXT_B_BGA1-IC,TBD   I127 @BASEBOARD_FAB2_LIB.BASEBOARD_FAB2(SCH_1):PAGE39

TP_CPU0_RSVD_50 @BASEBOARD_FAB2_LIB.BASEBOARD_FAB2(SCH_1):TP_CPU0_RSVD_50
  U5D1 DA52 RSVD<50> SKX_EXT_B_BGA1-IC,TBD   I127 @BASEBOARD_FAB2_LIB.BASEBOARD_FAB2(SCH_1):PAGE39

TP_CPU0_RSVD_51 @BASEBOARD_FAB2_LIB.BASEBOARD_FAB2(SCH_1):TP_CPU0_RSVD_51
  U5D1 DA40 RSVD<51> SKX_EXT_B_BGA1-IC,TBD   I127 @BASEBOARD_FAB2_LIB.BASEBOARD_FAB2(SCH_1):PAGE39

TP_CPU0_RSVD_53 @BASEBOARD_FAB2_LIB.BASEBOARD_FAB2(SCH_1):TP_CPU0_RSVD_53
  U5D1 CY73 RSVD<53> SKX_EXT_B_BGA1-IC,TBD   I127 @BASEBOARD_FAB2_LIB.BASEBOARD_FAB2(SCH_1):PAGE39

TP_CPU0_RSVD_54 @BASEBOARD_FAB2_LIB.BASEBOARD_FAB2(SCH_1):TP_CPU0_RSVD_54
  U5D1 CY63 RSVD<54> SKX_EXT_B_BGA1-IC,TBD   I127 @BASEBOARD_FAB2_LIB.BASEBOARD_FAB2(SCH_1):PAGE39

TP_CPU0_RSVD_55 @BASEBOARD_FAB2_LIB.BASEBOARD_FAB2(SCH_1):TP_CPU0_RSVD_55
  U5D1 CY57 RSVD<55> SKX_EXT_B_BGA1-IC,TBD   I127 @BASEBOARD_FAB2_LIB.BASEBOARD_FAB2(SCH_1):PAGE39

TP_CPU0_RSVD_56 @BASEBOARD_FAB2_LIB.BASEBOARD_FAB2(SCH_1):TP_CPU0_RSVD_56
  U5D1 CY53 RSVD<56> SKX_EXT_B_BGA1-IC,TBD   I127 @BASEBOARD_FAB2_LIB.BASEBOARD_FAB2(SCH_1):PAGE39

TP_CPU0_RSVD_57 @BASEBOARD_FAB2_LIB.BASEBOARD_FAB2(SCH_1):TP_CPU0_RSVD_57
  U5D1 CY39 RSVD<57> SKX_EXT_B_BGA1-IC,TBD   I127 @BASEBOARD_FAB2_LIB.BASEBOARD_FAB2(SCH_1):PAGE39

TP_CPU0_RSVD_59 @BASEBOARD_FAB2_LIB.BASEBOARD_FAB2(SCH_1):TP_CPU0_RSVD_59
  U5D1 CY23 RSVD<59> SKX_EXT_B_BGA1-IC,TBD   I127 @BASEBOARD_FAB2_LIB.BASEBOARD_FAB2(SCH_1):PAGE39

TP_CPU0_RSVD_6 @BASEBOARD_FAB2_LIB.BASEBOARD_FAB2(SCH_1):TP_CPU0_RSVD_6
  U5D1  EE6 RSVD<6> SKX_EXT_B_BGA1-IC,TBD   I127 @BASEBOARD_FAB2_LIB.BASEBOARD_FAB2(SCH_1):PAGE39

TP_CPU0_RSVD_60 @BASEBOARD_FAB2_LIB.BASEBOARD_FAB2(SCH_1):TP_CPU0_RSVD_60
  U5D1 CW62 RSVD<60> SKX_EXT_B_BGA1-IC,TBD   I127 @BASEBOARD_FAB2_LIB.BASEBOARD_FAB2(SCH_1):PAGE39

TP_CPU0_RSVD_61 @BASEBOARD_FAB2_LIB.BASEBOARD_FAB2(SCH_1):TP_CPU0_RSVD_61
  U5D1 CW60 RSVD<61> SKX_EXT_B_BGA1-IC,TBD   I127 @BASEBOARD_FAB2_LIB.BASEBOARD_FAB2(SCH_1):PAGE39

TP_CPU0_RSVD_64 @BASEBOARD_FAB2_LIB.BASEBOARD_FAB2(SCH_1):TP_CPU0_RSVD_64
  U5D1 CV69 RSVD<64> SKX_EXT_B_BGA1-IC,TBD   I127 @BASEBOARD_FAB2_LIB.BASEBOARD_FAB2(SCH_1):PAGE39

TP_CPU0_RSVD_66 @BASEBOARD_FAB2_LIB.BASEBOARD_FAB2(SCH_1):TP_CPU0_RSVD_66
  U5D1 CU60 RSVD<66> SKX_EXT_B_BGA1-IC,TBD   I127 @BASEBOARD_FAB2_LIB.BASEBOARD_FAB2(SCH_1):PAGE39

TP_CPU0_RSVD_67 @BASEBOARD_FAB2_LIB.BASEBOARD_FAB2(SCH_1):TP_CPU0_RSVD_67
  U5D1  CU6 RSVD<67> SKX_EXT_B_BGA1-IC,TBD   I127 @BASEBOARD_FAB2_LIB.BASEBOARD_FAB2(SCH_1):PAGE39

TP_CPU0_RSVD_69 @BASEBOARD_FAB2_LIB.BASEBOARD_FAB2(SCH_1):TP_CPU0_RSVD_69
  U5D1 CT69 RSVD<69> SKX_EXT_B_BGA1-IC,TBD   I127 @BASEBOARD_FAB2_LIB.BASEBOARD_FAB2(SCH_1):PAGE39

TP_CPU0_RSVD_7 @BASEBOARD_FAB2_LIB.BASEBOARD_FAB2(SCH_1):TP_CPU0_RSVD_7
  U5D1 EE46 RSVD<7> SKX_EXT_B_BGA1-IC,TBD   I127 @BASEBOARD_FAB2_LIB.BASEBOARD_FAB2(SCH_1):PAGE39

TP_CPU0_RSVD_70 @BASEBOARD_FAB2_LIB.BASEBOARD_FAB2(SCH_1):TP_CPU0_RSVD_70
  U5D1  CT5 RSVD<70> SKX_EXT_B_BGA1-IC,TBD   I127 @BASEBOARD_FAB2_LIB.BASEBOARD_FAB2(SCH_1):PAGE39

TP_CPU0_RSVD_72 @BASEBOARD_FAB2_LIB.BASEBOARD_FAB2(SCH_1):TP_CPU0_RSVD_72
  U5D1 CR60 RSVD<72> SKX_EXT_B_BGA1-IC,TBD   I127 @BASEBOARD_FAB2_LIB.BASEBOARD_FAB2(SCH_1):PAGE39

TP_CPU0_RSVD_73 @BASEBOARD_FAB2_LIB.BASEBOARD_FAB2(SCH_1):TP_CPU0_RSVD_73
  U5D1 CP31 RSVD<73> SKX_EXT_B_BGA1-IC,TBD   I127 @BASEBOARD_FAB2_LIB.BASEBOARD_FAB2(SCH_1):PAGE39

TP_CPU0_RSVD_8 @BASEBOARD_FAB2_LIB.BASEBOARD_FAB2(SCH_1):TP_CPU0_RSVD_8
  U5D1 EE16 RSVD<8> SKX_EXT_B_BGA1-IC,TBD   I127 @BASEBOARD_FAB2_LIB.BASEBOARD_FAB2(SCH_1):PAGE39

TP_CPU0_RSVD_82 @BASEBOARD_FAB2_LIB.BASEBOARD_FAB2(SCH_1):TP_CPU0_RSVD_82
  U5D1 CK77 RSVD<82> SKX_EXT_B_BGA1-IC,TBD    I16 @BASEBOARD_FAB2_LIB.BASEBOARD_FAB2(SCH_1):PAGE36

TP_CPU0_RSVD_85 @BASEBOARD_FAB2_LIB.BASEBOARD_FAB2(SCH_1):TP_CPU0_RSVD_85
  U5D1 CK19 RSVD<85> SKX_EXT_B_BGA1-IC,TBD    I16 @BASEBOARD_FAB2_LIB.BASEBOARD_FAB2(SCH_1):PAGE36

TP_CPU0_RSVD_9 @BASEBOARD_FAB2_LIB.BASEBOARD_FAB2(SCH_1):TP_CPU0_RSVD_9
  U5D1 ED83 RSVD<9> SKX_EXT_B_BGA1-IC,TBD   I127 @BASEBOARD_FAB2_LIB.BASEBOARD_FAB2(SCH_1):PAGE39

TP_CPU0_RSVD_90 @BASEBOARD_FAB2_LIB.BASEBOARD_FAB2(SCH_1):TP_CPU0_RSVD_90
  U5D1 CH77 RSVD<90> SKX_EXT_B_BGA1-IC,TBD    I16 @BASEBOARD_FAB2_LIB.BASEBOARD_FAB2(SCH_1):PAGE36

TP_CPU0_RSVD_91 @BASEBOARD_FAB2_LIB.BASEBOARD_FAB2(SCH_1):TP_CPU0_RSVD_91
  U5D1 CH25 RSVD<91> SKX_EXT_B_BGA1-IC,TBD    I16 @BASEBOARD_FAB2_LIB.BASEBOARD_FAB2(SCH_1):PAGE36

TP_CPU0_RSVD_94 @BASEBOARD_FAB2_LIB.BASEBOARD_FAB2(SCH_1):TP_CPU0_RSVD_94
  U5D1 CG82 RSVD<94> SKX_EXT_B_BGA1-IC,TBD    I15 @BASEBOARD_FAB2_LIB.BASEBOARD_FAB2(SCH_1):PAGE36

TP_CPU0_RSVD_95 @BASEBOARD_FAB2_LIB.BASEBOARD_FAB2(SCH_1):TP_CPU0_RSVD_95
  U5D1 CG78 RSVD<95> SKX_EXT_B_BGA1-IC,TBD    I15 @BASEBOARD_FAB2_LIB.BASEBOARD_FAB2(SCH_1):PAGE36

TP_CPU0_RSVD_97 @BASEBOARD_FAB2_LIB.BASEBOARD_FAB2(SCH_1):TP_CPU0_RSVD_97
  U5D1 CG24 RSVD<97> SKX_EXT_B_BGA1-IC,TBD    I15 @BASEBOARD_FAB2_LIB.BASEBOARD_FAB2(SCH_1):PAGE36

TP_CPU0_RSVD_99 @BASEBOARD_FAB2_LIB.BASEBOARD_FAB2(SCH_1):TP_CPU0_RSVD_99
  U5D1 CG10 RSVD<99> SKX_EXT_B_BGA1-IC,TBD    I15 @BASEBOARD_FAB2_LIB.BASEBOARD_FAB2(SCH_1):PAGE36

TP_CPU0_RSVD_TEST_11 @BASEBOARD_FAB2_LIB.BASEBOARD_FAB2(SCH_1):TP_CPU0_RSVD_TEST_11
  U5D1 AY13 TEST_11 SKX_EXT_B_BGA1-IC,TBD   I204 @BASEBOARD_FAB2_LIB.BASEBOARD_FAB2(SCH_1):PAGE22

TP_CPU0_RSVD_TEST_3 @BASEBOARD_FAB2_LIB.BASEBOARD_FAB2(SCH_1):TP_CPU0_RSVD_TEST_3
  U5D1 AM13 TEST_3 SKX_EXT_B_BGA1-IC,TBD   I204 @BASEBOARD_FAB2_LIB.BASEBOARD_FAB2(SCH_1):PAGE22

TP_CPU0_RSVD_TEST_4 @BASEBOARD_FAB2_LIB.BASEBOARD_FAB2(SCH_1):TP_CPU0_RSVD_TEST_4
  U5D1 AN12 TEST_4 SKX_EXT_B_BGA1-IC,TBD   I204 @BASEBOARD_FAB2_LIB.BASEBOARD_FAB2(SCH_1):PAGE22

TP_CPU0_RSVD_TEST_5 @BASEBOARD_FAB2_LIB.BASEBOARD_FAB2(SCH_1):TP_CPU0_RSVD_TEST_5
  U5D1 AN14 TEST_5 SKX_EXT_B_BGA1-IC,TBD   I204 @BASEBOARD_FAB2_LIB.BASEBOARD_FAB2(SCH_1):PAGE22

TP_CPU0_SOCKET_ID_2 @BASEBOARD_FAB2_LIB.BASEBOARD_FAB2(SCH_1):TP_CPU0_SOCKET_ID_2
  U5D1 AU20 SOCKET_ID<2> SKX_EXT_B_BGA1-IC,TBD   I259 @BASEBOARD_FAB2_LIB.BASEBOARD_FAB2(SCH_1):PAGE21

TP_CPU0_TEST_10 @BASEBOARD_FAB2_LIB.BASEBOARD_FAB2(SCH_1):TP_CPU0_TEST_10
  U5D1 AW22 TEST_10 SKX_EXT_B_BGA1-IC,TBD    I16 @BASEBOARD_FAB2_LIB.BASEBOARD_FAB2(SCH_1):PAGE36

TP_CPU0_TEST_6 @BASEBOARD_FAB2_LIB.BASEBOARD_FAB2(SCH_1):TP_CPU0_TEST_6
  U5D1 AR16 TEST_6 SKX_EXT_B_BGA1-IC,TBD    I16 @BASEBOARD_FAB2_LIB.BASEBOARD_FAB2(SCH_1):PAGE36

TP_CPU0_TEST_7 @BASEBOARD_FAB2_LIB.BASEBOARD_FAB2(SCH_1):TP_CPU0_TEST_7
  U5D1 AU18 TEST_7 SKX_EXT_B_BGA1-IC,TBD    I16 @BASEBOARD_FAB2_LIB.BASEBOARD_FAB2(SCH_1):PAGE36

TP_CPU0_TEST_8 @BASEBOARD_FAB2_LIB.BASEBOARD_FAB2(SCH_1):TP_CPU0_TEST_8
  U5D1 AW16 TEST_8 SKX_EXT_B_BGA1-IC,TBD    I16 @BASEBOARD_FAB2_LIB.BASEBOARD_FAB2(SCH_1):PAGE36

TP_CPU0_TEST_9 @BASEBOARD_FAB2_LIB.BASEBOARD_FAB2(SCH_1):TP_CPU0_TEST_9
  U5D1 AW20 TEST_9 SKX_EXT_B_BGA1-IC,TBD    I16 @BASEBOARD_FAB2_LIB.BASEBOARD_FAB2(SCH_1):PAGE36

TP_CPU0_UPI2_RSVD_CA12 @BASEBOARD_FAB2_LIB.BASEBOARD_FAB2(SCH_1):TP_CPU0_UPI2_RSVD_CA12
  U5D1 DP21 UPI2_TX_DP<0> SKX_EXT_B_BGA1-IC,TBD     I3 @BASEBOARD_FAB2_LIB.BASEBOARD_FAB2(SCH_1):PAGE35

TP_CPU0_UPI2_RSVD_CB11 @BASEBOARD_FAB2_LIB.BASEBOARD_FAB2(SCH_1):TP_CPU0_UPI2_RSVD_CB11
  U5D1 DN20 UPI2_TX_DP<1> SKX_EXT_B_BGA1-IC,TBD     I3 @BASEBOARD_FAB2_LIB.BASEBOARD_FAB2(SCH_1):PAGE35

TP_CPU0_UPI2_RSVD_CC10 @BASEBOARD_FAB2_LIB.BASEBOARD_FAB2(SCH_1):TP_CPU0_UPI2_RSVD_CC10
  U5D1 DM21 UPI2_TX_DN<1> SKX_EXT_B_BGA1-IC,TBD     I3 @BASEBOARD_FAB2_LIB.BASEBOARD_FAB2(SCH_1):PAGE35

TP_CPU0_UPI2_RSVD_CC12 @BASEBOARD_FAB2_LIB.BASEBOARD_FAB2(SCH_1):TP_CPU0_UPI2_RSVD_CC12
  U5D1 DT21 UPI2_TX_DN<0> SKX_EXT_B_BGA1-IC,TBD     I3 @BASEBOARD_FAB2_LIB.BASEBOARD_FAB2(SCH_1):PAGE35

TP_CPU0_UPI2_RSVD_CD11 @BASEBOARD_FAB2_LIB.BASEBOARD_FAB2(SCH_1):TP_CPU0_UPI2_RSVD_CD11
  U5D1 DK19 UPI2_TX_DP<2> SKX_EXT_B_BGA1-IC,TBD     I3 @BASEBOARD_FAB2_LIB.BASEBOARD_FAB2(SCH_1):PAGE35

TP_CPU0_UPI2_RSVD_CE12 @BASEBOARD_FAB2_LIB.BASEBOARD_FAB2(SCH_1):TP_CPU0_UPI2_RSVD_CE12
  U5D1 DL20 UPI2_TX_DN<2> SKX_EXT_B_BGA1-IC,TBD     I3 @BASEBOARD_FAB2_LIB.BASEBOARD_FAB2(SCH_1):PAGE35

TP_CPU0_UPI2_RSVD_CF11 @BASEBOARD_FAB2_LIB.BASEBOARD_FAB2(SCH_1):TP_CPU0_UPI2_RSVD_CF11
  U5D1 DJ20 UPI2_TX_DP<3> SKX_EXT_B_BGA1-IC,TBD     I3 @BASEBOARD_FAB2_LIB.BASEBOARD_FAB2(SCH_1):PAGE35

TP_CPU0_UPI2_RSVD_CF13 @BASEBOARD_FAB2_LIB.BASEBOARD_FAB2(SCH_1):TP_CPU0_UPI2_RSVD_CF13
  U5D1 DH19 UPI2_TX_DN<4> SKX_EXT_B_BGA1-IC,TBD     I3 @BASEBOARD_FAB2_LIB.BASEBOARD_FAB2(SCH_1):PAGE35

TP_CPU0_UPI2_RSVD_CG12 @BASEBOARD_FAB2_LIB.BASEBOARD_FAB2(SCH_1):TP_CPU0_UPI2_RSVD_CG12
  U5D1 DJ18 UPI2_TX_DP<4> SKX_EXT_B_BGA1-IC,TBD     I3 @BASEBOARD_FAB2_LIB.BASEBOARD_FAB2(SCH_1):PAGE35

TP_CPU0_UPI2_RSVD_CH11 @BASEBOARD_FAB2_LIB.BASEBOARD_FAB2(SCH_1):TP_CPU0_UPI2_RSVD_CH11
  U5D1 DG20 UPI2_TX_DN<3> SKX_EXT_B_BGA1-IC,TBD     I3 @BASEBOARD_FAB2_LIB.BASEBOARD_FAB2(SCH_1):PAGE35

TP_CPU0_UPI2_RSVD_CH13 @BASEBOARD_FAB2_LIB.BASEBOARD_FAB2(SCH_1):TP_CPU0_UPI2_RSVD_CH13
  U5D1 DH17 UPI2_TX_DP<5> SKX_EXT_B_BGA1-IC,TBD     I3 @BASEBOARD_FAB2_LIB.BASEBOARD_FAB2(SCH_1):PAGE35

TP_CPU0_UPI2_RSVD_CJ14 @BASEBOARD_FAB2_LIB.BASEBOARD_FAB2(SCH_1):TP_CPU0_UPI2_RSVD_CJ14
  U5D1 DK17 UPI2_TX_DN<5> SKX_EXT_B_BGA1-IC,TBD     I3 @BASEBOARD_FAB2_LIB.BASEBOARD_FAB2(SCH_1):PAGE35

TP_CPU0_UPI2_RSVD_CK13 @BASEBOARD_FAB2_LIB.BASEBOARD_FAB2(SCH_1):TP_CPU0_UPI2_RSVD_CK13
  U5D1 DF17 UPI2_TX_DP<6> SKX_EXT_B_BGA1-IC,TBD     I3 @BASEBOARD_FAB2_LIB.BASEBOARD_FAB2(SCH_1):PAGE35

TP_CPU0_UPI2_RSVD_CM13 @BASEBOARD_FAB2_LIB.BASEBOARD_FAB2(SCH_1):TP_CPU0_UPI2_RSVD_CM13
  U5D1 DG18 UPI2_TX_DN<6> SKX_EXT_B_BGA1-IC,TBD     I3 @BASEBOARD_FAB2_LIB.BASEBOARD_FAB2(SCH_1):PAGE35

TP_CPU0_UPI2_RSVD_CR14 @BASEBOARD_FAB2_LIB.BASEBOARD_FAB2(SCH_1):TP_CPU0_UPI2_RSVD_CR14
  U5D1 DE16 UPI2_TX_DP<7> SKX_EXT_B_BGA1-IC,TBD     I3 @BASEBOARD_FAB2_LIB.BASEBOARD_FAB2(SCH_1):PAGE35

TP_CPU0_UPI2_RSVD_CU14 @BASEBOARD_FAB2_LIB.BASEBOARD_FAB2(SCH_1):TP_CPU0_UPI2_RSVD_CU14
  U5D1 DD17 UPI2_TX_DN<7> SKX_EXT_B_BGA1-IC,TBD     I3 @BASEBOARD_FAB2_LIB.BASEBOARD_FAB2(SCH_1):PAGE35

TP_CPU0_UPI2_RSVD_CV13 @BASEBOARD_FAB2_LIB.BASEBOARD_FAB2(SCH_1):TP_CPU0_UPI2_RSVD_CV13
  U5D1 DD15 UPI2_TX_DP<8> SKX_EXT_B_BGA1-IC,TBD     I3 @BASEBOARD_FAB2_LIB.BASEBOARD_FAB2(SCH_1):PAGE35

TP_CPU0_UPI2_RSVD_CW14 @BASEBOARD_FAB2_LIB.BASEBOARD_FAB2(SCH_1):TP_CPU0_UPI2_RSVD_CW14
  U5D1 DF15 UPI2_TX_DN<8> SKX_EXT_B_BGA1-IC,TBD     I3 @BASEBOARD_FAB2_LIB.BASEBOARD_FAB2(SCH_1):PAGE35

TP_CPU0_UPI2_RSVD_CW16 @BASEBOARD_FAB2_LIB.BASEBOARD_FAB2(SCH_1):TP_CPU0_UPI2_RSVD_CW16
  U5D1 DB15 UPI2_TX_DP<9> SKX_EXT_B_BGA1-IC,TBD     I3 @BASEBOARD_FAB2_LIB.BASEBOARD_FAB2(SCH_1):PAGE35

TP_CPU0_UPI2_RSVD_DA16 @BASEBOARD_FAB2_LIB.BASEBOARD_FAB2(SCH_1):TP_CPU0_UPI2_RSVD_DA16
  U5D1 DC16 UPI2_TX_DN<9> SKX_EXT_B_BGA1-IC,TBD     I3 @BASEBOARD_FAB2_LIB.BASEBOARD_FAB2(SCH_1):PAGE35

TP_CPU0_UPI2_RSVD_DB15 @BASEBOARD_FAB2_LIB.BASEBOARD_FAB2(SCH_1):TP_CPU0_UPI2_RSVD_DB15
  U5D1 CW16 UPI2_TX_DP<10> SKX_EXT_B_BGA1-IC,TBD     I3 @BASEBOARD_FAB2_LIB.BASEBOARD_FAB2(SCH_1):PAGE35

TP_CPU0_UPI2_RSVD_DC16 @BASEBOARD_FAB2_LIB.BASEBOARD_FAB2(SCH_1):TP_CPU0_UPI2_RSVD_DC16
  U5D1 DA16 UPI2_TX_DN<10> SKX_EXT_B_BGA1-IC,TBD     I3 @BASEBOARD_FAB2_LIB.BASEBOARD_FAB2(SCH_1):PAGE35

TP_CPU0_UPI2_RSVD_DD15 @BASEBOARD_FAB2_LIB.BASEBOARD_FAB2(SCH_1):TP_CPU0_UPI2_RSVD_DD15
  U5D1 CV13 UPI2_TX_DP<11> SKX_EXT_B_BGA1-IC,TBD     I3 @BASEBOARD_FAB2_LIB.BASEBOARD_FAB2(SCH_1):PAGE35

TP_CPU0_UPI2_RSVD_DD17 @BASEBOARD_FAB2_LIB.BASEBOARD_FAB2(SCH_1):TP_CPU0_UPI2_RSVD_DD17
  U5D1 CU14 UPI2_TX_DN<12> SKX_EXT_B_BGA1-IC,TBD     I3 @BASEBOARD_FAB2_LIB.BASEBOARD_FAB2(SCH_1):PAGE35

TP_CPU0_UPI2_RSVD_DE16 @BASEBOARD_FAB2_LIB.BASEBOARD_FAB2(SCH_1):TP_CPU0_UPI2_RSVD_DE16
  U5D1 CR14 UPI2_TX_DP<12> SKX_EXT_B_BGA1-IC,TBD     I3 @BASEBOARD_FAB2_LIB.BASEBOARD_FAB2(SCH_1):PAGE35

TP_CPU0_UPI2_RSVD_DF15 @BASEBOARD_FAB2_LIB.BASEBOARD_FAB2(SCH_1):TP_CPU0_UPI2_RSVD_DF15
  U5D1 CW14 UPI2_TX_DN<11> SKX_EXT_B_BGA1-IC,TBD     I3 @BASEBOARD_FAB2_LIB.BASEBOARD_FAB2(SCH_1):PAGE35

TP_CPU0_UPI2_RSVD_DF17 @BASEBOARD_FAB2_LIB.BASEBOARD_FAB2(SCH_1):TP_CPU0_UPI2_RSVD_DF17
  U5D1 CK13 UPI2_TX_DP<13> SKX_EXT_B_BGA1-IC,TBD     I3 @BASEBOARD_FAB2_LIB.BASEBOARD_FAB2(SCH_1):PAGE35

TP_CPU0_UPI2_RSVD_DG18 @BASEBOARD_FAB2_LIB.BASEBOARD_FAB2(SCH_1):TP_CPU0_UPI2_RSVD_DG18
  U5D1 CM13 UPI2_TX_DN<13> SKX_EXT_B_BGA1-IC,TBD     I3 @BASEBOARD_FAB2_LIB.BASEBOARD_FAB2(SCH_1):PAGE35

TP_CPU0_UPI2_RSVD_DG20 @BASEBOARD_FAB2_LIB.BASEBOARD_FAB2(SCH_1):TP_CPU0_UPI2_RSVD_DG20
  U5D1 CH11 UPI2_TX_DN<16> SKX_EXT_B_BGA1-IC,TBD     I3 @BASEBOARD_FAB2_LIB.BASEBOARD_FAB2(SCH_1):PAGE35

TP_CPU0_UPI2_RSVD_DH17 @BASEBOARD_FAB2_LIB.BASEBOARD_FAB2(SCH_1):TP_CPU0_UPI2_RSVD_DH17
  U5D1 CH13 UPI2_TX_DP<14> SKX_EXT_B_BGA1-IC,TBD     I3 @BASEBOARD_FAB2_LIB.BASEBOARD_FAB2(SCH_1):PAGE35

TP_CPU0_UPI2_RSVD_DH19 @BASEBOARD_FAB2_LIB.BASEBOARD_FAB2(SCH_1):TP_CPU0_UPI2_RSVD_DH19
  U5D1 CF13 UPI2_TX_DN<15> SKX_EXT_B_BGA1-IC,TBD     I3 @BASEBOARD_FAB2_LIB.BASEBOARD_FAB2(SCH_1):PAGE35

TP_CPU0_UPI2_RSVD_DJ18 @BASEBOARD_FAB2_LIB.BASEBOARD_FAB2(SCH_1):TP_CPU0_UPI2_RSVD_DJ18
  U5D1 CG12 UPI2_TX_DP<15> SKX_EXT_B_BGA1-IC,TBD     I3 @BASEBOARD_FAB2_LIB.BASEBOARD_FAB2(SCH_1):PAGE35

TP_CPU0_UPI2_RSVD_DJ20 @BASEBOARD_FAB2_LIB.BASEBOARD_FAB2(SCH_1):TP_CPU0_UPI2_RSVD_DJ20
  U5D1 CF11 UPI2_TX_DP<16> SKX_EXT_B_BGA1-IC,TBD     I3 @BASEBOARD_FAB2_LIB.BASEBOARD_FAB2(SCH_1):PAGE35

TP_CPU0_UPI2_RSVD_DK17 @BASEBOARD_FAB2_LIB.BASEBOARD_FAB2(SCH_1):TP_CPU0_UPI2_RSVD_DK17
  U5D1 CJ14 UPI2_TX_DN<14> SKX_EXT_B_BGA1-IC,TBD     I3 @BASEBOARD_FAB2_LIB.BASEBOARD_FAB2(SCH_1):PAGE35

TP_CPU0_UPI2_RSVD_DK19 @BASEBOARD_FAB2_LIB.BASEBOARD_FAB2(SCH_1):TP_CPU0_UPI2_RSVD_DK19
  U5D1 CD11 UPI2_TX_DP<17> SKX_EXT_B_BGA1-IC,TBD     I3 @BASEBOARD_FAB2_LIB.BASEBOARD_FAB2(SCH_1):PAGE35

TP_CPU0_UPI2_RSVD_DL20 @BASEBOARD_FAB2_LIB.BASEBOARD_FAB2(SCH_1):TP_CPU0_UPI2_RSVD_DL20
  U5D1 CE12 UPI2_TX_DN<17> SKX_EXT_B_BGA1-IC,TBD     I3 @BASEBOARD_FAB2_LIB.BASEBOARD_FAB2(SCH_1):PAGE35

TP_CPU0_UPI2_RSVD_DM21 @BASEBOARD_FAB2_LIB.BASEBOARD_FAB2(SCH_1):TP_CPU0_UPI2_RSVD_DM21
  U5D1 CC10 UPI2_TX_DN<18> SKX_EXT_B_BGA1-IC,TBD     I3 @BASEBOARD_FAB2_LIB.BASEBOARD_FAB2(SCH_1):PAGE35

TP_CPU0_UPI2_RSVD_DN20 @BASEBOARD_FAB2_LIB.BASEBOARD_FAB2(SCH_1):TP_CPU0_UPI2_RSVD_DN20
  U5D1 CB11 UPI2_TX_DP<18> SKX_EXT_B_BGA1-IC,TBD     I3 @BASEBOARD_FAB2_LIB.BASEBOARD_FAB2(SCH_1):PAGE35

TP_CPU0_UPI2_RSVD_DP21 @BASEBOARD_FAB2_LIB.BASEBOARD_FAB2(SCH_1):TP_CPU0_UPI2_RSVD_DP21
  U5D1 CA12 UPI2_TX_DP<19> SKX_EXT_B_BGA1-IC,TBD     I3 @BASEBOARD_FAB2_LIB.BASEBOARD_FAB2(SCH_1):PAGE35

TP_CPU0_UPI2_RSVD_DT21 @BASEBOARD_FAB2_LIB.BASEBOARD_FAB2(SCH_1):TP_CPU0_UPI2_RSVD_DT21
  U5D1 CC12 UPI2_TX_DN<19> SKX_EXT_B_BGA1-IC,TBD     I3 @BASEBOARD_FAB2_LIB.BASEBOARD_FAB2(SCH_1):PAGE35

TP_CPU1_DMI_RX_DN0 @BASEBOARD_FAB2_LIB.BASEBOARD_FAB2(SCH_1):TP_CPU1_DMI_RX_DN0
  U2D1  CK9 DMI_RX_DN<0> SKX_EXT_B_BGA1-IC,TBD    I23 @BASEBOARD_FAB2_LIB.BASEBOARD_FAB2(SCH_1):PAGE63

TP_CPU1_DMI_RX_DN1 @BASEBOARD_FAB2_LIB.BASEBOARD_FAB2(SCH_1):TP_CPU1_DMI_RX_DN1
  U2D1 CM11 DMI_RX_DN<1> SKX_EXT_B_BGA1-IC,TBD    I23 @BASEBOARD_FAB2_LIB.BASEBOARD_FAB2(SCH_1):PAGE63

TP_CPU1_DMI_RX_DN2 @BASEBOARD_FAB2_LIB.BASEBOARD_FAB2(SCH_1):TP_CPU1_DMI_RX_DN2
  U2D1 CR12 DMI_RX_DN<2> SKX_EXT_B_BGA1-IC,TBD    I23 @BASEBOARD_FAB2_LIB.BASEBOARD_FAB2(SCH_1):PAGE63

TP_CPU1_DMI_RX_DN3 @BASEBOARD_FAB2_LIB.BASEBOARD_FAB2(SCH_1):TP_CPU1_DMI_RX_DN3
  U2D1 CT11 DMI_RX_DN<3> SKX_EXT_B_BGA1-IC,TBD    I23 @BASEBOARD_FAB2_LIB.BASEBOARD_FAB2(SCH_1):PAGE63

TP_CPU1_DMI_RX_DP0 @BASEBOARD_FAB2_LIB.BASEBOARD_FAB2(SCH_1):TP_CPU1_DMI_RX_DP0
  U2D1 CL10 DMI_RX_DP<0> SKX_EXT_B_BGA1-IC,TBD    I23 @BASEBOARD_FAB2_LIB.BASEBOARD_FAB2(SCH_1):PAGE63

TP_CPU1_DMI_RX_DP1 @BASEBOARD_FAB2_LIB.BASEBOARD_FAB2(SCH_1):TP_CPU1_DMI_RX_DP1
  U2D1 CN10 DMI_RX_DP<1> SKX_EXT_B_BGA1-IC,TBD    I23 @BASEBOARD_FAB2_LIB.BASEBOARD_FAB2(SCH_1):PAGE63

TP_CPU1_DMI_RX_DP2 @BASEBOARD_FAB2_LIB.BASEBOARD_FAB2(SCH_1):TP_CPU1_DMI_RX_DP2
  U2D1 CP11 DMI_RX_DP<2> SKX_EXT_B_BGA1-IC,TBD    I23 @BASEBOARD_FAB2_LIB.BASEBOARD_FAB2(SCH_1):PAGE63

TP_CPU1_DMI_RX_DP3 @BASEBOARD_FAB2_LIB.BASEBOARD_FAB2(SCH_1):TP_CPU1_DMI_RX_DP3
  U2D1 CV11 DMI_RX_DP<3> SKX_EXT_B_BGA1-IC,TBD    I23 @BASEBOARD_FAB2_LIB.BASEBOARD_FAB2(SCH_1):PAGE63

TP_CPU1_DMI_TX_DN0 @BASEBOARD_FAB2_LIB.BASEBOARD_FAB2(SCH_1):TP_CPU1_DMI_TX_DN0
  U2D1  CG4 DMI_TX_DN<0> SKX_EXT_B_BGA1-IC,TBD    I23 @BASEBOARD_FAB2_LIB.BASEBOARD_FAB2(SCH_1):PAGE63

TP_CPU1_DMI_TX_DN1 @BASEBOARD_FAB2_LIB.BASEBOARD_FAB2(SCH_1):TP_CPU1_DMI_TX_DN1
  U2D1  CJ4 DMI_TX_DN<1> SKX_EXT_B_BGA1-IC,TBD    I23 @BASEBOARD_FAB2_LIB.BASEBOARD_FAB2(SCH_1):PAGE63

TP_CPU1_DMI_TX_DN2 @BASEBOARD_FAB2_LIB.BASEBOARD_FAB2(SCH_1):TP_CPU1_DMI_TX_DN2
  U2D1  CN4 DMI_TX_DN<2> SKX_EXT_B_BGA1-IC,TBD    I23 @BASEBOARD_FAB2_LIB.BASEBOARD_FAB2(SCH_1):PAGE63

TP_CPU1_DMI_TX_DN3 @BASEBOARD_FAB2_LIB.BASEBOARD_FAB2(SCH_1):TP_CPU1_DMI_TX_DN3
  U2D1  CP5 DMI_TX_DN<3> SKX_EXT_B_BGA1-IC,TBD    I23 @BASEBOARD_FAB2_LIB.BASEBOARD_FAB2(SCH_1):PAGE63

TP_CPU1_DMI_TX_DP0 @BASEBOARD_FAB2_LIB.BASEBOARD_FAB2(SCH_1):TP_CPU1_DMI_TX_DP0
  U2D1  CH5 DMI_TX_DP<0> SKX_EXT_B_BGA1-IC,TBD    I23 @BASEBOARD_FAB2_LIB.BASEBOARD_FAB2(SCH_1):PAGE63

TP_CPU1_DMI_TX_DP1 @BASEBOARD_FAB2_LIB.BASEBOARD_FAB2(SCH_1):TP_CPU1_DMI_TX_DP1
  U2D1  CL4 DMI_TX_DP<1> SKX_EXT_B_BGA1-IC,TBD    I23 @BASEBOARD_FAB2_LIB.BASEBOARD_FAB2(SCH_1):PAGE63

TP_CPU1_DMI_TX_DP2 @BASEBOARD_FAB2_LIB.BASEBOARD_FAB2(SCH_1):TP_CPU1_DMI_TX_DP2
  U2D1  CM3 DMI_TX_DP<2> SKX_EXT_B_BGA1-IC,TBD    I23 @BASEBOARD_FAB2_LIB.BASEBOARD_FAB2(SCH_1):PAGE63

TP_CPU1_DMI_TX_DP3 @BASEBOARD_FAB2_LIB.BASEBOARD_FAB2(SCH_1):TP_CPU1_DMI_TX_DP3
  U2D1  CR4 DMI_TX_DP<3> SKX_EXT_B_BGA1-IC,TBD    I23 @BASEBOARD_FAB2_LIB.BASEBOARD_FAB2(SCH_1):PAGE63

TP_CPU1_KTI2_AMONV @BASEBOARD_FAB2_LIB.BASEBOARD_FAB2(SCH_1):TP_CPU1_KTI2_AMONV
  U2D1 CN22 RSVD<77> SKX_EXT_B_BGA1-IC,TBD   I107 @BASEBOARD_FAB2_LIB.BASEBOARD_FAB2(SCH_1):PAGE73

TP_CPU1_KTI2_DFX_DN @BASEBOARD_FAB2_LIB.BASEBOARD_FAB2(SCH_1):TP_CPU1_KTI2_DFX_DN
  U2D1 CW22 RSVD<63> SKX_EXT_B_BGA1-IC,TBD   I107 @BASEBOARD_FAB2_LIB.BASEBOARD_FAB2(SCH_1):PAGE73

TP_CPU1_NMI @BASEBOARD_FAB2_LIB.BASEBOARD_FAB2(SCH_1):TP_CPU1_NMI
  U2D1 AP11    NMI SKX_EXT_B_BGA1-IC,TBD   I172 @BASEBOARD_FAB2_LIB.BASEBOARD_FAB2(SCH_1):PAGE55

TP_CPU1_PROC_DIS_G_N @BASEBOARD_FAB2_LIB.BASEBOARD_FAB2(SCH_1):TP_CPU1_PROC_DIS_G_N
  U2D1 AB17 PROCDIS_N SKX_EXT_B_BGA1-IC,TBD   I172 @BASEBOARD_FAB2_LIB.BASEBOARD_FAB2(SCH_1):PAGE55

TP_CPU1_RSVD_0 @BASEBOARD_FAB2_LIB.BASEBOARD_FAB2(SCH_1):TP_CPU1_RSVD_0
  U2D1 EF83 RSVD<0> SKX_EXT_B_BGA1-IC,TBD   I107 @BASEBOARD_FAB2_LIB.BASEBOARD_FAB2(SCH_1):PAGE73

TP_CPU1_RSVD_1 @BASEBOARD_FAB2_LIB.BASEBOARD_FAB2(SCH_1):TP_CPU1_RSVD_1
  U2D1 EF81 RSVD<1> SKX_EXT_B_BGA1-IC,TBD   I107 @BASEBOARD_FAB2_LIB.BASEBOARD_FAB2(SCH_1):PAGE73

TP_CPU1_RSVD_10 @BASEBOARD_FAB2_LIB.BASEBOARD_FAB2(SCH_1):TP_CPU1_RSVD_10
  U2D1  ED5 RSVD<10> SKX_EXT_B_BGA1-IC,TBD   I107 @BASEBOARD_FAB2_LIB.BASEBOARD_FAB2(SCH_1):PAGE73

TP_CPU1_RSVD_100 @BASEBOARD_FAB2_LIB.BASEBOARD_FAB2(SCH_1):TP_CPU1_RSVD_100
  U2D1 CF81 RSVD<100> SKX_EXT_B_BGA1-IC,TBD     I9 @BASEBOARD_FAB2_LIB.BASEBOARD_FAB2(SCH_1):PAGE70

TP_CPU1_RSVD_101 @BASEBOARD_FAB2_LIB.BASEBOARD_FAB2(SCH_1):TP_CPU1_RSVD_101
  U2D1 CF79 RSVD<101> SKX_EXT_B_BGA1-IC,TBD     I9 @BASEBOARD_FAB2_LIB.BASEBOARD_FAB2(SCH_1):PAGE70

TP_CPU1_RSVD_105 @BASEBOARD_FAB2_LIB.BASEBOARD_FAB2(SCH_1):TP_CPU1_RSVD_105
  U2D1 CE80 RSVD<105> SKX_EXT_B_BGA1-IC,TBD     I9 @BASEBOARD_FAB2_LIB.BASEBOARD_FAB2(SCH_1):PAGE70

TP_CPU1_RSVD_106 @BASEBOARD_FAB2_LIB.BASEBOARD_FAB2(SCH_1):TP_CPU1_RSVD_106
  U2D1 CE78 RSVD<106> SKX_EXT_B_BGA1-IC,TBD     I9 @BASEBOARD_FAB2_LIB.BASEBOARD_FAB2(SCH_1):PAGE70

TP_CPU1_RSVD_108 @BASEBOARD_FAB2_LIB.BASEBOARD_FAB2(SCH_1):TP_CPU1_RSVD_108
  U2D1 CD25 RSVD<108> SKX_EXT_B_BGA1-IC,TBD     I9 @BASEBOARD_FAB2_LIB.BASEBOARD_FAB2(SCH_1):PAGE70

TP_CPU1_RSVD_11 @BASEBOARD_FAB2_LIB.BASEBOARD_FAB2(SCH_1):TP_CPU1_RSVD_11
  U2D1 ED45 RSVD<11> SKX_EXT_B_BGA1-IC,TBD   I107 @BASEBOARD_FAB2_LIB.BASEBOARD_FAB2(SCH_1):PAGE73

TP_CPU1_RSVD_111 @BASEBOARD_FAB2_LIB.BASEBOARD_FAB2(SCH_1):TP_CPU1_RSVD_111
  U2D1  CC6 RSVD<111> SKX_EXT_B_BGA1-IC,TBD     I9 @BASEBOARD_FAB2_LIB.BASEBOARD_FAB2(SCH_1):PAGE70

TP_CPU1_RSVD_113 @BASEBOARD_FAB2_LIB.BASEBOARD_FAB2(SCH_1):TP_CPU1_RSVD_113
  U2D1  CB5 RSVD<113> SKX_EXT_B_BGA1-IC,TBD     I9 @BASEBOARD_FAB2_LIB.BASEBOARD_FAB2(SCH_1):PAGE70

TP_CPU1_RSVD_114 @BASEBOARD_FAB2_LIB.BASEBOARD_FAB2(SCH_1):TP_CPU1_RSVD_114
  U2D1 CB25 RSVD<114> SKX_EXT_B_BGA1-IC,TBD     I9 @BASEBOARD_FAB2_LIB.BASEBOARD_FAB2(SCH_1):PAGE70

TP_CPU1_RSVD_117 @BASEBOARD_FAB2_LIB.BASEBOARD_FAB2(SCH_1):TP_CPU1_RSVD_117
  U2D1 CA24 RSVD<117> SKX_EXT_B_BGA1-IC,TBD     I9 @BASEBOARD_FAB2_LIB.BASEBOARD_FAB2(SCH_1):PAGE70

TP_CPU1_RSVD_119 @BASEBOARD_FAB2_LIB.BASEBOARD_FAB2(SCH_1):TP_CPU1_RSVD_119
  U2D1 BY25 RSVD<119> SKX_EXT_B_BGA1-IC,TBD     I9 @BASEBOARD_FAB2_LIB.BASEBOARD_FAB2(SCH_1):PAGE70

TP_CPU1_RSVD_12 @BASEBOARD_FAB2_LIB.BASEBOARD_FAB2(SCH_1):TP_CPU1_RSVD_12
  U2D1 EC84 RSVD<12> SKX_EXT_B_BGA1-IC,TBD   I107 @BASEBOARD_FAB2_LIB.BASEBOARD_FAB2(SCH_1):PAGE73

TP_CPU1_RSVD_121 @BASEBOARD_FAB2_LIB.BASEBOARD_FAB2(SCH_1):TP_CPU1_RSVD_121
  U2D1 BW22 RSVD<121> SKX_EXT_B_BGA1-IC,TBD     I9 @BASEBOARD_FAB2_LIB.BASEBOARD_FAB2(SCH_1):PAGE70

TP_CPU1_RSVD_123 @BASEBOARD_FAB2_LIB.BASEBOARD_FAB2(SCH_1):TP_CPU1_RSVD_123
  U2D1 BW10 RSVD<123> SKX_EXT_B_BGA1-IC,TBD     I9 @BASEBOARD_FAB2_LIB.BASEBOARD_FAB2(SCH_1):PAGE70

TP_CPU1_RSVD_124 @BASEBOARD_FAB2_LIB.BASEBOARD_FAB2(SCH_1):TP_CPU1_RSVD_124
  U2D1 BV23 RSVD<124> SKX_EXT_B_BGA1-IC,TBD     I9 @BASEBOARD_FAB2_LIB.BASEBOARD_FAB2(SCH_1):PAGE70

TP_CPU1_RSVD_13 @BASEBOARD_FAB2_LIB.BASEBOARD_FAB2(SCH_1):TP_CPU1_RSVD_13
  U2D1 EC44 RSVD<13> SKX_EXT_B_BGA1-IC,TBD   I107 @BASEBOARD_FAB2_LIB.BASEBOARD_FAB2(SCH_1):PAGE73

TP_CPU1_RSVD_14 @BASEBOARD_FAB2_LIB.BASEBOARD_FAB2(SCH_1):TP_CPU1_RSVD_14
  U2D1  EC4 RSVD<14> SKX_EXT_B_BGA1-IC,TBD   I107 @BASEBOARD_FAB2_LIB.BASEBOARD_FAB2(SCH_1):PAGE73

TP_CPU1_RSVD_144 @BASEBOARD_FAB2_LIB.BASEBOARD_FAB2(SCH_1):TP_CPU1_RSVD_144
  U2D1 BG20 RSVD<144> SKX_EXT_B_BGA1-IC,TBD     I9 @BASEBOARD_FAB2_LIB.BASEBOARD_FAB2(SCH_1):PAGE70

TP_CPU1_RSVD_145 @BASEBOARD_FAB2_LIB.BASEBOARD_FAB2(SCH_1):TP_CPU1_RSVD_145
  U2D1 BG18 RSVD<145> SKX_EXT_B_BGA1-IC,TBD     I9 @BASEBOARD_FAB2_LIB.BASEBOARD_FAB2(SCH_1):PAGE70

TP_CPU1_RSVD_146 @BASEBOARD_FAB2_LIB.BASEBOARD_FAB2(SCH_1):TP_CPU1_RSVD_146
  U2D1 BF21 RSVD<146> SKX_EXT_B_BGA1-IC,TBD     I9 @BASEBOARD_FAB2_LIB.BASEBOARD_FAB2(SCH_1):PAGE70

TP_CPU1_RSVD_147 @BASEBOARD_FAB2_LIB.BASEBOARD_FAB2(SCH_1):TP_CPU1_RSVD_147
  U2D1 BE22 RSVD<147> SKX_EXT_B_BGA1-IC,TBD     I9 @BASEBOARD_FAB2_LIB.BASEBOARD_FAB2(SCH_1):PAGE70

TP_CPU1_RSVD_148 @BASEBOARD_FAB2_LIB.BASEBOARD_FAB2(SCH_1):TP_CPU1_RSVD_148
  U2D1 BE20 RSVD<148> SKX_EXT_B_BGA1-IC,TBD     I9 @BASEBOARD_FAB2_LIB.BASEBOARD_FAB2(SCH_1):PAGE70

TP_CPU1_RSVD_149 @BASEBOARD_FAB2_LIB.BASEBOARD_FAB2(SCH_1):TP_CPU1_RSVD_149
  U2D1 BE18 RSVD<149> SKX_EXT_B_BGA1-IC,TBD     I9 @BASEBOARD_FAB2_LIB.BASEBOARD_FAB2(SCH_1):PAGE70

TP_CPU1_RSVD_15 @BASEBOARD_FAB2_LIB.BASEBOARD_FAB2(SCH_1):TP_CPU1_RSVD_15
  U2D1 EC16 RSVD<15> SKX_EXT_B_BGA1-IC,TBD   I107 @BASEBOARD_FAB2_LIB.BASEBOARD_FAB2(SCH_1):PAGE73

TP_CPU1_RSVD_150 @BASEBOARD_FAB2_LIB.BASEBOARD_FAB2(SCH_1):TP_CPU1_RSVD_150
  U2D1 BD69 RSVD<150> SKX_EXT_B_BGA1-IC,TBD     I9 @BASEBOARD_FAB2_LIB.BASEBOARD_FAB2(SCH_1):PAGE70

TP_CPU1_RSVD_151 @BASEBOARD_FAB2_LIB.BASEBOARD_FAB2(SCH_1):TP_CPU1_RSVD_151
  U2D1 BD67 RSVD<151> SKX_EXT_B_BGA1-IC,TBD     I9 @BASEBOARD_FAB2_LIB.BASEBOARD_FAB2(SCH_1):PAGE70

TP_CPU1_RSVD_152 @BASEBOARD_FAB2_LIB.BASEBOARD_FAB2(SCH_1):TP_CPU1_RSVD_152
  U2D1 BD65 RSVD<152> SKX_EXT_B_BGA1-IC,TBD     I9 @BASEBOARD_FAB2_LIB.BASEBOARD_FAB2(SCH_1):PAGE70

TP_CPU1_RSVD_154 @BASEBOARD_FAB2_LIB.BASEBOARD_FAB2(SCH_1):TP_CPU1_RSVD_154
  U2D1 BD19 RSVD<154> SKX_EXT_B_BGA1-IC,TBD     I9 @BASEBOARD_FAB2_LIB.BASEBOARD_FAB2(SCH_1):PAGE70

TP_CPU1_RSVD_155 @BASEBOARD_FAB2_LIB.BASEBOARD_FAB2(SCH_1):TP_CPU1_RSVD_155
  U2D1 BD17 RSVD<155> SKX_EXT_B_BGA1-IC,TBD     I9 @BASEBOARD_FAB2_LIB.BASEBOARD_FAB2(SCH_1):PAGE70

TP_CPU1_RSVD_156 @BASEBOARD_FAB2_LIB.BASEBOARD_FAB2(SCH_1):TP_CPU1_RSVD_156
  U2D1 BC68 RSVD<156> SKX_EXT_B_BGA1-IC,TBD     I9 @BASEBOARD_FAB2_LIB.BASEBOARD_FAB2(SCH_1):PAGE70

TP_CPU1_RSVD_157 @BASEBOARD_FAB2_LIB.BASEBOARD_FAB2(SCH_1):TP_CPU1_RSVD_157
  U2D1 BC66 RSVD<157> SKX_EXT_B_BGA1-IC,TBD     I9 @BASEBOARD_FAB2_LIB.BASEBOARD_FAB2(SCH_1):PAGE70

TP_CPU1_RSVD_158 @BASEBOARD_FAB2_LIB.BASEBOARD_FAB2(SCH_1):TP_CPU1_RSVD_158
  U2D1 BC64 RSVD<158> SKX_EXT_B_BGA1-IC,TBD     I9 @BASEBOARD_FAB2_LIB.BASEBOARD_FAB2(SCH_1):PAGE70

TP_CPU1_RSVD_159 @BASEBOARD_FAB2_LIB.BASEBOARD_FAB2(SCH_1):TP_CPU1_RSVD_159
  U2D1 BC22 RSVD<159> SKX_EXT_B_BGA1-IC,TBD     I9 @BASEBOARD_FAB2_LIB.BASEBOARD_FAB2(SCH_1):PAGE70

TP_CPU1_RSVD_16 @BASEBOARD_FAB2_LIB.BASEBOARD_FAB2(SCH_1):TP_CPU1_RSVD_16
  U2D1 EB85 RSVD<16> SKX_EXT_B_BGA1-IC,TBD   I107 @BASEBOARD_FAB2_LIB.BASEBOARD_FAB2(SCH_1):PAGE73

TP_CPU1_RSVD_160 @BASEBOARD_FAB2_LIB.BASEBOARD_FAB2(SCH_1):TP_CPU1_RSVD_160
  U2D1 BC20 RSVD<160> SKX_EXT_B_BGA1-IC,TBD     I9 @BASEBOARD_FAB2_LIB.BASEBOARD_FAB2(SCH_1):PAGE70

TP_CPU1_RSVD_161 @BASEBOARD_FAB2_LIB.BASEBOARD_FAB2(SCH_1):TP_CPU1_RSVD_161
  U2D1 BC18 RSVD<161> SKX_EXT_B_BGA1-IC,TBD     I9 @BASEBOARD_FAB2_LIB.BASEBOARD_FAB2(SCH_1):PAGE70

TP_CPU1_RSVD_162 @BASEBOARD_FAB2_LIB.BASEBOARD_FAB2(SCH_1):TP_CPU1_RSVD_162
  U2D1 BC14 RSVD<162> SKX_EXT_B_BGA1-IC,TBD     I9 @BASEBOARD_FAB2_LIB.BASEBOARD_FAB2(SCH_1):PAGE70

TP_CPU1_RSVD_163 @BASEBOARD_FAB2_LIB.BASEBOARD_FAB2(SCH_1):TP_CPU1_RSVD_163
  U2D1 BB67 RSVD<163> SKX_EXT_B_BGA1-IC,TBD     I9 @BASEBOARD_FAB2_LIB.BASEBOARD_FAB2(SCH_1):PAGE70

TP_CPU1_RSVD_164 @BASEBOARD_FAB2_LIB.BASEBOARD_FAB2(SCH_1):TP_CPU1_RSVD_164
  U2D1 BB65 RSVD<164> SKX_EXT_B_BGA1-IC,TBD     I9 @BASEBOARD_FAB2_LIB.BASEBOARD_FAB2(SCH_1):PAGE70

TP_CPU1_RSVD_166 @BASEBOARD_FAB2_LIB.BASEBOARD_FAB2(SCH_1):TP_CPU1_RSVD_166
  U2D1 BB21 RSVD<166> SKX_EXT_B_BGA1-IC,TBD     I9 @BASEBOARD_FAB2_LIB.BASEBOARD_FAB2(SCH_1):PAGE70

TP_CPU1_RSVD_167 @BASEBOARD_FAB2_LIB.BASEBOARD_FAB2(SCH_1):TP_CPU1_RSVD_167
  U2D1 BB17 RSVD<167> SKX_EXT_B_BGA1-IC,TBD     I9 @BASEBOARD_FAB2_LIB.BASEBOARD_FAB2(SCH_1):PAGE70

TP_CPU1_RSVD_168 @BASEBOARD_FAB2_LIB.BASEBOARD_FAB2(SCH_1):TP_CPU1_RSVD_168
  U2D1 BB15 RSVD<168> SKX_EXT_B_BGA1-IC,TBD     I9 @BASEBOARD_FAB2_LIB.BASEBOARD_FAB2(SCH_1):PAGE70

TP_CPU1_RSVD_169 @BASEBOARD_FAB2_LIB.BASEBOARD_FAB2(SCH_1):TP_CPU1_RSVD_169
  U2D1 BB13 RSVD<169> SKX_EXT_B_BGA1-IC,TBD     I9 @BASEBOARD_FAB2_LIB.BASEBOARD_FAB2(SCH_1):PAGE70

TP_CPU1_RSVD_17 @BASEBOARD_FAB2_LIB.BASEBOARD_FAB2(SCH_1):TP_CPU1_RSVD_17
  U2D1  EB5 RSVD<17> SKX_EXT_B_BGA1-IC,TBD   I107 @BASEBOARD_FAB2_LIB.BASEBOARD_FAB2(SCH_1):PAGE73

TP_CPU1_RSVD_170 @BASEBOARD_FAB2_LIB.BASEBOARD_FAB2(SCH_1):TP_CPU1_RSVD_170
  U2D1 BA82 RSVD<170> SKX_EXT_B_BGA1-IC,TBD     I9 @BASEBOARD_FAB2_LIB.BASEBOARD_FAB2(SCH_1):PAGE70

TP_CPU1_RSVD_171 @BASEBOARD_FAB2_LIB.BASEBOARD_FAB2(SCH_1):TP_CPU1_RSVD_171
  U2D1 BA78 RSVD<171> SKX_EXT_B_BGA1-IC,TBD     I9 @BASEBOARD_FAB2_LIB.BASEBOARD_FAB2(SCH_1):PAGE70

TP_CPU1_RSVD_172 @BASEBOARD_FAB2_LIB.BASEBOARD_FAB2(SCH_1):TP_CPU1_RSVD_172
  U2D1 BA76 RSVD<172> SKX_EXT_B_BGA1-IC,TBD    I23 @BASEBOARD_FAB2_LIB.BASEBOARD_FAB2(SCH_1):PAGE63

TP_CPU1_RSVD_173 @BASEBOARD_FAB2_LIB.BASEBOARD_FAB2(SCH_1):TP_CPU1_RSVD_173
  U2D1 BA66 RSVD<173> SKX_EXT_B_BGA1-IC,TBD    I23 @BASEBOARD_FAB2_LIB.BASEBOARD_FAB2(SCH_1):PAGE63

TP_CPU1_RSVD_174 @BASEBOARD_FAB2_LIB.BASEBOARD_FAB2(SCH_1):TP_CPU1_RSVD_174
  U2D1 BA64 RSVD<174> SKX_EXT_B_BGA1-IC,TBD    I23 @BASEBOARD_FAB2_LIB.BASEBOARD_FAB2(SCH_1):PAGE63

TP_CPU1_RSVD_175 @BASEBOARD_FAB2_LIB.BASEBOARD_FAB2(SCH_1):TP_CPU1_RSVD_175
  U2D1 BA22 RSVD<175> SKX_EXT_B_BGA1-IC,TBD    I23 @BASEBOARD_FAB2_LIB.BASEBOARD_FAB2(SCH_1):PAGE63

TP_CPU1_RSVD_176 @BASEBOARD_FAB2_LIB.BASEBOARD_FAB2(SCH_1):TP_CPU1_RSVD_176
  U2D1 BA18 RSVD<176> SKX_EXT_B_BGA1-IC,TBD    I23 @BASEBOARD_FAB2_LIB.BASEBOARD_FAB2(SCH_1):PAGE63

TP_CPU1_RSVD_177 @BASEBOARD_FAB2_LIB.BASEBOARD_FAB2(SCH_1):TP_CPU1_RSVD_177
  U2D1 BA16 RSVD<177> SKX_EXT_B_BGA1-IC,TBD    I23 @BASEBOARD_FAB2_LIB.BASEBOARD_FAB2(SCH_1):PAGE63

TP_CPU1_RSVD_178 @BASEBOARD_FAB2_LIB.BASEBOARD_FAB2(SCH_1):TP_CPU1_RSVD_178
  U2D1 BA14 RSVD<178> SKX_EXT_B_BGA1-IC,TBD    I23 @BASEBOARD_FAB2_LIB.BASEBOARD_FAB2(SCH_1):PAGE63

TP_CPU1_RSVD_179 @BASEBOARD_FAB2_LIB.BASEBOARD_FAB2(SCH_1):TP_CPU1_RSVD_179
  U2D1 AY77 RSVD<179> SKX_EXT_B_BGA1-IC,TBD    I23 @BASEBOARD_FAB2_LIB.BASEBOARD_FAB2(SCH_1):PAGE63

TP_CPU1_RSVD_18 @BASEBOARD_FAB2_LIB.BASEBOARD_FAB2(SCH_1):TP_CPU1_RSVD_18
  U2D1  EB3 RSVD<18> SKX_EXT_B_BGA1-IC,TBD   I107 @BASEBOARD_FAB2_LIB.BASEBOARD_FAB2(SCH_1):PAGE73

TP_CPU1_RSVD_180 @BASEBOARD_FAB2_LIB.BASEBOARD_FAB2(SCH_1):TP_CPU1_RSVD_180
  U2D1 AY75 RSVD<180> SKX_EXT_B_BGA1-IC,TBD    I23 @BASEBOARD_FAB2_LIB.BASEBOARD_FAB2(SCH_1):PAGE63

TP_CPU1_RSVD_181 @BASEBOARD_FAB2_LIB.BASEBOARD_FAB2(SCH_1):TP_CPU1_RSVD_181
  U2D1 AY67 RSVD<181> SKX_EXT_B_BGA1-IC,TBD    I23 @BASEBOARD_FAB2_LIB.BASEBOARD_FAB2(SCH_1):PAGE63

TP_CPU1_RSVD_182 @BASEBOARD_FAB2_LIB.BASEBOARD_FAB2(SCH_1):TP_CPU1_RSVD_182
  U2D1 AY65 RSVD<182> SKX_EXT_B_BGA1-IC,TBD    I23 @BASEBOARD_FAB2_LIB.BASEBOARD_FAB2(SCH_1):PAGE63

TP_CPU1_RSVD_183 @BASEBOARD_FAB2_LIB.BASEBOARD_FAB2(SCH_1):TP_CPU1_RSVD_183
  U2D1 AW76 RSVD<183> SKX_EXT_B_BGA1-IC,TBD    I23 @BASEBOARD_FAB2_LIB.BASEBOARD_FAB2(SCH_1):PAGE63

TP_CPU1_RSVD_184 @BASEBOARD_FAB2_LIB.BASEBOARD_FAB2(SCH_1):TP_CPU1_RSVD_184
  U2D1 AW64 RSVD<184> SKX_EXT_B_BGA1-IC,TBD    I23 @BASEBOARD_FAB2_LIB.BASEBOARD_FAB2(SCH_1):PAGE63

TP_CPU1_RSVD_186 @BASEBOARD_FAB2_LIB.BASEBOARD_FAB2(SCH_1):TP_CPU1_RSVD_186
  U2D1 AV77 RSVD<186> SKX_EXT_B_BGA1-IC,TBD    I23 @BASEBOARD_FAB2_LIB.BASEBOARD_FAB2(SCH_1):PAGE63

TP_CPU1_RSVD_189 @BASEBOARD_FAB2_LIB.BASEBOARD_FAB2(SCH_1):TP_CPU1_RSVD_189
  U2D1 AT13 RSVD<189> SKX_EXT_B_BGA1-IC,TBD    I23 @BASEBOARD_FAB2_LIB.BASEBOARD_FAB2(SCH_1):PAGE63

TP_CPU1_RSVD_19 @BASEBOARD_FAB2_LIB.BASEBOARD_FAB2(SCH_1):TP_CPU1_RSVD_19
  U2D1 EA44 RSVD<19> SKX_EXT_B_BGA1-IC,TBD   I107 @BASEBOARD_FAB2_LIB.BASEBOARD_FAB2(SCH_1):PAGE73

TP_CPU1_RSVD_190 @BASEBOARD_FAB2_LIB.BASEBOARD_FAB2(SCH_1):TP_CPU1_RSVD_190
  U2D1 AR62 RSVD<190> SKX_EXT_B_BGA1-IC,TBD    I23 @BASEBOARD_FAB2_LIB.BASEBOARD_FAB2(SCH_1):PAGE63

TP_CPU1_RSVD_194 @BASEBOARD_FAB2_LIB.BASEBOARD_FAB2(SCH_1):TP_CPU1_RSVD_194
  U2D1 AP61 RSVD<194> SKX_EXT_B_BGA1-IC,TBD   I169 @BASEBOARD_FAB2_LIB.BASEBOARD_FAB2(SCH_1):PAGE56

TP_CPU1_RSVD_198 @BASEBOARD_FAB2_LIB.BASEBOARD_FAB2(SCH_1):TP_CPU1_RSVD_198
  U2D1 AN62 RSVD<198> SKX_EXT_B_BGA1-IC,TBD   I169 @BASEBOARD_FAB2_LIB.BASEBOARD_FAB2(SCH_1):PAGE56

TP_CPU1_RSVD_199 @BASEBOARD_FAB2_LIB.BASEBOARD_FAB2(SCH_1):TP_CPU1_RSVD_199
  U2D1 AN60 RSVD<199> SKX_EXT_B_BGA1-IC,TBD   I169 @BASEBOARD_FAB2_LIB.BASEBOARD_FAB2(SCH_1):PAGE56

TP_CPU1_RSVD_2 @BASEBOARD_FAB2_LIB.BASEBOARD_FAB2(SCH_1):TP_CPU1_RSVD_2
  U2D1 EF77 RSVD<2> SKX_EXT_B_BGA1-IC,TBD   I107 @BASEBOARD_FAB2_LIB.BASEBOARD_FAB2(SCH_1):PAGE73

TP_CPU1_RSVD_20 @BASEBOARD_FAB2_LIB.BASEBOARD_FAB2(SCH_1):TP_CPU1_RSVD_20
  U2D1  EA4 RSVD<20> SKX_EXT_B_BGA1-IC,TBD   I107 @BASEBOARD_FAB2_LIB.BASEBOARD_FAB2(SCH_1):PAGE73

TP_CPU1_RSVD_204 @BASEBOARD_FAB2_LIB.BASEBOARD_FAB2(SCH_1):TP_CPU1_RSVD_204
  U2D1 AM61 RSVD<204> SKX_EXT_B_BGA1-IC,TBD   I169 @BASEBOARD_FAB2_LIB.BASEBOARD_FAB2(SCH_1):PAGE56

TP_CPU1_RSVD_205 @BASEBOARD_FAB2_LIB.BASEBOARD_FAB2(SCH_1):TP_CPU1_RSVD_205
  U2D1 AM59 RSVD<205> SKX_EXT_B_BGA1-IC,TBD   I169 @BASEBOARD_FAB2_LIB.BASEBOARD_FAB2(SCH_1):PAGE56

TP_CPU1_RSVD_208 @BASEBOARD_FAB2_LIB.BASEBOARD_FAB2(SCH_1):TP_CPU1_RSVD_208
  U2D1 AM23 RSVD<208> SKX_EXT_B_BGA1-IC,TBD   I169 @BASEBOARD_FAB2_LIB.BASEBOARD_FAB2(SCH_1):PAGE56

TP_CPU1_RSVD_21 @BASEBOARD_FAB2_LIB.BASEBOARD_FAB2(SCH_1):TP_CPU1_RSVD_21
  U2D1  DY3 RSVD<21> SKX_EXT_B_BGA1-IC,TBD   I107 @BASEBOARD_FAB2_LIB.BASEBOARD_FAB2(SCH_1):PAGE73

TP_CPU1_RSVD_210 @BASEBOARD_FAB2_LIB.BASEBOARD_FAB2(SCH_1):TP_CPU1_RSVD_210
  U2D1 AL62 RSVD<210> SKX_EXT_B_BGA1-IC,TBD   I169 @BASEBOARD_FAB2_LIB.BASEBOARD_FAB2(SCH_1):PAGE56

TP_CPU1_RSVD_211 @BASEBOARD_FAB2_LIB.BASEBOARD_FAB2(SCH_1):TP_CPU1_RSVD_211
  U2D1 AL60 RSVD<211> SKX_EXT_B_BGA1-IC,TBD   I169 @BASEBOARD_FAB2_LIB.BASEBOARD_FAB2(SCH_1):PAGE56

TP_CPU1_RSVD_212 @BASEBOARD_FAB2_LIB.BASEBOARD_FAB2(SCH_1):TP_CPU1_RSVD_212
  U2D1 AL58 RSVD<212> SKX_EXT_B_BGA1-IC,TBD   I169 @BASEBOARD_FAB2_LIB.BASEBOARD_FAB2(SCH_1):PAGE56

TP_CPU1_RSVD_214 @BASEBOARD_FAB2_LIB.BASEBOARD_FAB2(SCH_1):TP_CPU1_RSVD_214
  U2D1 AL22 RSVD<214> SKX_EXT_B_BGA1-IC,TBD   I169 @BASEBOARD_FAB2_LIB.BASEBOARD_FAB2(SCH_1):PAGE56

TP_CPU1_RSVD_216 @BASEBOARD_FAB2_LIB.BASEBOARD_FAB2(SCH_1):TP_CPU1_RSVD_216
  U2D1 AK69 RSVD<216> SKX_EXT_B_BGA1-IC,TBD   I169 @BASEBOARD_FAB2_LIB.BASEBOARD_FAB2(SCH_1):PAGE56

TP_CPU1_RSVD_217 @BASEBOARD_FAB2_LIB.BASEBOARD_FAB2(SCH_1):TP_CPU1_RSVD_217
  U2D1 AK61 RSVD<217> SKX_EXT_B_BGA1-IC,TBD   I169 @BASEBOARD_FAB2_LIB.BASEBOARD_FAB2(SCH_1):PAGE56

TP_CPU1_RSVD_218 @BASEBOARD_FAB2_LIB.BASEBOARD_FAB2(SCH_1):TP_CPU1_RSVD_218
  U2D1 AK59 RSVD<218> SKX_EXT_B_BGA1-IC,TBD   I169 @BASEBOARD_FAB2_LIB.BASEBOARD_FAB2(SCH_1):PAGE56

TP_CPU1_RSVD_219 @BASEBOARD_FAB2_LIB.BASEBOARD_FAB2(SCH_1):TP_CPU1_RSVD_219
  U2D1 AK57 RSVD<219> SKX_EXT_B_BGA1-IC,TBD   I169 @BASEBOARD_FAB2_LIB.BASEBOARD_FAB2(SCH_1):PAGE56

TP_CPU1_RSVD_22 @BASEBOARD_FAB2_LIB.BASEBOARD_FAB2(SCH_1):TP_CPU1_RSVD_22
  U2D1 DW46 RSVD<22> SKX_EXT_B_BGA1-IC,TBD   I107 @BASEBOARD_FAB2_LIB.BASEBOARD_FAB2(SCH_1):PAGE73

TP_CPU1_RSVD_222 @BASEBOARD_FAB2_LIB.BASEBOARD_FAB2(SCH_1):TP_CPU1_RSVD_222
  U2D1 AJ70 RSVD<222> SKX_EXT_B_BGA1-IC,TBD   I169 @BASEBOARD_FAB2_LIB.BASEBOARD_FAB2(SCH_1):PAGE56

TP_CPU1_RSVD_223 @BASEBOARD_FAB2_LIB.BASEBOARD_FAB2(SCH_1):TP_CPU1_RSVD_223
  U2D1 AJ62 RSVD<223> SKX_EXT_B_BGA1-IC,TBD   I169 @BASEBOARD_FAB2_LIB.BASEBOARD_FAB2(SCH_1):PAGE56

TP_CPU1_RSVD_224 @BASEBOARD_FAB2_LIB.BASEBOARD_FAB2(SCH_1):TP_CPU1_RSVD_224
  U2D1 AJ60 RSVD<224> SKX_EXT_B_BGA1-IC,TBD   I169 @BASEBOARD_FAB2_LIB.BASEBOARD_FAB2(SCH_1):PAGE56

TP_CPU1_RSVD_225 @BASEBOARD_FAB2_LIB.BASEBOARD_FAB2(SCH_1):TP_CPU1_RSVD_225
  U2D1 AJ58 RSVD<225> SKX_EXT_B_BGA1-IC,TBD   I169 @BASEBOARD_FAB2_LIB.BASEBOARD_FAB2(SCH_1):PAGE56

TP_CPU1_RSVD_226 @BASEBOARD_FAB2_LIB.BASEBOARD_FAB2(SCH_1):TP_CPU1_RSVD_226
  U2D1 AJ56 RSVD<226> SKX_EXT_B_BGA1-IC,TBD   I169 @BASEBOARD_FAB2_LIB.BASEBOARD_FAB2(SCH_1):PAGE56

TP_CPU1_RSVD_227 @BASEBOARD_FAB2_LIB.BASEBOARD_FAB2(SCH_1):TP_CPU1_RSVD_227
  U2D1 AJ20 RSVD<227> SKX_EXT_B_BGA1-IC,TBD   I169 @BASEBOARD_FAB2_LIB.BASEBOARD_FAB2(SCH_1):PAGE56

TP_CPU1_RSVD_228 @BASEBOARD_FAB2_LIB.BASEBOARD_FAB2(SCH_1):TP_CPU1_RSVD_228
  U2D1 AH73 RSVD<228> SKX_EXT_B_BGA1-IC,TBD   I169 @BASEBOARD_FAB2_LIB.BASEBOARD_FAB2(SCH_1):PAGE56

TP_CPU1_RSVD_229 @BASEBOARD_FAB2_LIB.BASEBOARD_FAB2(SCH_1):TP_CPU1_RSVD_229
  U2D1 AH71 RSVD<229> SKX_EXT_B_BGA1-IC,TBD   I169 @BASEBOARD_FAB2_LIB.BASEBOARD_FAB2(SCH_1):PAGE56

TP_CPU1_RSVD_23 @BASEBOARD_FAB2_LIB.BASEBOARD_FAB2(SCH_1):TP_CPU1_RSVD_23
  U2D1 DW44 RSVD<23> SKX_EXT_B_BGA1-IC,TBD   I107 @BASEBOARD_FAB2_LIB.BASEBOARD_FAB2(SCH_1):PAGE73

TP_CPU1_RSVD_230 @BASEBOARD_FAB2_LIB.BASEBOARD_FAB2(SCH_1):TP_CPU1_RSVD_230
  U2D1 AH57 RSVD<230> SKX_EXT_B_BGA1-IC,TBD   I169 @BASEBOARD_FAB2_LIB.BASEBOARD_FAB2(SCH_1):PAGE56

TP_CPU1_RSVD_231 @BASEBOARD_FAB2_LIB.BASEBOARD_FAB2(SCH_1):TP_CPU1_RSVD_231
  U2D1 AH55 RSVD<231> SKX_EXT_B_BGA1-IC,TBD   I169 @BASEBOARD_FAB2_LIB.BASEBOARD_FAB2(SCH_1):PAGE56

TP_CPU1_RSVD_232 @BASEBOARD_FAB2_LIB.BASEBOARD_FAB2(SCH_1):TP_CPU1_RSVD_232
  U2D1 AH19 RSVD<232> SKX_EXT_B_BGA1-IC,TBD   I169 @BASEBOARD_FAB2_LIB.BASEBOARD_FAB2(SCH_1):PAGE56

TP_CPU1_RSVD_233 @BASEBOARD_FAB2_LIB.BASEBOARD_FAB2(SCH_1):TP_CPU1_RSVD_233
  U2D1 AH15 RSVD<233> SKX_EXT_B_BGA1-IC,TBD   I169 @BASEBOARD_FAB2_LIB.BASEBOARD_FAB2(SCH_1):PAGE56

TP_CPU1_RSVD_234 @BASEBOARD_FAB2_LIB.BASEBOARD_FAB2(SCH_1):TP_CPU1_RSVD_234
  U2D1 AG72 RSVD<234> SKX_EXT_B_BGA1-IC,TBD   I169 @BASEBOARD_FAB2_LIB.BASEBOARD_FAB2(SCH_1):PAGE56

TP_CPU1_RSVD_235 @BASEBOARD_FAB2_LIB.BASEBOARD_FAB2(SCH_1):TP_CPU1_RSVD_235
  U2D1 AG56 RSVD<235> SKX_EXT_B_BGA1-IC,TBD   I169 @BASEBOARD_FAB2_LIB.BASEBOARD_FAB2(SCH_1):PAGE56

TP_CPU1_RSVD_236 @BASEBOARD_FAB2_LIB.BASEBOARD_FAB2(SCH_1):TP_CPU1_RSVD_236
  U2D1 AG54 RSVD<236> SKX_EXT_B_BGA1-IC,TBD   I169 @BASEBOARD_FAB2_LIB.BASEBOARD_FAB2(SCH_1):PAGE56

TP_CPU1_RSVD_237 @BASEBOARD_FAB2_LIB.BASEBOARD_FAB2(SCH_1):TP_CPU1_RSVD_237
  U2D1 AG52 RSVD<237> SKX_EXT_B_BGA1-IC,TBD   I169 @BASEBOARD_FAB2_LIB.BASEBOARD_FAB2(SCH_1):PAGE56

TP_CPU1_RSVD_238 @BASEBOARD_FAB2_LIB.BASEBOARD_FAB2(SCH_1):TP_CPU1_RSVD_238
  U2D1 AG50 RSVD<238> SKX_EXT_B_BGA1-IC,TBD   I169 @BASEBOARD_FAB2_LIB.BASEBOARD_FAB2(SCH_1):PAGE56

TP_CPU1_RSVD_239 @BASEBOARD_FAB2_LIB.BASEBOARD_FAB2(SCH_1):TP_CPU1_RSVD_239
  U2D1 AG48 RSVD<239> SKX_EXT_B_BGA1-IC,TBD   I169 @BASEBOARD_FAB2_LIB.BASEBOARD_FAB2(SCH_1):PAGE56

TP_CPU1_RSVD_24 @BASEBOARD_FAB2_LIB.BASEBOARD_FAB2(SCH_1):TP_CPU1_RSVD_24
  U2D1 DV71 RSVD<24> SKX_EXT_B_BGA1-IC,TBD   I107 @BASEBOARD_FAB2_LIB.BASEBOARD_FAB2(SCH_1):PAGE73

TP_CPU1_RSVD_240 @BASEBOARD_FAB2_LIB.BASEBOARD_FAB2(SCH_1):TP_CPU1_RSVD_240
  U2D1 AG20 RSVD<240> SKX_EXT_B_BGA1-IC,TBD   I169 @BASEBOARD_FAB2_LIB.BASEBOARD_FAB2(SCH_1):PAGE56

TP_CPU1_RSVD_241 @BASEBOARD_FAB2_LIB.BASEBOARD_FAB2(SCH_1):TP_CPU1_RSVD_241
  U2D1 AF71 RSVD<241> SKX_EXT_B_BGA1-IC,TBD   I169 @BASEBOARD_FAB2_LIB.BASEBOARD_FAB2(SCH_1):PAGE56

TP_CPU1_RSVD_242 @BASEBOARD_FAB2_LIB.BASEBOARD_FAB2(SCH_1):TP_CPU1_RSVD_242
  U2D1 AF53 RSVD<242> SKX_EXT_B_BGA1-IC,TBD   I169 @BASEBOARD_FAB2_LIB.BASEBOARD_FAB2(SCH_1):PAGE56

TP_CPU1_RSVD_243 @BASEBOARD_FAB2_LIB.BASEBOARD_FAB2(SCH_1):TP_CPU1_RSVD_243
  U2D1 AF51 RSVD<243> SKX_EXT_B_BGA1-IC,TBD   I169 @BASEBOARD_FAB2_LIB.BASEBOARD_FAB2(SCH_1):PAGE56

TP_CPU1_RSVD_244 @BASEBOARD_FAB2_LIB.BASEBOARD_FAB2(SCH_1):TP_CPU1_RSVD_244
  U2D1 AF49 RSVD<244> SKX_EXT_B_BGA1-IC,TBD   I169 @BASEBOARD_FAB2_LIB.BASEBOARD_FAB2(SCH_1):PAGE56

TP_CPU1_RSVD_245 @BASEBOARD_FAB2_LIB.BASEBOARD_FAB2(SCH_1):TP_CPU1_RSVD_245
  U2D1 AF47 RSVD<245> SKX_EXT_B_BGA1-IC,TBD   I169 @BASEBOARD_FAB2_LIB.BASEBOARD_FAB2(SCH_1):PAGE56

TP_CPU1_RSVD_246 @BASEBOARD_FAB2_LIB.BASEBOARD_FAB2(SCH_1):TP_CPU1_RSVD_246
  U2D1 AF19 RSVD<246> SKX_EXT_B_BGA1-IC,TBD   I169 @BASEBOARD_FAB2_LIB.BASEBOARD_FAB2(SCH_1):PAGE56

TP_CPU1_RSVD_247 @BASEBOARD_FAB2_LIB.BASEBOARD_FAB2(SCH_1):TP_CPU1_RSVD_247
  U2D1 AE72 RSVD<247> SKX_EXT_B_BGA1-IC,TBD   I169 @BASEBOARD_FAB2_LIB.BASEBOARD_FAB2(SCH_1):PAGE56

TP_CPU1_RSVD_248 @BASEBOARD_FAB2_LIB.BASEBOARD_FAB2(SCH_1):TP_CPU1_RSVD_248
  U2D1 AE52 RSVD<248> SKX_EXT_B_BGA1-IC,TBD   I169 @BASEBOARD_FAB2_LIB.BASEBOARD_FAB2(SCH_1):PAGE56

TP_CPU1_RSVD_249 @BASEBOARD_FAB2_LIB.BASEBOARD_FAB2(SCH_1):TP_CPU1_RSVD_249
  U2D1 AE50 RSVD<249> SKX_EXT_B_BGA1-IC,TBD   I169 @BASEBOARD_FAB2_LIB.BASEBOARD_FAB2(SCH_1):PAGE56

TP_CPU1_RSVD_25 @BASEBOARD_FAB2_LIB.BASEBOARD_FAB2(SCH_1):TP_CPU1_RSVD_25
  U2D1 DV61 RSVD<25> SKX_EXT_B_BGA1-IC,TBD   I107 @BASEBOARD_FAB2_LIB.BASEBOARD_FAB2(SCH_1):PAGE73

TP_CPU1_RSVD_250 @BASEBOARD_FAB2_LIB.BASEBOARD_FAB2(SCH_1):TP_CPU1_RSVD_250
  U2D1 AE48 RSVD<250> SKX_EXT_B_BGA1-IC,TBD   I169 @BASEBOARD_FAB2_LIB.BASEBOARD_FAB2(SCH_1):PAGE56

TP_CPU1_RSVD_251 @BASEBOARD_FAB2_LIB.BASEBOARD_FAB2(SCH_1):TP_CPU1_RSVD_251
  U2D1 AE46 RSVD<251> SKX_EXT_B_BGA1-IC,TBD   I169 @BASEBOARD_FAB2_LIB.BASEBOARD_FAB2(SCH_1):PAGE56

TP_CPU1_RSVD_252 @BASEBOARD_FAB2_LIB.BASEBOARD_FAB2(SCH_1):TP_CPU1_RSVD_252
  U2D1 AD51 RSVD<252> SKX_EXT_B_BGA1-IC,TBD   I169 @BASEBOARD_FAB2_LIB.BASEBOARD_FAB2(SCH_1):PAGE56

TP_CPU1_RSVD_253 @BASEBOARD_FAB2_LIB.BASEBOARD_FAB2(SCH_1):TP_CPU1_RSVD_253
  U2D1 AD49 RSVD<253> SKX_EXT_B_BGA1-IC,TBD   I169 @BASEBOARD_FAB2_LIB.BASEBOARD_FAB2(SCH_1):PAGE56

TP_CPU1_RSVD_254 @BASEBOARD_FAB2_LIB.BASEBOARD_FAB2(SCH_1):TP_CPU1_RSVD_254
  U2D1 AD47 RSVD<254> SKX_EXT_B_BGA1-IC,TBD   I169 @BASEBOARD_FAB2_LIB.BASEBOARD_FAB2(SCH_1):PAGE56

TP_CPU1_RSVD_255 @BASEBOARD_FAB2_LIB.BASEBOARD_FAB2(SCH_1):TP_CPU1_RSVD_255
  U2D1 AY83 RSVD<255> SKX_EXT_B_BGA1-IC,TBD     I9 @BASEBOARD_FAB2_LIB.BASEBOARD_FAB2(SCH_1):PAGE70

TP_CPU1_RSVD_256 @BASEBOARD_FAB2_LIB.BASEBOARD_FAB2(SCH_1):TP_CPU1_RSVD_256
  U2D1  Y65 RSVD<256> SKX_EXT_B_BGA1-IC,TBD   I169 @BASEBOARD_FAB2_LIB.BASEBOARD_FAB2(SCH_1):PAGE56

TP_CPU1_RSVD_258 @BASEBOARD_FAB2_LIB.BASEBOARD_FAB2(SCH_1):TP_CPU1_RSVD_258
  U2D1  W66 RSVD<258> SKX_EXT_B_BGA1-IC,TBD   I169 @BASEBOARD_FAB2_LIB.BASEBOARD_FAB2(SCH_1):PAGE56

TP_CPU1_RSVD_259 @BASEBOARD_FAB2_LIB.BASEBOARD_FAB2(SCH_1):TP_CPU1_RSVD_259
  U2D1  V67 RSVD<259> SKX_EXT_B_BGA1-IC,TBD   I169 @BASEBOARD_FAB2_LIB.BASEBOARD_FAB2(SCH_1):PAGE56

TP_CPU1_RSVD_26 @BASEBOARD_FAB2_LIB.BASEBOARD_FAB2(SCH_1):TP_CPU1_RSVD_26
  U2D1 DU44 RSVD<26> SKX_EXT_B_BGA1-IC,TBD   I107 @BASEBOARD_FAB2_LIB.BASEBOARD_FAB2(SCH_1):PAGE73

TP_CPU1_RSVD_260 @BASEBOARD_FAB2_LIB.BASEBOARD_FAB2(SCH_1):TP_CPU1_RSVD_260
  U2D1  V65 RSVD<260> SKX_EXT_B_BGA1-IC,TBD   I169 @BASEBOARD_FAB2_LIB.BASEBOARD_FAB2(SCH_1):PAGE56

TP_CPU1_RSVD_261 @BASEBOARD_FAB2_LIB.BASEBOARD_FAB2(SCH_1):TP_CPU1_RSVD_261
  U2D1  U66 RSVD<261> SKX_EXT_B_BGA1-IC,TBD   I169 @BASEBOARD_FAB2_LIB.BASEBOARD_FAB2(SCH_1):PAGE56

TP_CPU1_RSVD_262 @BASEBOARD_FAB2_LIB.BASEBOARD_FAB2(SCH_1):TP_CPU1_RSVD_262
  U2D1  T67 RSVD<262> SKX_EXT_B_BGA1-IC,TBD   I169 @BASEBOARD_FAB2_LIB.BASEBOARD_FAB2(SCH_1):PAGE56

TP_CPU1_RSVD_263 @BASEBOARD_FAB2_LIB.BASEBOARD_FAB2(SCH_1):TP_CPU1_RSVD_263
  U2D1  R66 RSVD<263> SKX_EXT_B_BGA1-IC,TBD   I169 @BASEBOARD_FAB2_LIB.BASEBOARD_FAB2(SCH_1):PAGE56

TP_CPU1_RSVD_264 @BASEBOARD_FAB2_LIB.BASEBOARD_FAB2(SCH_1):TP_CPU1_RSVD_264
  U2D1  R62 RSVD<264> SKX_EXT_B_BGA1-IC,TBD   I169 @BASEBOARD_FAB2_LIB.BASEBOARD_FAB2(SCH_1):PAGE56

TP_CPU1_RSVD_265 @BASEBOARD_FAB2_LIB.BASEBOARD_FAB2(SCH_1):TP_CPU1_RSVD_265
  U2D1  P65 RSVD<265> SKX_EXT_B_BGA1-IC,TBD   I169 @BASEBOARD_FAB2_LIB.BASEBOARD_FAB2(SCH_1):PAGE56

TP_CPU1_RSVD_266 @BASEBOARD_FAB2_LIB.BASEBOARD_FAB2(SCH_1):TP_CPU1_RSVD_266
  U2D1  M63 RSVD<266> SKX_EXT_B_BGA1-IC,TBD   I169 @BASEBOARD_FAB2_LIB.BASEBOARD_FAB2(SCH_1):PAGE56

TP_CPU1_RSVD_267 @BASEBOARD_FAB2_LIB.BASEBOARD_FAB2(SCH_1):TP_CPU1_RSVD_267
  U2D1  K61 RSVD<267> SKX_EXT_B_BGA1-IC,TBD   I169 @BASEBOARD_FAB2_LIB.BASEBOARD_FAB2(SCH_1):PAGE56

TP_CPU1_RSVD_268 @BASEBOARD_FAB2_LIB.BASEBOARD_FAB2(SCH_1):TP_CPU1_RSVD_268
  U2D1  J62 RSVD<268> SKX_EXT_B_BGA1-IC,TBD   I169 @BASEBOARD_FAB2_LIB.BASEBOARD_FAB2(SCH_1):PAGE56

TP_CPU1_RSVD_269 @BASEBOARD_FAB2_LIB.BASEBOARD_FAB2(SCH_1):TP_CPU1_RSVD_269
  U2D1  J46 RSVD<269> SKX_EXT_B_BGA1-IC,TBD   I169 @BASEBOARD_FAB2_LIB.BASEBOARD_FAB2(SCH_1):PAGE56

TP_CPU1_RSVD_27 @BASEBOARD_FAB2_LIB.BASEBOARD_FAB2(SCH_1):TP_CPU1_RSVD_27
  U2D1 DT71 RSVD<27> SKX_EXT_B_BGA1-IC,TBD   I107 @BASEBOARD_FAB2_LIB.BASEBOARD_FAB2(SCH_1):PAGE73

TP_CPU1_RSVD_270 @BASEBOARD_FAB2_LIB.BASEBOARD_FAB2(SCH_1):TP_CPU1_RSVD_270
  U2D1  H85 RSVD<270> SKX_EXT_B_BGA1-IC,TBD   I169 @BASEBOARD_FAB2_LIB.BASEBOARD_FAB2(SCH_1):PAGE56

TP_CPU1_RSVD_271 @BASEBOARD_FAB2_LIB.BASEBOARD_FAB2(SCH_1):TP_CPU1_RSVD_271
  U2D1  H83 RSVD<271> SKX_EXT_B_BGA1-IC,TBD   I169 @BASEBOARD_FAB2_LIB.BASEBOARD_FAB2(SCH_1):PAGE56

TP_CPU1_RSVD_272 @BASEBOARD_FAB2_LIB.BASEBOARD_FAB2(SCH_1):TP_CPU1_RSVD_272
  U2D1   H1 RSVD<272> SKX_EXT_B_BGA1-IC,TBD   I169 @BASEBOARD_FAB2_LIB.BASEBOARD_FAB2(SCH_1):PAGE56

TP_CPU1_RSVD_273 @BASEBOARD_FAB2_LIB.BASEBOARD_FAB2(SCH_1):TP_CPU1_RSVD_273
  U2D1  G84 RSVD<273> SKX_EXT_B_BGA1-IC,TBD   I169 @BASEBOARD_FAB2_LIB.BASEBOARD_FAB2(SCH_1):PAGE56

TP_CPU1_RSVD_274 @BASEBOARD_FAB2_LIB.BASEBOARD_FAB2(SCH_1):TP_CPU1_RSVD_274
  U2D1  G64 RSVD<274> SKX_EXT_B_BGA1-IC,TBD   I169 @BASEBOARD_FAB2_LIB.BASEBOARD_FAB2(SCH_1):PAGE56

TP_CPU1_RSVD_275 @BASEBOARD_FAB2_LIB.BASEBOARD_FAB2(SCH_1):TP_CPU1_RSVD_275
  U2D1   G2 RSVD<275> SKX_EXT_B_BGA1-IC,TBD   I169 @BASEBOARD_FAB2_LIB.BASEBOARD_FAB2(SCH_1):PAGE56

TP_CPU1_RSVD_276 @BASEBOARD_FAB2_LIB.BASEBOARD_FAB2(SCH_1):TP_CPU1_RSVD_276
  U2D1  F83 RSVD<276> SKX_EXT_B_BGA1-IC,TBD   I169 @BASEBOARD_FAB2_LIB.BASEBOARD_FAB2(SCH_1):PAGE56

TP_CPU1_RSVD_277 @BASEBOARD_FAB2_LIB.BASEBOARD_FAB2(SCH_1):TP_CPU1_RSVD_277
  U2D1  F65 RSVD<277> SKX_EXT_B_BGA1-IC,TBD   I169 @BASEBOARD_FAB2_LIB.BASEBOARD_FAB2(SCH_1):PAGE56

TP_CPU1_RSVD_278 @BASEBOARD_FAB2_LIB.BASEBOARD_FAB2(SCH_1):TP_CPU1_RSVD_278
  U2D1  F23 RSVD<278> SKX_EXT_B_BGA1-IC,TBD   I169 @BASEBOARD_FAB2_LIB.BASEBOARD_FAB2(SCH_1):PAGE56

TP_CPU1_RSVD_279 @BASEBOARD_FAB2_LIB.BASEBOARD_FAB2(SCH_1):TP_CPU1_RSVD_279
  U2D1   F3 RSVD<279> SKX_EXT_B_BGA1-IC,TBD   I169 @BASEBOARD_FAB2_LIB.BASEBOARD_FAB2(SCH_1):PAGE56

TP_CPU1_RSVD_28 @BASEBOARD_FAB2_LIB.BASEBOARD_FAB2(SCH_1):TP_CPU1_RSVD_28
  U2D1 DR44 RSVD<28> SKX_EXT_B_BGA1-IC,TBD   I107 @BASEBOARD_FAB2_LIB.BASEBOARD_FAB2(SCH_1):PAGE73

TP_CPU1_RSVD_280 @BASEBOARD_FAB2_LIB.BASEBOARD_FAB2(SCH_1):TP_CPU1_RSVD_280
  U2D1  E84 RSVD<280> SKX_EXT_B_BGA1-IC,TBD   I169 @BASEBOARD_FAB2_LIB.BASEBOARD_FAB2(SCH_1):PAGE56

TP_CPU1_RSVD_281 @BASEBOARD_FAB2_LIB.BASEBOARD_FAB2(SCH_1):TP_CPU1_RSVD_281
  U2D1  E24 RSVD<281> SKX_EXT_B_BGA1-IC,TBD   I169 @BASEBOARD_FAB2_LIB.BASEBOARD_FAB2(SCH_1):PAGE56

TP_CPU1_RSVD_282 @BASEBOARD_FAB2_LIB.BASEBOARD_FAB2(SCH_1):TP_CPU1_RSVD_282
  U2D1   E4 RSVD<282> SKX_EXT_B_BGA1-IC,TBD   I169 @BASEBOARD_FAB2_LIB.BASEBOARD_FAB2(SCH_1):PAGE56

TP_CPU1_RSVD_283 @BASEBOARD_FAB2_LIB.BASEBOARD_FAB2(SCH_1):TP_CPU1_RSVD_283
  U2D1   E2 RSVD<283> SKX_EXT_B_BGA1-IC,TBD   I169 @BASEBOARD_FAB2_LIB.BASEBOARD_FAB2(SCH_1):PAGE56

TP_CPU1_RSVD_284 @BASEBOARD_FAB2_LIB.BASEBOARD_FAB2(SCH_1):TP_CPU1_RSVD_284
  U2D1  D83 RSVD<284> SKX_EXT_B_BGA1-IC,TBD   I169 @BASEBOARD_FAB2_LIB.BASEBOARD_FAB2(SCH_1):PAGE56

TP_CPU1_RSVD_285 @BASEBOARD_FAB2_LIB.BASEBOARD_FAB2(SCH_1):TP_CPU1_RSVD_285
  U2D1  D65 RSVD<285> SKX_EXT_B_BGA1-IC,TBD   I169 @BASEBOARD_FAB2_LIB.BASEBOARD_FAB2(SCH_1):PAGE56

TP_CPU1_RSVD_286 @BASEBOARD_FAB2_LIB.BASEBOARD_FAB2(SCH_1):TP_CPU1_RSVD_286
  U2D1  D17 RSVD<286> SKX_EXT_B_BGA1-IC,TBD   I169 @BASEBOARD_FAB2_LIB.BASEBOARD_FAB2(SCH_1):PAGE56

TP_CPU1_RSVD_287 @BASEBOARD_FAB2_LIB.BASEBOARD_FAB2(SCH_1):TP_CPU1_RSVD_287
  U2D1   D5 RSVD<287> SKX_EXT_B_BGA1-IC,TBD   I169 @BASEBOARD_FAB2_LIB.BASEBOARD_FAB2(SCH_1):PAGE56

TP_CPU1_RSVD_288 @BASEBOARD_FAB2_LIB.BASEBOARD_FAB2(SCH_1):TP_CPU1_RSVD_288
  U2D1  C82 RSVD<288> SKX_EXT_B_BGA1-IC,TBD   I169 @BASEBOARD_FAB2_LIB.BASEBOARD_FAB2(SCH_1):PAGE56

TP_CPU1_RSVD_289 @BASEBOARD_FAB2_LIB.BASEBOARD_FAB2(SCH_1):TP_CPU1_RSVD_289
  U2D1  C24 RSVD<289> SKX_EXT_B_BGA1-IC,TBD   I169 @BASEBOARD_FAB2_LIB.BASEBOARD_FAB2(SCH_1):PAGE56

TP_CPU1_RSVD_29 @BASEBOARD_FAB2_LIB.BASEBOARD_FAB2(SCH_1):TP_CPU1_RSVD_29
  U2D1 DP65 RSVD<29> SKX_EXT_B_BGA1-IC,TBD   I107 @BASEBOARD_FAB2_LIB.BASEBOARD_FAB2(SCH_1):PAGE73

TP_CPU1_RSVD_290 @BASEBOARD_FAB2_LIB.BASEBOARD_FAB2(SCH_1):TP_CPU1_RSVD_290
  U2D1  C18 RSVD<290> SKX_EXT_B_BGA1-IC,TBD   I169 @BASEBOARD_FAB2_LIB.BASEBOARD_FAB2(SCH_1):PAGE56

TP_CPU1_RSVD_291 @BASEBOARD_FAB2_LIB.BASEBOARD_FAB2(SCH_1):TP_CPU1_RSVD_291
  U2D1   C6 RSVD<291> SKX_EXT_B_BGA1-IC,TBD   I169 @BASEBOARD_FAB2_LIB.BASEBOARD_FAB2(SCH_1):PAGE56

TP_CPU1_RSVD_292 @BASEBOARD_FAB2_LIB.BASEBOARD_FAB2(SCH_1):TP_CPU1_RSVD_292
  U2D1  B81 RSVD<292> SKX_EXT_B_BGA1-IC,TBD   I169 @BASEBOARD_FAB2_LIB.BASEBOARD_FAB2(SCH_1):PAGE56

TP_CPU1_RSVD_293 @BASEBOARD_FAB2_LIB.BASEBOARD_FAB2(SCH_1):TP_CPU1_RSVD_293
  U2D1  B77 RSVD<293> SKX_EXT_B_BGA1-IC,TBD   I169 @BASEBOARD_FAB2_LIB.BASEBOARD_FAB2(SCH_1):PAGE56

TP_CPU1_RSVD_298 @BASEBOARD_FAB2_LIB.BASEBOARD_FAB2(SCH_1):TP_CPU1_RSVD_298
  U2D1   B7 RSVD<298> SKX_EXT_B_BGA1-IC,TBD   I169 @BASEBOARD_FAB2_LIB.BASEBOARD_FAB2(SCH_1):PAGE56

TP_CPU1_RSVD_299 @BASEBOARD_FAB2_LIB.BASEBOARD_FAB2(SCH_1):TP_CPU1_RSVD_299
  U2D1   B3 RSVD<299> SKX_EXT_B_BGA1-IC,TBD   I169 @BASEBOARD_FAB2_LIB.BASEBOARD_FAB2(SCH_1):PAGE56

TP_CPU1_RSVD_3 @BASEBOARD_FAB2_LIB.BASEBOARD_FAB2(SCH_1):TP_CPU1_RSVD_3
  U2D1 EF47 RSVD<3> SKX_EXT_B_BGA1-IC,TBD   I107 @BASEBOARD_FAB2_LIB.BASEBOARD_FAB2(SCH_1):PAGE73

TP_CPU1_RSVD_30 @BASEBOARD_FAB2_LIB.BASEBOARD_FAB2(SCH_1):TP_CPU1_RSVD_30
  U2D1 DP17 RSVD<30> SKX_EXT_B_BGA1-IC,TBD   I107 @BASEBOARD_FAB2_LIB.BASEBOARD_FAB2(SCH_1):PAGE73

TP_CPU1_RSVD_300 @BASEBOARD_FAB2_LIB.BASEBOARD_FAB2(SCH_1):TP_CPU1_RSVD_300
  U2D1  A24 RSVD<300> SKX_EXT_B_BGA1-IC,TBD   I169 @BASEBOARD_FAB2_LIB.BASEBOARD_FAB2(SCH_1):PAGE56

TP_CPU1_RSVD_303 @BASEBOARD_FAB2_LIB.BASEBOARD_FAB2(SCH_1):TP_CPU1_RSVD_303
  U2D1   A6 RSVD<303> SKX_EXT_B_BGA1-IC,TBD   I169 @BASEBOARD_FAB2_LIB.BASEBOARD_FAB2(SCH_1):PAGE56

TP_CPU1_RSVD_304 @BASEBOARD_FAB2_LIB.BASEBOARD_FAB2(SCH_1):TP_CPU1_RSVD_304
  U2D1   A4 RSVD<304> SKX_EXT_B_BGA1-IC,TBD   I169 @BASEBOARD_FAB2_LIB.BASEBOARD_FAB2(SCH_1):PAGE56

TP_CPU1_RSVD_31 @BASEBOARD_FAB2_LIB.BASEBOARD_FAB2(SCH_1):TP_CPU1_RSVD_31
  U2D1 DN66 RSVD<31> SKX_EXT_B_BGA1-IC,TBD   I107 @BASEBOARD_FAB2_LIB.BASEBOARD_FAB2(SCH_1):PAGE73

TP_CPU1_RSVD_32 @BASEBOARD_FAB2_LIB.BASEBOARD_FAB2(SCH_1):TP_CPU1_RSVD_32
  U2D1 DN62 RSVD<32> SKX_EXT_B_BGA1-IC,TBD   I107 @BASEBOARD_FAB2_LIB.BASEBOARD_FAB2(SCH_1):PAGE73

TP_CPU1_RSVD_33 @BASEBOARD_FAB2_LIB.BASEBOARD_FAB2(SCH_1):TP_CPU1_RSVD_33
  U2D1 DM67 RSVD<33> SKX_EXT_B_BGA1-IC,TBD   I107 @BASEBOARD_FAB2_LIB.BASEBOARD_FAB2(SCH_1):PAGE73

TP_CPU1_RSVD_34 @BASEBOARD_FAB2_LIB.BASEBOARD_FAB2(SCH_1):TP_CPU1_RSVD_34
  U2D1 DL66 RSVD<34> SKX_EXT_B_BGA1-IC,TBD   I107 @BASEBOARD_FAB2_LIB.BASEBOARD_FAB2(SCH_1):PAGE73

TP_CPU1_RSVD_35 @BASEBOARD_FAB2_LIB.BASEBOARD_FAB2(SCH_1):TP_CPU1_RSVD_35
  U2D1 DL38 RSVD<35> SKX_EXT_B_BGA1-IC,TBD   I107 @BASEBOARD_FAB2_LIB.BASEBOARD_FAB2(SCH_1):PAGE73

TP_CPU1_RSVD_36 @BASEBOARD_FAB2_LIB.BASEBOARD_FAB2(SCH_1):TP_CPU1_RSVD_36
  U2D1 DK67 RSVD<36> SKX_EXT_B_BGA1-IC,TBD   I107 @BASEBOARD_FAB2_LIB.BASEBOARD_FAB2(SCH_1):PAGE73

TP_CPU1_RSVD_37 @BASEBOARD_FAB2_LIB.BASEBOARD_FAB2(SCH_1):TP_CPU1_RSVD_37
  U2D1 DK65 RSVD<37> SKX_EXT_B_BGA1-IC,TBD   I107 @BASEBOARD_FAB2_LIB.BASEBOARD_FAB2(SCH_1):PAGE73

TP_CPU1_RSVD_38 @BASEBOARD_FAB2_LIB.BASEBOARD_FAB2(SCH_1):TP_CPU1_RSVD_38
  U2D1 DK37 RSVD<38> SKX_EXT_B_BGA1-IC,TBD   I107 @BASEBOARD_FAB2_LIB.BASEBOARD_FAB2(SCH_1):PAGE73

TP_CPU1_RSVD_39 @BASEBOARD_FAB2_LIB.BASEBOARD_FAB2(SCH_1):TP_CPU1_RSVD_39
  U2D1 DK15 RSVD<39> SKX_EXT_B_BGA1-IC,TBD   I107 @BASEBOARD_FAB2_LIB.BASEBOARD_FAB2(SCH_1):PAGE73

TP_CPU1_RSVD_4 @BASEBOARD_FAB2_LIB.BASEBOARD_FAB2(SCH_1):TP_CPU1_RSVD_4
  U2D1 EE84 RSVD<4> SKX_EXT_B_BGA1-IC,TBD   I107 @BASEBOARD_FAB2_LIB.BASEBOARD_FAB2(SCH_1):PAGE73

TP_CPU1_RSVD_40 @BASEBOARD_FAB2_LIB.BASEBOARD_FAB2(SCH_1):TP_CPU1_RSVD_40
  U2D1 DJ66 RSVD<40> SKX_EXT_B_BGA1-IC,TBD   I107 @BASEBOARD_FAB2_LIB.BASEBOARD_FAB2(SCH_1):PAGE73

TP_CPU1_RSVD_41 @BASEBOARD_FAB2_LIB.BASEBOARD_FAB2(SCH_1):TP_CPU1_RSVD_41
  U2D1 DJ36 RSVD<41> SKX_EXT_B_BGA1-IC,TBD   I107 @BASEBOARD_FAB2_LIB.BASEBOARD_FAB2(SCH_1):PAGE73

TP_CPU1_RSVD_42 @BASEBOARD_FAB2_LIB.BASEBOARD_FAB2(SCH_1):TP_CPU1_RSVD_42
  U2D1 DH65 RSVD<42> SKX_EXT_B_BGA1-IC,TBD   I107 @BASEBOARD_FAB2_LIB.BASEBOARD_FAB2(SCH_1):PAGE73

TP_CPU1_RSVD_43 @BASEBOARD_FAB2_LIB.BASEBOARD_FAB2(SCH_1):TP_CPU1_RSVD_43
  U2D1 DG64 RSVD<43> SKX_EXT_B_BGA1-IC,TBD   I107 @BASEBOARD_FAB2_LIB.BASEBOARD_FAB2(SCH_1):PAGE73

TP_CPU1_RSVD_44 @BASEBOARD_FAB2_LIB.BASEBOARD_FAB2(SCH_1):TP_CPU1_RSVD_44
  U2D1 DG36 RSVD<44> SKX_EXT_B_BGA1-IC,TBD   I107 @BASEBOARD_FAB2_LIB.BASEBOARD_FAB2(SCH_1):PAGE73

TP_CPU1_RSVD_45 @BASEBOARD_FAB2_LIB.BASEBOARD_FAB2(SCH_1):TP_CPU1_RSVD_45
  U2D1 DD51 RSVD<45> SKX_EXT_B_BGA1-IC,TBD   I107 @BASEBOARD_FAB2_LIB.BASEBOARD_FAB2(SCH_1):PAGE73

TP_CPU1_RSVD_46 @BASEBOARD_FAB2_LIB.BASEBOARD_FAB2(SCH_1):TP_CPU1_RSVD_46
  U2D1 DC52 RSVD<46> SKX_EXT_B_BGA1-IC,TBD   I107 @BASEBOARD_FAB2_LIB.BASEBOARD_FAB2(SCH_1):PAGE73

TP_CPU1_RSVD_47 @BASEBOARD_FAB2_LIB.BASEBOARD_FAB2(SCH_1):TP_CPU1_RSVD_47
  U2D1 DC46 RSVD<47> SKX_EXT_B_BGA1-IC,TBD   I107 @BASEBOARD_FAB2_LIB.BASEBOARD_FAB2(SCH_1):PAGE73

TP_CPU1_RSVD_48 @BASEBOARD_FAB2_LIB.BASEBOARD_FAB2(SCH_1):TP_CPU1_RSVD_48
  U2D1 DA56 RSVD<48> SKX_EXT_B_BGA1-IC,TBD   I107 @BASEBOARD_FAB2_LIB.BASEBOARD_FAB2(SCH_1):PAGE73

TP_CPU1_RSVD_49 @BASEBOARD_FAB2_LIB.BASEBOARD_FAB2(SCH_1):TP_CPU1_RSVD_49
  U2D1 DA54 RSVD<49> SKX_EXT_B_BGA1-IC,TBD   I107 @BASEBOARD_FAB2_LIB.BASEBOARD_FAB2(SCH_1):PAGE73

TP_CPU1_RSVD_5 @BASEBOARD_FAB2_LIB.BASEBOARD_FAB2(SCH_1):TP_CPU1_RSVD_5
  U2D1 EE82 RSVD<5> SKX_EXT_B_BGA1-IC,TBD   I107 @BASEBOARD_FAB2_LIB.BASEBOARD_FAB2(SCH_1):PAGE73

TP_CPU1_RSVD_50 @BASEBOARD_FAB2_LIB.BASEBOARD_FAB2(SCH_1):TP_CPU1_RSVD_50
  U2D1 DA52 RSVD<50> SKX_EXT_B_BGA1-IC,TBD   I107 @BASEBOARD_FAB2_LIB.BASEBOARD_FAB2(SCH_1):PAGE73

TP_CPU1_RSVD_51 @BASEBOARD_FAB2_LIB.BASEBOARD_FAB2(SCH_1):TP_CPU1_RSVD_51
  U2D1 DA40 RSVD<51> SKX_EXT_B_BGA1-IC,TBD   I107 @BASEBOARD_FAB2_LIB.BASEBOARD_FAB2(SCH_1):PAGE73

TP_CPU1_RSVD_53 @BASEBOARD_FAB2_LIB.BASEBOARD_FAB2(SCH_1):TP_CPU1_RSVD_53
  U2D1 CY73 RSVD<53> SKX_EXT_B_BGA1-IC,TBD   I107 @BASEBOARD_FAB2_LIB.BASEBOARD_FAB2(SCH_1):PAGE73

TP_CPU1_RSVD_54 @BASEBOARD_FAB2_LIB.BASEBOARD_FAB2(SCH_1):TP_CPU1_RSVD_54
  U2D1 CY63 RSVD<54> SKX_EXT_B_BGA1-IC,TBD   I107 @BASEBOARD_FAB2_LIB.BASEBOARD_FAB2(SCH_1):PAGE73

TP_CPU1_RSVD_55 @BASEBOARD_FAB2_LIB.BASEBOARD_FAB2(SCH_1):TP_CPU1_RSVD_55
  U2D1 CY57 RSVD<55> SKX_EXT_B_BGA1-IC,TBD   I107 @BASEBOARD_FAB2_LIB.BASEBOARD_FAB2(SCH_1):PAGE73

TP_CPU1_RSVD_56 @BASEBOARD_FAB2_LIB.BASEBOARD_FAB2(SCH_1):TP_CPU1_RSVD_56
  U2D1 CY53 RSVD<56> SKX_EXT_B_BGA1-IC,TBD   I107 @BASEBOARD_FAB2_LIB.BASEBOARD_FAB2(SCH_1):PAGE73

TP_CPU1_RSVD_57 @BASEBOARD_FAB2_LIB.BASEBOARD_FAB2(SCH_1):TP_CPU1_RSVD_57
  U2D1 CY39 RSVD<57> SKX_EXT_B_BGA1-IC,TBD   I107 @BASEBOARD_FAB2_LIB.BASEBOARD_FAB2(SCH_1):PAGE73

TP_CPU1_RSVD_59 @BASEBOARD_FAB2_LIB.BASEBOARD_FAB2(SCH_1):TP_CPU1_RSVD_59
  U2D1 CY23 RSVD<59> SKX_EXT_B_BGA1-IC,TBD   I107 @BASEBOARD_FAB2_LIB.BASEBOARD_FAB2(SCH_1):PAGE73

TP_CPU1_RSVD_6 @BASEBOARD_FAB2_LIB.BASEBOARD_FAB2(SCH_1):TP_CPU1_RSVD_6
  U2D1  EE6 RSVD<6> SKX_EXT_B_BGA1-IC,TBD   I107 @BASEBOARD_FAB2_LIB.BASEBOARD_FAB2(SCH_1):PAGE73

TP_CPU1_RSVD_60 @BASEBOARD_FAB2_LIB.BASEBOARD_FAB2(SCH_1):TP_CPU1_RSVD_60
  U2D1 CW62 RSVD<60> SKX_EXT_B_BGA1-IC,TBD   I107 @BASEBOARD_FAB2_LIB.BASEBOARD_FAB2(SCH_1):PAGE73

TP_CPU1_RSVD_61 @BASEBOARD_FAB2_LIB.BASEBOARD_FAB2(SCH_1):TP_CPU1_RSVD_61
  U2D1 CW60 RSVD<61> SKX_EXT_B_BGA1-IC,TBD   I107 @BASEBOARD_FAB2_LIB.BASEBOARD_FAB2(SCH_1):PAGE73

TP_CPU1_RSVD_64 @BASEBOARD_FAB2_LIB.BASEBOARD_FAB2(SCH_1):TP_CPU1_RSVD_64
  U2D1 CV69 RSVD<64> SKX_EXT_B_BGA1-IC,TBD   I107 @BASEBOARD_FAB2_LIB.BASEBOARD_FAB2(SCH_1):PAGE73

TP_CPU1_RSVD_66 @BASEBOARD_FAB2_LIB.BASEBOARD_FAB2(SCH_1):TP_CPU1_RSVD_66
  U2D1 CU60 RSVD<66> SKX_EXT_B_BGA1-IC,TBD   I107 @BASEBOARD_FAB2_LIB.BASEBOARD_FAB2(SCH_1):PAGE73

TP_CPU1_RSVD_67 @BASEBOARD_FAB2_LIB.BASEBOARD_FAB2(SCH_1):TP_CPU1_RSVD_67
  U2D1  CU6 RSVD<67> SKX_EXT_B_BGA1-IC,TBD   I107 @BASEBOARD_FAB2_LIB.BASEBOARD_FAB2(SCH_1):PAGE73

TP_CPU1_RSVD_69 @BASEBOARD_FAB2_LIB.BASEBOARD_FAB2(SCH_1):TP_CPU1_RSVD_69
  U2D1 CT69 RSVD<69> SKX_EXT_B_BGA1-IC,TBD   I107 @BASEBOARD_FAB2_LIB.BASEBOARD_FAB2(SCH_1):PAGE73

TP_CPU1_RSVD_7 @BASEBOARD_FAB2_LIB.BASEBOARD_FAB2(SCH_1):TP_CPU1_RSVD_7
  U2D1 EE46 RSVD<7> SKX_EXT_B_BGA1-IC,TBD   I107 @BASEBOARD_FAB2_LIB.BASEBOARD_FAB2(SCH_1):PAGE73

TP_CPU1_RSVD_70 @BASEBOARD_FAB2_LIB.BASEBOARD_FAB2(SCH_1):TP_CPU1_RSVD_70
  U2D1  CT5 RSVD<70> SKX_EXT_B_BGA1-IC,TBD   I107 @BASEBOARD_FAB2_LIB.BASEBOARD_FAB2(SCH_1):PAGE73

TP_CPU1_RSVD_72 @BASEBOARD_FAB2_LIB.BASEBOARD_FAB2(SCH_1):TP_CPU1_RSVD_72
  U2D1 CR60 RSVD<72> SKX_EXT_B_BGA1-IC,TBD   I107 @BASEBOARD_FAB2_LIB.BASEBOARD_FAB2(SCH_1):PAGE73

TP_CPU1_RSVD_73 @BASEBOARD_FAB2_LIB.BASEBOARD_FAB2(SCH_1):TP_CPU1_RSVD_73
  U2D1 CP31 RSVD<73> SKX_EXT_B_BGA1-IC,TBD   I107 @BASEBOARD_FAB2_LIB.BASEBOARD_FAB2(SCH_1):PAGE73

TP_CPU1_RSVD_8 @BASEBOARD_FAB2_LIB.BASEBOARD_FAB2(SCH_1):TP_CPU1_RSVD_8
  U2D1 EE16 RSVD<8> SKX_EXT_B_BGA1-IC,TBD   I107 @BASEBOARD_FAB2_LIB.BASEBOARD_FAB2(SCH_1):PAGE73

TP_CPU1_RSVD_82 @BASEBOARD_FAB2_LIB.BASEBOARD_FAB2(SCH_1):TP_CPU1_RSVD_82
  U2D1 CK77 RSVD<82> SKX_EXT_B_BGA1-IC,TBD    I10 @BASEBOARD_FAB2_LIB.BASEBOARD_FAB2(SCH_1):PAGE70

TP_CPU1_RSVD_85 @BASEBOARD_FAB2_LIB.BASEBOARD_FAB2(SCH_1):TP_CPU1_RSVD_85
  U2D1 CK19 RSVD<85> SKX_EXT_B_BGA1-IC,TBD    I10 @BASEBOARD_FAB2_LIB.BASEBOARD_FAB2(SCH_1):PAGE70

TP_CPU1_RSVD_9 @BASEBOARD_FAB2_LIB.BASEBOARD_FAB2(SCH_1):TP_CPU1_RSVD_9
  U2D1 ED83 RSVD<9> SKX_EXT_B_BGA1-IC,TBD   I107 @BASEBOARD_FAB2_LIB.BASEBOARD_FAB2(SCH_1):PAGE73

TP_CPU1_RSVD_90 @BASEBOARD_FAB2_LIB.BASEBOARD_FAB2(SCH_1):TP_CPU1_RSVD_90
  U2D1 CH77 RSVD<90> SKX_EXT_B_BGA1-IC,TBD    I10 @BASEBOARD_FAB2_LIB.BASEBOARD_FAB2(SCH_1):PAGE70

TP_CPU1_RSVD_91 @BASEBOARD_FAB2_LIB.BASEBOARD_FAB2(SCH_1):TP_CPU1_RSVD_91
  U2D1 CH25 RSVD<91> SKX_EXT_B_BGA1-IC,TBD    I10 @BASEBOARD_FAB2_LIB.BASEBOARD_FAB2(SCH_1):PAGE70

TP_CPU1_RSVD_94 @BASEBOARD_FAB2_LIB.BASEBOARD_FAB2(SCH_1):TP_CPU1_RSVD_94
  U2D1 CG82 RSVD<94> SKX_EXT_B_BGA1-IC,TBD     I9 @BASEBOARD_FAB2_LIB.BASEBOARD_FAB2(SCH_1):PAGE70

TP_CPU1_RSVD_95 @BASEBOARD_FAB2_LIB.BASEBOARD_FAB2(SCH_1):TP_CPU1_RSVD_95
  U2D1 CG78 RSVD<95> SKX_EXT_B_BGA1-IC,TBD     I9 @BASEBOARD_FAB2_LIB.BASEBOARD_FAB2(SCH_1):PAGE70

TP_CPU1_RSVD_97 @BASEBOARD_FAB2_LIB.BASEBOARD_FAB2(SCH_1):TP_CPU1_RSVD_97
  U2D1 CG24 RSVD<97> SKX_EXT_B_BGA1-IC,TBD     I9 @BASEBOARD_FAB2_LIB.BASEBOARD_FAB2(SCH_1):PAGE70

TP_CPU1_RSVD_99 @BASEBOARD_FAB2_LIB.BASEBOARD_FAB2(SCH_1):TP_CPU1_RSVD_99
  U2D1 CG10 RSVD<99> SKX_EXT_B_BGA1-IC,TBD     I9 @BASEBOARD_FAB2_LIB.BASEBOARD_FAB2(SCH_1):PAGE70

TP_CPU1_RSVD_TEST_11 @BASEBOARD_FAB2_LIB.BASEBOARD_FAB2(SCH_1):TP_CPU1_RSVD_TEST_11
  U2D1 AY13 TEST_11 SKX_EXT_B_BGA1-IC,TBD   I169 @BASEBOARD_FAB2_LIB.BASEBOARD_FAB2(SCH_1):PAGE56

TP_CPU1_RSVD_TEST_3 @BASEBOARD_FAB2_LIB.BASEBOARD_FAB2(SCH_1):TP_CPU1_RSVD_TEST_3
  U2D1 AM13 TEST_3 SKX_EXT_B_BGA1-IC,TBD   I169 @BASEBOARD_FAB2_LIB.BASEBOARD_FAB2(SCH_1):PAGE56

TP_CPU1_RSVD_TEST_4 @BASEBOARD_FAB2_LIB.BASEBOARD_FAB2(SCH_1):TP_CPU1_RSVD_TEST_4
  U2D1 AN12 TEST_4 SKX_EXT_B_BGA1-IC,TBD   I169 @BASEBOARD_FAB2_LIB.BASEBOARD_FAB2(SCH_1):PAGE56

TP_CPU1_RSVD_TEST_5 @BASEBOARD_FAB2_LIB.BASEBOARD_FAB2(SCH_1):TP_CPU1_RSVD_TEST_5
  U2D1 AN14 TEST_5 SKX_EXT_B_BGA1-IC,TBD   I169 @BASEBOARD_FAB2_LIB.BASEBOARD_FAB2(SCH_1):PAGE56

TP_CPU1_SOCKET_ID_2 @BASEBOARD_FAB2_LIB.BASEBOARD_FAB2(SCH_1):TP_CPU1_SOCKET_ID_2
  U2D1 AU20 SOCKET_ID<2> SKX_EXT_B_BGA1-IC,TBD   I172 @BASEBOARD_FAB2_LIB.BASEBOARD_FAB2(SCH_1):PAGE55

TP_CPU1_TEST_10 @BASEBOARD_FAB2_LIB.BASEBOARD_FAB2(SCH_1):TP_CPU1_TEST_10
  U2D1 AW22 TEST_10 SKX_EXT_B_BGA1-IC,TBD    I10 @BASEBOARD_FAB2_LIB.BASEBOARD_FAB2(SCH_1):PAGE70

TP_CPU1_TEST_6 @BASEBOARD_FAB2_LIB.BASEBOARD_FAB2(SCH_1):TP_CPU1_TEST_6
  U2D1 AR16 TEST_6 SKX_EXT_B_BGA1-IC,TBD    I10 @BASEBOARD_FAB2_LIB.BASEBOARD_FAB2(SCH_1):PAGE70

TP_CPU1_TEST_7 @BASEBOARD_FAB2_LIB.BASEBOARD_FAB2(SCH_1):TP_CPU1_TEST_7
  U2D1 AU18 TEST_7 SKX_EXT_B_BGA1-IC,TBD    I10 @BASEBOARD_FAB2_LIB.BASEBOARD_FAB2(SCH_1):PAGE70

TP_CPU1_TEST_8 @BASEBOARD_FAB2_LIB.BASEBOARD_FAB2(SCH_1):TP_CPU1_TEST_8
  U2D1 AW16 TEST_8 SKX_EXT_B_BGA1-IC,TBD    I10 @BASEBOARD_FAB2_LIB.BASEBOARD_FAB2(SCH_1):PAGE70

TP_CPU1_TEST_9 @BASEBOARD_FAB2_LIB.BASEBOARD_FAB2(SCH_1):TP_CPU1_TEST_9
  U2D1 AW20 TEST_9 SKX_EXT_B_BGA1-IC,TBD    I10 @BASEBOARD_FAB2_LIB.BASEBOARD_FAB2(SCH_1):PAGE70

TP_CPU1_UPI2_RSVD_CA12 @BASEBOARD_FAB2_LIB.BASEBOARD_FAB2(SCH_1):TP_CPU1_UPI2_RSVD_CA12
  U2D1 DP21 UPI2_TX_DP<0> SKX_EXT_B_BGA1-IC,TBD     I1 @BASEBOARD_FAB2_LIB.BASEBOARD_FAB2(SCH_1):PAGE69

TP_CPU1_UPI2_RSVD_CB11 @BASEBOARD_FAB2_LIB.BASEBOARD_FAB2(SCH_1):TP_CPU1_UPI2_RSVD_CB11
  U2D1 DN20 UPI2_TX_DP<1> SKX_EXT_B_BGA1-IC,TBD     I1 @BASEBOARD_FAB2_LIB.BASEBOARD_FAB2(SCH_1):PAGE69

TP_CPU1_UPI2_RSVD_CC10 @BASEBOARD_FAB2_LIB.BASEBOARD_FAB2(SCH_1):TP_CPU1_UPI2_RSVD_CC10
  U2D1 DM21 UPI2_TX_DN<1> SKX_EXT_B_BGA1-IC,TBD     I1 @BASEBOARD_FAB2_LIB.BASEBOARD_FAB2(SCH_1):PAGE69

TP_CPU1_UPI2_RSVD_CC12 @BASEBOARD_FAB2_LIB.BASEBOARD_FAB2(SCH_1):TP_CPU1_UPI2_RSVD_CC12
  U2D1 DT21 UPI2_TX_DN<0> SKX_EXT_B_BGA1-IC,TBD     I1 @BASEBOARD_FAB2_LIB.BASEBOARD_FAB2(SCH_1):PAGE69

TP_CPU1_UPI2_RSVD_CD11 @BASEBOARD_FAB2_LIB.BASEBOARD_FAB2(SCH_1):TP_CPU1_UPI2_RSVD_CD11
  U2D1 DK19 UPI2_TX_DP<2> SKX_EXT_B_BGA1-IC,TBD     I1 @BASEBOARD_FAB2_LIB.BASEBOARD_FAB2(SCH_1):PAGE69

TP_CPU1_UPI2_RSVD_CE12 @BASEBOARD_FAB2_LIB.BASEBOARD_FAB2(SCH_1):TP_CPU1_UPI2_RSVD_CE12
  U2D1 DL20 UPI2_TX_DN<2> SKX_EXT_B_BGA1-IC,TBD     I1 @BASEBOARD_FAB2_LIB.BASEBOARD_FAB2(SCH_1):PAGE69

TP_CPU1_UPI2_RSVD_CF11 @BASEBOARD_FAB2_LIB.BASEBOARD_FAB2(SCH_1):TP_CPU1_UPI2_RSVD_CF11
  U2D1 DJ20 UPI2_TX_DP<3> SKX_EXT_B_BGA1-IC,TBD     I1 @BASEBOARD_FAB2_LIB.BASEBOARD_FAB2(SCH_1):PAGE69

TP_CPU1_UPI2_RSVD_CF13 @BASEBOARD_FAB2_LIB.BASEBOARD_FAB2(SCH_1):TP_CPU1_UPI2_RSVD_CF13
  U2D1 DH19 UPI2_TX_DN<4> SKX_EXT_B_BGA1-IC,TBD     I1 @BASEBOARD_FAB2_LIB.BASEBOARD_FAB2(SCH_1):PAGE69

TP_CPU1_UPI2_RSVD_CG12 @BASEBOARD_FAB2_LIB.BASEBOARD_FAB2(SCH_1):TP_CPU1_UPI2_RSVD_CG12
  U2D1 DJ18 UPI2_TX_DP<4> SKX_EXT_B_BGA1-IC,TBD     I1 @BASEBOARD_FAB2_LIB.BASEBOARD_FAB2(SCH_1):PAGE69

TP_CPU1_UPI2_RSVD_CH11 @BASEBOARD_FAB2_LIB.BASEBOARD_FAB2(SCH_1):TP_CPU1_UPI2_RSVD_CH11
  U2D1 DG20 UPI2_TX_DN<3> SKX_EXT_B_BGA1-IC,TBD     I1 @BASEBOARD_FAB2_LIB.BASEBOARD_FAB2(SCH_1):PAGE69

TP_CPU1_UPI2_RSVD_CH13 @BASEBOARD_FAB2_LIB.BASEBOARD_FAB2(SCH_1):TP_CPU1_UPI2_RSVD_CH13
  U2D1 DH17 UPI2_TX_DP<5> SKX_EXT_B_BGA1-IC,TBD     I1 @BASEBOARD_FAB2_LIB.BASEBOARD_FAB2(SCH_1):PAGE69

TP_CPU1_UPI2_RSVD_CJ14 @BASEBOARD_FAB2_LIB.BASEBOARD_FAB2(SCH_1):TP_CPU1_UPI2_RSVD_CJ14
  U2D1 DK17 UPI2_TX_DN<5> SKX_EXT_B_BGA1-IC,TBD     I1 @BASEBOARD_FAB2_LIB.BASEBOARD_FAB2(SCH_1):PAGE69

TP_CPU1_UPI2_RSVD_CK13 @BASEBOARD_FAB2_LIB.BASEBOARD_FAB2(SCH_1):TP_CPU1_UPI2_RSVD_CK13
  U2D1 DF17 UPI2_TX_DP<6> SKX_EXT_B_BGA1-IC,TBD     I1 @BASEBOARD_FAB2_LIB.BASEBOARD_FAB2(SCH_1):PAGE69

TP_CPU1_UPI2_RSVD_CM13 @BASEBOARD_FAB2_LIB.BASEBOARD_FAB2(SCH_1):TP_CPU1_UPI2_RSVD_CM13
  U2D1 DG18 UPI2_TX_DN<6> SKX_EXT_B_BGA1-IC,TBD     I1 @BASEBOARD_FAB2_LIB.BASEBOARD_FAB2(SCH_1):PAGE69

TP_CPU1_UPI2_RSVD_CR14 @BASEBOARD_FAB2_LIB.BASEBOARD_FAB2(SCH_1):TP_CPU1_UPI2_RSVD_CR14
  U2D1 DE16 UPI2_TX_DP<7> SKX_EXT_B_BGA1-IC,TBD     I1 @BASEBOARD_FAB2_LIB.BASEBOARD_FAB2(SCH_1):PAGE69

TP_CPU1_UPI2_RSVD_CU14 @BASEBOARD_FAB2_LIB.BASEBOARD_FAB2(SCH_1):TP_CPU1_UPI2_RSVD_CU14
  U2D1 DD17 UPI2_TX_DN<7> SKX_EXT_B_BGA1-IC,TBD     I1 @BASEBOARD_FAB2_LIB.BASEBOARD_FAB2(SCH_1):PAGE69

TP_CPU1_UPI2_RSVD_CV13 @BASEBOARD_FAB2_LIB.BASEBOARD_FAB2(SCH_1):TP_CPU1_UPI2_RSVD_CV13
  U2D1 DD15 UPI2_TX_DP<8> SKX_EXT_B_BGA1-IC,TBD     I1 @BASEBOARD_FAB2_LIB.BASEBOARD_FAB2(SCH_1):PAGE69

TP_CPU1_UPI2_RSVD_CW14 @BASEBOARD_FAB2_LIB.BASEBOARD_FAB2(SCH_1):TP_CPU1_UPI2_RSVD_CW14
  U2D1 DF15 UPI2_TX_DN<8> SKX_EXT_B_BGA1-IC,TBD     I1 @BASEBOARD_FAB2_LIB.BASEBOARD_FAB2(SCH_1):PAGE69

TP_CPU1_UPI2_RSVD_CW16 @BASEBOARD_FAB2_LIB.BASEBOARD_FAB2(SCH_1):TP_CPU1_UPI2_RSVD_CW16
  U2D1 DB15 UPI2_TX_DP<9> SKX_EXT_B_BGA1-IC,TBD     I1 @BASEBOARD_FAB2_LIB.BASEBOARD_FAB2(SCH_1):PAGE69

TP_CPU1_UPI2_RSVD_DA16 @BASEBOARD_FAB2_LIB.BASEBOARD_FAB2(SCH_1):TP_CPU1_UPI2_RSVD_DA16
  U2D1 DC16 UPI2_TX_DN<9> SKX_EXT_B_BGA1-IC,TBD     I1 @BASEBOARD_FAB2_LIB.BASEBOARD_FAB2(SCH_1):PAGE69

TP_CPU1_UPI2_RSVD_DB15 @BASEBOARD_FAB2_LIB.BASEBOARD_FAB2(SCH_1):TP_CPU1_UPI2_RSVD_DB15
  U2D1 CW16 UPI2_TX_DP<10> SKX_EXT_B_BGA1-IC,TBD     I1 @BASEBOARD_FAB2_LIB.BASEBOARD_FAB2(SCH_1):PAGE69

TP_CPU1_UPI2_RSVD_DC16 @BASEBOARD_FAB2_LIB.BASEBOARD_FAB2(SCH_1):TP_CPU1_UPI2_RSVD_DC16
  U2D1 DA16 UPI2_TX_DN<10> SKX_EXT_B_BGA1-IC,TBD     I1 @BASEBOARD_FAB2_LIB.BASEBOARD_FAB2(SCH_1):PAGE69

TP_CPU1_UPI2_RSVD_DD15 @BASEBOARD_FAB2_LIB.BASEBOARD_FAB2(SCH_1):TP_CPU1_UPI2_RSVD_DD15
  U2D1 CV13 UPI2_TX_DP<11> SKX_EXT_B_BGA1-IC,TBD     I1 @BASEBOARD_FAB2_LIB.BASEBOARD_FAB2(SCH_1):PAGE69

TP_CPU1_UPI2_RSVD_DD17 @BASEBOARD_FAB2_LIB.BASEBOARD_FAB2(SCH_1):TP_CPU1_UPI2_RSVD_DD17
  U2D1 CU14 UPI2_TX_DN<12> SKX_EXT_B_BGA1-IC,TBD     I1 @BASEBOARD_FAB2_LIB.BASEBOARD_FAB2(SCH_1):PAGE69

TP_CPU1_UPI2_RSVD_DE16 @BASEBOARD_FAB2_LIB.BASEBOARD_FAB2(SCH_1):TP_CPU1_UPI2_RSVD_DE16
  U2D1 CR14 UPI2_TX_DP<12> SKX_EXT_B_BGA1-IC,TBD     I1 @BASEBOARD_FAB2_LIB.BASEBOARD_FAB2(SCH_1):PAGE69

TP_CPU1_UPI2_RSVD_DF15 @BASEBOARD_FAB2_LIB.BASEBOARD_FAB2(SCH_1):TP_CPU1_UPI2_RSVD_DF15
  U2D1 CW14 UPI2_TX_DN<11> SKX_EXT_B_BGA1-IC,TBD     I1 @BASEBOARD_FAB2_LIB.BASEBOARD_FAB2(SCH_1):PAGE69

TP_CPU1_UPI2_RSVD_DF17 @BASEBOARD_FAB2_LIB.BASEBOARD_FAB2(SCH_1):TP_CPU1_UPI2_RSVD_DF17
  U2D1 CK13 UPI2_TX_DP<13> SKX_EXT_B_BGA1-IC,TBD     I1 @BASEBOARD_FAB2_LIB.BASEBOARD_FAB2(SCH_1):PAGE69

TP_CPU1_UPI2_RSVD_DG18 @BASEBOARD_FAB2_LIB.BASEBOARD_FAB2(SCH_1):TP_CPU1_UPI2_RSVD_DG18
  U2D1 CM13 UPI2_TX_DN<13> SKX_EXT_B_BGA1-IC,TBD     I1 @BASEBOARD_FAB2_LIB.BASEBOARD_FAB2(SCH_1):PAGE69

TP_CPU1_UPI2_RSVD_DG20 @BASEBOARD_FAB2_LIB.BASEBOARD_FAB2(SCH_1):TP_CPU1_UPI2_RSVD_DG20
  U2D1 CH11 UPI2_TX_DN<16> SKX_EXT_B_BGA1-IC,TBD     I1 @BASEBOARD_FAB2_LIB.BASEBOARD_FAB2(SCH_1):PAGE69

TP_CPU1_UPI2_RSVD_DH17 @BASEBOARD_FAB2_LIB.BASEBOARD_FAB2(SCH_1):TP_CPU1_UPI2_RSVD_DH17
  U2D1 CH13 UPI2_TX_DP<14> SKX_EXT_B_BGA1-IC,TBD     I1 @BASEBOARD_FAB2_LIB.BASEBOARD_FAB2(SCH_1):PAGE69

TP_CPU1_UPI2_RSVD_DH19 @BASEBOARD_FAB2_LIB.BASEBOARD_FAB2(SCH_1):TP_CPU1_UPI2_RSVD_DH19
  U2D1 CF13 UPI2_TX_DN<15> SKX_EXT_B_BGA1-IC,TBD     I1 @BASEBOARD_FAB2_LIB.BASEBOARD_FAB2(SCH_1):PAGE69

TP_CPU1_UPI2_RSVD_DJ18 @BASEBOARD_FAB2_LIB.BASEBOARD_FAB2(SCH_1):TP_CPU1_UPI2_RSVD_DJ18
  U2D1 CG12 UPI2_TX_DP<15> SKX_EXT_B_BGA1-IC,TBD     I1 @BASEBOARD_FAB2_LIB.BASEBOARD_FAB2(SCH_1):PAGE69

TP_CPU1_UPI2_RSVD_DJ20 @BASEBOARD_FAB2_LIB.BASEBOARD_FAB2(SCH_1):TP_CPU1_UPI2_RSVD_DJ20
  U2D1 CF11 UPI2_TX_DP<16> SKX_EXT_B_BGA1-IC,TBD     I1 @BASEBOARD_FAB2_LIB.BASEBOARD_FAB2(SCH_1):PAGE69

TP_CPU1_UPI2_RSVD_DK17 @BASEBOARD_FAB2_LIB.BASEBOARD_FAB2(SCH_1):TP_CPU1_UPI2_RSVD_DK17
  U2D1 CJ14 UPI2_TX_DN<14> SKX_EXT_B_BGA1-IC,TBD     I1 @BASEBOARD_FAB2_LIB.BASEBOARD_FAB2(SCH_1):PAGE69

TP_CPU1_UPI2_RSVD_DK19 @BASEBOARD_FAB2_LIB.BASEBOARD_FAB2(SCH_1):TP_CPU1_UPI2_RSVD_DK19
  U2D1 CD11 UPI2_TX_DP<17> SKX_EXT_B_BGA1-IC,TBD     I1 @BASEBOARD_FAB2_LIB.BASEBOARD_FAB2(SCH_1):PAGE69

TP_CPU1_UPI2_RSVD_DL20 @BASEBOARD_FAB2_LIB.BASEBOARD_FAB2(SCH_1):TP_CPU1_UPI2_RSVD_DL20
  U2D1 CE12 UPI2_TX_DN<17> SKX_EXT_B_BGA1-IC,TBD     I1 @BASEBOARD_FAB2_LIB.BASEBOARD_FAB2(SCH_1):PAGE69

TP_CPU1_UPI2_RSVD_DM21 @BASEBOARD_FAB2_LIB.BASEBOARD_FAB2(SCH_1):TP_CPU1_UPI2_RSVD_DM21
  U2D1 CC10 UPI2_TX_DN<18> SKX_EXT_B_BGA1-IC,TBD     I1 @BASEBOARD_FAB2_LIB.BASEBOARD_FAB2(SCH_1):PAGE69

TP_CPU1_UPI2_RSVD_DN20 @BASEBOARD_FAB2_LIB.BASEBOARD_FAB2(SCH_1):TP_CPU1_UPI2_RSVD_DN20
  U2D1 CB11 UPI2_TX_DP<18> SKX_EXT_B_BGA1-IC,TBD     I1 @BASEBOARD_FAB2_LIB.BASEBOARD_FAB2(SCH_1):PAGE69

TP_CPU1_UPI2_RSVD_DP21 @BASEBOARD_FAB2_LIB.BASEBOARD_FAB2(SCH_1):TP_CPU1_UPI2_RSVD_DP21
  U2D1 CA12 UPI2_TX_DP<19> SKX_EXT_B_BGA1-IC,TBD     I1 @BASEBOARD_FAB2_LIB.BASEBOARD_FAB2(SCH_1):PAGE69

TP_CPU1_UPI2_RSVD_DT21 @BASEBOARD_FAB2_LIB.BASEBOARD_FAB2(SCH_1):TP_CPU1_UPI2_RSVD_DT21
  U2D1 CC12 UPI2_TX_DN<19> SKX_EXT_B_BGA1-IC,TBD     I1 @BASEBOARD_FAB2_LIB.BASEBOARD_FAB2(SCH_1):PAGE69

TP_CPU_PCH_TRIGGER_IN @BASEBOARD_FAB2_LIB.BASEBOARD_FAB2(SCH_1):TP_CPU_PCH_TRIGGER_IN
  U7C1   M7 TRIGGER_IN LBG_CORE_QAT_EXT_D_BGA1-IC,H91A    I73 @BASEBOARD_FAB2_LIB.BASEBOARD_FAB2(SCH_1):PAGE118

TP_CPU_PCH_TRIGGER_OUT @BASEBOARD_FAB2_LIB.BASEBOARD_FAB2(SCH_1):TP_CPU_PCH_TRIGGER_OUT
  U7C1  R13 TRIGGER_OUT LBG_CORE_QAT_EXT_D_BGA1-IC,H91A    I73 @BASEBOARD_FAB2_LIB.BASEBOARD_FAB2(SCH_1):PAGE118

TP_DACB @BASEBOARD_FAB2_LIB.BASEBOARD_FAB2(SCH_1):TP_DACB
 U25W4   J2   DACB AST2520A1-GP-GP_ASIC2-GB1-AST2A    I95 @BASEBOARD_FAB2_LIB.BASEBOARD_FAB2(SCH_1):PAGE144

TP_DACG @BASEBOARD_FAB2_LIB.BASEBOARD_FAB2(SCH_1):TP_DACG
 U25W4   J3   DACG AST2520A1-GP-GP_ASIC2-GB1-AST2A    I95 @BASEBOARD_FAB2_LIB.BASEBOARD_FAB2(SCH_1):PAGE144

TP_DACR @BASEBOARD_FAB2_LIB.BASEBOARD_FAB2(SCH_1):TP_DACR
 U25W4   J4   DACR AST2520A1-GP-GP_ASIC2-GB1-AST2A    I95 @BASEBOARD_FAB2_LIB.BASEBOARD_FAB2(SCH_1):PAGE144

TP_DDCCLK_GPIOJ6 @BASEBOARD_FAB2_LIB.BASEBOARD_FAB2(SCH_1):TP_DDCCLK_GPIOJ6
 U25W4   R3 GPIOJ6_DDCCLK AST2520A1-GP-GP_ASIC2-GB1-AST2A   I105 @BASEBOARD_FAB2_LIB.BASEBOARD_FAB2(SCH_1):PAGE146

TP_DDCDAT_GPIOJ7 @BASEBOARD_FAB2_LIB.BASEBOARD_FAB2(SCH_1):TP_DDCDAT_GPIOJ7
 U25W4   T3 GPIOJ7_DDCDAT AST2520A1-GP-GP_ASIC2-GB1-AST2A   I105 @BASEBOARD_FAB2_LIB.BASEBOARD_FAB2(SCH_1):PAGE146

TP_EXT_MDIO_I2C_SEL @BASEBOARD_FAB2_LIB.BASEBOARD_FAB2(SCH_1):TP_EXT_MDIO_I2C_SEL
  J8E4    3    IO3 SCONN64_H87568002_A_SMT-CONN,HA    I27 @BASEBOARD_FAB2_LIB.BASEBOARD_FAB2(SCH_1):PAGE188

TP_FAN_0 @BASEBOARD_FAB2_LIB.BASEBOARD_FAB2(SCH_1):TP_FAN_0
  J1F2    6    IO6 CONN6_C74770005_PIP-HDR,C74770A     I1 @BASEBOARD_FAB2_LIB.BASEBOARD_FAB2(SCH_1):PAGE161

TP_FAN_1 @BASEBOARD_FAB2_LIB.BASEBOARD_FAB2(SCH_1):TP_FAN_1
  J1B2    6    IO6 CONN6_C74770005_PIP-HDR,C74770A    I32 @BASEBOARD_FAB2_LIB.BASEBOARD_FAB2(SCH_1):PAGE161

TP_FET_Q56_3 @BASEBOARD_FAB2_LIB.BASEBOARD_FAB2(SCH_1):TP_FET_Q56_3
  Q1L4    3 DRAIN<0> FET_N_DUAL_SMLF-2N7002DW,FET,DA    I18 @BASEBOARD_FAB2_LIB.BASEBOARD_FAB2(SCH_1):PAGE168

TP_FET_Q56_4 @BASEBOARD_FAB2_LIB.BASEBOARD_FAB2(SCH_1):TP_FET_Q56_4
  Q1L4    5 GATE<0> FET_N_DUAL_SMLF-2N7002DW,FET,DA    I18 @BASEBOARD_FAB2_LIB.BASEBOARD_FAB2(SCH_1):PAGE168
  Q1L4    4 SOURCE<0> FET_N_DUAL_SMLF-2N7002DW,FET,DA    I18 @BASEBOARD_FAB2_LIB.BASEBOARD_FAB2(SCH_1):PAGE168

TP_FM_CPU1_CD_HFI0_MODPRST_N @BASEBOARD_FAB2_LIB.BASEBOARD_FAB2(SCH_1):TP_FM_CPU1_CD_HFI0_MODPRST_N
  U2D1 BR20 CD_HFI0_MODPRST_N SKX_EXT_B_BGA1-IC,TBD    I23 @BASEBOARD_FAB2_LIB.BASEBOARD_FAB2(SCH_1):PAGE63

TP_FM_QAT_CBL_PRSNT0_R_N @BASEBOARD_FAB2_LIB.BASEBOARD_FAB2(SCH_1):TP_FM_QAT_CBL_PRSNT0_R_N
  J8A1  1A1 SIDEBANDA_7 CONN72_G97614002_A_CP-CONN,G97A   I163 @BASEBOARD_FAB2_LIB.BASEBOARD_FAB2(SCH_1):PAGE173

TP_FM_QAT_CBL_PRSNT1_N_R @BASEBOARD_FAB2_LIB.BASEBOARD_FAB2(SCH_1):TP_FM_QAT_CBL_PRSNT1_N_R
  J8A1  2A1 SIDEBANDB_7 CONN72_G97614002_A_CP-CONN,G97A   I163 @BASEBOARD_FAB2_LIB.BASEBOARD_FAB2(SCH_1):PAGE173

TP_FM_QAT_CBL_PRSNT2_N @BASEBOARD_FAB2_LIB.BASEBOARD_FAB2(SCH_1):TP_FM_QAT_CBL_PRSNT2_N
  J8A2   A1 SIDEBAND7 CONN36_G97614001_CP-CONN,G9761A    I26 @BASEBOARD_FAB2_LIB.BASEBOARD_FAB2(SCH_1):PAGE174

TP_FM_WAKE_N @BASEBOARD_FAB2_LIB.BASEBOARD_FAB2(SCH_1):TP_FM_WAKE_N
  J1C1   B4   IOB4 CONN76_H22707001_THMT1-CONN,H2A    I18 @BASEBOARD_FAB2_LIB.BASEBOARD_FAB2(SCH_1):PAGE182

TP_GPIO0_DSRB_N @BASEBOARD_FAB2_LIB.BASEBOARD_FAB2(SCH_1):TP_GPIO0_DSRB_N
 EU9F3   13 GPIO0_DSRB_N PI7C9X1172_QFN-IC,H66899-001     I1 @BASEBOARD_FAB2_LIB.BASEBOARD_FAB2(SCH_1):PAGE183

TP_GPIO1_DTRB_N @BASEBOARD_FAB2_LIB.BASEBOARD_FAB2(SCH_1):TP_GPIO1_DTRB_N
 EU9F3   23 GPIO1_DTRB_N PI7C9X1172_QFN-IC,H66899-001     I1 @BASEBOARD_FAB2_LIB.BASEBOARD_FAB2(SCH_1):PAGE183

TP_GPIO2_CDB_N @BASEBOARD_FAB2_LIB.BASEBOARD_FAB2(SCH_1):TP_GPIO2_CDB_N
 EU9F3   11 GPIO2_CDB_N PI7C9X1172_QFN-IC,H66899-001     I1 @BASEBOARD_FAB2_LIB.BASEBOARD_FAB2(SCH_1):PAGE183

TP_GPIO3_RIB_N @BASEBOARD_FAB2_LIB.BASEBOARD_FAB2(SCH_1):TP_GPIO3_RIB_N
 EU9F3   14 GPIO3_RIB_N PI7C9X1172_QFN-IC,H66899-001     I1 @BASEBOARD_FAB2_LIB.BASEBOARD_FAB2(SCH_1):PAGE183

TP_GPIO4_DSRA_N @BASEBOARD_FAB2_LIB.BASEBOARD_FAB2(SCH_1):TP_GPIO4_DSRA_N
 EU9F3   26 GPIO4_DSRA_N PI7C9X1172_QFN-IC,H66899-001     I1 @BASEBOARD_FAB2_LIB.BASEBOARD_FAB2(SCH_1):PAGE183

TP_GPIO5_DTRA_N @BASEBOARD_FAB2_LIB.BASEBOARD_FAB2(SCH_1):TP_GPIO5_DTRA_N
 EU9F3   22 GPIO5_DTRA_N PI7C9X1172_QFN-IC,H66899-001     I1 @BASEBOARD_FAB2_LIB.BASEBOARD_FAB2(SCH_1):PAGE183

TP_GPIO6_CDA_N @BASEBOARD_FAB2_LIB.BASEBOARD_FAB2(SCH_1):TP_GPIO6_CDA_N
 EU9F3   27 GPIO6_CDA_N PI7C9X1172_QFN-IC,H66899-001     I1 @BASEBOARD_FAB2_LIB.BASEBOARD_FAB2(SCH_1):PAGE183

TP_GPIO7_RIA_N @BASEBOARD_FAB2_LIB.BASEBOARD_FAB2(SCH_1):TP_GPIO7_RIA_N
 EU9F3   28 GPIO7_RIA_N PI7C9X1172_QFN-IC,H66899-001     I1 @BASEBOARD_FAB2_LIB.BASEBOARD_FAB2(SCH_1):PAGE183

TP_HFI_IO_CONN0_RSVD_17 @BASEBOARD_FAB2_LIB.BASEBOARD_FAB2(SCH_1):TP_HFI_IO_CONN0_RSVD_17
  J8B1   17   IO17 SCONN24_H46321001_SM-SCONN,H46A     I1 @BASEBOARD_FAB2_LIB.BASEBOARD_FAB2(SCH_1):PAGE91

TP_HSC_ALERT2_N @BASEBOARD_FAB2_LIB.BASEBOARD_FAB2(SCH_1):TP_HSC_ALERT2_N
 EU1D2   14 GPO2_ALERT2_N ADM1278_SM-IC,G99251-001    I10 @BASEBOARD_FAB2_LIB.BASEBOARD_FAB2(SCH_1):PAGE199

TP_HSC_MCLK @BASEBOARD_FAB2_LIB.BASEBOARD_FAB2(SCH_1):TP_HSC_MCLK
 EU1D2   10   MCLK ADM1278_SM-IC,G99251-001    I10 @BASEBOARD_FAB2_LIB.BASEBOARD_FAB2(SCH_1):PAGE199

TP_HSC_MDAT @BASEBOARD_FAB2_LIB.BASEBOARD_FAB2(SCH_1):TP_HSC_MDAT
 EU1D2   11   MDAT ADM1278_SM-IC,G99251-001    I10 @BASEBOARD_FAB2_LIB.BASEBOARD_FAB2(SCH_1):PAGE199

TP_HSC_SPISSN @BASEBOARD_FAB2_LIB.BASEBOARD_FAB2(SCH_1):TP_HSC_SPISSN
 EU1D2    9 SPISS_N ADM1278_SM-IC,G99251-001    I10 @BASEBOARD_FAB2_LIB.BASEBOARD_FAB2(SCH_1):PAGE199

TP_IE_DEBUG_MODE @BASEBOARD_FAB2_LIB.BASEBOARD_FAB2(SCH_1):TP_IE_DEBUG_MODE
  J9G1    7    IO7 CONN12_C73564003_PIP-CONN,C735A   I128 @BASEBOARD_FAB2_LIB.BASEBOARD_FAB2(SCH_1):PAGE137

TP_IOA5 @BASEBOARD_FAB2_LIB.BASEBOARD_FAB2(SCH_1):TP_IOA5
  J1C1   A5   IOA5 CONN76_H22707001_THMT1-CONN,H2A    I18 @BASEBOARD_FAB2_LIB.BASEBOARD_FAB2(SCH_1):PAGE182

TP_IOE4 @BASEBOARD_FAB2_LIB.BASEBOARD_FAB2(SCH_1):TP_IOE4
  J1C1   E4   IOE4 CONN76_H22707001_THMT1-CONN,H2A    I18 @BASEBOARD_FAB2_LIB.BASEBOARD_FAB2(SCH_1):PAGE182

TP_IOF4 @BASEBOARD_FAB2_LIB.BASEBOARD_FAB2(SCH_1):TP_IOF4
  J1C1   F4   IOF4 CONN76_H22707001_THMT1-CONN,H2A    I18 @BASEBOARD_FAB2_LIB.BASEBOARD_FAB2(SCH_1):PAGE182

TP_IOG3 @BASEBOARD_FAB2_LIB.BASEBOARD_FAB2(SCH_1):TP_IOG3
  J1C1   G3   IOG3 CONN76_H22707001_THMT1-CONN,H2A    I18 @BASEBOARD_FAB2_LIB.BASEBOARD_FAB2(SCH_1):PAGE182

TP_IOH3 @BASEBOARD_FAB2_LIB.BASEBOARD_FAB2(SCH_1):TP_IOH3
  J1C1   H3   IOH3 CONN76_H22707001_THMT1-CONN,H2A    I18 @BASEBOARD_FAB2_LIB.BASEBOARD_FAB2(SCH_1):PAGE182

TP_IOH4 @BASEBOARD_FAB2_LIB.BASEBOARD_FAB2(SCH_1):TP_IOH4
  J1C1   H4   IOH4 CONN76_H22707001_THMT1-CONN,H2A    I18 @BASEBOARD_FAB2_LIB.BASEBOARD_FAB2(SCH_1):PAGE182

TP_IOI4 @BASEBOARD_FAB2_LIB.BASEBOARD_FAB2(SCH_1):TP_IOI4
  J1C1   I4   IOI4 CONN76_H22707001_THMT1-CONN,H2A    I18 @BASEBOARD_FAB2_LIB.BASEBOARD_FAB2(SCH_1):PAGE182

TP_IRQ_CPU1_CD_HFI0_N @BASEBOARD_FAB2_LIB.BASEBOARD_FAB2(SCH_1):TP_IRQ_CPU1_CD_HFI0_N
  U2D1 BP19 CD_HFI0_INT_N SKX_EXT_B_BGA1-IC,TBD    I23 @BASEBOARD_FAB2_LIB.BASEBOARD_FAB2(SCH_1):PAGE63

TP_JTAG_BMC_RTCK @BASEBOARD_FAB2_LIB.BASEBOARD_FAB2(SCH_1):TP_JTAG_BMC_RTCK
 U25W4   C9   RTCK AST2520A1-GP-GP_ASIC2-GB1-AST2A    I95 @BASEBOARD_FAB2_LIB.BASEBOARD_FAB2(SCH_1):PAGE144

TP_JTAG_MCP_IO8_RSVD @BASEBOARD_FAB2_LIB.BASEBOARD_FAB2(SCH_1):TP_JTAG_MCP_IO8_RSVD
  J9B4    8    IO8 SCONN10_C12536004_SMLF-CONN,C1A   I175 @BASEBOARD_FAB2_LIB.BASEBOARD_FAB2(SCH_1):PAGE113

TP_JUMPER_BLOCK_1_1 @BASEBOARD_FAB2_LIB.BASEBOARD_FAB2(SCH_1):TP_JUMPER_BLOCK_1_1
  J8G2    1    IO1 CONN12_C73564003_PIP-CONN,C735A   I124 @BASEBOARD_FAB2_LIB.BASEBOARD_FAB2(SCH_1):PAGE135

TP_JUMPER_BLOCK_1_2 @BASEBOARD_FAB2_LIB.BASEBOARD_FAB2(SCH_1):TP_JUMPER_BLOCK_1_2
  J8G2    2    IO2 CONN12_C73564003_PIP-CONN,C735A   I124 @BASEBOARD_FAB2_LIB.BASEBOARD_FAB2(SCH_1):PAGE135

TP_JUMPER_BLOCK_1_7 @BASEBOARD_FAB2_LIB.BASEBOARD_FAB2(SCH_1):TP_JUMPER_BLOCK_ 1_7
  J8G2    7    IO7 CONN12_C73564003_PIP-CONN,C735A   I124 @BASEBOARD_FAB2_LIB.BASEBOARD_FAB2(SCH_1):PAGE135

TP_JUMPER_BLOCK_1_8 @BASEBOARD_FAB2_LIB.BASEBOARD_FAB2(SCH_1):TP_JUMPER_BLOCK_1_8
  J8G2    8    IO8 CONN12_C73564003_PIP-CONN,C735A   I124 @BASEBOARD_FAB2_LIB.BASEBOARD_FAB2(SCH_1):PAGE135

TP_JUMPER_BLOCK_2_10 @BASEBOARD_FAB2_LIB.BASEBOARD_FAB2(SCH_1):TP_JUMPER_BLOCK_2_10
  J9G1   10   IO10 CONN12_C73564003_PIP-CONN,C735A   I128 @BASEBOARD_FAB2_LIB.BASEBOARD_FAB2(SCH_1):PAGE137

TP_JUMPER_BLOCK_2_12 @BASEBOARD_FAB2_LIB.BASEBOARD_FAB2(SCH_1):TP_JUMPER_BLOCK_2_12
  J9G1   12   IO12 CONN12_C73564003_PIP-CONN,C735A   I128 @BASEBOARD_FAB2_LIB.BASEBOARD_FAB2(SCH_1):PAGE137

TP_JUMPER_BLOCK_2_8 @BASEBOARD_FAB2_LIB.BASEBOARD_FAB2(SCH_1):TP_JUMPER_BLOCK_2_8
  J9G1    8    IO8 CONN12_C73564003_PIP-CONN,C735A   I128 @BASEBOARD_FAB2_LIB.BASEBOARD_FAB2(SCH_1):PAGE137

TP_LED_CPU1_CD_HFI0_N @BASEBOARD_FAB2_LIB.BASEBOARD_FAB2(SCH_1):TP_LED_CPU1_CD_HFI0_N
  U2D1 BK21 CD_HFI0_LED_N SKX_EXT_B_BGA1-IC,TBD    I23 @BASEBOARD_FAB2_LIB.BASEBOARD_FAB2(SCH_1):PAGE63

TP_LED_M2_ACT_N @BASEBOARD_FAB2_LIB.BASEBOARD_FAB2(SCH_1):TP_LED_M2_ACT_N
  J8F1   10 DAS_DSS_N SCONN75K_H17033002_SMT1-SCONN,A    I53 @BASEBOARD_FAB2_LIB.BASEBOARD_FAB2(SCH_1):PAGE185

TP_M2_32M_SUSCLK @BASEBOARD_FAB2_LIB.BASEBOARD_FAB2(SCH_1):TP_M2_32M_SUSCLK
  J8F1   68 SUSCLK SCONN75K_H17033002_SMT1-SCONN,A    I53 @BASEBOARD_FAB2_LIB.BASEBOARD_FAB2(SCH_1):PAGE185

TP_M2_DEVSLP @BASEBOARD_FAB2_LIB.BASEBOARD_FAB2(SCH_1):TP_M2_DEVSLP
  J8F1   38 DEVSLP SCONN75K_H17033002_SMT1-SCONN,A    I53 @BASEBOARD_FAB2_LIB.BASEBOARD_FAB2(SCH_1):PAGE185

TP_ME_RCVR_BOOT @BASEBOARD_FAB2_LIB.BASEBOARD_FAB2(SCH_1):TP_ME_RCVR_BOOT
  J7G3    1    IO1 CONN12_C73564003_PIP-CONN,C735A   I174 @BASEBOARD_FAB2_LIB.BASEBOARD_FAB2(SCH_1):PAGE136

TP_NMI_CPU0 @BASEBOARD_FAB2_LIB.BASEBOARD_FAB2(SCH_1):TP_NMI_CPU0
  U5D1 AP11    NMI SKX_EXT_B_BGA1-IC,TBD   I259 @BASEBOARD_FAB2_LIB.BASEBOARD_FAB2(SCH_1):PAGE21

TP_P1V05_PCH_GL_0 @BASEBOARD_FAB2_LIB.BASEBOARD_FAB2(SCH_1):TP_P1V05_PCH_GL_0
 EU7A2    6  GL<0> IR354XX_SM-IR35412,IC,H73684-0A   I117 @BASEBOARD_FAB2_LIB.BASEBOARD_FAB2(SCH_1):PAGE236

TP_P1V05_PCH_GL_1 @BASEBOARD_FAB2_LIB.BASEBOARD_FAB2(SCH_1):TP_P1V05_PCH_GL_1
 EU7A2   41  GL<1> IR354XX_SM-IR35412,IC,H73684-0A   I117 @BASEBOARD_FAB2_LIB.BASEBOARD_FAB2(SCH_1):PAGE236

TP_P3E_CPU1_PE1_MP_RXN<0> @BASEBOARD_FAB2_LIB.BASEBOARD_FAB2(SCH_1):TP_P3E_CPU1_PE1_MP_RXN(0)
  U2D1  CW8 PE1_RX_DN<0> SKX_EXT_B_BGA1-IC,TBD    I68 @BASEBOARD_FAB2_LIB.BASEBOARD_FAB2(SCH_1):PAGE64

TP_P3E_CPU1_PE1_MP_RXN<1> @BASEBOARD_FAB2_LIB.BASEBOARD_FAB2(SCH_1):TP_P3E_CPU1_PE1_MP_RXN(1)
  U2D1  DA8 PE1_RX_DN<1> SKX_EXT_B_BGA1-IC,TBD    I68 @BASEBOARD_FAB2_LIB.BASEBOARD_FAB2(SCH_1):PAGE64

TP_P3E_CPU1_PE1_MP_RXN<2> @BASEBOARD_FAB2_LIB.BASEBOARD_FAB2(SCH_1):TP_P3E_CPU1_PE1_MP_RXN(2)
  U2D1  DC8 PE1_RX_DN<2> SKX_EXT_B_BGA1-IC,TBD    I68 @BASEBOARD_FAB2_LIB.BASEBOARD_FAB2(SCH_1):PAGE64

TP_P3E_CPU1_PE1_MP_RXN<3> @BASEBOARD_FAB2_LIB.BASEBOARD_FAB2(SCH_1):TP_P3E_CPU1_PE1_MP_RXN(3)
  U2D1 DC10 PE1_RX_DN<3> SKX_EXT_B_BGA1-IC,TBD    I68 @BASEBOARD_FAB2_LIB.BASEBOARD_FAB2(SCH_1):PAGE64

TP_P3E_CPU1_PE1_MP_RXN<4> @BASEBOARD_FAB2_LIB.BASEBOARD_FAB2(SCH_1):TP_P3E_CPU1_PE1_MP_RXN(4)
  U2D1 DE10 PE1_RX_DN<4> SKX_EXT_B_BGA1-IC,TBD    I68 @BASEBOARD_FAB2_LIB.BASEBOARD_FAB2(SCH_1):PAGE64

TP_P3E_CPU1_PE1_MP_RXN<5> @BASEBOARD_FAB2_LIB.BASEBOARD_FAB2(SCH_1):TP_P3E_CPU1_PE1_MP_RXN(5)
  U2D1  DH9 PE1_RX_DN<5> SKX_EXT_B_BGA1-IC,TBD    I68 @BASEBOARD_FAB2_LIB.BASEBOARD_FAB2(SCH_1):PAGE64

TP_P3E_CPU1_PE1_MP_RXN<6> @BASEBOARD_FAB2_LIB.BASEBOARD_FAB2(SCH_1):TP_P3E_CPU1_PE1_MP_RXN(6)
  U2D1  DK9 PE1_RX_DN<6> SKX_EXT_B_BGA1-IC,TBD    I68 @BASEBOARD_FAB2_LIB.BASEBOARD_FAB2(SCH_1):PAGE64

TP_P3E_CPU1_PE1_MP_RXN<7> @BASEBOARD_FAB2_LIB.BASEBOARD_FAB2(SCH_1):TP_P3E_CPU1_PE1_MP_RXN(7)
  U2D1  DM9 PE1_RX_DN<7> SKX_EXT_B_BGA1-IC,TBD    I68 @BASEBOARD_FAB2_LIB.BASEBOARD_FAB2(SCH_1):PAGE64

TP_P3E_CPU1_PE1_MP_RXP<0> @BASEBOARD_FAB2_LIB.BASEBOARD_FAB2(SCH_1):TP_P3E_CPU1_PE1_MP_RXP(0)
  U2D1  CU8 PE1_RX_DP<0> SKX_EXT_B_BGA1-IC,TBD    I68 @BASEBOARD_FAB2_LIB.BASEBOARD_FAB2(SCH_1):PAGE64

TP_P3E_CPU1_PE1_MP_RXP<1> @BASEBOARD_FAB2_LIB.BASEBOARD_FAB2(SCH_1):TP_P3E_CPU1_PE1_MP_RXP(1)
  U2D1  CY7 PE1_RX_DP<1> SKX_EXT_B_BGA1-IC,TBD    I68 @BASEBOARD_FAB2_LIB.BASEBOARD_FAB2(SCH_1):PAGE64

TP_P3E_CPU1_PE1_MP_RXP<2> @BASEBOARD_FAB2_LIB.BASEBOARD_FAB2(SCH_1):TP_P3E_CPU1_PE1_MP_RXP(2)
  U2D1  DB9 PE1_RX_DP<2> SKX_EXT_B_BGA1-IC,TBD    I68 @BASEBOARD_FAB2_LIB.BASEBOARD_FAB2(SCH_1):PAGE64

TP_P3E_CPU1_PE1_MP_RXP<3> @BASEBOARD_FAB2_LIB.BASEBOARD_FAB2(SCH_1):TP_P3E_CPU1_PE1_MP_RXP(3)
  U2D1 DA10 PE1_RX_DP<3> SKX_EXT_B_BGA1-IC,TBD    I68 @BASEBOARD_FAB2_LIB.BASEBOARD_FAB2(SCH_1):PAGE64

TP_P3E_CPU1_PE1_MP_RXP<4> @BASEBOARD_FAB2_LIB.BASEBOARD_FAB2(SCH_1):TP_P3E_CPU1_PE1_MP_RXP(4)
  U2D1  DD9 PE1_RX_DP<4> SKX_EXT_B_BGA1-IC,TBD    I68 @BASEBOARD_FAB2_LIB.BASEBOARD_FAB2(SCH_1):PAGE64

TP_P3E_CPU1_PE1_MP_RXP<5> @BASEBOARD_FAB2_LIB.BASEBOARD_FAB2(SCH_1):TP_P3E_CPU1_PE1_MP_RXP(5)
  U2D1  DF9 PE1_RX_DP<5> SKX_EXT_B_BGA1-IC,TBD    I68 @BASEBOARD_FAB2_LIB.BASEBOARD_FAB2(SCH_1):PAGE64

TP_P3E_CPU1_PE1_MP_RXP<6> @BASEBOARD_FAB2_LIB.BASEBOARD_FAB2(SCH_1):TP_P3E_CPU1_PE1_MP_RXP(6)
  U2D1  DJ8 PE1_RX_DP<6> SKX_EXT_B_BGA1-IC,TBD    I68 @BASEBOARD_FAB2_LIB.BASEBOARD_FAB2(SCH_1):PAGE64

TP_P3E_CPU1_PE1_MP_RXP<7> @BASEBOARD_FAB2_LIB.BASEBOARD_FAB2(SCH_1):TP_P3E_CPU1_PE1_MP_RXP(7)
  U2D1 DL10 PE1_RX_DP<7> SKX_EXT_B_BGA1-IC,TBD    I68 @BASEBOARD_FAB2_LIB.BASEBOARD_FAB2(SCH_1):PAGE64

TP_P3E_CPU1_PE1_MP_TXN<0> @BASEBOARD_FAB2_LIB.BASEBOARD_FAB2(SCH_1):TP_P3E_CPU1_PE1_MP_TXN(0)
  U2D1  DA2 PE1_TX_DN<0> SKX_EXT_B_BGA1-IC,TBD    I68 @BASEBOARD_FAB2_LIB.BASEBOARD_FAB2(SCH_1):PAGE64

TP_P3E_CPU1_PE1_MP_TXN<1> @BASEBOARD_FAB2_LIB.BASEBOARD_FAB2(SCH_1):TP_P3E_CPU1_PE1_MP_TXN(1)
  U2D1  DC2 PE1_TX_DN<1> SKX_EXT_B_BGA1-IC,TBD    I68 @BASEBOARD_FAB2_LIB.BASEBOARD_FAB2(SCH_1):PAGE64

TP_P3E_CPU1_PE1_MP_TXN<2> @BASEBOARD_FAB2_LIB.BASEBOARD_FAB2(SCH_1):TP_P3E_CPU1_PE1_MP_TXN(2)
  U2D1  DE2 PE1_TX_DN<2> SKX_EXT_B_BGA1-IC,TBD    I68 @BASEBOARD_FAB2_LIB.BASEBOARD_FAB2(SCH_1):PAGE64

TP_P3E_CPU1_PE1_MP_TXN<3> @BASEBOARD_FAB2_LIB.BASEBOARD_FAB2(SCH_1):TP_P3E_CPU1_PE1_MP_TXN(3)
  U2D1  DE4 PE1_TX_DN<3> SKX_EXT_B_BGA1-IC,TBD    I68 @BASEBOARD_FAB2_LIB.BASEBOARD_FAB2(SCH_1):PAGE64

TP_P3E_CPU1_PE1_MP_TXN<4> @BASEBOARD_FAB2_LIB.BASEBOARD_FAB2(SCH_1):TP_P3E_CPU1_PE1_MP_TXN(4)
  U2D1  DG4 PE1_TX_DN<4> SKX_EXT_B_BGA1-IC,TBD    I68 @BASEBOARD_FAB2_LIB.BASEBOARD_FAB2(SCH_1):PAGE64

TP_P3E_CPU1_PE1_MP_TXN<5> @BASEBOARD_FAB2_LIB.BASEBOARD_FAB2(SCH_1):TP_P3E_CPU1_PE1_MP_TXN(5)
  U2D1  DK3 PE1_TX_DN<5> SKX_EXT_B_BGA1-IC,TBD    I68 @BASEBOARD_FAB2_LIB.BASEBOARD_FAB2(SCH_1):PAGE64

TP_P3E_CPU1_PE1_MP_TXN<6> @BASEBOARD_FAB2_LIB.BASEBOARD_FAB2(SCH_1):TP_P3E_CPU1_PE1_MP_TXN(6)
  U2D1  DM3 PE1_TX_DN<6> SKX_EXT_B_BGA1-IC,TBD    I68 @BASEBOARD_FAB2_LIB.BASEBOARD_FAB2(SCH_1):PAGE64

TP_P3E_CPU1_PE1_MP_TXN<7> @BASEBOARD_FAB2_LIB.BASEBOARD_FAB2(SCH_1):TP_P3E_CPU1_PE1_MP_TXN(7)
  U2D1  DN4 PE1_TX_DN<7> SKX_EXT_B_BGA1-IC,TBD    I68 @BASEBOARD_FAB2_LIB.BASEBOARD_FAB2(SCH_1):PAGE64

TP_P3E_CPU1_PE1_MP_TXP<0> @BASEBOARD_FAB2_LIB.BASEBOARD_FAB2(SCH_1):TP_P3E_CPU1_PE1_MP_TXP(0)
  U2D1  CW2 PE1_TX_DP<0> SKX_EXT_B_BGA1-IC,TBD    I68 @BASEBOARD_FAB2_LIB.BASEBOARD_FAB2(SCH_1):PAGE64

TP_P3E_CPU1_PE1_MP_TXP<1> @BASEBOARD_FAB2_LIB.BASEBOARD_FAB2(SCH_1):TP_P3E_CPU1_PE1_MP_TXP(1)
  U2D1  DB1 PE1_TX_DP<1> SKX_EXT_B_BGA1-IC,TBD    I68 @BASEBOARD_FAB2_LIB.BASEBOARD_FAB2(SCH_1):PAGE64

TP_P3E_CPU1_PE1_MP_TXP<2> @BASEBOARD_FAB2_LIB.BASEBOARD_FAB2(SCH_1):TP_P3E_CPU1_PE1_MP_TXP(2)
  U2D1  DD3 PE1_TX_DP<2> SKX_EXT_B_BGA1-IC,TBD    I68 @BASEBOARD_FAB2_LIB.BASEBOARD_FAB2(SCH_1):PAGE64

TP_P3E_CPU1_PE1_MP_TXP<3> @BASEBOARD_FAB2_LIB.BASEBOARD_FAB2(SCH_1):TP_P3E_CPU1_PE1_MP_TXP(3)
  U2D1  DC4 PE1_TX_DP<3> SKX_EXT_B_BGA1-IC,TBD    I68 @BASEBOARD_FAB2_LIB.BASEBOARD_FAB2(SCH_1):PAGE64

TP_P3E_CPU1_PE1_MP_TXP<4> @BASEBOARD_FAB2_LIB.BASEBOARD_FAB2(SCH_1):TP_P3E_CPU1_PE1_MP_TXP(4)
  U2D1  DF3 PE1_TX_DP<4> SKX_EXT_B_BGA1-IC,TBD    I68 @BASEBOARD_FAB2_LIB.BASEBOARD_FAB2(SCH_1):PAGE64

TP_P3E_CPU1_PE1_MP_TXP<5> @BASEBOARD_FAB2_LIB.BASEBOARD_FAB2(SCH_1):TP_P3E_CPU1_PE1_MP_TXP(5)
  U2D1  DH3 PE1_TX_DP<5> SKX_EXT_B_BGA1-IC,TBD    I68 @BASEBOARD_FAB2_LIB.BASEBOARD_FAB2(SCH_1):PAGE64

TP_P3E_CPU1_PE1_MP_TXP<6> @BASEBOARD_FAB2_LIB.BASEBOARD_FAB2(SCH_1):TP_P3E_CPU1_PE1_MP_TXP(6)
  U2D1  DL2 PE1_TX_DP<6> SKX_EXT_B_BGA1-IC,TBD    I68 @BASEBOARD_FAB2_LIB.BASEBOARD_FAB2(SCH_1):PAGE64

TP_P3E_CPU1_PE1_MP_TXP<7> @BASEBOARD_FAB2_LIB.BASEBOARD_FAB2(SCH_1):TP_P3E_CPU1_PE1_MP_TXP(7)
  U2D1  DP3 PE1_TX_DP<7> SKX_EXT_B_BGA1-IC,TBD    I68 @BASEBOARD_FAB2_LIB.BASEBOARD_FAB2(SCH_1):PAGE64

TP_P3E_CPU1_PE1_RSR3_RXN<10> @BASEBOARD_FAB2_LIB.BASEBOARD_FAB2(SCH_1):TP_P3E_CPU1_PE1_RSR3_RXN(10)
  U2D1 DT11 PE1_RX_DN<10> SKX_EXT_B_BGA1-IC,TBD    I68 @BASEBOARD_FAB2_LIB.BASEBOARD_FAB2(SCH_1):PAGE64

TP_P3E_CPU1_PE1_RSR3_RXN<11> @BASEBOARD_FAB2_LIB.BASEBOARD_FAB2(SCH_1):TP_P3E_CPU1_PE1_RSR3_RXN(11)
  U2D1 DT13 PE1_RX_DN<11> SKX_EXT_B_BGA1-IC,TBD    I68 @BASEBOARD_FAB2_LIB.BASEBOARD_FAB2(SCH_1):PAGE64

TP_P3E_CPU1_PE1_RSR3_RXN<12> @BASEBOARD_FAB2_LIB.BASEBOARD_FAB2(SCH_1):TP_P3E_CPU1_PE1_RSR3_RXN(12)
  U2D1 DV13 PE1_RX_DN<12> SKX_EXT_B_BGA1-IC,TBD    I68 @BASEBOARD_FAB2_LIB.BASEBOARD_FAB2(SCH_1):PAGE64

TP_P3E_CPU1_PE1_RSR3_RXN<13> @BASEBOARD_FAB2_LIB.BASEBOARD_FAB2(SCH_1):TP_P3E_CPU1_PE1_RSR3_RXN(13)
  U2D1 DW14 PE1_RX_DN<13> SKX_EXT_B_BGA1-IC,TBD    I68 @BASEBOARD_FAB2_LIB.BASEBOARD_FAB2(SCH_1):PAGE64

TP_P3E_CPU1_PE1_RSR3_RXN<14> @BASEBOARD_FAB2_LIB.BASEBOARD_FAB2(SCH_1):TP_P3E_CPU1_PE1_RSR3_RXN(14)
  U2D1 DY15 PE1_RX_DN<14> SKX_EXT_B_BGA1-IC,TBD    I68 @BASEBOARD_FAB2_LIB.BASEBOARD_FAB2(SCH_1):PAGE64

TP_P3E_CPU1_PE1_RSR3_RXN<15> @BASEBOARD_FAB2_LIB.BASEBOARD_FAB2(SCH_1):TP_P3E_CPU1_PE1_RSR3_RXN(15)
  U2D1 DU16 PE1_RX_DN<15> SKX_EXT_B_BGA1-IC,TBD    I68 @BASEBOARD_FAB2_LIB.BASEBOARD_FAB2(SCH_1):PAGE64

TP_P3E_CPU1_PE1_RSR3_RXN<8> @BASEBOARD_FAB2_LIB.BASEBOARD_FAB2(SCH_1):TP_P3E_CPU1_PE1_RSR3_RXN(8)
  U2D1 DM11 PE1_RX_DN<8> SKX_EXT_B_BGA1-IC,TBD    I68 @BASEBOARD_FAB2_LIB.BASEBOARD_FAB2(SCH_1):PAGE64

TP_P3E_CPU1_PE1_RSR3_RXN<9> @BASEBOARD_FAB2_LIB.BASEBOARD_FAB2(SCH_1):TP_P3E_CPU1_PE1_RSR3_RXN(9)
  U2D1 DP11 PE1_RX_DN<9> SKX_EXT_B_BGA1-IC,TBD    I68 @BASEBOARD_FAB2_LIB.BASEBOARD_FAB2(SCH_1):PAGE64

TP_P3E_CPU1_PE1_RSR3_RXP<10> @BASEBOARD_FAB2_LIB.BASEBOARD_FAB2(SCH_1):TP_P3E_CPU1_PE1_RSR3_RXP(10)
  U2D1 DR12 PE1_RX_DP<10> SKX_EXT_B_BGA1-IC,TBD    I68 @BASEBOARD_FAB2_LIB.BASEBOARD_FAB2(SCH_1):PAGE64

TP_P3E_CPU1_PE1_RSR3_RXP<11> @BASEBOARD_FAB2_LIB.BASEBOARD_FAB2(SCH_1):TP_P3E_CPU1_PE1_RSR3_RXP(11)
  U2D1 DP13 PE1_RX_DP<11> SKX_EXT_B_BGA1-IC,TBD    I68 @BASEBOARD_FAB2_LIB.BASEBOARD_FAB2(SCH_1):PAGE64

TP_P3E_CPU1_PE1_RSR3_RXP<12> @BASEBOARD_FAB2_LIB.BASEBOARD_FAB2(SCH_1):TP_P3E_CPU1_PE1_RSR3_RXP(12)
  U2D1 DU12 PE1_RX_DP<12> SKX_EXT_B_BGA1-IC,TBD    I68 @BASEBOARD_FAB2_LIB.BASEBOARD_FAB2(SCH_1):PAGE64

TP_P3E_CPU1_PE1_RSR3_RXP<13> @BASEBOARD_FAB2_LIB.BASEBOARD_FAB2(SCH_1):TP_P3E_CPU1_PE1_RSR3_RXP(13)
  U2D1 DY13 PE1_RX_DP<13> SKX_EXT_B_BGA1-IC,TBD    I68 @BASEBOARD_FAB2_LIB.BASEBOARD_FAB2(SCH_1):PAGE64

TP_P3E_CPU1_PE1_RSR3_RXP<14> @BASEBOARD_FAB2_LIB.BASEBOARD_FAB2(SCH_1):TP_P3E_CPU1_PE1_RSR3_RXP(14)
  U2D1 DV15 PE1_RX_DP<14> SKX_EXT_B_BGA1-IC,TBD    I68 @BASEBOARD_FAB2_LIB.BASEBOARD_FAB2(SCH_1):PAGE64

TP_P3E_CPU1_PE1_RSR3_RXP<15> @BASEBOARD_FAB2_LIB.BASEBOARD_FAB2(SCH_1):TP_P3E_CPU1_PE1_RSR3_RXP(15)
  U2D1 DT15 PE1_RX_DP<15> SKX_EXT_B_BGA1-IC,TBD    I68 @BASEBOARD_FAB2_LIB.BASEBOARD_FAB2(SCH_1):PAGE64

TP_P3E_CPU1_PE1_RSR3_RXP<8> @BASEBOARD_FAB2_LIB.BASEBOARD_FAB2(SCH_1):TP_P3E_CPU1_PE1_RSR3_RXP(8)
  U2D1 DK11 PE1_RX_DP<8> SKX_EXT_B_BGA1-IC,TBD    I68 @BASEBOARD_FAB2_LIB.BASEBOARD_FAB2(SCH_1):PAGE64

TP_P3E_CPU1_PE1_RSR3_RXP<9> @BASEBOARD_FAB2_LIB.BASEBOARD_FAB2(SCH_1):TP_P3E_CPU1_PE1_RSR3_RXP(9)
  U2D1 DN10 PE1_RX_DP<9> SKX_EXT_B_BGA1-IC,TBD    I68 @BASEBOARD_FAB2_LIB.BASEBOARD_FAB2(SCH_1):PAGE64

TP_P3E_CPU1_PE1_RSR3_TXN<10> @BASEBOARD_FAB2_LIB.BASEBOARD_FAB2(SCH_1):TP_P3E_CPU1_PE1_RSR3_TXN(10)
  U2D1  DW4 PE1_TX_DN<10> SKX_EXT_B_BGA1-IC,TBD    I68 @BASEBOARD_FAB2_LIB.BASEBOARD_FAB2(SCH_1):PAGE64

TP_P3E_CPU1_PE1_RSR3_TXN<11> @BASEBOARD_FAB2_LIB.BASEBOARD_FAB2(SCH_1):TP_P3E_CPU1_PE1_RSR3_TXN(11)
  U2D1  DU6 PE1_TX_DN<11> SKX_EXT_B_BGA1-IC,TBD    I68 @BASEBOARD_FAB2_LIB.BASEBOARD_FAB2(SCH_1):PAGE64

TP_P3E_CPU1_PE1_RSR3_TXN<12> @BASEBOARD_FAB2_LIB.BASEBOARD_FAB2(SCH_1):TP_P3E_CPU1_PE1_RSR3_TXN(12)
  U2D1  DV7 PE1_TX_DN<12> SKX_EXT_B_BGA1-IC,TBD    I68 @BASEBOARD_FAB2_LIB.BASEBOARD_FAB2(SCH_1):PAGE64

TP_P3E_CPU1_PE1_RSR3_TXN<13> @BASEBOARD_FAB2_LIB.BASEBOARD_FAB2(SCH_1):TP_P3E_CPU1_PE1_RSR3_TXN(13)
  U2D1  DY7 PE1_TX_DN<13> SKX_EXT_B_BGA1-IC,TBD    I68 @BASEBOARD_FAB2_LIB.BASEBOARD_FAB2(SCH_1):PAGE64

TP_P3E_CPU1_PE1_RSR3_TXN<14> @BASEBOARD_FAB2_LIB.BASEBOARD_FAB2(SCH_1):TP_P3E_CPU1_PE1_RSR3_TXN(14)
  U2D1  EA8 PE1_TX_DN<14> SKX_EXT_B_BGA1-IC,TBD    I68 @BASEBOARD_FAB2_LIB.BASEBOARD_FAB2(SCH_1):PAGE64

TP_P3E_CPU1_PE1_RSR3_TXN<15> @BASEBOARD_FAB2_LIB.BASEBOARD_FAB2(SCH_1):TP_P3E_CPU1_PE1_RSR3_TXN(15)
  U2D1  ED9 PE1_TX_DN<15> SKX_EXT_B_BGA1-IC,TBD    I68 @BASEBOARD_FAB2_LIB.BASEBOARD_FAB2(SCH_1):PAGE64

TP_P3E_CPU1_PE1_RSR3_TXN<8> @BASEBOARD_FAB2_LIB.BASEBOARD_FAB2(SCH_1):TP_P3E_CPU1_PE1_RSR3_TXN(8)
  U2D1  DT5 PE1_TX_DN<8> SKX_EXT_B_BGA1-IC,TBD    I68 @BASEBOARD_FAB2_LIB.BASEBOARD_FAB2(SCH_1):PAGE64

TP_P3E_CPU1_PE1_RSR3_TXN<9> @BASEBOARD_FAB2_LIB.BASEBOARD_FAB2(SCH_1):TP_P3E_CPU1_PE1_RSR3_TXN(9)
  U2D1  DV3 PE1_TX_DN<9> SKX_EXT_B_BGA1-IC,TBD    I68 @BASEBOARD_FAB2_LIB.BASEBOARD_FAB2(SCH_1):PAGE64

TP_P3E_CPU1_PE1_RSR3_TXP<10> @BASEBOARD_FAB2_LIB.BASEBOARD_FAB2(SCH_1):TP_P3E_CPU1_PE1_RSR3_TXP(10)
  U2D1  DU4 PE1_TX_DP<10> SKX_EXT_B_BGA1-IC,TBD    I68 @BASEBOARD_FAB2_LIB.BASEBOARD_FAB2(SCH_1):PAGE64

TP_P3E_CPU1_PE1_RSR3_TXP<11> @BASEBOARD_FAB2_LIB.BASEBOARD_FAB2(SCH_1):TP_P3E_CPU1_PE1_RSR3_TXP(11)
  U2D1  DV5 PE1_TX_DP<11> SKX_EXT_B_BGA1-IC,TBD    I68 @BASEBOARD_FAB2_LIB.BASEBOARD_FAB2(SCH_1):PAGE64

TP_P3E_CPU1_PE1_RSR3_TXP<12> @BASEBOARD_FAB2_LIB.BASEBOARD_FAB2(SCH_1):TP_P3E_CPU1_PE1_RSR3_TXP(12)
  U2D1  DT7 PE1_TX_DP<12> SKX_EXT_B_BGA1-IC,TBD    I68 @BASEBOARD_FAB2_LIB.BASEBOARD_FAB2(SCH_1):PAGE64

TP_P3E_CPU1_PE1_RSR3_TXP<13> @BASEBOARD_FAB2_LIB.BASEBOARD_FAB2(SCH_1):TP_P3E_CPU1_PE1_RSR3_TXP(13)
  U2D1  DW6 PE1_TX_DP<13> SKX_EXT_B_BGA1-IC,TBD    I68 @BASEBOARD_FAB2_LIB.BASEBOARD_FAB2(SCH_1):PAGE64

TP_P3E_CPU1_PE1_RSR3_TXP<14> @BASEBOARD_FAB2_LIB.BASEBOARD_FAB2(SCH_1):TP_P3E_CPU1_PE1_RSR3_TXP(14)
  U2D1  EB7 PE1_TX_DP<14> SKX_EXT_B_BGA1-IC,TBD    I68 @BASEBOARD_FAB2_LIB.BASEBOARD_FAB2(SCH_1):PAGE64

TP_P3E_CPU1_PE1_RSR3_TXP<15> @BASEBOARD_FAB2_LIB.BASEBOARD_FAB2(SCH_1):TP_P3E_CPU1_PE1_RSR3_TXP(15)
  U2D1  EC8 PE1_TX_DP<15> SKX_EXT_B_BGA1-IC,TBD    I68 @BASEBOARD_FAB2_LIB.BASEBOARD_FAB2(SCH_1):PAGE64

TP_P3E_CPU1_PE1_RSR3_TXP<8> @BASEBOARD_FAB2_LIB.BASEBOARD_FAB2(SCH_1):TP_P3E_CPU1_PE1_RSR3_TXP(8)
  U2D1  DR4 PE1_TX_DP<8> SKX_EXT_B_BGA1-IC,TBD    I68 @BASEBOARD_FAB2_LIB.BASEBOARD_FAB2(SCH_1):PAGE64

TP_P3E_CPU1_PE1_RSR3_TXP<9> @BASEBOARD_FAB2_LIB.BASEBOARD_FAB2(SCH_1):TP_P3E_CPU1_PE1_RSR3_TXP(9)
  U2D1  DU2 PE1_TX_DP<9> SKX_EXT_B_BGA1-IC,TBD    I68 @BASEBOARD_FAB2_LIB.BASEBOARD_FAB2(SCH_1):PAGE64

TP_P3E_CPU1_PE2_RSR_RXN<0> @BASEBOARD_FAB2_LIB.BASEBOARD_FAB2(SCH_1):TP_P3E_CPU1_PE2_RSR_RXN(0)
  U2D1  CT9 PE2_RX_DN<0> SKX_EXT_B_BGA1-IC,TBD    I68 @BASEBOARD_FAB2_LIB.BASEBOARD_FAB2(SCH_1):PAGE65

TP_P3E_CPU1_PE2_RSR_RXN<10> @BASEBOARD_FAB2_LIB.BASEBOARD_FAB2(SCH_1):TP_P3E_CPU1_PE2_RSR_RXN(10)
  U2D1  BV7 PE2_RX_DN<10> SKX_EXT_B_BGA1-IC,TBD    I68 @BASEBOARD_FAB2_LIB.BASEBOARD_FAB2(SCH_1):PAGE65

TP_P3E_CPU1_PE2_RSR_RXN<11> @BASEBOARD_FAB2_LIB.BASEBOARD_FAB2(SCH_1):TP_P3E_CPU1_PE2_RSR_RXN(11)
  U2D1  BT7 PE2_RX_DN<11> SKX_EXT_B_BGA1-IC,TBD    I68 @BASEBOARD_FAB2_LIB.BASEBOARD_FAB2(SCH_1):PAGE65

TP_P3E_CPU1_PE2_RSR_RXN<12> @BASEBOARD_FAB2_LIB.BASEBOARD_FAB2(SCH_1):TP_P3E_CPU1_PE2_RSR_RXN(12)
  U2D1  BR8 PE2_RX_DN<12> SKX_EXT_B_BGA1-IC,TBD    I68 @BASEBOARD_FAB2_LIB.BASEBOARD_FAB2(SCH_1):PAGE65

TP_P3E_CPU1_PE2_RSR_RXN<13> @BASEBOARD_FAB2_LIB.BASEBOARD_FAB2(SCH_1):TP_P3E_CPU1_PE2_RSR_RXN(13)
  U2D1  BN8 PE2_RX_DN<13> SKX_EXT_B_BGA1-IC,TBD    I68 @BASEBOARD_FAB2_LIB.BASEBOARD_FAB2(SCH_1):PAGE65

TP_P3E_CPU1_PE2_RSR_RXN<14> @BASEBOARD_FAB2_LIB.BASEBOARD_FAB2(SCH_1):TP_P3E_CPU1_PE2_RSR_RXN(14)
  U2D1  BL8 PE2_RX_DN<14> SKX_EXT_B_BGA1-IC,TBD    I68 @BASEBOARD_FAB2_LIB.BASEBOARD_FAB2(SCH_1):PAGE65

TP_P3E_CPU1_PE2_RSR_RXN<15> @BASEBOARD_FAB2_LIB.BASEBOARD_FAB2(SCH_1):TP_P3E_CPU1_PE2_RSR_RXN(15)
  U2D1  BK9 PE2_RX_DN<15> SKX_EXT_B_BGA1-IC,TBD    I68 @BASEBOARD_FAB2_LIB.BASEBOARD_FAB2(SCH_1):PAGE65

TP_P3E_CPU1_PE2_RSR_RXN<1> @BASEBOARD_FAB2_LIB.BASEBOARD_FAB2(SCH_1):TP_P3E_CPU1_PE2_RSR_RXN(1)
  U2D1  CP9 PE2_RX_DN<1> SKX_EXT_B_BGA1-IC,TBD    I68 @BASEBOARD_FAB2_LIB.BASEBOARD_FAB2(SCH_1):PAGE65

TP_P3E_CPU1_PE2_RSR_RXN<2> @BASEBOARD_FAB2_LIB.BASEBOARD_FAB2(SCH_1):TP_P3E_CPU1_PE2_RSR_RXN(2)
  U2D1  CP7 PE2_RX_DN<2> SKX_EXT_B_BGA1-IC,TBD    I68 @BASEBOARD_FAB2_LIB.BASEBOARD_FAB2(SCH_1):PAGE65

TP_P3E_CPU1_PE2_RSR_RXN<3> @BASEBOARD_FAB2_LIB.BASEBOARD_FAB2(SCH_1):TP_P3E_CPU1_PE2_RSR_RXN(3)
  U2D1  CM7 PE2_RX_DN<3> SKX_EXT_B_BGA1-IC,TBD    I68 @BASEBOARD_FAB2_LIB.BASEBOARD_FAB2(SCH_1):PAGE65

TP_P3E_CPU1_PE2_RSR_RXN<4> @BASEBOARD_FAB2_LIB.BASEBOARD_FAB2(SCH_1):TP_P3E_CPU1_PE2_RSR_RXN(4)
  U2D1  CK7 PE2_RX_DN<4> SKX_EXT_B_BGA1-IC,TBD    I68 @BASEBOARD_FAB2_LIB.BASEBOARD_FAB2(SCH_1):PAGE65

TP_P3E_CPU1_PE2_RSR_RXN<5> @BASEBOARD_FAB2_LIB.BASEBOARD_FAB2(SCH_1):TP_P3E_CPU1_PE2_RSR_RXN(5)
  U2D1  CG8 PE2_RX_DN<5> SKX_EXT_B_BGA1-IC,TBD    I68 @BASEBOARD_FAB2_LIB.BASEBOARD_FAB2(SCH_1):PAGE65

TP_P3E_CPU1_PE2_RSR_RXN<6> @BASEBOARD_FAB2_LIB.BASEBOARD_FAB2(SCH_1):TP_P3E_CPU1_PE2_RSR_RXN(6)
  U2D1  CE6 PE2_RX_DN<6> SKX_EXT_B_BGA1-IC,TBD    I68 @BASEBOARD_FAB2_LIB.BASEBOARD_FAB2(SCH_1):PAGE65

TP_P3E_CPU1_PE2_RSR_RXN<7> @BASEBOARD_FAB2_LIB.BASEBOARD_FAB2(SCH_1):TP_P3E_CPU1_PE2_RSR_RXN(7)
  U2D1  CE8 PE2_RX_DN<7> SKX_EXT_B_BGA1-IC,TBD    I68 @BASEBOARD_FAB2_LIB.BASEBOARD_FAB2(SCH_1):PAGE65

TP_P3E_CPU1_PE2_RSR_RXN<8> @BASEBOARD_FAB2_LIB.BASEBOARD_FAB2(SCH_1):TP_P3E_CPU1_PE2_RSR_RXN(8)
  U2D1  BY9 PE2_RX_DN<8> SKX_EXT_B_BGA1-IC,TBD    I68 @BASEBOARD_FAB2_LIB.BASEBOARD_FAB2(SCH_1):PAGE65

TP_P3E_CPU1_PE2_RSR_RXN<9> @BASEBOARD_FAB2_LIB.BASEBOARD_FAB2(SCH_1):TP_P3E_CPU1_PE2_RSR_RXN(9)
  U2D1  BY7 PE2_RX_DN<9> SKX_EXT_B_BGA1-IC,TBD    I68 @BASEBOARD_FAB2_LIB.BASEBOARD_FAB2(SCH_1):PAGE65

TP_P3E_CPU1_PE2_RSR_RXP<0> @BASEBOARD_FAB2_LIB.BASEBOARD_FAB2(SCH_1):TP_P3E_CPU1_PE2_RSR_RXP(0)
  U2D1  CR8 PE2_RX_DP<0> SKX_EXT_B_BGA1-IC,TBD    I68 @BASEBOARD_FAB2_LIB.BASEBOARD_FAB2(SCH_1):PAGE65

TP_P3E_CPU1_PE2_RSR_RXP<10> @BASEBOARD_FAB2_LIB.BASEBOARD_FAB2(SCH_1):TP_P3E_CPU1_PE2_RSR_RXP(10)
  U2D1  BU6 PE2_RX_DP<10> SKX_EXT_B_BGA1-IC,TBD    I68 @BASEBOARD_FAB2_LIB.BASEBOARD_FAB2(SCH_1):PAGE65

TP_P3E_CPU1_PE2_RSR_RXP<11> @BASEBOARD_FAB2_LIB.BASEBOARD_FAB2(SCH_1):TP_P3E_CPU1_PE2_RSR_RXP(11)
  U2D1  BP7 PE2_RX_DP<11> SKX_EXT_B_BGA1-IC,TBD    I68 @BASEBOARD_FAB2_LIB.BASEBOARD_FAB2(SCH_1):PAGE65

TP_P3E_CPU1_PE2_RSR_RXP<12> @BASEBOARD_FAB2_LIB.BASEBOARD_FAB2(SCH_1):TP_P3E_CPU1_PE2_RSR_RXP(12)
  U2D1  BP9 PE2_RX_DP<12> SKX_EXT_B_BGA1-IC,TBD    I68 @BASEBOARD_FAB2_LIB.BASEBOARD_FAB2(SCH_1):PAGE65

TP_P3E_CPU1_PE2_RSR_RXP<13> @BASEBOARD_FAB2_LIB.BASEBOARD_FAB2(SCH_1):TP_P3E_CPU1_PE2_RSR_RXP(13)
  U2D1  BM7 PE2_RX_DP<13> SKX_EXT_B_BGA1-IC,TBD    I68 @BASEBOARD_FAB2_LIB.BASEBOARD_FAB2(SCH_1):PAGE65

TP_P3E_CPU1_PE2_RSR_RXP<14> @BASEBOARD_FAB2_LIB.BASEBOARD_FAB2(SCH_1):TP_P3E_CPU1_PE2_RSR_RXP(14)
  U2D1  BJ8 PE2_RX_DP<14> SKX_EXT_B_BGA1-IC,TBD    I68 @BASEBOARD_FAB2_LIB.BASEBOARD_FAB2(SCH_1):PAGE65

TP_P3E_CPU1_PE2_RSR_RXP<15> @BASEBOARD_FAB2_LIB.BASEBOARD_FAB2(SCH_1):TP_P3E_CPU1_PE2_RSR_RXP(15)
  U2D1 BJ10 PE2_RX_DP<15> SKX_EXT_B_BGA1-IC,TBD    I68 @BASEBOARD_FAB2_LIB.BASEBOARD_FAB2(SCH_1):PAGE65

TP_P3E_CPU1_PE2_RSR_RXP<1> @BASEBOARD_FAB2_LIB.BASEBOARD_FAB2(SCH_1):TP_P3E_CPU1_PE2_RSR_RXP(1)
  U2D1  CM9 PE2_RX_DP<1> SKX_EXT_B_BGA1-IC,TBD    I68 @BASEBOARD_FAB2_LIB.BASEBOARD_FAB2(SCH_1):PAGE65

TP_P3E_CPU1_PE2_RSR_RXP<2> @BASEBOARD_FAB2_LIB.BASEBOARD_FAB2(SCH_1):TP_P3E_CPU1_PE2_RSR_RXP(2)
  U2D1  CN8 PE2_RX_DP<2> SKX_EXT_B_BGA1-IC,TBD    I68 @BASEBOARD_FAB2_LIB.BASEBOARD_FAB2(SCH_1):PAGE65

TP_P3E_CPU1_PE2_RSR_RXP<3> @BASEBOARD_FAB2_LIB.BASEBOARD_FAB2(SCH_1):TP_P3E_CPU1_PE2_RSR_RXP(3)
  U2D1  CL6 PE2_RX_DP<3> SKX_EXT_B_BGA1-IC,TBD    I68 @BASEBOARD_FAB2_LIB.BASEBOARD_FAB2(SCH_1):PAGE65

TP_P3E_CPU1_PE2_RSR_RXP<4> @BASEBOARD_FAB2_LIB.BASEBOARD_FAB2(SCH_1):TP_P3E_CPU1_PE2_RSR_RXP(4)
  U2D1  CH7 PE2_RX_DP<4> SKX_EXT_B_BGA1-IC,TBD    I68 @BASEBOARD_FAB2_LIB.BASEBOARD_FAB2(SCH_1):PAGE65

TP_P3E_CPU1_PE2_RSR_RXP<5> @BASEBOARD_FAB2_LIB.BASEBOARD_FAB2(SCH_1):TP_P3E_CPU1_PE2_RSR_RXP(5)
  U2D1  CF7 PE2_RX_DP<5> SKX_EXT_B_BGA1-IC,TBD    I68 @BASEBOARD_FAB2_LIB.BASEBOARD_FAB2(SCH_1):PAGE65

TP_P3E_CPU1_PE2_RSR_RXP<6> @BASEBOARD_FAB2_LIB.BASEBOARD_FAB2(SCH_1):TP_P3E_CPU1_PE2_RSR_RXP(6)
  U2D1  CD7 PE2_RX_DP<6> SKX_EXT_B_BGA1-IC,TBD    I68 @BASEBOARD_FAB2_LIB.BASEBOARD_FAB2(SCH_1):PAGE65

TP_P3E_CPU1_PE2_RSR_RXP<7> @BASEBOARD_FAB2_LIB.BASEBOARD_FAB2(SCH_1):TP_P3E_CPU1_PE2_RSR_RXP(7)
  U2D1  CC8 PE2_RX_DP<7> SKX_EXT_B_BGA1-IC,TBD    I68 @BASEBOARD_FAB2_LIB.BASEBOARD_FAB2(SCH_1):PAGE65

TP_P3E_CPU1_PE2_RSR_RXP<8> @BASEBOARD_FAB2_LIB.BASEBOARD_FAB2(SCH_1):TP_P3E_CPU1_PE2_RSR_RXP(8)
  U2D1  BV9 PE2_RX_DP<8> SKX_EXT_B_BGA1-IC,TBD    I68 @BASEBOARD_FAB2_LIB.BASEBOARD_FAB2(SCH_1):PAGE65

TP_P3E_CPU1_PE2_RSR_RXP<9> @BASEBOARD_FAB2_LIB.BASEBOARD_FAB2(SCH_1):TP_P3E_CPU1_PE2_RSR_RXP(9)
  U2D1  BW8 PE2_RX_DP<9> SKX_EXT_B_BGA1-IC,TBD    I68 @BASEBOARD_FAB2_LIB.BASEBOARD_FAB2(SCH_1):PAGE65

TP_P3E_CPU1_PE2_RSR_TXN<0> @BASEBOARD_FAB2_LIB.BASEBOARD_FAB2(SCH_1):TP_P3E_CPU1_PE2_RSR_TXN(0)
  U2D1  CY3 PE2_TX_DN<0> SKX_EXT_B_BGA1-IC,TBD    I68 @BASEBOARD_FAB2_LIB.BASEBOARD_FAB2(SCH_1):PAGE65

TP_P3E_CPU1_PE2_RSR_TXN<10> @BASEBOARD_FAB2_LIB.BASEBOARD_FAB2(SCH_1):TP_P3E_CPU1_PE2_RSR_TXN(10)
  U2D1  CA4 PE2_TX_DN<10> SKX_EXT_B_BGA1-IC,TBD    I68 @BASEBOARD_FAB2_LIB.BASEBOARD_FAB2(SCH_1):PAGE65

TP_P3E_CPU1_PE2_RSR_TXN<11> @BASEBOARD_FAB2_LIB.BASEBOARD_FAB2(SCH_1):TP_P3E_CPU1_PE2_RSR_TXN(11)
  U2D1  BW4 PE2_TX_DN<11> SKX_EXT_B_BGA1-IC,TBD    I68 @BASEBOARD_FAB2_LIB.BASEBOARD_FAB2(SCH_1):PAGE65

TP_P3E_CPU1_PE2_RSR_TXN<12> @BASEBOARD_FAB2_LIB.BASEBOARD_FAB2(SCH_1):TP_P3E_CPU1_PE2_RSR_TXN(12)
  U2D1  BU4 PE2_TX_DN<12> SKX_EXT_B_BGA1-IC,TBD    I68 @BASEBOARD_FAB2_LIB.BASEBOARD_FAB2(SCH_1):PAGE65

TP_P3E_CPU1_PE2_RSR_TXN<13> @BASEBOARD_FAB2_LIB.BASEBOARD_FAB2(SCH_1):TP_P3E_CPU1_PE2_RSR_TXN(13)
  U2D1  BP5 PE2_TX_DN<13> SKX_EXT_B_BGA1-IC,TBD    I68 @BASEBOARD_FAB2_LIB.BASEBOARD_FAB2(SCH_1):PAGE65

TP_P3E_CPU1_PE2_RSR_TXN<14> @BASEBOARD_FAB2_LIB.BASEBOARD_FAB2(SCH_1):TP_P3E_CPU1_PE2_RSR_TXN(14)
  U2D1  BL4 PE2_TX_DN<14> SKX_EXT_B_BGA1-IC,TBD    I68 @BASEBOARD_FAB2_LIB.BASEBOARD_FAB2(SCH_1):PAGE65

TP_P3E_CPU1_PE2_RSR_TXN<15> @BASEBOARD_FAB2_LIB.BASEBOARD_FAB2(SCH_1):TP_P3E_CPU1_PE2_RSR_TXN(15)
  U2D1  BM5 PE2_TX_DN<15> SKX_EXT_B_BGA1-IC,TBD    I68 @BASEBOARD_FAB2_LIB.BASEBOARD_FAB2(SCH_1):PAGE65

TP_P3E_CPU1_PE2_RSR_TXN<1> @BASEBOARD_FAB2_LIB.BASEBOARD_FAB2(SCH_1):TP_P3E_CPU1_PE2_RSR_TXN(1)
  U2D1  CV3 PE2_TX_DN<1> SKX_EXT_B_BGA1-IC,TBD    I68 @BASEBOARD_FAB2_LIB.BASEBOARD_FAB2(SCH_1):PAGE65

TP_P3E_CPU1_PE2_RSR_TXN<2> @BASEBOARD_FAB2_LIB.BASEBOARD_FAB2(SCH_1):TP_P3E_CPU1_PE2_RSR_TXN(2)
  U2D1  CT1 PE2_TX_DN<2> SKX_EXT_B_BGA1-IC,TBD    I68 @BASEBOARD_FAB2_LIB.BASEBOARD_FAB2(SCH_1):PAGE65

TP_P3E_CPU1_PE2_RSR_TXN<3> @BASEBOARD_FAB2_LIB.BASEBOARD_FAB2(SCH_1):TP_P3E_CPU1_PE2_RSR_TXN(3)
  U2D1  CT3 PE2_TX_DN<3> SKX_EXT_B_BGA1-IC,TBD    I68 @BASEBOARD_FAB2_LIB.BASEBOARD_FAB2(SCH_1):PAGE65

TP_P3E_CPU1_PE2_RSR_TXN<4> @BASEBOARD_FAB2_LIB.BASEBOARD_FAB2(SCH_1):TP_P3E_CPU1_PE2_RSR_TXN(4)
  U2D1  CM1 PE2_TX_DN<4> SKX_EXT_B_BGA1-IC,TBD    I68 @BASEBOARD_FAB2_LIB.BASEBOARD_FAB2(SCH_1):PAGE65

TP_P3E_CPU1_PE2_RSR_TXN<5> @BASEBOARD_FAB2_LIB.BASEBOARD_FAB2(SCH_1):TP_P3E_CPU1_PE2_RSR_TXN(5)
  U2D1  CL2 PE2_TX_DN<5> SKX_EXT_B_BGA1-IC,TBD    I68 @BASEBOARD_FAB2_LIB.BASEBOARD_FAB2(SCH_1):PAGE65

TP_P3E_CPU1_PE2_RSR_TXN<6> @BASEBOARD_FAB2_LIB.BASEBOARD_FAB2(SCH_1):TP_P3E_CPU1_PE2_RSR_TXN(6)
  U2D1  CG2 PE2_TX_DN<6> SKX_EXT_B_BGA1-IC,TBD    I68 @BASEBOARD_FAB2_LIB.BASEBOARD_FAB2(SCH_1):PAGE65

TP_P3E_CPU1_PE2_RSR_TXN<7> @BASEBOARD_FAB2_LIB.BASEBOARD_FAB2(SCH_1):TP_P3E_CPU1_PE2_RSR_TXN(7)
  U2D1  CF3 PE2_TX_DN<7> SKX_EXT_B_BGA1-IC,TBD    I68 @BASEBOARD_FAB2_LIB.BASEBOARD_FAB2(SCH_1):PAGE65

TP_P3E_CPU1_PE2_RSR_TXN<8> @BASEBOARD_FAB2_LIB.BASEBOARD_FAB2(SCH_1):TP_P3E_CPU1_PE2_RSR_TXN(8)
  U2D1  CC2 PE2_TX_DN<8> SKX_EXT_B_BGA1-IC,TBD    I68 @BASEBOARD_FAB2_LIB.BASEBOARD_FAB2(SCH_1):PAGE65

TP_P3E_CPU1_PE2_RSR_TXN<9> @BASEBOARD_FAB2_LIB.BASEBOARD_FAB2(SCH_1):TP_P3E_CPU1_PE2_RSR_TXN(9)
  U2D1  CB3 PE2_TX_DN<9> SKX_EXT_B_BGA1-IC,TBD    I68 @BASEBOARD_FAB2_LIB.BASEBOARD_FAB2(SCH_1):PAGE65

TP_P3E_CPU1_PE2_RSR_TXP<0> @BASEBOARD_FAB2_LIB.BASEBOARD_FAB2(SCH_1):TP_P3E_CPU1_PE2_RSR_TXP(0)
  U2D1  CW4 PE2_TX_DP<0> SKX_EXT_B_BGA1-IC,TBD    I68 @BASEBOARD_FAB2_LIB.BASEBOARD_FAB2(SCH_1):PAGE65

TP_P3E_CPU1_PE2_RSR_TXP<10> @BASEBOARD_FAB2_LIB.BASEBOARD_FAB2(SCH_1):TP_P3E_CPU1_PE2_RSR_TXP(10)
  U2D1  BY5 PE2_TX_DP<10> SKX_EXT_B_BGA1-IC,TBD    I68 @BASEBOARD_FAB2_LIB.BASEBOARD_FAB2(SCH_1):PAGE65

TP_P3E_CPU1_PE2_RSR_TXP<11> @BASEBOARD_FAB2_LIB.BASEBOARD_FAB2(SCH_1):TP_P3E_CPU1_PE2_RSR_TXP(11)
  U2D1  BV3 PE2_TX_DP<11> SKX_EXT_B_BGA1-IC,TBD    I68 @BASEBOARD_FAB2_LIB.BASEBOARD_FAB2(SCH_1):PAGE65

TP_P3E_CPU1_PE2_RSR_TXP<12> @BASEBOARD_FAB2_LIB.BASEBOARD_FAB2(SCH_1):TP_P3E_CPU1_PE2_RSR_TXP(12)
  U2D1  BR4 PE2_TX_DP<12> SKX_EXT_B_BGA1-IC,TBD    I68 @BASEBOARD_FAB2_LIB.BASEBOARD_FAB2(SCH_1):PAGE65

TP_P3E_CPU1_PE2_RSR_TXP<13> @BASEBOARD_FAB2_LIB.BASEBOARD_FAB2(SCH_1):TP_P3E_CPU1_PE2_RSR_TXP(13)
  U2D1  BN4 PE2_TX_DP<13> SKX_EXT_B_BGA1-IC,TBD    I68 @BASEBOARD_FAB2_LIB.BASEBOARD_FAB2(SCH_1):PAGE65

TP_P3E_CPU1_PE2_RSR_TXP<14> @BASEBOARD_FAB2_LIB.BASEBOARD_FAB2(SCH_1):TP_P3E_CPU1_PE2_RSR_TXP(14)
  U2D1  BM3 PE2_TX_DP<14> SKX_EXT_B_BGA1-IC,TBD    I68 @BASEBOARD_FAB2_LIB.BASEBOARD_FAB2(SCH_1):PAGE65

TP_P3E_CPU1_PE2_RSR_TXP<15> @BASEBOARD_FAB2_LIB.BASEBOARD_FAB2(SCH_1):TP_P3E_CPU1_PE2_RSR_TXP(15)
  U2D1  BK5 PE2_TX_DP<15> SKX_EXT_B_BGA1-IC,TBD    I68 @BASEBOARD_FAB2_LIB.BASEBOARD_FAB2(SCH_1):PAGE65

TP_P3E_CPU1_PE2_RSR_TXP<1> @BASEBOARD_FAB2_LIB.BASEBOARD_FAB2(SCH_1):TP_P3E_CPU1_PE2_RSR_TXP(1)
  U2D1  CU2 PE2_TX_DP<1> SKX_EXT_B_BGA1-IC,TBD    I68 @BASEBOARD_FAB2_LIB.BASEBOARD_FAB2(SCH_1):PAGE65

TP_P3E_CPU1_PE2_RSR_TXP<2> @BASEBOARD_FAB2_LIB.BASEBOARD_FAB2(SCH_1):TP_P3E_CPU1_PE2_RSR_TXP(2)
  U2D1  CR2 PE2_TX_DP<2> SKX_EXT_B_BGA1-IC,TBD    I68 @BASEBOARD_FAB2_LIB.BASEBOARD_FAB2(SCH_1):PAGE65

TP_P3E_CPU1_PE2_RSR_TXP<3> @BASEBOARD_FAB2_LIB.BASEBOARD_FAB2(SCH_1):TP_P3E_CPU1_PE2_RSR_TXP(3)
  U2D1  CP3 PE2_TX_DP<3> SKX_EXT_B_BGA1-IC,TBD    I68 @BASEBOARD_FAB2_LIB.BASEBOARD_FAB2(SCH_1):PAGE65

TP_P3E_CPU1_PE2_RSR_TXP<4> @BASEBOARD_FAB2_LIB.BASEBOARD_FAB2(SCH_1):TP_P3E_CPU1_PE2_RSR_TXP(4)
  U2D1  CK1 PE2_TX_DP<4> SKX_EXT_B_BGA1-IC,TBD    I68 @BASEBOARD_FAB2_LIB.BASEBOARD_FAB2(SCH_1):PAGE65

TP_P3E_CPU1_PE2_RSR_TXP<5> @BASEBOARD_FAB2_LIB.BASEBOARD_FAB2(SCH_1):TP_P3E_CPU1_PE2_RSR_TXP(5)
  U2D1  CK3 PE2_TX_DP<5> SKX_EXT_B_BGA1-IC,TBD    I68 @BASEBOARD_FAB2_LIB.BASEBOARD_FAB2(SCH_1):PAGE65

TP_P3E_CPU1_PE2_RSR_TXP<6> @BASEBOARD_FAB2_LIB.BASEBOARD_FAB2(SCH_1):TP_P3E_CPU1_PE2_RSR_TXP(6)
  U2D1  CE2 PE2_TX_DP<6> SKX_EXT_B_BGA1-IC,TBD    I68 @BASEBOARD_FAB2_LIB.BASEBOARD_FAB2(SCH_1):PAGE65

TP_P3E_CPU1_PE2_RSR_TXP<7> @BASEBOARD_FAB2_LIB.BASEBOARD_FAB2(SCH_1):TP_P3E_CPU1_PE2_RSR_TXP(7)
  U2D1  CE4 PE2_TX_DP<7> SKX_EXT_B_BGA1-IC,TBD    I68 @BASEBOARD_FAB2_LIB.BASEBOARD_FAB2(SCH_1):PAGE65

TP_P3E_CPU1_PE2_RSR_TXP<8> @BASEBOARD_FAB2_LIB.BASEBOARD_FAB2(SCH_1):TP_P3E_CPU1_PE2_RSR_TXP(8)
  U2D1  CD3 PE2_TX_DP<8> SKX_EXT_B_BGA1-IC,TBD    I68 @BASEBOARD_FAB2_LIB.BASEBOARD_FAB2(SCH_1):PAGE65

TP_P3E_CPU1_PE2_RSR_TXP<9> @BASEBOARD_FAB2_LIB.BASEBOARD_FAB2(SCH_1):TP_P3E_CPU1_PE2_RSR_TXP(9)
  U2D1  BY3 PE2_TX_DP<9> SKX_EXT_B_BGA1-IC,TBD    I68 @BASEBOARD_FAB2_LIB.BASEBOARD_FAB2(SCH_1):PAGE65

TP_PASSWORD_CLEAR @BASEBOARD_FAB2_LIB.BASEBOARD_FAB2(SCH_1):TP_PASSWORD_CLEAR
  J7G3    7    IO7 CONN12_C73564003_PIP-CONN,C735A   I174 @BASEBOARD_FAB2_LIB.BASEBOARD_FAB2(SCH_1):PAGE136

TP_PCH_DISPA_BCLK @BASEBOARD_FAB2_LIB.BASEBOARD_FAB2(SCH_1):TP_PCH_DISPA_BCLK
  U7C1  U20 RSVD<66> LBG_CORE_QAT_EXT_D_BGA1-IC,H91A    I34 @BASEBOARD_FAB2_LIB.BASEBOARD_FAB2(SCH_1):PAGE121

TP_PCH_DISPA_SDI @BASEBOARD_FAB2_LIB.BASEBOARD_FAB2(SCH_1):TP_PCH_DISPA_SDI
  U7C1  R20 RSVD<67> LBG_CORE_QAT_EXT_D_BGA1-IC,H91A    I34 @BASEBOARD_FAB2_LIB.BASEBOARD_FAB2(SCH_1):PAGE121

TP_PCH_DISPA_SDO @BASEBOARD_FAB2_LIB.BASEBOARD_FAB2(SCH_1):TP_PCH_DISPA_SDO
  U7C1  V22 RSVD<68> LBG_CORE_QAT_EXT_D_BGA1-IC,H91A    I34 @BASEBOARD_FAB2_LIB.BASEBOARD_FAB2(SCH_1):PAGE121

TP_PCH_GPP_D12 @BASEBOARD_FAB2_LIB.BASEBOARD_FAB2(SCH_1):TP_PCH_GPP_D12
  U7C1 BN40 GPP_D12_SSATA_SDATAOUT1 LBG_CORE_QAT_EXT_D_BGA1-IC,H91A   I115 @BASEBOARD_FAB2_LIB.BASEBOARD_FAB2(SCH_1):PAGE119

TP_PCH_GPP_F12 @BASEBOARD_FAB2_LIB.BASEBOARD_FAB2(SCH_1):TP_PCH_GPP_F12
  U7C1  AP7 GPP_F12_SATA_SDATAOUT1 LBG_CORE_QAT_EXT_D_BGA1-IC,H91A   I147 @BASEBOARD_FAB2_LIB.BASEBOARD_FAB2(SCH_1):PAGE120

TP_PCH_GPP_J17 @BASEBOARD_FAB2_LIB.BASEBOARD_FAB2(SCH_1):TP_PCH_GPP_J17
  U7C1 CA11 GPP_J17_LAN_SDP_P0_1 LBG_CORE_QAT_EXT_D_BGA1-IC,H91A   I147 @BASEBOARD_FAB2_LIB.BASEBOARD_FAB2(SCH_1):PAGE120

TP_PCH_GPP_J19 @BASEBOARD_FAB2_LIB.BASEBOARD_FAB2(SCH_1):TP_PCH_GPP_J19
  U7C1 BY14 GPP_J19_LAN_SDP_P1_1 LBG_CORE_QAT_EXT_D_BGA1-IC,H91A   I147 @BASEBOARD_FAB2_LIB.BASEBOARD_FAB2(SCH_1):PAGE120

TP_PCH_GPP_J21 @BASEBOARD_FAB2_LIB.BASEBOARD_FAB2(SCH_1):TP_PCH_GPP_J21
  U7C1 BV12 GPP_J21_LAN_SDP_P2_1 LBG_CORE_QAT_EXT_D_BGA1-IC,H91A   I147 @BASEBOARD_FAB2_LIB.BASEBOARD_FAB2(SCH_1):PAGE120

TP_PCH_GPP_J23 @BASEBOARD_FAB2_LIB.BASEBOARD_FAB2(SCH_1):TP_PCH_GPP_J23
  U7C1 BV14 GPP_J23_LAN_SDP_P3_1 LBG_CORE_QAT_EXT_D_BGA1-IC,H91A   I147 @BASEBOARD_FAB2_LIB.BASEBOARD_FAB2(SCH_1):PAGE120

TP_PCH_GPP_L10 @BASEBOARD_FAB2_LIB.BASEBOARD_FAB2(SCH_1):TP_PCH_GPP_L10
  U7C1 AF20 GPP_L10_TESTCH0_CLK LBG_CORE_QAT_EXT_D_BGA1-IC,H91A    I34 @BASEBOARD_FAB2_LIB.BASEBOARD_FAB2(SCH_1):PAGE121

TP_PCH_GPP_L11 @BASEBOARD_FAB2_LIB.BASEBOARD_FAB2(SCH_1):TP_PCH_GPP_L11
  U7C1 AD20 GPP_L11_TESTCH1_D0 LBG_CORE_QAT_EXT_D_BGA1-IC,H91A    I34 @BASEBOARD_FAB2_LIB.BASEBOARD_FAB2(SCH_1):PAGE121

TP_PCH_HDA_BCLK @BASEBOARD_FAB2_LIB.BASEBOARD_FAB2(SCH_1):TP_PCH_HDA_BCLK
  U7C1  P18 HDA_BCLK LBG_CORE_QAT_EXT_D_BGA1-IC,H91A    I34 @BASEBOARD_FAB2_LIB.BASEBOARD_FAB2(SCH_1):PAGE121

TP_PCH_HDA_SDI_0 @BASEBOARD_FAB2_LIB.BASEBOARD_FAB2(SCH_1):TP_PCH_HDA_SDI_0
  U7C1  K20 HDA_SDI_0 LBG_CORE_QAT_EXT_D_BGA1-IC,H91A    I34 @BASEBOARD_FAB2_LIB.BASEBOARD_FAB2(SCH_1):PAGE121

TP_PCH_HDA_SDI_1 @BASEBOARD_FAB2_LIB.BASEBOARD_FAB2(SCH_1):TP_PCH_HDA_SDI_1
  U7C1  V18 HDA_SDI_1 LBG_CORE_QAT_EXT_D_BGA1-IC,H91A    I34 @BASEBOARD_FAB2_LIB.BASEBOARD_FAB2(SCH_1):PAGE121

TP_PCH_HDA_SYNC @BASEBOARD_FAB2_LIB.BASEBOARD_FAB2(SCH_1):TP_PCH_HDA_SYNC
  U7C1  H20 HDA_SYNC LBG_CORE_QAT_EXT_D_BGA1-IC,H91A    I34 @BASEBOARD_FAB2_LIB.BASEBOARD_FAB2(SCH_1):PAGE121

TP_PCH_HSA_RST_N @BASEBOARD_FAB2_LIB.BASEBOARD_FAB2(SCH_1):TP_PCH_HSA_RST_N
  U7C1  M18 HDA_RST_N LBG_CORE_QAT_EXT_D_BGA1-IC,H91A    I34 @BASEBOARD_FAB2_LIB.BASEBOARD_FAB2(SCH_1):PAGE121

TP_PCH_RSVD0 @BASEBOARD_FAB2_LIB.BASEBOARD_FAB2(SCH_1):TP_PCH_RSVD0
  U7C1 AF61 RSVD<0> LBG_CORE_QAT_EXT_D_BGA1-IC,H91A    I34 @BASEBOARD_FAB2_LIB.BASEBOARD_FAB2(SCH_1):PAGE121

TP_PCH_RSVD1 @BASEBOARD_FAB2_LIB.BASEBOARD_FAB2(SCH_1):TP_PCH_RSVD1
  U7C1 AC56 RSVD<1> LBG_CORE_QAT_EXT_D_BGA1-IC,H91A    I34 @BASEBOARD_FAB2_LIB.BASEBOARD_FAB2(SCH_1):PAGE121

TP_PCH_RSVD12 @BASEBOARD_FAB2_LIB.BASEBOARD_FAB2(SCH_1):TP_PCH_RSVD12
  U7C1  C68 RSVD<12> LBG_CORE_QAT_EXT_D_BGA1-IC,H91A    I34 @BASEBOARD_FAB2_LIB.BASEBOARD_FAB2(SCH_1):PAGE121

TP_PCH_RSVD13 @BASEBOARD_FAB2_LIB.BASEBOARD_FAB2(SCH_1):TP_PCH_RSVD13
  U7C1  C67 RSVD<13> LBG_CORE_QAT_EXT_D_BGA1-IC,H91A    I34 @BASEBOARD_FAB2_LIB.BASEBOARD_FAB2(SCH_1):PAGE121

TP_PCH_RSVD14 @BASEBOARD_FAB2_LIB.BASEBOARD_FAB2(SCH_1):TP_PCH_RSVD14
  U7C1  E18 RSVD<14> LBG_CORE_QAT_EXT_D_BGA1-IC,H91A    I34 @BASEBOARD_FAB2_LIB.BASEBOARD_FAB2(SCH_1):PAGE121

TP_PCH_RSVD15 @BASEBOARD_FAB2_LIB.BASEBOARD_FAB2(SCH_1):TP_PCH_RSVD15
  U7C1   C6 RSVD<15> LBG_CORE_QAT_EXT_D_BGA1-IC,H91A    I34 @BASEBOARD_FAB2_LIB.BASEBOARD_FAB2(SCH_1):PAGE121

TP_PCH_RSVD16 @BASEBOARD_FAB2_LIB.BASEBOARD_FAB2(SCH_1):TP_PCH_RSVD16
  U7C1   C5 RSVD<16> LBG_CORE_QAT_EXT_D_BGA1-IC,H91A    I34 @BASEBOARD_FAB2_LIB.BASEBOARD_FAB2(SCH_1):PAGE121

TP_PCH_RSVD17 @BASEBOARD_FAB2_LIB.BASEBOARD_FAB2(SCH_1):TP_PCH_RSVD17
  U7C1  B10 RSVD<17> LBG_CORE_QAT_EXT_D_BGA1-IC,H91A    I34 @BASEBOARD_FAB2_LIB.BASEBOARD_FAB2(SCH_1):PAGE121

TP_PCH_RSVD18 @BASEBOARD_FAB2_LIB.BASEBOARD_FAB2(SCH_1):TP_PCH_RSVD18
  U7C1  C11 RSVD<18> LBG_CORE_QAT_EXT_D_BGA1-IC,H91A    I34 @BASEBOARD_FAB2_LIB.BASEBOARD_FAB2(SCH_1):PAGE121

TP_PCH_RSVD19 @BASEBOARD_FAB2_LIB.BASEBOARD_FAB2(SCH_1):TP_PCH_RSVD19
  U7C1   C9 RSVD<19> LBG_CORE_QAT_EXT_D_BGA1-IC,H91A    I34 @BASEBOARD_FAB2_LIB.BASEBOARD_FAB2(SCH_1):PAGE121

TP_PCH_RSVD2 @BASEBOARD_FAB2_LIB.BASEBOARD_FAB2(SCH_1):TP_PCH_RSVD2
  U7C1 AA58 RSVD<2> LBG_CORE_QAT_EXT_D_BGA1-IC,H91A    I34 @BASEBOARD_FAB2_LIB.BASEBOARD_FAB2(SCH_1):PAGE121

TP_PCH_RSVD20 @BASEBOARD_FAB2_LIB.BASEBOARD_FAB2(SCH_1):TP_PCH_RSVD20
  U7C1  D10 RSVD<20> LBG_CORE_QAT_EXT_D_BGA1-IC,H91A    I34 @BASEBOARD_FAB2_LIB.BASEBOARD_FAB2(SCH_1):PAGE121

TP_PCH_RSVD21 @BASEBOARD_FAB2_LIB.BASEBOARD_FAB2(SCH_1):TP_PCH_RSVD21
  U7C1  A11 RSVD<21> LBG_CORE_QAT_EXT_D_BGA1-IC,H91A    I34 @BASEBOARD_FAB2_LIB.BASEBOARD_FAB2(SCH_1):PAGE121

TP_PCH_RSVD22 @BASEBOARD_FAB2_LIB.BASEBOARD_FAB2(SCH_1):TP_PCH_RSVD22
  U7C1 AT71 RSVD<22> LBG_CORE_QAT_EXT_D_BGA1-IC,H91A    I34 @BASEBOARD_FAB2_LIB.BASEBOARD_FAB2(SCH_1):PAGE121

TP_PCH_RSVD23 @BASEBOARD_FAB2_LIB.BASEBOARD_FAB2(SCH_1):TP_PCH_RSVD23
  U7C1  P40 RSVD<23> LBG_CORE_QAT_EXT_D_BGA1-IC,H91A    I34 @BASEBOARD_FAB2_LIB.BASEBOARD_FAB2(SCH_1):PAGE121

TP_PCH_RSVD24 @BASEBOARD_FAB2_LIB.BASEBOARD_FAB2(SCH_1):TP_PCH_RSVD24
  U7C1  P44 RSVD<24> LBG_CORE_QAT_EXT_D_BGA1-IC,H91A    I34 @BASEBOARD_FAB2_LIB.BASEBOARD_FAB2(SCH_1):PAGE121

TP_PCH_RSVD25 @BASEBOARD_FAB2_LIB.BASEBOARD_FAB2(SCH_1):TP_PCH_RSVD25
  U7C1  P48 RSVD<25> LBG_CORE_QAT_EXT_D_BGA1-IC,H91A    I34 @BASEBOARD_FAB2_LIB.BASEBOARD_FAB2(SCH_1):PAGE121

TP_PCH_RSVD26 @BASEBOARD_FAB2_LIB.BASEBOARD_FAB2(SCH_1):TP_PCH_RSVD26
  U7C1 BH24 RSVD<26> LBG_CORE_QAT_EXT_D_BGA1-IC,H91A    I34 @BASEBOARD_FAB2_LIB.BASEBOARD_FAB2(SCH_1):PAGE121

TP_PCH_RSVD27 @BASEBOARD_FAB2_LIB.BASEBOARD_FAB2(SCH_1):TP_PCH_RSVD27
  U7C1 BG26 RSVD<27> LBG_CORE_QAT_EXT_D_BGA1-IC,H91A    I34 @BASEBOARD_FAB2_LIB.BASEBOARD_FAB2(SCH_1):PAGE121

TP_PCH_RSVD28 @BASEBOARD_FAB2_LIB.BASEBOARD_FAB2(SCH_1):TP_PCH_RSVD28
  U7C1  R35 RSVD<28> LBG_CORE_QAT_EXT_D_BGA1-IC,H91A    I63 @BASEBOARD_FAB2_LIB.BASEBOARD_FAB2(SCH_1):PAGE122

TP_PCH_RSVD29 @BASEBOARD_FAB2_LIB.BASEBOARD_FAB2(SCH_1):TP_PCH_RSVD29
  U7C1  P33 RSVD<29> LBG_CORE_QAT_EXT_D_BGA1-IC,H91A    I63 @BASEBOARD_FAB2_LIB.BASEBOARD_FAB2(SCH_1):PAGE122

TP_PCH_RSVD3 @BASEBOARD_FAB2_LIB.BASEBOARD_FAB2(SCH_1):TP_PCH_RSVD3
  U7C1  V11 RSVD<3> LBG_CORE_QAT_EXT_D_BGA1-IC,H91A    I34 @BASEBOARD_FAB2_LIB.BASEBOARD_FAB2(SCH_1):PAGE121

TP_PCH_RSVD30 @BASEBOARD_FAB2_LIB.BASEBOARD_FAB2(SCH_1):TP_PCH_RSVD30
  U7C1  R31 RSVD<30> LBG_CORE_QAT_EXT_D_BGA1-IC,H91A    I63 @BASEBOARD_FAB2_LIB.BASEBOARD_FAB2(SCH_1):PAGE122

TP_PCH_RSVD31 @BASEBOARD_FAB2_LIB.BASEBOARD_FAB2(SCH_1):TP_PCH_RSVD31
  U7C1  P29 RSVD<31> LBG_CORE_QAT_EXT_D_BGA1-IC,H91A    I63 @BASEBOARD_FAB2_LIB.BASEBOARD_FAB2(SCH_1):PAGE122

TP_PCH_RSVD32 @BASEBOARD_FAB2_LIB.BASEBOARD_FAB2(SCH_1):TP_PCH_RSVD32
  U7C1 AA54 RSVD<32> LBG_CORE_QAT_EXT_D_BGA1-IC,H91A    I73 @BASEBOARD_FAB2_LIB.BASEBOARD_FAB2(SCH_1):PAGE118

TP_PCH_RSVD33 @BASEBOARD_FAB2_LIB.BASEBOARD_FAB2(SCH_1):TP_PCH_RSVD33
  U7C1  V56 RSVD<33> LBG_CORE_QAT_EXT_D_BGA1-IC,H91A    I73 @BASEBOARD_FAB2_LIB.BASEBOARD_FAB2(SCH_1):PAGE118

TP_PCH_RSVD34 @BASEBOARD_FAB2_LIB.BASEBOARD_FAB2(SCH_1):TP_PCH_RSVD34
  U7C1  Y56 RSVD<34> LBG_CORE_QAT_EXT_D_BGA1-IC,H91A    I73 @BASEBOARD_FAB2_LIB.BASEBOARD_FAB2(SCH_1):PAGE118

TP_PCH_RSVD35 @BASEBOARD_FAB2_LIB.BASEBOARD_FAB2(SCH_1):TP_PCH_RSVD35
  U7C1  W54 RSVD<35> LBG_CORE_QAT_EXT_D_BGA1-IC,H91A    I73 @BASEBOARD_FAB2_LIB.BASEBOARD_FAB2(SCH_1):PAGE118

TP_PCH_RSVD36 @BASEBOARD_FAB2_LIB.BASEBOARD_FAB2(SCH_1):TP_PCH_RSVD36
  U7C1 AK54 RSVD<36> LBG_CORE_QAT_EXT_D_BGA1-IC,H91A    I73 @BASEBOARD_FAB2_LIB.BASEBOARD_FAB2(SCH_1):PAGE118

TP_PCH_RSVD37 @BASEBOARD_FAB2_LIB.BASEBOARD_FAB2(SCH_1):TP_PCH_RSVD37
  U7C1 BN29 RSVD<37> LBG_CORE_QAT_EXT_D_BGA1-IC,H91A    I73 @BASEBOARD_FAB2_LIB.BASEBOARD_FAB2(SCH_1):PAGE118

TP_PCH_RSVD38 @BASEBOARD_FAB2_LIB.BASEBOARD_FAB2(SCH_1):TP_PCH_RSVD38
  U7C1 BL29 RSVD<38> LBG_CORE_QAT_EXT_D_BGA1-IC,H91A    I73 @BASEBOARD_FAB2_LIB.BASEBOARD_FAB2(SCH_1):PAGE118

TP_PCH_RSVD4 @BASEBOARD_FAB2_LIB.BASEBOARD_FAB2(SCH_1):TP_PCH_RSVD4
  U7C1  P37 RSVD<4> LBG_CORE_QAT_EXT_D_BGA1-IC,H91A    I34 @BASEBOARD_FAB2_LIB.BASEBOARD_FAB2(SCH_1):PAGE121

TP_PCH_RSVD41 @BASEBOARD_FAB2_LIB.BASEBOARD_FAB2(SCH_1):TP_PCH_RSVD41
  U7C1 BJ40 RSVD<41> LBG_CORE_QAT_EXT_D_BGA1-IC,H91A    I73 @BASEBOARD_FAB2_LIB.BASEBOARD_FAB2(SCH_1):PAGE118

TP_PCH_RSVD42 @BASEBOARD_FAB2_LIB.BASEBOARD_FAB2(SCH_1):TP_PCH_RSVD42
  U7C1 BG40 RSVD<42> LBG_CORE_QAT_EXT_D_BGA1-IC,H91A    I73 @BASEBOARD_FAB2_LIB.BASEBOARD_FAB2(SCH_1):PAGE118

TP_PCH_RSVD45 @BASEBOARD_FAB2_LIB.BASEBOARD_FAB2(SCH_1):TP_PCH_RSVD45
  U7C1  P22 RSVD<45> LBG_CORE_QAT_EXT_D_BGA1-IC,H91A    I73 @BASEBOARD_FAB2_LIB.BASEBOARD_FAB2(SCH_1):PAGE118

TP_PCH_RSVD46 @BASEBOARD_FAB2_LIB.BASEBOARD_FAB2(SCH_1):TP_PCH_RSVD46
  U7C1  BW3 RSVD<46> LBG_CORE_QAT_EXT_D_BGA1-IC,H91A    I34 @BASEBOARD_FAB2_LIB.BASEBOARD_FAB2(SCH_1):PAGE121

TP_PCH_RSVD47 @BASEBOARD_FAB2_LIB.BASEBOARD_FAB2(SCH_1):TP_PCH_RSVD47
  U7C1 AP69 RSVD<47> LBG_CORE_QAT_EXT_D_BGA1-IC,H91A   I220 @BASEBOARD_FAB2_LIB.BASEBOARD_FAB2(SCH_1):PAGE116

TP_PCH_RSVD48 @BASEBOARD_FAB2_LIB.BASEBOARD_FAB2(SCH_1):TP_PCH_RSVD48
  U7C1 AP71 RSVD<48> LBG_CORE_QAT_EXT_D_BGA1-IC,H91A   I220 @BASEBOARD_FAB2_LIB.BASEBOARD_FAB2(SCH_1):PAGE116

TP_PCH_RSVD49 @BASEBOARD_FAB2_LIB.BASEBOARD_FAB2(SCH_1):TP_PCH_RSVD49
  U7C1  G67 RSVD<49> LBG_CORE_QAT_EXT_D_BGA1-IC,H91A   I220 @BASEBOARD_FAB2_LIB.BASEBOARD_FAB2(SCH_1):PAGE116

TP_PCH_RSVD5 @BASEBOARD_FAB2_LIB.BASEBOARD_FAB2(SCH_1):TP_PCH_RSVD5
  U7C1 AG15 RSVD<5> LBG_CORE_QAT_EXT_D_BGA1-IC,H91A    I34 @BASEBOARD_FAB2_LIB.BASEBOARD_FAB2(SCH_1):PAGE121

TP_PCH_RSVD50 @BASEBOARD_FAB2_LIB.BASEBOARD_FAB2(SCH_1):TP_PCH_RSVD50
  U7C1  H69 RSVD<50> LBG_CORE_QAT_EXT_D_BGA1-IC,H91A   I220 @BASEBOARD_FAB2_LIB.BASEBOARD_FAB2(SCH_1):PAGE116

TP_PCH_RSVD51 @BASEBOARD_FAB2_LIB.BASEBOARD_FAB2(SCH_1):TP_PCH_RSVD51
  U7C1 AA69 RSVD<51> LBG_CORE_QAT_EXT_D_BGA1-IC,H91A   I220 @BASEBOARD_FAB2_LIB.BASEBOARD_FAB2(SCH_1):PAGE116

TP_PCH_RSVD52 @BASEBOARD_FAB2_LIB.BASEBOARD_FAB2(SCH_1):TP_PCH_RSVD52
  U7C1 AA71 RSVD<52> LBG_CORE_QAT_EXT_D_BGA1-IC,H91A   I220 @BASEBOARD_FAB2_LIB.BASEBOARD_FAB2(SCH_1):PAGE116

TP_PCH_RSVD53 @BASEBOARD_FAB2_LIB.BASEBOARD_FAB2(SCH_1):TP_PCH_RSVD53
  U7C1  P26 RSVD<53> LBG_CORE_QAT_EXT_D_BGA1-IC,H91A    I73 @BASEBOARD_FAB2_LIB.BASEBOARD_FAB2(SCH_1):PAGE118

TP_PCH_RSVD54 @BASEBOARD_FAB2_LIB.BASEBOARD_FAB2(SCH_1):TP_PCH_RSVD54
  U7C1  R24 RSVD<54> LBG_CORE_QAT_EXT_D_BGA1-IC,H91A    I73 @BASEBOARD_FAB2_LIB.BASEBOARD_FAB2(SCH_1):PAGE118

TP_PCH_RSVD55 @BASEBOARD_FAB2_LIB.BASEBOARD_FAB2(SCH_1):TP_PCH_RSVD55
  U7C1 BN68 RSVD<55> LBG_CORE_QAT_EXT_D_BGA1-IC,H91A    I74 @BASEBOARD_FAB2_LIB.BASEBOARD_FAB2(SCH_1):PAGE115

TP_PCH_RSVD58 @BASEBOARD_FAB2_LIB.BASEBOARD_FAB2(SCH_1):TP_PCH_RSVD58
  U7C1 AP27 RSVD<58> LBG_CORE_QAT_EXT_D_BGA1-IC,H91A    I63 @BASEBOARD_FAB2_LIB.BASEBOARD_FAB2(SCH_1):PAGE122

TP_PCH_RSVD59 @BASEBOARD_FAB2_LIB.BASEBOARD_FAB2(SCH_1):TP_PCH_RSVD59
  U7C1 AT27 RSVD<59> LBG_CORE_QAT_EXT_D_BGA1-IC,H91A    I63 @BASEBOARD_FAB2_LIB.BASEBOARD_FAB2(SCH_1):PAGE122

TP_PCH_RSVD6 @BASEBOARD_FAB2_LIB.BASEBOARD_FAB2(SCH_1):TP_PCH_RSVD6
  U7C1 AT69 RSVD<6> LBG_CORE_QAT_EXT_D_BGA1-IC,H91A    I34 @BASEBOARD_FAB2_LIB.BASEBOARD_FAB2(SCH_1):PAGE121

TP_PCH_RSVD64 @BASEBOARD_FAB2_LIB.BASEBOARD_FAB2(SCH_1):TP_PCH_RSVD64
  U7C1  C26 RSVD<64> LBG_CORE_QAT_EXT_D_BGA1-IC,H91A    I40 @BASEBOARD_FAB2_LIB.BASEBOARD_FAB2(SCH_1):PAGE114

TP_PCH_RSVD65 @BASEBOARD_FAB2_LIB.BASEBOARD_FAB2(SCH_1):TP_PCH_RSVD65
  U7C1  A26 RSVD<65> LBG_CORE_QAT_EXT_D_BGA1-IC,H91A    I40 @BASEBOARD_FAB2_LIB.BASEBOARD_FAB2(SCH_1):PAGE114

TP_PCH_RSVD7 @BASEBOARD_FAB2_LIB.BASEBOARD_FAB2(SCH_1):TP_PCH_RSVD7
  U7C1   F8 RSVD<7> LBG_CORE_QAT_EXT_D_BGA1-IC,H91A    I34 @BASEBOARD_FAB2_LIB.BASEBOARD_FAB2(SCH_1):PAGE121

TP_PCH_RSVD8 @BASEBOARD_FAB2_LIB.BASEBOARD_FAB2(SCH_1):TP_PCH_RSVD8
  U7C1  F69 RSVD<8> LBG_CORE_QAT_EXT_D_BGA1-IC,H91A    I34 @BASEBOARD_FAB2_LIB.BASEBOARD_FAB2(SCH_1):PAGE121

TP_PCH_RSVD9 @BASEBOARD_FAB2_LIB.BASEBOARD_FAB2(SCH_1):TP_PCH_RSVD9
  U7C1  F66 RSVD<9> LBG_CORE_QAT_EXT_D_BGA1-IC,H91A    I34 @BASEBOARD_FAB2_LIB.BASEBOARD_FAB2(SCH_1):PAGE121

TP_PI7C9X1172_EN485_N @BASEBOARD_FAB2_LIB.BASEBOARD_FAB2(SCH_1):TP_PI7C9X1172_EN485_N
 EU9F3   19 EN485_N PI7C9X1172_QFN-IC,H66899-001     I1 @BASEBOARD_FAB2_LIB.BASEBOARD_FAB2(SCH_1):PAGE183

TP_PI7C9X1172_ENIR_N @BASEBOARD_FAB2_LIB.BASEBOARD_FAB2(SCH_1):TP_PI7C9X1172_ENIR_N
 EU9F3   18 ENIR_N PI7C9X1172_QFN-IC,H66899-001     I1 @BASEBOARD_FAB2_LIB.BASEBOARD_FAB2(SCH_1):PAGE183

TP_PI7C9X1172_RTSA_N @BASEBOARD_FAB2_LIB.BASEBOARD_FAB2(SCH_1):TP_PI7C9X1172_RTSA_N
 EU9F3   21 RTSA_N PI7C9X1172_QFN-IC,H66899-001     I1 @BASEBOARD_FAB2_LIB.BASEBOARD_FAB2(SCH_1):PAGE183

TP_PI7C9X1172_RTSB_N @BASEBOARD_FAB2_LIB.BASEBOARD_FAB2(SCH_1):TP_PI7C9X1172_RTSB_N
 EU9F3   15 RTSB_N PI7C9X1172_QFN-IC,H66899-001     I1 @BASEBOARD_FAB2_LIB.BASEBOARD_FAB2(SCH_1):PAGE183

TP_PI7C9X1172_SO @BASEBOARD_FAB2_LIB.BASEBOARD_FAB2(SCH_1):TP_PI7C9X1172_SO
 EU9F3    2     SO PI7C9X1172_QFN-IC,H66899-001     I1 @BASEBOARD_FAB2_LIB.BASEBOARD_FAB2(SCH_1):PAGE183

TP_PLTRST_CPU_N @BASEBOARD_FAB2_LIB.BASEBOARD_FAB2(SCH_1):TP_PLTRST_CPU_N
  U7C1  U17 PLTRST_CPU_N LBG_CORE_QAT_EXT_D_BGA1-IC,H91A    I73 @BASEBOARD_FAB2_LIB.BASEBOARD_FAB2(SCH_1):PAGE118

TP_PM_SYNC_GTL @BASEBOARD_FAB2_LIB.BASEBOARD_FAB2(SCH_1):TP_PM_SYNC_GTL
  U7C1   V7 PM_SYNC2 LBG_CORE_QAT_EXT_D_BGA1-IC,H91A    I73 @BASEBOARD_FAB2_LIB.BASEBOARD_FAB2(SCH_1):PAGE118

TP_PVCCINC_CPU1_PH1_GL_0 @BASEBOARD_FAB2_LIB.BASEBOARD_FAB2(SCH_1):TP_PVCCINC_CPU1_PH1_GL_0
 EU1E2    6  GL<0> IR354XX_SM-IR35411,IC,H73688-0A    I20 @BASEBOARD_FAB2_LIB.BASEBOARD_FAB2(SCH_1):PAGE207

TP_PVCCINC_CPU1_PH1_GL_1 @BASEBOARD_FAB2_LIB.BASEBOARD_FAB2(SCH_1):TP_PVCCINC_CPU1_PH1_GL_1
 EU1E2   41  GL<1> IR354XX_SM-IR35411,IC,H73688-0A    I20 @BASEBOARD_FAB2_LIB.BASEBOARD_FAB2(SCH_1):PAGE207

TP_PVCCINC_CPU1_PH2_GL_0 @BASEBOARD_FAB2_LIB.BASEBOARD_FAB2(SCH_1):TP_PVCCINC_CPU1_PH2_GL_0
 EU1D4    6  GL<0> IR354XX_SM-IR35411,IC,H73688-0A    I24 @BASEBOARD_FAB2_LIB.BASEBOARD_FAB2(SCH_1):PAGE207

TP_PVCCINC_CPU1_PH2_GL_1 @BASEBOARD_FAB2_LIB.BASEBOARD_FAB2(SCH_1):TP_PVCCINC_CPU1_PH2_GL_1
 EU1D4   41  GL<1> IR354XX_SM-IR35411,IC,H73688-0A    I24 @BASEBOARD_FAB2_LIB.BASEBOARD_FAB2(SCH_1):PAGE207

TP_PVCCIN_CPU0_AIREF6 @BASEBOARD_FAB2_LIB.BASEBOARD_FAB2(SCH_1):TP_PVCCIN_CPU0_AIREF6
 EU4D4   33 AIREF6 PXE1610B_QFN-IC,H79206-001   I155 @BASEBOARD_FAB2_LIB.BASEBOARD_FAB2(SCH_1):PAGE201

TP_PVCCIN_CPU0_AISEN6 @BASEBOARD_FAB2_LIB.BASEBOARD_FAB2(SCH_1):TP_PVCCIN_CPU0_AISEN6
 EU4D4   34 AISEN6 PXE1610B_QFN-IC,H79206-001   I155 @BASEBOARD_FAB2_LIB.BASEBOARD_FAB2(SCH_1):PAGE201

TP_PVCCIN_CPU0_APWM6 @BASEBOARD_FAB2_LIB.BASEBOARD_FAB2(SCH_1):TP_PVCCIN_CPU0_APWM6
 EU4D4    2  APWM6 PXE1610B_QFN-IC,H79206-001   I155 @BASEBOARD_FAB2_LIB.BASEBOARD_FAB2(SCH_1):PAGE201

TP_PVCCIN_CPU0_FAULT1_20 @BASEBOARD_FAB2_LIB.BASEBOARD_FAB2(SCH_1):TP_PVCCIN_CPU0_FAULT1_20
 EU4D4   40    MP4 PXE1610B_QFN-IC,H79206-001   I155 @BASEBOARD_FAB2_LIB.BASEBOARD_FAB2(SCH_1):PAGE201

TP_PVCCIN_CPU0_GP1 @BASEBOARD_FAB2_LIB.BASEBOARD_FAB2(SCH_1):TP_PVCCIN_CPU0_GP1
 EU4D4   16    MP1 PXE1610B_QFN-IC,H79206-001   I155 @BASEBOARD_FAB2_LIB.BASEBOARD_FAB2(SCH_1):PAGE201

TP_PVCCIN_CPU0_PH1_GL_0 @BASEBOARD_FAB2_LIB.BASEBOARD_FAB2(SCH_1):TP_PVCCIN_CPU0_PH1_GL_0
 EU4E1    6  GL<0> IR354XX_SM-IR35411,IC,H73688-0A    I63 @BASEBOARD_FAB2_LIB.BASEBOARD_FAB2(SCH_1):PAGE202

TP_PVCCIN_CPU0_PH1_GL_1 @BASEBOARD_FAB2_LIB.BASEBOARD_FAB2(SCH_1):TP_PVCCIN_CPU0_PH1_GL_1
 EU4E1   41  GL<1> IR354XX_SM-IR35411,IC,H73688-0A    I63 @BASEBOARD_FAB2_LIB.BASEBOARD_FAB2(SCH_1):PAGE202

TP_PVCCIN_CPU0_PH2_GL_0 @BASEBOARD_FAB2_LIB.BASEBOARD_FAB2(SCH_1):TP_PVCCIN_CPU0_PH2_GL_0
 EU4D6    6  GL<0> IR354XX_SM-IR35411,IC,H73688-0A    I64 @BASEBOARD_FAB2_LIB.BASEBOARD_FAB2(SCH_1):PAGE202

TP_PVCCIN_CPU0_PH2_GL_1 @BASEBOARD_FAB2_LIB.BASEBOARD_FAB2(SCH_1):TP_PVCCIN_CPU0_PH2_GL_1
 EU4D6   41  GL<1> IR354XX_SM-IR35411,IC,H73688-0A    I64 @BASEBOARD_FAB2_LIB.BASEBOARD_FAB2(SCH_1):PAGE202

TP_PVCCIN_CPU0_PH3_GL_0 @BASEBOARD_FAB2_LIB.BASEBOARD_FAB2(SCH_1):TP_PVCCIN_CPU0_PH3_GL_0
 EU4D3    6  GL<0> IR354XX_SM-IR35411,IC,H73688-0A    I70 @BASEBOARD_FAB2_LIB.BASEBOARD_FAB2(SCH_1):PAGE203

TP_PVCCIN_CPU0_PH3_GL_1 @BASEBOARD_FAB2_LIB.BASEBOARD_FAB2(SCH_1):TP_PVCCIN_CPU0_PH3_GL_1
 EU4D3   41  GL<1> IR354XX_SM-IR35411,IC,H73688-0A    I70 @BASEBOARD_FAB2_LIB.BASEBOARD_FAB2(SCH_1):PAGE203

TP_PVCCIN_CPU0_PH4_GL_0 @BASEBOARD_FAB2_LIB.BASEBOARD_FAB2(SCH_1):TP_PVCCIN_CPU0_PH4_GL_0
 EU4D1    6  GL<0> IR354XX_SM-IR35411,IC,H73688-0A    I71 @BASEBOARD_FAB2_LIB.BASEBOARD_FAB2(SCH_1):PAGE203

TP_PVCCIN_CPU0_PH4_GL_1 @BASEBOARD_FAB2_LIB.BASEBOARD_FAB2(SCH_1):TP_PVCCIN_CPU0_PH4_GL_1
 EU4D1   41  GL<1> IR354XX_SM-IR35411,IC,H73688-0A    I71 @BASEBOARD_FAB2_LIB.BASEBOARD_FAB2(SCH_1):PAGE203

TP_PVCCIN_CPU0_PH5_GL_0 @BASEBOARD_FAB2_LIB.BASEBOARD_FAB2(SCH_1):TP_PVCCIN_CPU0_PH5_GL_0
 EU4C2    6  GL<0> IR354XX_SM-IR35411,IC,H73688-0A    I71 @BASEBOARD_FAB2_LIB.BASEBOARD_FAB2(SCH_1):PAGE204

TP_PVCCIN_CPU0_PH5_GL_1 @BASEBOARD_FAB2_LIB.BASEBOARD_FAB2(SCH_1):TP_PVCCIN_CPU0_PH5_GL_1
 EU4C2   41  GL<1> IR354XX_SM-IR35411,IC,H73688-0A    I71 @BASEBOARD_FAB2_LIB.BASEBOARD_FAB2(SCH_1):PAGE204

TP_PVCCIN_CPU0_RESET @BASEBOARD_FAB2_LIB.BASEBOARD_FAB2(SCH_1):TP_PVCCIN_CPU0_RESET
 EU4D4   10 RESET_N PXE1610B_QFN-IC,H79206-001   I155 @BASEBOARD_FAB2_LIB.BASEBOARD_FAB2(SCH_1):PAGE201

TP_PVCCIN_CPU1_AIREF6 @BASEBOARD_FAB2_LIB.BASEBOARD_FAB2(SCH_1):TP_PVCCIN_CPU1_AIREF6
 EU1C2   33 AIREF6 PXE1610B_QFN-IC,H79206-001   I130 @BASEBOARD_FAB2_LIB.BASEBOARD_FAB2(SCH_1):PAGE206

TP_PVCCIN_CPU1_AISEN6 @BASEBOARD_FAB2_LIB.BASEBOARD_FAB2(SCH_1):TP_PVCCIN_CPU1_AISEN6
 EU1C2   34 AISEN6 PXE1610B_QFN-IC,H79206-001   I130 @BASEBOARD_FAB2_LIB.BASEBOARD_FAB2(SCH_1):PAGE206

TP_PVCCIN_CPU1_APWM6 @BASEBOARD_FAB2_LIB.BASEBOARD_FAB2(SCH_1):TP_PVCCIN_CPU1_APWM6
 EU1C2    2  APWM6 PXE1610B_QFN-IC,H79206-001   I130 @BASEBOARD_FAB2_LIB.BASEBOARD_FAB2(SCH_1):PAGE206

TP_PVCCIN_CPU1_FAULT1_20 @BASEBOARD_FAB2_LIB.BASEBOARD_FAB2(SCH_1):TP_PVCCIN_CPU1_FAULT1_20
 EU1C2   40    MP4 PXE1610B_QFN-IC,H79206-001   I130 @BASEBOARD_FAB2_LIB.BASEBOARD_FAB2(SCH_1):PAGE206

TP_PVCCIN_CPU1_GP1 @BASEBOARD_FAB2_LIB.BASEBOARD_FAB2(SCH_1):TP_PVCCIN_CPU1_GP1
 EU1C2   16    MP1 PXE1610B_QFN-IC,H79206-001   I130 @BASEBOARD_FAB2_LIB.BASEBOARD_FAB2(SCH_1):PAGE206

TP_PVCCIN_CPU1_PH3_GL_0 @BASEBOARD_FAB2_LIB.BASEBOARD_FAB2(SCH_1):TP_PVCCIN_CPU1_PH3_GL_0
 EU1D3    6  GL<0> IR354XX_SM-IR35411,IC,H73688-0A    I27 @BASEBOARD_FAB2_LIB.BASEBOARD_FAB2(SCH_1):PAGE208

TP_PVCCIN_CPU1_PH3_GL_1 @BASEBOARD_FAB2_LIB.BASEBOARD_FAB2(SCH_1):TP_PVCCIN_CPU1_PH3_GL_1
 EU1D3   41  GL<1> IR354XX_SM-IR35411,IC,H73688-0A    I27 @BASEBOARD_FAB2_LIB.BASEBOARD_FAB2(SCH_1):PAGE208

TP_PVCCIN_CPU1_PH4_GL_0 @BASEBOARD_FAB2_LIB.BASEBOARD_FAB2(SCH_1):TP_PVCCIN_CPU1_PH4_GL_0
 EU1D1    6  GL<0> IR354XX_SM-IR35411,IC,H73688-0A    I71 @BASEBOARD_FAB2_LIB.BASEBOARD_FAB2(SCH_1):PAGE208

TP_PVCCIN_CPU1_PH4_GL_1 @BASEBOARD_FAB2_LIB.BASEBOARD_FAB2(SCH_1):TP_PVCCIN_CPU1_PH4_GL_1
 EU1D1   41  GL<1> IR354XX_SM-IR35411,IC,H73688-0A    I71 @BASEBOARD_FAB2_LIB.BASEBOARD_FAB2(SCH_1):PAGE208

TP_PVCCIN_CPU1_PH5_GL_0 @BASEBOARD_FAB2_LIB.BASEBOARD_FAB2(SCH_1):TP_PVCCIN_CPU1_PH5_GL_0
 EU1C3    6  GL<0> IR354XX_SM-IR35411,IC,H73688-0A    I56 @BASEBOARD_FAB2_LIB.BASEBOARD_FAB2(SCH_1):PAGE209

TP_PVCCIN_CPU1_PH5_GL_1 @BASEBOARD_FAB2_LIB.BASEBOARD_FAB2(SCH_1):TP_PVCCIN_CPU1_PH5_GL_1
 EU1C3   41  GL<1> IR354XX_SM-IR35411,IC,H73688-0A    I56 @BASEBOARD_FAB2_LIB.BASEBOARD_FAB2(SCH_1):PAGE209

TP_PVCCIN_CPU1_RESET_N @BASEBOARD_FAB2_LIB.BASEBOARD_FAB2(SCH_1):TP_PVCCIN_CPU1_RESET_N
 EU1C2   10 RESET_N PXE1610B_QFN-IC,H79206-001   I130 @BASEBOARD_FAB2_LIB.BASEBOARD_FAB2(SCH_1):PAGE206

TP_PVCCIO_CPU0_BIREF1 @BASEBOARD_FAB2_LIB.BASEBOARD_FAB2(SCH_1):TP_PVCCIO_CPU0_BIREF1
 EU3P1   25 BIREF1 PXE1110B_QFN-IC,H89187-001    I93 @BASEBOARD_FAB2_LIB.BASEBOARD_FAB2(SCH_1):PAGE211

TP_PVCCIO_CPU0_BPWM1 @BASEBOARD_FAB2_LIB.BASEBOARD_FAB2(SCH_1):TP_PVCCIO_CPU0_BPWM1
 EU3P1    3  BPWM1 PXE1110B_QFN-IC,H89187-001    I93 @BASEBOARD_FAB2_LIB.BASEBOARD_FAB2(SCH_1):PAGE211

TP_PVCCIO_CPU0_BTSEN @BASEBOARD_FAB2_LIB.BASEBOARD_FAB2(SCH_1):TP_PVCCIO_CPU0_BTSEN
 EU3P1   34  BTSEN PXE1110B_QFN-IC,H89187-001    I93 @BASEBOARD_FAB2_LIB.BASEBOARD_FAB2(SCH_1):PAGE211

TP_PVCCIO_CPU0_BVREF @BASEBOARD_FAB2_LIB.BASEBOARD_FAB2(SCH_1):TP_PVCCIO_CPU0_BVREF
 EU3P1   30  BVREF PXE1110B_QFN-IC,H89187-001    I93 @BASEBOARD_FAB2_LIB.BASEBOARD_FAB2(SCH_1):PAGE211

TP_PVCCIO_CPU0_BVSEN @BASEBOARD_FAB2_LIB.BASEBOARD_FAB2(SCH_1):TP_PVCCIO_CPU0_BVSEN
 EU3P1   29  BVSEN PXE1110B_QFN-IC,H89187-001    I93 @BASEBOARD_FAB2_LIB.BASEBOARD_FAB2(SCH_1):PAGE211

TP_PVCCIO_CPU0_GL_0 @BASEBOARD_FAB2_LIB.BASEBOARD_FAB2(SCH_1):TP_PVCCIO_CPU0_GL_0
 EU7C1    6  GL<0> IR354XX_SM-IR35412,IC,H73684-0A   I101 @BASEBOARD_FAB2_LIB.BASEBOARD_FAB2(SCH_1):PAGE212

TP_PVCCIO_CPU0_GL_1 @BASEBOARD_FAB2_LIB.BASEBOARD_FAB2(SCH_1):TP_PVCCIO_CPU0_GL_1
 EU7C1   41  GL<1> IR354XX_SM-IR35412,IC,H73684-0A   I101 @BASEBOARD_FAB2_LIB.BASEBOARD_FAB2(SCH_1):PAGE212

TP_PVCCIO_CPU0_PINALRT_N @BASEBOARD_FAB2_LIB.BASEBOARD_FAB2(SCH_1):TP_PVCCIO_CPU0_PINALRT_N
 EU3P1   12 PINALRT_N PXE1110B_QFN-IC,H89187-001    I93 @BASEBOARD_FAB2_LIB.BASEBOARD_FAB2(SCH_1):PAGE211

TP_PVCCIO_CPU0_RESET_N @BASEBOARD_FAB2_LIB.BASEBOARD_FAB2(SCH_1):TP_PVCCIO_CPU0_RESET_N
 EU3P1    8 RESET_N PXE1110B_QFN-IC,H89187-001    I93 @BASEBOARD_FAB2_LIB.BASEBOARD_FAB2(SCH_1):PAGE211

TP_PVCCIO_CPU1_BIREF1 @BASEBOARD_FAB2_LIB.BASEBOARD_FAB2(SCH_1):TP_PVCCIO_CPU1_BIREF1
 EU4D5   25 BIREF1 PXE1110B_QFN-IC,H89187-001    I96 @BASEBOARD_FAB2_LIB.BASEBOARD_FAB2(SCH_1):PAGE213

TP_PVCCIO_CPU1_BPWM1 @BASEBOARD_FAB2_LIB.BASEBOARD_FAB2(SCH_1):TP_PVCCIO_CPU1_BPWM1
 EU4D5    3  BPWM1 PXE1110B_QFN-IC,H89187-001    I96 @BASEBOARD_FAB2_LIB.BASEBOARD_FAB2(SCH_1):PAGE213

TP_PVCCIO_CPU1_BTSEN @BASEBOARD_FAB2_LIB.BASEBOARD_FAB2(SCH_1):TP_PVCCIO_CPU1_BTSEN
 EU4D5   34  BTSEN PXE1110B_QFN-IC,H89187-001    I96 @BASEBOARD_FAB2_LIB.BASEBOARD_FAB2(SCH_1):PAGE213

TP_PVCCIO_CPU1_BVREF @BASEBOARD_FAB2_LIB.BASEBOARD_FAB2(SCH_1):TP_PVCCIO_CPU1_BVREF
 EU4D5   30  BVREF PXE1110B_QFN-IC,H89187-001    I96 @BASEBOARD_FAB2_LIB.BASEBOARD_FAB2(SCH_1):PAGE213

TP_PVCCIO_CPU1_BVSEN @BASEBOARD_FAB2_LIB.BASEBOARD_FAB2(SCH_1):TP_PVCCIO_CPU1_BVSEN
 EU4D5   29  BVSEN PXE1110B_QFN-IC,H89187-001    I96 @BASEBOARD_FAB2_LIB.BASEBOARD_FAB2(SCH_1):PAGE213

TP_PVCCIO_CPU1_GL_0 @BASEBOARD_FAB2_LIB.BASEBOARD_FAB2(SCH_1):TP_PVCCIO_CPU1_GL_0
 EU4E2    6  GL<0> IR354XX_SM-IR35412,IC,H73684-0A   I126 @BASEBOARD_FAB2_LIB.BASEBOARD_FAB2(SCH_1):PAGE214

TP_PVCCIO_CPU1_GL_1 @BASEBOARD_FAB2_LIB.BASEBOARD_FAB2(SCH_1):TP_PVCCIO_CPU1_GL_1
 EU4E2   41  GL<1> IR354XX_SM-IR35412,IC,H73684-0A   I126 @BASEBOARD_FAB2_LIB.BASEBOARD_FAB2(SCH_1):PAGE214

TP_PVCCIO_CPU1_PINALRT_N @BASEBOARD_FAB2_LIB.BASEBOARD_FAB2(SCH_1):TP_PVCCIO_CPU1_PINALRT_N
 EU4D5   12 PINALRT_N PXE1110B_QFN-IC,H89187-001    I96 @BASEBOARD_FAB2_LIB.BASEBOARD_FAB2(SCH_1):PAGE213

TP_PVCCIO_CPU1_RESET_N @BASEBOARD_FAB2_LIB.BASEBOARD_FAB2(SCH_1):TP_PVCCIO_CPU1_RESET_N
 EU4D5    8 RESET_N PXE1110B_QFN-IC,H89187-001    I96 @BASEBOARD_FAB2_LIB.BASEBOARD_FAB2(SCH_1):PAGE213

TP_PVDDQ_ABC_BPWM1 @BASEBOARD_FAB2_LIB.BASEBOARD_FAB2(SCH_1):TP_PVDDQ_ABC_BPWM1
 EU7G1    1  BPWM1 PXM1310B_QFN-IC,H89186-001   I358 @BASEBOARD_FAB2_LIB.BASEBOARD_FAB2(SCH_1):PAGE215

TP_PVDDQ_ABC_BREF1 @BASEBOARD_FAB2_LIB.BASEBOARD_FAB2(SCH_1):TP_PVDDQ_ABC_BREF1
 EU7G1   31 BIREF1 PXM1310B_QFN-IC,H89186-001   I358 @BASEBOARD_FAB2_LIB.BASEBOARD_FAB2(SCH_1):PAGE215

TP_PVDDQ_ABC_BTSEN @BASEBOARD_FAB2_LIB.BASEBOARD_FAB2(SCH_1):TP_PVDDQ_ABC_BTSEN
 EU7G1   34  BTSEN PXM1310B_QFN-IC,H89186-001   I358 @BASEBOARD_FAB2_LIB.BASEBOARD_FAB2(SCH_1):PAGE215

TP_PVDDQ_ABC_BVREF @BASEBOARD_FAB2_LIB.BASEBOARD_FAB2(SCH_1):TP_PVDDQ_ABC_BVREF
 EU7G1   30  BVREF PXM1310B_QFN-IC,H89186-001   I358 @BASEBOARD_FAB2_LIB.BASEBOARD_FAB2(SCH_1):PAGE215

TP_PVDDQ_ABC_BVSEN @BASEBOARD_FAB2_LIB.BASEBOARD_FAB2(SCH_1):TP_PVDDQ_ABC_BVSEN
 EU7G1   29  BVSEN PXM1310B_QFN-IC,H89186-001   I358 @BASEBOARD_FAB2_LIB.BASEBOARD_FAB2(SCH_1):PAGE215

TP_PVDDQ_ABC_MP1 @BASEBOARD_FAB2_LIB.BASEBOARD_FAB2(SCH_1):TP_PVDDQ_ABC_MP1
 EU7G1   14    MP1 PXM1310B_QFN-IC,H89186-001   I358 @BASEBOARD_FAB2_LIB.BASEBOARD_FAB2(SCH_1):PAGE215

TP_PVDDQ_ABC_MP2 @BASEBOARD_FAB2_LIB.BASEBOARD_FAB2(SCH_1):TP_PVDDQ_ABC_MP2
 EU7G1   18    MP2 PXM1310B_QFN-IC,H89186-001   I358 @BASEBOARD_FAB2_LIB.BASEBOARD_FAB2(SCH_1):PAGE215

TP_PVDDQ_ABC_PH1_GL_0 @BASEBOARD_FAB2_LIB.BASEBOARD_FAB2(SCH_1):TP_PVDDQ_ABC_PH1_GL_0
 EU7G2    6  GL<0> IR354XX_SM-IR35411,IC,H73688-0A   I102 @BASEBOARD_FAB2_LIB.BASEBOARD_FAB2(SCH_1):PAGE216

TP_PVDDQ_ABC_PH1_GL_1 @BASEBOARD_FAB2_LIB.BASEBOARD_FAB2(SCH_1):TP_PVDDQ_ABC_PH1_GL_1
 EU7G2   41  GL<1> IR354XX_SM-IR35411,IC,H73688-0A   I102 @BASEBOARD_FAB2_LIB.BASEBOARD_FAB2(SCH_1):PAGE216

TP_PVDDQ_ABC_PH2_GL_0 @BASEBOARD_FAB2_LIB.BASEBOARD_FAB2(SCH_1):TP_PVDDQ_ABC_PH2_GL_0
 EU7G3    6  GL<0> IR354XX_SM-IR35411,IC,H73688-0A   I103 @BASEBOARD_FAB2_LIB.BASEBOARD_FAB2(SCH_1):PAGE216

TP_PVDDQ_ABC_PH2_GL_1 @BASEBOARD_FAB2_LIB.BASEBOARD_FAB2(SCH_1):TP_PVDDQ_ABC_PH2_GL_1
 EU7G3   41  GL<1> IR354XX_SM-IR35411,IC,H73688-0A   I103 @BASEBOARD_FAB2_LIB.BASEBOARD_FAB2(SCH_1):PAGE216

TP_PVDDQ_ABC_PH3_IMON @BASEBOARD_FAB2_LIB.BASEBOARD_FAB2(SCH_1):TP_PVDDQ_ABC_PH3_IMON
 EU7G1   26 AISEN3 PXM1310B_QFN-IC,H89186-001   I358 @BASEBOARD_FAB2_LIB.BASEBOARD_FAB2(SCH_1):PAGE215

TP_PVDDQ_ABC_PH3_IMON_REF @BASEBOARD_FAB2_LIB.BASEBOARD_FAB2(SCH_1):TP_PVDDQ_ABC_PH3_IMON_REF
 EU7G1   25 AIREF3 PXM1310B_QFN-IC,H89186-001   I358 @BASEBOARD_FAB2_LIB.BASEBOARD_FAB2(SCH_1):PAGE215

TP_PVDDQ_ABC_PINALRT_N @BASEBOARD_FAB2_LIB.BASEBOARD_FAB2(SCH_1):TP_PVDDQ_ABC_PINALRT_N
 EU7G1   12 PINALRT_N PXM1310B_QFN-IC,H89186-001   I358 @BASEBOARD_FAB2_LIB.BASEBOARD_FAB2(SCH_1):PAGE215

TP_PVDDQ_ABC_PWM3 @BASEBOARD_FAB2_LIB.BASEBOARD_FAB2(SCH_1):TP_PVDDQ_ABC_PWM3
 EU7G1    3  APWM3 PXM1310B_QFN-IC,H89186-001   I358 @BASEBOARD_FAB2_LIB.BASEBOARD_FAB2(SCH_1):PAGE215

TP_PVDDQ_ABC_RESET_N @BASEBOARD_FAB2_LIB.BASEBOARD_FAB2(SCH_1):TP_PVDDQ_ABC_RESET_N
 EU7G1    8 RESET_N PXM1310B_QFN-IC,H89186-001   I358 @BASEBOARD_FAB2_LIB.BASEBOARD_FAB2(SCH_1):PAGE215

TP_PVDDQ_DEF_BPWM1 @BASEBOARD_FAB2_LIB.BASEBOARD_FAB2(SCH_1):TP_PVDDQ_DEF_BPWM1
 EU7A5    1  BPWM1 PXM1310B_QFN-IC,H89186-001    I75 @BASEBOARD_FAB2_LIB.BASEBOARD_FAB2(SCH_1):PAGE218

TP_PVDDQ_DEF_BREF1 @BASEBOARD_FAB2_LIB.BASEBOARD_FAB2(SCH_1):TP_PVDDQ_DEF_BREF1
 EU7A5   31 BIREF1 PXM1310B_QFN-IC,H89186-001    I75 @BASEBOARD_FAB2_LIB.BASEBOARD_FAB2(SCH_1):PAGE218

TP_PVDDQ_DEF_BTSEN @BASEBOARD_FAB2_LIB.BASEBOARD_FAB2(SCH_1):TP_PVDDQ_DEF_BTSEN
 EU7A5   34  BTSEN PXM1310B_QFN-IC,H89186-001    I75 @BASEBOARD_FAB2_LIB.BASEBOARD_FAB2(SCH_1):PAGE218

TP_PVDDQ_DEF_BVREF @BASEBOARD_FAB2_LIB.BASEBOARD_FAB2(SCH_1):TP_PVDDQ_DEF_BVREF
 EU7A5   30  BVREF PXM1310B_QFN-IC,H89186-001    I75 @BASEBOARD_FAB2_LIB.BASEBOARD_FAB2(SCH_1):PAGE218

TP_PVDDQ_DEF_BVSEN @BASEBOARD_FAB2_LIB.BASEBOARD_FAB2(SCH_1):TP_PVDDQ_DEF_BVSEN
 EU7A5   29  BVSEN PXM1310B_QFN-IC,H89186-001    I75 @BASEBOARD_FAB2_LIB.BASEBOARD_FAB2(SCH_1):PAGE218

TP_PVDDQ_DEF_MP1 @BASEBOARD_FAB2_LIB.BASEBOARD_FAB2(SCH_1):TP_PVDDQ_DEF_MP1
 EU7A5   14    MP1 PXM1310B_QFN-IC,H89186-001    I75 @BASEBOARD_FAB2_LIB.BASEBOARD_FAB2(SCH_1):PAGE218

TP_PVDDQ_DEF_MP2 @BASEBOARD_FAB2_LIB.BASEBOARD_FAB2(SCH_1):TP_PVDDQ_DEF_MP2
 EU7A5   18    MP2 PXM1310B_QFN-IC,H89186-001    I75 @BASEBOARD_FAB2_LIB.BASEBOARD_FAB2(SCH_1):PAGE218

TP_PVDDQ_DEF_PH1_GL_0 @BASEBOARD_FAB2_LIB.BASEBOARD_FAB2(SCH_1):TP_PVDDQ_DEF_PH1_GL_0
 EU7A1    6  GL<0> IR354XX_SM-IR35411,IC,H73688-0A   I106 @BASEBOARD_FAB2_LIB.BASEBOARD_FAB2(SCH_1):PAGE219

TP_PVDDQ_DEF_PH1_GL_1 @BASEBOARD_FAB2_LIB.BASEBOARD_FAB2(SCH_1):TP_PVDDQ_DEF_PH1_GL_1
 EU7A1   41  GL<1> IR354XX_SM-IR35411,IC,H73688-0A   I106 @BASEBOARD_FAB2_LIB.BASEBOARD_FAB2(SCH_1):PAGE219

TP_PVDDQ_DEF_PH2_GL_0 @BASEBOARD_FAB2_LIB.BASEBOARD_FAB2(SCH_1):TP_PVDDQ_DEF_PH2_GL_0
 EU7A4    6  GL<0> IR354XX_SM-IR35411,IC,H73688-0A   I107 @BASEBOARD_FAB2_LIB.BASEBOARD_FAB2(SCH_1):PAGE219

TP_PVDDQ_DEF_PH2_GL_1 @BASEBOARD_FAB2_LIB.BASEBOARD_FAB2(SCH_1):TP_PVDDQ_DEF_PH2_GL_1
 EU7A4   41  GL<1> IR354XX_SM-IR35411,IC,H73688-0A   I107 @BASEBOARD_FAB2_LIB.BASEBOARD_FAB2(SCH_1):PAGE219

TP_PVDDQ_DEF_PH3_IMON @BASEBOARD_FAB2_LIB.BASEBOARD_FAB2(SCH_1):TP_PVDDQ_DEF_PH3_IMON
 EU7A5   26 AISEN3 PXM1310B_QFN-IC,H89186-001    I75 @BASEBOARD_FAB2_LIB.BASEBOARD_FAB2(SCH_1):PAGE218

TP_PVDDQ_DEF_PH3_IMON_REF @BASEBOARD_FAB2_LIB.BASEBOARD_FAB2(SCH_1):TP_PVDDQ_DEF_PH3_IMON_REF
 EU7A5   25 AIREF3 PXM1310B_QFN-IC,H89186-001    I75 @BASEBOARD_FAB2_LIB.BASEBOARD_FAB2(SCH_1):PAGE218

TP_PVDDQ_DEF_PINALRT_N @BASEBOARD_FAB2_LIB.BASEBOARD_FAB2(SCH_1):TP_PVDDQ_DEF_PINALRT_N
 EU7A5   12 PINALRT_N PXM1310B_QFN-IC,H89186-001    I75 @BASEBOARD_FAB2_LIB.BASEBOARD_FAB2(SCH_1):PAGE218

TP_PVDDQ_DEF_PWM3 @BASEBOARD_FAB2_LIB.BASEBOARD_FAB2(SCH_1):TP_PVDDQ_DEF_PWM3
 EU7A5    3  APWM3 PXM1310B_QFN-IC,H89186-001    I75 @BASEBOARD_FAB2_LIB.BASEBOARD_FAB2(SCH_1):PAGE218

TP_PVDDQ_DEF_RESET_N @BASEBOARD_FAB2_LIB.BASEBOARD_FAB2(SCH_1):TP_PVDDQ_DEF_RESET_N
 EU7A5    8 RESET_N PXM1310B_QFN-IC,H89186-001    I75 @BASEBOARD_FAB2_LIB.BASEBOARD_FAB2(SCH_1):PAGE218

TP_PVDDQ_GHJ_BPWM1 @BASEBOARD_FAB2_LIB.BASEBOARD_FAB2(SCH_1):TP_PVDDQ_GHJ_BPWM1
 EU1G2    1  BPWM1 PXM1310B_QFN-IC,H89186-001    I90 @BASEBOARD_FAB2_LIB.BASEBOARD_FAB2(SCH_1):PAGE223

TP_PVDDQ_GHJ_BREF1 @BASEBOARD_FAB2_LIB.BASEBOARD_FAB2(SCH_1):TP_PVDDQ_GHJ_BREF1
 EU1G2   31 BIREF1 PXM1310B_QFN-IC,H89186-001    I90 @BASEBOARD_FAB2_LIB.BASEBOARD_FAB2(SCH_1):PAGE223

TP_PVDDQ_GHJ_BTSEN @BASEBOARD_FAB2_LIB.BASEBOARD_FAB2(SCH_1):TP_PVDDQ_GHJ_BTSEN
 EU1G2   34  BTSEN PXM1310B_QFN-IC,H89186-001    I90 @BASEBOARD_FAB2_LIB.BASEBOARD_FAB2(SCH_1):PAGE223

TP_PVDDQ_GHJ_BVREF @BASEBOARD_FAB2_LIB.BASEBOARD_FAB2(SCH_1):TP_PVDDQ_GHJ_BVREF
 EU1G2   30  BVREF PXM1310B_QFN-IC,H89186-001    I90 @BASEBOARD_FAB2_LIB.BASEBOARD_FAB2(SCH_1):PAGE223

TP_PVDDQ_GHJ_BVSEN @BASEBOARD_FAB2_LIB.BASEBOARD_FAB2(SCH_1):TP_PVDDQ_GHJ_BVSEN
 EU1G2   29  BVSEN PXM1310B_QFN-IC,H89186-001    I90 @BASEBOARD_FAB2_LIB.BASEBOARD_FAB2(SCH_1):PAGE223

TP_PVDDQ_GHJ_MP1 @BASEBOARD_FAB2_LIB.BASEBOARD_FAB2(SCH_1):TP_PVDDQ_GHJ_MP1
 EU1G2   14    MP1 PXM1310B_QFN-IC,H89186-001    I90 @BASEBOARD_FAB2_LIB.BASEBOARD_FAB2(SCH_1):PAGE223

TP_PVDDQ_GHJ_MP2 @BASEBOARD_FAB2_LIB.BASEBOARD_FAB2(SCH_1):TP_PVDDQ_GHJ_MP2
 EU1G2   18    MP2 PXM1310B_QFN-IC,H89186-001    I90 @BASEBOARD_FAB2_LIB.BASEBOARD_FAB2(SCH_1):PAGE223

TP_PVDDQ_GHJ_PH1_GL_0 @BASEBOARD_FAB2_LIB.BASEBOARD_FAB2(SCH_1):TP_PVDDQ_GHJ_PH1_GL_0
 EU1G1    6  GL<0> IR354XX_SM-IR35411,IC,H73688-0A   I110 @BASEBOARD_FAB2_LIB.BASEBOARD_FAB2(SCH_1):PAGE224

TP_PVDDQ_GHJ_PH1_GL_1 @BASEBOARD_FAB2_LIB.BASEBOARD_FAB2(SCH_1):TP_PVDDQ_GHJ_PH1_GL_1
 EU1G1   41  GL<1> IR354XX_SM-IR35411,IC,H73688-0A   I110 @BASEBOARD_FAB2_LIB.BASEBOARD_FAB2(SCH_1):PAGE224

TP_PVDDQ_GHJ_PH2_GL_0 @BASEBOARD_FAB2_LIB.BASEBOARD_FAB2(SCH_1):TP_PVDDQ_GHJ_PH2_GL_0
 EU1F1    6  GL<0> IR354XX_SM-IR35411,IC,H73688-0A   I111 @BASEBOARD_FAB2_LIB.BASEBOARD_FAB2(SCH_1):PAGE224

TP_PVDDQ_GHJ_PH2_GL_1 @BASEBOARD_FAB2_LIB.BASEBOARD_FAB2(SCH_1):TP_PVDDQ_GHJ_PH2_GL_1
 EU1F1   41  GL<1> IR354XX_SM-IR35411,IC,H73688-0A   I111 @BASEBOARD_FAB2_LIB.BASEBOARD_FAB2(SCH_1):PAGE224

TP_PVDDQ_GHJ_PH3_IMON @BASEBOARD_FAB2_LIB.BASEBOARD_FAB2(SCH_1):TP_PVDDQ_GHJ_PH3_IMON
 EU1G2   26 AISEN3 PXM1310B_QFN-IC,H89186-001    I90 @BASEBOARD_FAB2_LIB.BASEBOARD_FAB2(SCH_1):PAGE223

TP_PVDDQ_GHJ_PH3_IMON_REF @BASEBOARD_FAB2_LIB.BASEBOARD_FAB2(SCH_1):TP_PVDDQ_GHJ_PH3_IMON_REF
 EU1G2   25 AIREF3 PXM1310B_QFN-IC,H89186-001    I90 @BASEBOARD_FAB2_LIB.BASEBOARD_FAB2(SCH_1):PAGE223

TP_PVDDQ_GHJ_PWM3 @BASEBOARD_FAB2_LIB.BASEBOARD_FAB2(SCH_1):TP_PVDDQ_GHJ_PWM3
 EU1G2    3  APWM3 PXM1310B_QFN-IC,H89186-001    I90 @BASEBOARD_FAB2_LIB.BASEBOARD_FAB2(SCH_1):PAGE223

TP_PVDDQ_GHJ_RESET_N @BASEBOARD_FAB2_LIB.BASEBOARD_FAB2(SCH_1):TP_PVDDQ_GHJ_RESET_N
 EU1G2    8 RESET_N PXM1310B_QFN-IC,H89186-001    I90 @BASEBOARD_FAB2_LIB.BASEBOARD_FAB2(SCH_1):PAGE223

TP_PVDDQ_KLM_BPWM1 @BASEBOARD_FAB2_LIB.BASEBOARD_FAB2(SCH_1):TP_PVDDQ_KLM_BPWM1
 EU1B1    1  BPWM1 PXM1310B_QFN-IC,H89186-001    I90 @BASEBOARD_FAB2_LIB.BASEBOARD_FAB2(SCH_1):PAGE226

TP_PVDDQ_KLM_BREF1 @BASEBOARD_FAB2_LIB.BASEBOARD_FAB2(SCH_1):TP_PVDDQ_KLM_BREF1
 EU1B1   31 BIREF1 PXM1310B_QFN-IC,H89186-001    I90 @BASEBOARD_FAB2_LIB.BASEBOARD_FAB2(SCH_1):PAGE226

TP_PVDDQ_KLM_BTSEN @BASEBOARD_FAB2_LIB.BASEBOARD_FAB2(SCH_1):TP_PVDDQ_KLM_BTSEN
 EU1B1   34  BTSEN PXM1310B_QFN-IC,H89186-001    I90 @BASEBOARD_FAB2_LIB.BASEBOARD_FAB2(SCH_1):PAGE226

TP_PVDDQ_KLM_BVREF @BASEBOARD_FAB2_LIB.BASEBOARD_FAB2(SCH_1):TP_PVDDQ_KLM_BVREF
 EU1B1   30  BVREF PXM1310B_QFN-IC,H89186-001    I90 @BASEBOARD_FAB2_LIB.BASEBOARD_FAB2(SCH_1):PAGE226

TP_PVDDQ_KLM_BVSEN @BASEBOARD_FAB2_LIB.BASEBOARD_FAB2(SCH_1):TP_PVDDQ_KLM_BVSEN
 EU1B1   29  BVSEN PXM1310B_QFN-IC,H89186-001    I90 @BASEBOARD_FAB2_LIB.BASEBOARD_FAB2(SCH_1):PAGE226

TP_PVDDQ_KLM_PH1_GL_0 @BASEBOARD_FAB2_LIB.BASEBOARD_FAB2(SCH_1):TP_PVDDQ_KLM_PH1_GL_0
 EU1A2    6  GL<0> IR354XX_SM-IR35411,IC,H73688-0A   I101 @BASEBOARD_FAB2_LIB.BASEBOARD_FAB2(SCH_1):PAGE227

TP_PVDDQ_KLM_PH1_GL_1 @BASEBOARD_FAB2_LIB.BASEBOARD_FAB2(SCH_1):TP_PVDDQ_KLM_PH1_GL_1
 EU1A2   41  GL<1> IR354XX_SM-IR35411,IC,H73688-0A   I101 @BASEBOARD_FAB2_LIB.BASEBOARD_FAB2(SCH_1):PAGE227

TP_PVDDQ_KLM_PH2_GL_0 @BASEBOARD_FAB2_LIB.BASEBOARD_FAB2(SCH_1):TP_PVDDQ_KLM_PH2_GL_0
 EU1A1    6  GL<0> IR354XX_SM-IR35411,IC,H73688-0A   I102 @BASEBOARD_FAB2_LIB.BASEBOARD_FAB2(SCH_1):PAGE227

TP_PVDDQ_KLM_PH2_GL_1 @BASEBOARD_FAB2_LIB.BASEBOARD_FAB2(SCH_1):TP_PVDDQ_KLM_PH2_GL_1
 EU1A1   41  GL<1> IR354XX_SM-IR35411,IC,H73688-0A   I102 @BASEBOARD_FAB2_LIB.BASEBOARD_FAB2(SCH_1):PAGE227

TP_PVDDQ_KLM_PH3_IMON @BASEBOARD_FAB2_LIB.BASEBOARD_FAB2(SCH_1):TP_PVDDQ_KLM_PH3_IMON
 EU1B1   26 AISEN3 PXM1310B_QFN-IC,H89186-001    I90 @BASEBOARD_FAB2_LIB.BASEBOARD_FAB2(SCH_1):PAGE226

TP_PVDDQ_KLM_PH3_IMON_REF @BASEBOARD_FAB2_LIB.BASEBOARD_FAB2(SCH_1):TP_PVDDQ_KLM_PH3_IMON_REF
 EU1B1   25 AIREF3 PXM1310B_QFN-IC,H89186-001    I90 @BASEBOARD_FAB2_LIB.BASEBOARD_FAB2(SCH_1):PAGE226

TP_PVDDQ_KLM_RESET_N @BASEBOARD_FAB2_LIB.BASEBOARD_FAB2(SCH_1):TP_PVDDQ_KLM_RESET_N
 EU1B1    8 RESET_N PXM1310B_QFN-IC,H89186-001    I90 @BASEBOARD_FAB2_LIB.BASEBOARD_FAB2(SCH_1):PAGE226

TP_PVNN_PCH_GL_0 @BASEBOARD_FAB2_LIB.BASEBOARD_FAB2(SCH_1):TP_PVNN_PCH_GL_0
 EU7A3    6  GL<0> IR354XX_SM-IR35412,IC,H73684-0A   I116 @BASEBOARD_FAB2_LIB.BASEBOARD_FAB2(SCH_1):PAGE236

TP_PVNN_PCH_GL_1 @BASEBOARD_FAB2_LIB.BASEBOARD_FAB2(SCH_1):TP_PVNN_PCH_GL_1
 EU7A3   41  GL<1> IR354XX_SM-IR35412,IC,H73684-0A   I116 @BASEBOARD_FAB2_LIB.BASEBOARD_FAB2(SCH_1):PAGE236

TP_PVNN_PCH_MP2 @BASEBOARD_FAB2_LIB.BASEBOARD_FAB2(SCH_1):TP_PVNN_PCH_MP2
 EU8A1   18    MP2 PXE1110B_QFN-IC,H89187-001   I229 @BASEBOARD_FAB2_LIB.BASEBOARD_FAB2(SCH_1):PAGE235

TP_PVNN_PCH_MP3 @BASEBOARD_FAB2_LIB.BASEBOARD_FAB2(SCH_1):TP_PVNN_PCH_MP3
 EU8A1   31    MP3 PXE1110B_QFN-IC,H89187-001   I229 @BASEBOARD_FAB2_LIB.BASEBOARD_FAB2(SCH_1):PAGE235

TP_PVNN_PCH_PINALRT_N @BASEBOARD_FAB2_LIB.BASEBOARD_FAB2(SCH_1):TP_PVNN_PCH_PINALRT_N
 EU8A1   12 PINALRT_N PXE1110B_QFN-IC,H89187-001   I229 @BASEBOARD_FAB2_LIB.BASEBOARD_FAB2(SCH_1):PAGE235

TP_PVNN_PCH_RESET_N @BASEBOARD_FAB2_LIB.BASEBOARD_FAB2(SCH_1):TP_PVNN_PCH_RESET_N
 EU8A1    8 RESET_N PXE1110B_QFN-IC,H89187-001   I229 @BASEBOARD_FAB2_LIB.BASEBOARD_FAB2(SCH_1):PAGE235

TP_PVNN_PCH_SVID_ALERT @BASEBOARD_FAB2_LIB.BASEBOARD_FAB2(SCH_1):TP_PVNN_PCH_SVID_ALERT
 EU8A1   17 VALRT_N PXE1110B_QFN-IC,H89187-001   I229 @BASEBOARD_FAB2_LIB.BASEBOARD_FAB2(SCH_1):PAGE235

TP_PVNN_PCH_VCLK @BASEBOARD_FAB2_LIB.BASEBOARD_FAB2(SCH_1):TP_PVNN_PCH_VCLK
 EU8A1   15   VCLK PXE1110B_QFN-IC,H89187-001   I229 @BASEBOARD_FAB2_LIB.BASEBOARD_FAB2(SCH_1):PAGE235

TP_PVNN_PCH_VDIO @BASEBOARD_FAB2_LIB.BASEBOARD_FAB2(SCH_1):TP_PVNN_PCH_VDIO
 EU8A1   16   VDIO PXE1110B_QFN-IC,H89187-001   I229 @BASEBOARD_FAB2_LIB.BASEBOARD_FAB2(SCH_1):PAGE235

TP_PVSA_CPU0_GL_0 @BASEBOARD_FAB2_LIB.BASEBOARD_FAB2(SCH_1):TP_PVSA_CPU0_GL_0
 EU4C1    6  GL<0> IR354XX_SM-IR35412,IC,H73684-0A    I46 @BASEBOARD_FAB2_LIB.BASEBOARD_FAB2(SCH_1):PAGE205

TP_PVSA_CPU0_GL_1 @BASEBOARD_FAB2_LIB.BASEBOARD_FAB2(SCH_1):TP_PVSA_CPU0_GL_1
 EU4C1   41  GL<1> IR354XX_SM-IR35412,IC,H73684-0A    I46 @BASEBOARD_FAB2_LIB.BASEBOARD_FAB2(SCH_1):PAGE205

TP_PVSA_CPU1_GL_0 @BASEBOARD_FAB2_LIB.BASEBOARD_FAB2(SCH_1):TP_PVSA_CPU1_GL_0
 EU1C1    6  GL<0> IR354XX_SM-IR35412,IC,H73684-0A    I51 @BASEBOARD_FAB2_LIB.BASEBOARD_FAB2(SCH_1):PAGE210

TP_PVSA_CPU1_GL_1 @BASEBOARD_FAB2_LIB.BASEBOARD_FAB2(SCH_1):TP_PVSA_CPU1_GL_1
 EU1C1   41  GL<1> IR354XX_SM-IR35412,IC,H73684-0A    I51 @BASEBOARD_FAB2_LIB.BASEBOARD_FAB2(SCH_1):PAGE210

TP_RGMII1TXD2_GPIOT4 @BASEBOARD_FAB2_LIB.BASEBOARD_FAB2(SCH_1):TP_RGMII1TXD2_GPIOT4
R25W114    2      B RES_0402-4.75K,1%,1/16W,EMPTY,A    I46 @BASEBOARD_FAB2_LIB.BASEBOARD_FAB2(SCH_1):PAGE151
 U25W4   E7 RGMII1TXD2_GPIOT4 AST2520A1-GP-GP_ASIC2-GB1-AST2A   I106 @BASEBOARD_FAB2_LIB.BASEBOARD_FAB2(SCH_1):PAGE147

TP_RGMII1TXD3_GPIOT5 @BASEBOARD_FAB2_LIB.BASEBOARD_FAB2(SCH_1):TP_RGMII1TXD3_GPIOT5
R25W115    2      B RES_0402-4.75K,1%,1/16W,CHIP,GA    I47 @BASEBOARD_FAB2_LIB.BASEBOARD_FAB2(SCH_1):PAGE151
 U25W4   D7 RGMII1TXD3_GPIOT5 AST2520A1-GP-GP_ASIC2-GB1-AST2A   I106 @BASEBOARD_FAB2_LIB.BASEBOARD_FAB2(SCH_1):PAGE147

TP_RGMII2TXD2_GPIOT4 @BASEBOARD_FAB2_LIB.BASEBOARD_FAB2(SCH_1):TP_RGMII2TXD2_GPIOT4
R25W110    2      B RES_0402-4.75K,1%,1/16W,CHIP,GA    I36 @BASEBOARD_FAB2_LIB.BASEBOARD_FAB2(SCH_1):PAGE151
 U25W4   D5 RGMII2TXD2_GPIOU2 AST2520A1-GP-GP_ASIC2-GB1-AST2A   I106 @BASEBOARD_FAB2_LIB.BASEBOARD_FAB2(SCH_1):PAGE147

TP_RGMII2TXD3_GPIOT5 @BASEBOARD_FAB2_LIB.BASEBOARD_FAB2(SCH_1):TP_RGMII2TXD3_GPIOT5
R25W109    2      B RES_0402-4.75K,1%,1/16W,EMPTY,A    I35 @BASEBOARD_FAB2_LIB.BASEBOARD_FAB2(SCH_1):PAGE151
 U25W4   D4 RGMII2TXD3_GPIOU3 AST2520A1-GP-GP_ASIC2-GB1-AST2A   I106 @BASEBOARD_FAB2_LIB.BASEBOARD_FAB2(SCH_1):PAGE147

TP_RST_CPU1_CD_HFI0_N @BASEBOARD_FAB2_LIB.BASEBOARD_FAB2(SCH_1):TP_RST_CPU1_CD_HFI0_N
  U2D1 BN24 CD_HFI0_RESET_N SKX_EXT_B_BGA1-IC,TBD    I23 @BASEBOARD_FAB2_LIB.BASEBOARD_FAB2(SCH_1):PAGE63

TP_RST_RTCRST_N @BASEBOARD_FAB2_LIB.BASEBOARD_FAB2(SCH_1):TP_RST_RTCRST_N
  J9G1    2    IO2 CONN12_C73564003_PIP-CONN,C735A   I128 @BASEBOARD_FAB2_LIB.BASEBOARD_FAB2(SCH_1):PAGE137

TP_RSVD<0> @BASEBOARD_FAB2_LIB.BASEBOARD_FAB2(SCH_1):TP_RSVD(0)
  J8E4   36   IO36 SCONN64_H87568002_A_SMT-CONN,HA    I27 @BASEBOARD_FAB2_LIB.BASEBOARD_FAB2(SCH_1):PAGE188

TP_RSVD_B1 @BASEBOARD_FAB2_LIB.BASEBOARD_FAB2(SCH_1):TP_RSVD_B1
  J8E3    6    IO6 SCONN80_E67482007_SM-CONN,E674A   I119 @BASEBOARD_FAB2_LIB.BASEBOARD_FAB2(SCH_1):PAGE187

TP_SGPIO_SATA_CLOCK1_R @BASEBOARD_FAB2_LIB.BASEBOARD_FAB2(SCH_1):TP_SGPIO_SATA_CLOCK1_R
  J8A1  2A2 SIDEBANDB_0 CONN72_G97614002_A_CP-CONN,G97A   I163 @BASEBOARD_FAB2_LIB.BASEBOARD_FAB2(SCH_1):PAGE173

TP_SGPIO_SATA_DATA1_R @BASEBOARD_FAB2_LIB.BASEBOARD_FAB2(SCH_1):TP_SGPIO_SATA_DATA1_R
  J8A1  2C1 SIDEBANDB_4 CONN72_G97614002_A_CP-CONN,G97A   I163 @BASEBOARD_FAB2_LIB.BASEBOARD_FAB2(SCH_1):PAGE173

TP_SGPIO_SATA_LOAD1_R @BASEBOARD_FAB2_LIB.BASEBOARD_FAB2(SCH_1):TP_SGPIO_SATA_LOAD1_R
  J8A1  2B2 SIDEBANDB_1 CONN72_G97614002_A_CP-CONN,G97A   I163 @BASEBOARD_FAB2_LIB.BASEBOARD_FAB2(SCH_1):PAGE173

TP_SHARED_KR_MDC_0 @BASEBOARD_FAB2_LIB.BASEBOARD_FAB2(SCH_1):TP_SHARED_KR_MDC_0
  J8E4   49   IO49 SCONN64_H87568002_A_SMT-CONN,HA    I27 @BASEBOARD_FAB2_LIB.BASEBOARD_FAB2(SCH_1):PAGE188

TP_SHARED_KR_MDIO_0 @BASEBOARD_FAB2_LIB.BASEBOARD_FAB2(SCH_1):TP_SHARED_KR_MDIO_0
  J8E4   50   IO50 SCONN64_H87568002_A_SMT-CONN,HA    I27 @BASEBOARD_FAB2_LIB.BASEBOARD_FAB2(SCH_1):PAGE188

TP_SLG55021_P12V_FAN_8 @BASEBOARD_FAB2_LIB.BASEBOARD_FAB2(SCH_1):TP_SLG55021_P12V_FAN_8
 EU9M1    8     PG SLG55021_SM-IC,G56246-001    I69 @BASEBOARD_FAB2_LIB.BASEBOARD_FAB2(SCH_1):PAGE198

TP_SLG55021_P12V_MAIN_8 @BASEBOARD_FAB2_LIB.BASEBOARD_FAB2(SCH_1):TP_SLG55021_P12V_MAIN_8
 EU7E1    8     PG SLG55021_SM-IC,G56246-001    I19 @BASEBOARD_FAB2_LIB.BASEBOARD_FAB2(SCH_1):PAGE198

TP_SLG55021_P3V3_8 @BASEBOARD_FAB2_LIB.BASEBOARD_FAB2(SCH_1):TP_SLG55021_P3V3_8
 EU2T1    8     PG SLG55021_SM-IC,G56246-001     I1 @BASEBOARD_FAB2_LIB.BASEBOARD_FAB2(SCH_1):PAGE198

TP_SLG55021_P5V_8 @BASEBOARD_FAB2_LIB.BASEBOARD_FAB2(SCH_1):TP_SLG55021_P5V_8
 EU8B1    8     PG SLG55021_SM-IC,G56246-001    I13 @BASEBOARD_FAB2_LIB.BASEBOARD_FAB2(SCH_1):PAGE198

TP_SLP_LAN_N @BASEBOARD_FAB2_LIB.BASEBOARD_FAB2(SCH_1):TP_SLP_LAN_N
  U7C1  M15 SLP_GBE_N LBG_CORE_QAT_EXT_D_BGA1-IC,H91A    I73 @BASEBOARD_FAB2_LIB.BASEBOARD_FAB2(SCH_1):PAGE118

TP_SMB_BUS11_SCL @BASEBOARD_FAB2_LIB.BASEBOARD_FAB2(SCH_1):TP_SMB_BUS11_SCL
 U25W4  B12 GPIOC2_SD1DAT0_SCL11 AST2520A1-GP-GP_ASIC2-GB1-AST2A   I117 @BASEBOARD_FAB2_LIB.BASEBOARD_FAB2(SCH_1):PAGE145

TP_SMB_BUS11_SDA @BASEBOARD_FAB2_LIB.BASEBOARD_FAB2(SCH_1):TP_SMB_BUS11_SDA
 U25W4   D9 GPIOC3_SD1DAT1_SDA11 AST2520A1-GP-GP_ASIC2-GB1-AST2A   I117 @BASEBOARD_FAB2_LIB.BASEBOARD_FAB2(SCH_1):PAGE145

TP_SMB_CPU1_CD_HFI0_I2CCLK @BASEBOARD_FAB2_LIB.BASEBOARD_FAB2(SCH_1):TP_SMB_CPU1_CD_HFI0_I2CCLK
  U2D1 BN22 CD_HFI0_I2CCLK SKX_EXT_B_BGA1-IC,TBD    I23 @BASEBOARD_FAB2_LIB.BASEBOARD_FAB2(SCH_1):PAGE63

TP_SMB_CPU1_CD_HFI0_I2CDAT @BASEBOARD_FAB2_LIB.BASEBOARD_FAB2(SCH_1):TP_SMB_CPU1_CD_HFI0_I2CDAT
  U2D1 BP23 CD_HFI0_I2CDAT SKX_EXT_B_BGA1-IC,TBD    I23 @BASEBOARD_FAB2_LIB.BASEBOARD_FAB2(SCH_1):PAGE63

TP_SMB_DDR_ABC_EN @BASEBOARD_FAB2_LIB.BASEBOARD_FAB2(SCH_1):TP_SMB_DDR_ABC_EN
  U6F1    5     EN PCA9617_SSOP-IC,G81764-001-GNDA    I15 @BASEBOARD_FAB2_LIB.BASEBOARD_FAB2(SCH_1):PAGE99

TP_SMB_DDR_DEF_EN @BASEBOARD_FAB2_LIB.BASEBOARD_FAB2(SCH_1):TP_SMB_DDR_DEF_EN
  U7E1    5     EN PCA9617_SSOP-IC,G81764-001-GNDA    I61 @BASEBOARD_FAB2_LIB.BASEBOARD_FAB2(SCH_1):PAGE99

TP_SMB_DDR_GHJ_EN @BASEBOARD_FAB2_LIB.BASEBOARD_FAB2(SCH_1):TP_SMB_DDR_GHJ_EN
  U4G1    5     EN PCA9617_SSOP-IC,G81764-001-GNDA    I63 @BASEBOARD_FAB2_LIB.BASEBOARD_FAB2(SCH_1):PAGE99

TP_SMB_DDR_KLM_EN @BASEBOARD_FAB2_LIB.BASEBOARD_FAB2(SCH_1):TP_SMB_DDR_KLM_EN
  U3B1    5     EN PCA9617_SSOP-IC,G81764-001-GNDA    I75 @BASEBOARD_FAB2_LIB.BASEBOARD_FAB2(SCH_1):PAGE99

TP_SMB_PEHPCPU1_EN @BASEBOARD_FAB2_LIB.BASEBOARD_FAB2(SCH_1):TP_SMB_PEHPCPU1_EN
  U1B2    5     EN PCA9517_SM-IC,G77073-001-GND=GA     I1 @BASEBOARD_FAB2_LIB.BASEBOARD_FAB2(SCH_1):PAGE163

TP_SMB_STORAGE_BP_3V3AUX_SCL @BASEBOARD_FAB2_LIB.BASEBOARD_FAB2(SCH_1):TP_SMB_STORAGE_BP_3V3AUX_SCL
 U25W4  M20 GPIOY6_SCL2 AST2520A1-GP-GP_ASIC2-GB1-AST2A    I95 @BASEBOARD_FAB2_LIB.BASEBOARD_FAB2(SCH_1):PAGE144

TP_SMB_STORAGE_BP_3V3AUX_SDA @BASEBOARD_FAB2_LIB.BASEBOARD_FAB2(SCH_1):TP_SMB_STORAGE_BP_3V3AUX_SDA
 U25W4  P20 GPIOY7_SDA2 AST2520A1-GP-GP_ASIC2-GB1-AST2A    I95 @BASEBOARD_FAB2_LIB.BASEBOARD_FAB2(SCH_1):PAGE144

TP_SPI_0_0 @BASEBOARD_FAB2_LIB.BASEBOARD_FAB2(SCH_1):TP_SPI_0_0
  U7F1   14  NC<0> W25Q256_XSOI-IC,H25002-001   I146 @BASEBOARD_FAB2_LIB.BASEBOARD_FAB2(SCH_1):PAGE153

TP_SPI_0_1 @BASEBOARD_FAB2_LIB.BASEBOARD_FAB2(SCH_1):TP_SPI_0_1
  U7F1   13  NC<1> W25Q256_XSOI-IC,H25002-001   I146 @BASEBOARD_FAB2_LIB.BASEBOARD_FAB2(SCH_1):PAGE153

TP_SPI_0_2 @BASEBOARD_FAB2_LIB.BASEBOARD_FAB2(SCH_1):TP_SPI_0_2
  U7F1   12  NC<2> W25Q256_XSOI-IC,H25002-001   I146 @BASEBOARD_FAB2_LIB.BASEBOARD_FAB2(SCH_1):PAGE153

TP_SPI_0_3 @BASEBOARD_FAB2_LIB.BASEBOARD_FAB2(SCH_1):TP_SPI_0_3
  U7F1   11  NC<3> W25Q256_XSOI-IC,H25002-001   I146 @BASEBOARD_FAB2_LIB.BASEBOARD_FAB2(SCH_1):PAGE153

TP_SPI_0_4 @BASEBOARD_FAB2_LIB.BASEBOARD_FAB2(SCH_1):TP_SPI_0_4
  U7F1    6  NC<4> W25Q256_XSOI-IC,H25002-001   I146 @BASEBOARD_FAB2_LIB.BASEBOARD_FAB2(SCH_1):PAGE153

TP_SPI_0_5 @BASEBOARD_FAB2_LIB.BASEBOARD_FAB2(SCH_1):TP_SPI_0_5
  U7F1    5  NC<5> W25Q256_XSOI-IC,H25002-001   I146 @BASEBOARD_FAB2_LIB.BASEBOARD_FAB2(SCH_1):PAGE153

TP_SPI_0_6 @BASEBOARD_FAB2_LIB.BASEBOARD_FAB2(SCH_1):TP_SPI_0_6
  U7F1    4  NC<6> W25Q256_XSOI-IC,H25002-001   I146 @BASEBOARD_FAB2_LIB.BASEBOARD_FAB2(SCH_1):PAGE153

TP_SPI_1_0 @BASEBOARD_FAB2_LIB.BASEBOARD_FAB2(SCH_1):TP_SPI_1_0
  U3T1   14  NC<0> W25Q256_XSOI-IC,H25002-001   I165 @BASEBOARD_FAB2_LIB.BASEBOARD_FAB2(SCH_1):PAGE153

TP_SPI_1_1 @BASEBOARD_FAB2_LIB.BASEBOARD_FAB2(SCH_1):TP_SPI_1_1
  U3T1   13  NC<1> W25Q256_XSOI-IC,H25002-001   I165 @BASEBOARD_FAB2_LIB.BASEBOARD_FAB2(SCH_1):PAGE153

TP_SPI_1_2 @BASEBOARD_FAB2_LIB.BASEBOARD_FAB2(SCH_1):TP_SPI_1_2
  U3T1   12  NC<2> W25Q256_XSOI-IC,H25002-001   I165 @BASEBOARD_FAB2_LIB.BASEBOARD_FAB2(SCH_1):PAGE153

TP_SPI_1_3 @BASEBOARD_FAB2_LIB.BASEBOARD_FAB2(SCH_1):TP_SPI_1_3
  U3T1   11  NC<3> W25Q256_XSOI-IC,H25002-001   I165 @BASEBOARD_FAB2_LIB.BASEBOARD_FAB2(SCH_1):PAGE153

TP_SPI_1_4 @BASEBOARD_FAB2_LIB.BASEBOARD_FAB2(SCH_1):TP_SPI_1_4
  U3T1    6  NC<4> W25Q256_XSOI-IC,H25002-001   I165 @BASEBOARD_FAB2_LIB.BASEBOARD_FAB2(SCH_1):PAGE153

TP_SPI_1_5 @BASEBOARD_FAB2_LIB.BASEBOARD_FAB2(SCH_1):TP_SPI_1_5
  U3T1    5  NC<5> W25Q256_XSOI-IC,H25002-001   I165 @BASEBOARD_FAB2_LIB.BASEBOARD_FAB2(SCH_1):PAGE153

TP_SPI_1_6 @BASEBOARD_FAB2_LIB.BASEBOARD_FAB2(SCH_1):TP_SPI_1_6
  U3T1    4  NC<6> W25Q256_XSOI-IC,H25002-001   I165 @BASEBOARD_FAB2_LIB.BASEBOARD_FAB2(SCH_1):PAGE153

TP_SPI_2_0 @BASEBOARD_FAB2_LIB.BASEBOARD_FAB2(SCH_1):TP_SPI_2_0
  U8F2    4  NC<0> W25Q128_SKT16-IC,H12709-001    I32 @BASEBOARD_FAB2_LIB.BASEBOARD_FAB2(SCH_1):PAGE162

TP_SPI_2_1 @BASEBOARD_FAB2_LIB.BASEBOARD_FAB2(SCH_1):TP_SPI_2_1
  U8F2    5  NC<1> W25Q128_SKT16-IC,H12709-001    I32 @BASEBOARD_FAB2_LIB.BASEBOARD_FAB2(SCH_1):PAGE162

TP_SPI_2_2 @BASEBOARD_FAB2_LIB.BASEBOARD_FAB2(SCH_1):TP_SPI_2_2
  U8F2    6  NC<2> W25Q128_SKT16-IC,H12709-001    I32 @BASEBOARD_FAB2_LIB.BASEBOARD_FAB2(SCH_1):PAGE162

TP_SPI_2_3 @BASEBOARD_FAB2_LIB.BASEBOARD_FAB2(SCH_1):TP_SPI_2_3
  U8F2   11  NC<3> W25Q128_SKT16-IC,H12709-001    I32 @BASEBOARD_FAB2_LIB.BASEBOARD_FAB2(SCH_1):PAGE162

TP_SPI_2_4 @BASEBOARD_FAB2_LIB.BASEBOARD_FAB2(SCH_1):TP_SPI_2_4
  U8F2   12  NC<4> W25Q128_SKT16-IC,H12709-001    I32 @BASEBOARD_FAB2_LIB.BASEBOARD_FAB2(SCH_1):PAGE162

TP_SPI_2_5 @BASEBOARD_FAB2_LIB.BASEBOARD_FAB2(SCH_1):TP_SPI_2_5
  U8F2   13  NC<5> W25Q128_SKT16-IC,H12709-001    I32 @BASEBOARD_FAB2_LIB.BASEBOARD_FAB2(SCH_1):PAGE162

TP_SPI_2_6 @BASEBOARD_FAB2_LIB.BASEBOARD_FAB2(SCH_1):TP_SPI_2_6
  U8F2   14  NC<6> W25Q128_SKT16-IC,H12709-001    I32 @BASEBOARD_FAB2_LIB.BASEBOARD_FAB2(SCH_1):PAGE162

TP_SPI_PCH_CS1_R1_N @BASEBOARD_FAB2_LIB.BASEBOARD_FAB2(SCH_1):TP_SPI_PCH_CS1_R1_N
  U7C1   G7 SPI0_FLASH_CS1_N LBG_CORE_QAT_EXT_D_BGA1-IC,H91A    I34 @BASEBOARD_FAB2_LIB.BASEBOARD_FAB2(SCH_1):PAGE121

TP_SPI_SWITCH1_10 @BASEBOARD_FAB2_LIB.BASEBOARD_FAB2(SCH_1):TP_SPI_SWITCH1_10
  U2T1   10    IC1 PI3B3257A_TSSOPLF-IC,E16801-001    I75 @BASEBOARD_FAB2_LIB.BASEBOARD_FAB2(SCH_1):PAGE154

TP_SPI_SWITCH1_11 @BASEBOARD_FAB2_LIB.BASEBOARD_FAB2(SCH_1):TP_SPI_SWITCH1_11
  U2T1   11    IC0 PI3B3257A_TSSOPLF-IC,E16801-001    I75 @BASEBOARD_FAB2_LIB.BASEBOARD_FAB2(SCH_1):PAGE154

TP_SPI_SWITCH1_12 @BASEBOARD_FAB2_LIB.BASEBOARD_FAB2(SCH_1):TP_SPI_SWITCH1_12
  U2T1   12     YD PI3B3257A_TSSOPLF-IC,E16801-001    I75 @BASEBOARD_FAB2_LIB.BASEBOARD_FAB2(SCH_1):PAGE154

TP_SPI_SWITCH1_13 @BASEBOARD_FAB2_LIB.BASEBOARD_FAB2(SCH_1):TP_SPI_SWITCH1_13
  U2T1   13    ID1 PI3B3257A_TSSOPLF-IC,E16801-001    I75 @BASEBOARD_FAB2_LIB.BASEBOARD_FAB2(SCH_1):PAGE154

TP_SPI_SWITCH1_14 @BASEBOARD_FAB2_LIB.BASEBOARD_FAB2(SCH_1):TP_SPI_SWITCH1_14
  U2T1   14    ID0 PI3B3257A_TSSOPLF-IC,E16801-001    I75 @BASEBOARD_FAB2_LIB.BASEBOARD_FAB2(SCH_1):PAGE154

TP_SPI_SWITCH1_3 @BASEBOARD_FAB2_LIB.BASEBOARD_FAB2(SCH_1):TP_SPI_SWITCH1_3
  U2T1    3    IA1 PI3B3257A_TSSOPLF-IC,E16801-001    I75 @BASEBOARD_FAB2_LIB.BASEBOARD_FAB2(SCH_1):PAGE154

TP_SPI_SWITCH1_6 @BASEBOARD_FAB2_LIB.BASEBOARD_FAB2(SCH_1):TP_SPI_SWITCH1_6
  U2T1    6    IB1 PI3B3257A_TSSOPLF-IC,E16801-001    I75 @BASEBOARD_FAB2_LIB.BASEBOARD_FAB2(SCH_1):PAGE154

TP_SPI_SWITCH1_9 @BASEBOARD_FAB2_LIB.BASEBOARD_FAB2(SCH_1):TP_SPI_SWITCH1_9
  U2T1    9     YC PI3B3257A_TSSOPLF-IC,E16801-001    I75 @BASEBOARD_FAB2_LIB.BASEBOARD_FAB2(SCH_1):PAGE154

TP_SPRV_SDP0 @BASEBOARD_FAB2_LIB.BASEBOARD_FAB2(SCH_1):TP_SPRV_SDP0
 EU9E1   63   SDP0 SPRINGVILLE_SM1-IC,G47144-004    I72 @BASEBOARD_FAB2_LIB.BASEBOARD_FAB2(SCH_1):PAGE139

TP_SPRV_SDP1 @BASEBOARD_FAB2_LIB.BASEBOARD_FAB2(SCH_1):TP_SPRV_SDP1
 EU9E1   61 SDP1_PCIE_DIS_SDP1 SPRINGVILLE_SM1-IC,G47144-004    I72 @BASEBOARD_FAB2_LIB.BASEBOARD_FAB2(SCH_1):PAGE139

TP_SPRV_SDP2 @BASEBOARD_FAB2_LIB.BASEBOARD_FAB2(SCH_1):TP_SPRV_SDP2
 EU9E1   62   SDP2 SPRINGVILLE_SM1-IC,G47144-004    I72 @BASEBOARD_FAB2_LIB.BASEBOARD_FAB2(SCH_1):PAGE139

TP_SPRV_SDP3 @BASEBOARD_FAB2_LIB.BASEBOARD_FAB2(SCH_1):TP_SPRV_SDP3
 EU9E1   60   SDP3 SPRINGVILLE_SM1-IC,G47144-004    I72 @BASEBOARD_FAB2_LIB.BASEBOARD_FAB2(SCH_1):PAGE139

TP_TPM_SPI_0 @BASEBOARD_FAB2_LIB.BASEBOARD_FAB2(SCH_1):TP_TPM_SPI_0
 UN8F2   14  NC<0> W25Q256_XSOI-IC,H25002-001    I17 @BASEBOARD_FAB2_LIB.BASEBOARD_FAB2(SCH_1):PAGE246

TP_TPM_SPI_1 @BASEBOARD_FAB2_LIB.BASEBOARD_FAB2(SCH_1):TP_TPM_SPI_1
 UN8F2   13  NC<1> W25Q256_XSOI-IC,H25002-001    I17 @BASEBOARD_FAB2_LIB.BASEBOARD_FAB2(SCH_1):PAGE246

TP_TPM_SPI_2 @BASEBOARD_FAB2_LIB.BASEBOARD_FAB2(SCH_1):TP_TPM_SPI_2
 UN8F2   12  NC<2> W25Q256_XSOI-IC,H25002-001    I17 @BASEBOARD_FAB2_LIB.BASEBOARD_FAB2(SCH_1):PAGE246

TP_TPM_SPI_3 @BASEBOARD_FAB2_LIB.BASEBOARD_FAB2(SCH_1):TP_TPM_SPI_3
 UN8F2   11  NC<3> W25Q256_XSOI-IC,H25002-001    I17 @BASEBOARD_FAB2_LIB.BASEBOARD_FAB2(SCH_1):PAGE246

TP_TPM_SPI_4 @BASEBOARD_FAB2_LIB.BASEBOARD_FAB2(SCH_1):TP_TPM_SPI_4
 UN8F2    6  NC<4> W25Q256_XSOI-IC,H25002-001    I17 @BASEBOARD_FAB2_LIB.BASEBOARD_FAB2(SCH_1):PAGE246

TP_TPM_SPI_5 @BASEBOARD_FAB2_LIB.BASEBOARD_FAB2(SCH_1):TP_TPM_SPI_5
 UN8F2    5  NC<5> W25Q256_XSOI-IC,H25002-001    I17 @BASEBOARD_FAB2_LIB.BASEBOARD_FAB2(SCH_1):PAGE246

TP_TPM_SPI_6 @BASEBOARD_FAB2_LIB.BASEBOARD_FAB2(SCH_1):TP_TPM_SPI_6
 UN8F2    4  NC<6> W25Q256_XSOI-IC,H25002-001    I17 @BASEBOARD_FAB2_LIB.BASEBOARD_FAB2(SCH_1):PAGE246

TP_USB2_P03_DN @BASEBOARD_FAB2_LIB.BASEBOARD_FAB2(SCH_1):TP_USB2_P03_DN
  U7C1 CA59 USB2N_3 LBG_CORE_QAT_EXT_D_BGA1-IC,H91A    I74 @BASEBOARD_FAB2_LIB.BASEBOARD_FAB2(SCH_1):PAGE115

TP_USB2_P03_DP @BASEBOARD_FAB2_LIB.BASEBOARD_FAB2(SCH_1):TP_USB2_P03_DP
  U7C1 BW59 USB2P_3 LBG_CORE_QAT_EXT_D_BGA1-IC,H91A    I74 @BASEBOARD_FAB2_LIB.BASEBOARD_FAB2(SCH_1):PAGE115

TP_USB2_P06_DN @BASEBOARD_FAB2_LIB.BASEBOARD_FAB2(SCH_1):TP_USB2_P06_DN
  U7C1 CA63 USB2N_6 LBG_CORE_QAT_EXT_D_BGA1-IC,H91A    I74 @BASEBOARD_FAB2_LIB.BASEBOARD_FAB2(SCH_1):PAGE115

TP_USB2_P06_DP @BASEBOARD_FAB2_LIB.BASEBOARD_FAB2(SCH_1):TP_USB2_P06_DP
  U7C1 BW63 USB2P_6 LBG_CORE_QAT_EXT_D_BGA1-IC,H91A    I74 @BASEBOARD_FAB2_LIB.BASEBOARD_FAB2(SCH_1):PAGE115

TP_USB2_P07_DN @BASEBOARD_FAB2_LIB.BASEBOARD_FAB2(SCH_1):TP_USB2_P07_DN
  U7C1 CA57 USB2N_7 LBG_CORE_QAT_EXT_D_BGA1-IC,H91A    I74 @BASEBOARD_FAB2_LIB.BASEBOARD_FAB2(SCH_1):PAGE115

TP_USB2_P07_DP @BASEBOARD_FAB2_LIB.BASEBOARD_FAB2(SCH_1):TP_USB2_P07_DP
  U7C1 BW57 USB2P_7 LBG_CORE_QAT_EXT_D_BGA1-IC,H91A    I74 @BASEBOARD_FAB2_LIB.BASEBOARD_FAB2(SCH_1):PAGE115

TP_USB2_P10_DN @BASEBOARD_FAB2_LIB.BASEBOARD_FAB2(SCH_1):TP_USB2_P10_DN
  U7C1 BW65 USB2N_10 LBG_CORE_QAT_EXT_D_BGA1-IC,H91A    I74 @BASEBOARD_FAB2_LIB.BASEBOARD_FAB2(SCH_1):PAGE115

TP_USB2_P10_DP @BASEBOARD_FAB2_LIB.BASEBOARD_FAB2(SCH_1):TP_USB2_P10_DP
  U7C1 BU65 USB2P_10 LBG_CORE_QAT_EXT_D_BGA1-IC,H91A    I74 @BASEBOARD_FAB2_LIB.BASEBOARD_FAB2(SCH_1):PAGE115

TP_USB2_P11_DN @BASEBOARD_FAB2_LIB.BASEBOARD_FAB2(SCH_1):TP_USB2_P11_DN
  U7C1 CA54 USB2N_11 LBG_CORE_QAT_EXT_D_BGA1-IC,H91A    I74 @BASEBOARD_FAB2_LIB.BASEBOARD_FAB2(SCH_1):PAGE115

TP_USB2_P11_DP @BASEBOARD_FAB2_LIB.BASEBOARD_FAB2(SCH_1):TP_USB2_P11_DP
  U7C1 BW54 USB2P_11 LBG_CORE_QAT_EXT_D_BGA1-IC,H91A    I74 @BASEBOARD_FAB2_LIB.BASEBOARD_FAB2(SCH_1):PAGE115

TP_USB2_P12_DN @BASEBOARD_FAB2_LIB.BASEBOARD_FAB2(SCH_1):TP_USB2_P12_DN
  U7C1 BW67 USB2N_12 LBG_CORE_QAT_EXT_D_BGA1-IC,H91A    I74 @BASEBOARD_FAB2_LIB.BASEBOARD_FAB2(SCH_1):PAGE115

TP_USB2_P12_DP @BASEBOARD_FAB2_LIB.BASEBOARD_FAB2(SCH_1):TP_USB2_P12_DP
  U7C1 BV66 USB2P_12 LBG_CORE_QAT_EXT_D_BGA1-IC,H91A    I74 @BASEBOARD_FAB2_LIB.BASEBOARD_FAB2(SCH_1):PAGE115

TP_USB2_P13_DN @BASEBOARD_FAB2_LIB.BASEBOARD_FAB2(SCH_1):TP_USB2_P13_DN
  U7C1 BY53 USB2N_13 LBG_CORE_QAT_EXT_D_BGA1-IC,H91A    I74 @BASEBOARD_FAB2_LIB.BASEBOARD_FAB2(SCH_1):PAGE115

TP_USB2_P13_DP @BASEBOARD_FAB2_LIB.BASEBOARD_FAB2(SCH_1):TP_USB2_P13_DP
  U7C1 BV53 USB2P_13 LBG_CORE_QAT_EXT_D_BGA1-IC,H91A    I74 @BASEBOARD_FAB2_LIB.BASEBOARD_FAB2(SCH_1):PAGE115

TP_USB2_P14_DN @BASEBOARD_FAB2_LIB.BASEBOARD_FAB2(SCH_1):TP_USB2_P14_DN
  U7C1 BW68 USB2N_14 LBG_CORE_QAT_EXT_D_BGA1-IC,H91A    I74 @BASEBOARD_FAB2_LIB.BASEBOARD_FAB2(SCH_1):PAGE115

TP_USB2_P14_DP @BASEBOARD_FAB2_LIB.BASEBOARD_FAB2(SCH_1):TP_USB2_P14_DP
  U7C1 BU67 USB2P_14 LBG_CORE_QAT_EXT_D_BGA1-IC,H91A    I74 @BASEBOARD_FAB2_LIB.BASEBOARD_FAB2(SCH_1):PAGE115

TP_USB2_P8_DN @BASEBOARD_FAB2_LIB.BASEBOARD_FAB2(SCH_1):TP_USB2_P8_DN
  U7C1 BY64 USB2N_8 LBG_CORE_QAT_EXT_D_BGA1-IC,H91A    I74 @BASEBOARD_FAB2_LIB.BASEBOARD_FAB2(SCH_1):PAGE115

TP_USB2_P8_DP @BASEBOARD_FAB2_LIB.BASEBOARD_FAB2(SCH_1):TP_USB2_P8_DP
  U7C1 BV64 USB2P_8 LBG_CORE_QAT_EXT_D_BGA1-IC,H91A    I74 @BASEBOARD_FAB2_LIB.BASEBOARD_FAB2(SCH_1):PAGE115

TP_USB2_P9_DN @BASEBOARD_FAB2_LIB.BASEBOARD_FAB2(SCH_1):TP_USB2_P9_DN
  U7C1 BY55 USB2N_9 LBG_CORE_QAT_EXT_D_BGA1-IC,H91A    I74 @BASEBOARD_FAB2_LIB.BASEBOARD_FAB2(SCH_1):PAGE115

TP_USB2_P9_DP @BASEBOARD_FAB2_LIB.BASEBOARD_FAB2(SCH_1):TP_USB2_P9_DP
  U7C1 BV55 USB2P_9 LBG_CORE_QAT_EXT_D_BGA1-IC,H91A    I74 @BASEBOARD_FAB2_LIB.BASEBOARD_FAB2(SCH_1):PAGE115

TP_USB3_P02_RXN @BASEBOARD_FAB2_LIB.BASEBOARD_FAB2(SCH_1):TP_USB3_P02_RXN
  U7C1 BJ72 USB3_2_RXN LBG_CORE_QAT_EXT_D_BGA1-IC,H91A    I74 @BASEBOARD_FAB2_LIB.BASEBOARD_FAB2(SCH_1):PAGE115

TP_USB3_P02_RXP @BASEBOARD_FAB2_LIB.BASEBOARD_FAB2(SCH_1):TP_USB3_P02_RXP
  U7C1 BJ70 USB3_2_RXP LBG_CORE_QAT_EXT_D_BGA1-IC,H91A    I74 @BASEBOARD_FAB2_LIB.BASEBOARD_FAB2(SCH_1):PAGE115

TP_USB3_P02_TXN @BASEBOARD_FAB2_LIB.BASEBOARD_FAB2(SCH_1):TP_USB3_P02_TXN
  U7C1 BL56 USB3_2_TXN LBG_CORE_QAT_EXT_D_BGA1-IC,H91A    I74 @BASEBOARD_FAB2_LIB.BASEBOARD_FAB2(SCH_1):PAGE115

TP_USB3_P02_TXP @BASEBOARD_FAB2_LIB.BASEBOARD_FAB2(SCH_1):TP_USB3_P02_TXP
  U7C1 BJ56 USB3_2_TXP LBG_CORE_QAT_EXT_D_BGA1-IC,H91A    I74 @BASEBOARD_FAB2_LIB.BASEBOARD_FAB2(SCH_1):PAGE115

TP_USB3_P03_RXN @BASEBOARD_FAB2_LIB.BASEBOARD_FAB2(SCH_1):TP_USB3_P03_RXN
  U7C1 BH71 USB3_3_RXN LBG_CORE_QAT_EXT_D_BGA1-IC,H91A    I74 @BASEBOARD_FAB2_LIB.BASEBOARD_FAB2(SCH_1):PAGE115

TP_USB3_P03_RXP @BASEBOARD_FAB2_LIB.BASEBOARD_FAB2(SCH_1):TP_USB3_P03_RXP
  U7C1 BH69 USB3_3_RXP LBG_CORE_QAT_EXT_D_BGA1-IC,H91A    I74 @BASEBOARD_FAB2_LIB.BASEBOARD_FAB2(SCH_1):PAGE115

TP_USB3_P03_TXN @BASEBOARD_FAB2_LIB.BASEBOARD_FAB2(SCH_1):TP_USB3_P03_TXN
  U7C1 BM54 USB3_3_TXN LBG_CORE_QAT_EXT_D_BGA1-IC,H91A    I74 @BASEBOARD_FAB2_LIB.BASEBOARD_FAB2(SCH_1):PAGE115

TP_USB3_P03_TXP @BASEBOARD_FAB2_LIB.BASEBOARD_FAB2(SCH_1):TP_USB3_P03_TXP
  U7C1 BN56 USB3_3_TXP LBG_CORE_QAT_EXT_D_BGA1-IC,H91A    I74 @BASEBOARD_FAB2_LIB.BASEBOARD_FAB2(SCH_1):PAGE115

TP_USB3_P04_RXN @BASEBOARD_FAB2_LIB.BASEBOARD_FAB2(SCH_1):TP_USB3_P04_RXN
  U7C1 BF72 USB3_4_RXN LBG_CORE_QAT_EXT_D_BGA1-IC,H91A    I74 @BASEBOARD_FAB2_LIB.BASEBOARD_FAB2(SCH_1):PAGE115

TP_USB3_P04_RXP @BASEBOARD_FAB2_LIB.BASEBOARD_FAB2(SCH_1):TP_USB3_P04_RXP
  U7C1 BF70 USB3_4_RXP LBG_CORE_QAT_EXT_D_BGA1-IC,H91A    I74 @BASEBOARD_FAB2_LIB.BASEBOARD_FAB2(SCH_1):PAGE115

TP_USB3_P04_TXN @BASEBOARD_FAB2_LIB.BASEBOARD_FAB2(SCH_1):TP_USB3_P04_TXN
  U7C1 BH58 USB3_4_TXN LBG_CORE_QAT_EXT_D_BGA1-IC,H91A    I74 @BASEBOARD_FAB2_LIB.BASEBOARD_FAB2(SCH_1):PAGE115

TP_USB3_P04_TXP @BASEBOARD_FAB2_LIB.BASEBOARD_FAB2(SCH_1):TP_USB3_P04_TXP
  U7C1 BG56 USB3_4_TXP LBG_CORE_QAT_EXT_D_BGA1-IC,H91A    I74 @BASEBOARD_FAB2_LIB.BASEBOARD_FAB2(SCH_1):PAGE115

TP_USB3_P05_RXN @BASEBOARD_FAB2_LIB.BASEBOARD_FAB2(SCH_1):TP_USB3_P05_RXN
  U7C1 BE71 USB3_5_RXN LBG_CORE_QAT_EXT_D_BGA1-IC,H91A    I74 @BASEBOARD_FAB2_LIB.BASEBOARD_FAB2(SCH_1):PAGE115

TP_USB3_P05_RXP @BASEBOARD_FAB2_LIB.BASEBOARD_FAB2(SCH_1):TP_USB3_P05_RXP
  U7C1 BE69 USB3_5_RXP LBG_CORE_QAT_EXT_D_BGA1-IC,H91A    I74 @BASEBOARD_FAB2_LIB.BASEBOARD_FAB2(SCH_1):PAGE115

TP_USB3_P05_TXN @BASEBOARD_FAB2_LIB.BASEBOARD_FAB2(SCH_1):TP_USB3_P05_TXN
  U7C1 BK58 USB3_5_TXN LBG_CORE_QAT_EXT_D_BGA1-IC,H91A    I74 @BASEBOARD_FAB2_LIB.BASEBOARD_FAB2(SCH_1):PAGE115

TP_USB3_P05_TXP @BASEBOARD_FAB2_LIB.BASEBOARD_FAB2(SCH_1):TP_USB3_P05_TXP
  U7C1 BJ59 USB3_5_TXP LBG_CORE_QAT_EXT_D_BGA1-IC,H91A    I74 @BASEBOARD_FAB2_LIB.BASEBOARD_FAB2(SCH_1):PAGE115

TP_USB3_P06_RXN @BASEBOARD_FAB2_LIB.BASEBOARD_FAB2(SCH_1):TP_USB3_P06_RXN
  U7C1 BD72 USB3_6_RXN LBG_CORE_QAT_EXT_D_BGA1-IC,H91A    I74 @BASEBOARD_FAB2_LIB.BASEBOARD_FAB2(SCH_1):PAGE115

TP_USB3_P06_RXP @BASEBOARD_FAB2_LIB.BASEBOARD_FAB2(SCH_1):TP_USB3_P06_RXP
  U7C1 BD70 USB3_6_RXP LBG_CORE_QAT_EXT_D_BGA1-IC,H91A    I74 @BASEBOARD_FAB2_LIB.BASEBOARD_FAB2(SCH_1):PAGE115

TP_USB3_P06_TXN @BASEBOARD_FAB2_LIB.BASEBOARD_FAB2(SCH_1):TP_USB3_P06_TXN
  U7C1 BL59 USB3_6_TXN LBG_CORE_QAT_EXT_D_BGA1-IC,H91A    I74 @BASEBOARD_FAB2_LIB.BASEBOARD_FAB2(SCH_1):PAGE115

TP_USB3_P06_TXP @BASEBOARD_FAB2_LIB.BASEBOARD_FAB2(SCH_1):TP_USB3_P06_TXP
  U7C1 BM61 USB3_6_TXP LBG_CORE_QAT_EXT_D_BGA1-IC,H91A    I74 @BASEBOARD_FAB2_LIB.BASEBOARD_FAB2(SCH_1):PAGE115

TP_USB_ESD_AC2 @BASEBOARD_FAB2_LIB.BASEBOARD_FAB2(SCH_1):TP_USB_ESD_AC2
 CR1M2    4    AC2 DIODEAC_DUAL_ARRAY_SM9-ESD3V3UA    I98 @BASEBOARD_FAB2_LIB.BASEBOARD_FAB2(SCH_1):PAGE176

TP_USB_ESD_AC3 @BASEBOARD_FAB2_LIB.BASEBOARD_FAB2(SCH_1):TP_USB_ESD_AC3
 CR1M2    5    AC3 DIODEAC_DUAL_ARRAY_SM9-ESD3V3UA    I98 @BASEBOARD_FAB2_LIB.BASEBOARD_FAB2(SCH_1):PAGE176

TP_USB_ESD_OUT2 @BASEBOARD_FAB2_LIB.BASEBOARD_FAB2(SCH_1):TP_USB_ESD_OUT2
 CR1M2    7   OUT2 DIODEAC_DUAL_ARRAY_SM9-ESD3V3UA    I98 @BASEBOARD_FAB2_LIB.BASEBOARD_FAB2(SCH_1):PAGE176

TP_USB_ESD_OUT3 @BASEBOARD_FAB2_LIB.BASEBOARD_FAB2(SCH_1):TP_USB_ESD_OUT3
 CR1M2    6   OUT3 DIODEAC_DUAL_ARRAY_SM9-ESD3V3UA    I98 @BASEBOARD_FAB2_LIB.BASEBOARD_FAB2(SCH_1):PAGE176

TP_VGAHS_GPIOJ4 @BASEBOARD_FAB2_LIB.BASEBOARD_FAB2(SCH_1):TP_VGAHS_GPIOJ4
 U25W4   N5 GPIOJ4_VGAHS AST2520A1-GP-GP_ASIC2-GB1-AST2A   I105 @BASEBOARD_FAB2_LIB.BASEBOARD_FAB2(SCH_1):PAGE146

TP_VGAVS_GPIOJ5 @BASEBOARD_FAB2_LIB.BASEBOARD_FAB2(SCH_1):TP_VGAVS_GPIOJ5
 U25W4   R4 GPIOJ5_VGAVS AST2520A1-GP-GP_ASIC2-GB1-AST2A   I105 @BASEBOARD_FAB2_LIB.BASEBOARD_FAB2(SCH_1):PAGE146

TP_VR_PVCCIO_CPU0_AIINSEN @BASEBOARD_FAB2_LIB.BASEBOARD_FAB2(SCH_1):TP_VR_PVCCIO_CPU0_AIINSEN
 EU3P1   38 IINSEN PXE1110B_QFN-IC,H89187-001    I93 @BASEBOARD_FAB2_LIB.BASEBOARD_FAB2(SCH_1):PAGE211

TP_VR_PVCCIO_CPU0_MP0 @BASEBOARD_FAB2_LIB.BASEBOARD_FAB2(SCH_1):TP_VR_PVCCIO_CPU0_MP0
 EU3P1   13    MP0 PXE1110B_QFN-IC,H89187-001    I93 @BASEBOARD_FAB2_LIB.BASEBOARD_FAB2(SCH_1):PAGE211

TP_VR_PVCCIO_CPU0_MP1 @BASEBOARD_FAB2_LIB.BASEBOARD_FAB2(SCH_1):TP_VR_PVCCIO_CPU0_MP1
 EU3P1   14    MP1 PXE1110B_QFN-IC,H89187-001    I93 @BASEBOARD_FAB2_LIB.BASEBOARD_FAB2(SCH_1):PAGE211

TP_VR_PVCCIO_CPU0_MP2 @BASEBOARD_FAB2_LIB.BASEBOARD_FAB2(SCH_1):TP_VR_PVCCIO_CPU0_MP2
 EU3P1   18    MP2 PXE1110B_QFN-IC,H89187-001    I93 @BASEBOARD_FAB2_LIB.BASEBOARD_FAB2(SCH_1):PAGE211

TP_VR_PVCCIO_CPU0_MP3 @BASEBOARD_FAB2_LIB.BASEBOARD_FAB2(SCH_1):TP_VR_PVCCIO_CPU0_MP3
 EU3P1   31    MP3 PXE1110B_QFN-IC,H89187-001    I93 @BASEBOARD_FAB2_LIB.BASEBOARD_FAB2(SCH_1):PAGE211

TP_VR_PVCCIO_CPU1_AIINSEN @BASEBOARD_FAB2_LIB.BASEBOARD_FAB2(SCH_1):TP_VR_PVCCIO_CPU1_AIINSEN
 EU4D5   38 IINSEN PXE1110B_QFN-IC,H89187-001    I96 @BASEBOARD_FAB2_LIB.BASEBOARD_FAB2(SCH_1):PAGE213

TP_VR_PVCCIO_CPU1_MP0 @BASEBOARD_FAB2_LIB.BASEBOARD_FAB2(SCH_1):TP_VR_PVCCIO_CPU1_MP0
 EU4D5   13    MP0 PXE1110B_QFN-IC,H89187-001    I96 @BASEBOARD_FAB2_LIB.BASEBOARD_FAB2(SCH_1):PAGE213

TP_VR_PVCCIO_CPU1_MP1 @BASEBOARD_FAB2_LIB.BASEBOARD_FAB2(SCH_1):TP_VR_PVCCIO_CPU1_MP1
 EU4D5   14    MP1 PXE1110B_QFN-IC,H89187-001    I96 @BASEBOARD_FAB2_LIB.BASEBOARD_FAB2(SCH_1):PAGE213

TP_VR_PVCCIO_CPU1_MP2 @BASEBOARD_FAB2_LIB.BASEBOARD_FAB2(SCH_1):TP_VR_PVCCIO_CPU1_MP2
 EU4D5   18    MP2 PXE1110B_QFN-IC,H89187-001    I96 @BASEBOARD_FAB2_LIB.BASEBOARD_FAB2(SCH_1):PAGE213

TP_VR_PVCCIO_CPU1_MP3 @BASEBOARD_FAB2_LIB.BASEBOARD_FAB2(SCH_1):TP_VR_PVCCIO_CPU1_MP3
 EU4D5   31    MP3 PXE1110B_QFN-IC,H89187-001    I96 @BASEBOARD_FAB2_LIB.BASEBOARD_FAB2(SCH_1):PAGE213

TP_VR_PVNN_PCH_AIINSEN @BASEBOARD_FAB2_LIB.BASEBOARD_FAB2(SCH_1):TP_VR_PVNN_PCH_AIINSEN
 EU8A1   38 IINSEN PXE1110B_QFN-IC,H89187-001   I229 @BASEBOARD_FAB2_LIB.BASEBOARD_FAB2(SCH_1):PAGE235

TP_XDP_CPU0_OBSDATA_A0_MBP2_N @BASEBOARD_FAB2_LIB.BASEBOARD_FAB2(SCH_1):TP_XDP_CPU0_OBSDATA_A0_MBP2_N
  U5D1 AG10 BPM_N<2> SKX_EXT_B_BGA1-IC,TBD   I259 @BASEBOARD_FAB2_LIB.BASEBOARD_FAB2(SCH_1):PAGE21

TP_XDP_CPU0_OBSDATA_A1_MBP3_N @BASEBOARD_FAB2_LIB.BASEBOARD_FAB2(SCH_1):TP_XDP_CPU0_OBSDATA_A1_MBP3_N
  U5D1 AF11 BPM_N<3> SKX_EXT_B_BGA1-IC,TBD   I259 @BASEBOARD_FAB2_LIB.BASEBOARD_FAB2(SCH_1):PAGE21

TP_XDP_CPU0_OBSDATA_A2_MBP4_N @BASEBOARD_FAB2_LIB.BASEBOARD_FAB2(SCH_1):TP_XDP_CPU0_OBSDATA_A2_MBP4_N
  U5D1 AA12 BPM_N<4> SKX_EXT_B_BGA1-IC,TBD   I259 @BASEBOARD_FAB2_LIB.BASEBOARD_FAB2(SCH_1):PAGE21

TP_XDP_CPU0_OBSDATA_A3_MBP5_N @BASEBOARD_FAB2_LIB.BASEBOARD_FAB2(SCH_1):TP_XDP_CPU0_OBSDATA_A3_MBP5_N
  U5D1  Y11 BPM_N<5> SKX_EXT_B_BGA1-IC,TBD   I259 @BASEBOARD_FAB2_LIB.BASEBOARD_FAB2(SCH_1):PAGE21

TP_XDP_CPU1_OBSDATA_B0_MBP2_N @BASEBOARD_FAB2_LIB.BASEBOARD_FAB2(SCH_1):TP_XDP_CPU1_OBSDATA_B0_MBP2_N
  U2D1 AG10 BPM_N<2> SKX_EXT_B_BGA1-IC,TBD   I172 @BASEBOARD_FAB2_LIB.BASEBOARD_FAB2(SCH_1):PAGE55

TP_XDP_CPU1_OBSDATA_B1_MBP3_N @BASEBOARD_FAB2_LIB.BASEBOARD_FAB2(SCH_1):TP_XDP_CPU1_OBSDATA_B1_MBP3_N
  U2D1 AF11 BPM_N<3> SKX_EXT_B_BGA1-IC,TBD   I172 @BASEBOARD_FAB2_LIB.BASEBOARD_FAB2(SCH_1):PAGE55

TP_XDP_CPU1_OBSDATA_B2_MBP4_N @BASEBOARD_FAB2_LIB.BASEBOARD_FAB2(SCH_1):TP_XDP_CPU1_OBSDATA_B2_MBP4_N
  U2D1 AA12 BPM_N<4> SKX_EXT_B_BGA1-IC,TBD   I172 @BASEBOARD_FAB2_LIB.BASEBOARD_FAB2(SCH_1):PAGE55

TP_XDP_CPU1_OBSDATA_B3_MBP5_N @BASEBOARD_FAB2_LIB.BASEBOARD_FAB2(SCH_1):TP_XDP_CPU1_OBSDATA_B3_MBP5_N
  U2D1  Y11 BPM_N<5> SKX_EXT_B_BGA1-IC,TBD   I172 @BASEBOARD_FAB2_LIB.BASEBOARD_FAB2(SCH_1):PAGE55

TP_XDP_CPU_OBSDATA_C0 @BASEBOARD_FAB2_LIB.BASEBOARD_FAB2(SCH_1):TP_XDP_CPU_OBSDATA_C0
  J9A3   10   IO10 SCONN60_C21100002_SMLF-CONN,C2A    I26 @BASEBOARD_FAB2_LIB.BASEBOARD_FAB2(SCH_1):PAGE111

TP_XDP_CPU_OBSDATA_C1 @BASEBOARD_FAB2_LIB.BASEBOARD_FAB2(SCH_1):TP_XDP_CPU_OBSDATA_C1
  J9A3   12   IO12 SCONN60_C21100002_SMLF-CONN,C2A    I26 @BASEBOARD_FAB2_LIB.BASEBOARD_FAB2(SCH_1):PAGE111

TP_XDP_CPU_OBSDATA_C2 @BASEBOARD_FAB2_LIB.BASEBOARD_FAB2(SCH_1):TP_XDP_CPU_OBSDATA_C2
  J9A3   16   IO16 SCONN60_C21100002_SMLF-CONN,C2A    I26 @BASEBOARD_FAB2_LIB.BASEBOARD_FAB2(SCH_1):PAGE111

TP_XDP_CPU_OBSDATA_C3 @BASEBOARD_FAB2_LIB.BASEBOARD_FAB2(SCH_1):TP_XDP_CPU_OBSDATA_C3
  J9A3   18   IO18 SCONN60_C21100002_SMLF-CONN,C2A    I26 @BASEBOARD_FAB2_LIB.BASEBOARD_FAB2(SCH_1):PAGE111

TP_XDP_CPU_OBSDATA_D0 @BASEBOARD_FAB2_LIB.BASEBOARD_FAB2(SCH_1):TP_XDP_CPU_OBSDATA_D0
  J9A3   28   IO28 SCONN60_C21100002_SMLF-CONN,C2A    I26 @BASEBOARD_FAB2_LIB.BASEBOARD_FAB2(SCH_1):PAGE111

TP_XDP_CPU_OBSDATA_D1 @BASEBOARD_FAB2_LIB.BASEBOARD_FAB2(SCH_1):TP_XDP_CPU_OBSDATA_D1
  J9A3   30   IO30 SCONN60_C21100002_SMLF-CONN,C2A    I26 @BASEBOARD_FAB2_LIB.BASEBOARD_FAB2(SCH_1):PAGE111

TP_XDP_CPU_OBSDATA_D2 @BASEBOARD_FAB2_LIB.BASEBOARD_FAB2(SCH_1):TP_XDP_CPU_OBSDATA_D2
  J9A3   34   IO34 SCONN60_C21100002_SMLF-CONN,C2A    I26 @BASEBOARD_FAB2_LIB.BASEBOARD_FAB2(SCH_1):PAGE111

TP_XDP_CPU_OBSDATA_D3 @BASEBOARD_FAB2_LIB.BASEBOARD_FAB2(SCH_1):TP_XDP_CPU_OBSDATA_D3
  J9A3   36   IO36 SCONN60_C21100002_SMLF-CONN,C2A    I26 @BASEBOARD_FAB2_LIB.BASEBOARD_FAB2(SCH_1):PAGE111

TP_XDP_CPU_OBSFN_C0 @BASEBOARD_FAB2_LIB.BASEBOARD_FAB2(SCH_1):TP_XDP_CPU_OBSFN_C0
  J9A3    4    IO4 SCONN60_C21100002_SMLF-CONN,C2A    I26 @BASEBOARD_FAB2_LIB.BASEBOARD_FAB2(SCH_1):PAGE111

TP_XDP_OBSDATA_A0 @BASEBOARD_FAB2_LIB.BASEBOARD_FAB2(SCH_1):TP_XDP_OBSDATA_A0
  J9A3    9    IO9 SCONN60_C21100002_SMLF-CONN,C2A    I26 @BASEBOARD_FAB2_LIB.BASEBOARD_FAB2(SCH_1):PAGE111

TP_XDP_OBSDATA_A1 @BASEBOARD_FAB2_LIB.BASEBOARD_FAB2(SCH_1):TP_XDP_OBSDATA_A1
  J9A3   11   IO11 SCONN60_C21100002_SMLF-CONN,C2A    I26 @BASEBOARD_FAB2_LIB.BASEBOARD_FAB2(SCH_1):PAGE111

TP_XDP_OBSDATA_A2 @BASEBOARD_FAB2_LIB.BASEBOARD_FAB2(SCH_1):TP_XDP_OBSDATA_A2
  J9A3   15   IO15 SCONN60_C21100002_SMLF-CONN,C2A    I26 @BASEBOARD_FAB2_LIB.BASEBOARD_FAB2(SCH_1):PAGE111

TP_XDP_OBSDATA_A3 @BASEBOARD_FAB2_LIB.BASEBOARD_FAB2(SCH_1):TP_XDP_OBSDATA_A3
  J9A3   17   IO17 SCONN60_C21100002_SMLF-CONN,C2A    I26 @BASEBOARD_FAB2_LIB.BASEBOARD_FAB2(SCH_1):PAGE111

TP_XDP_OBSDATA_B0 @BASEBOARD_FAB2_LIB.BASEBOARD_FAB2(SCH_1):TP_XDP_OBSDATA_B0
  J9A3   27   IO27 SCONN60_C21100002_SMLF-CONN,C2A    I26 @BASEBOARD_FAB2_LIB.BASEBOARD_FAB2(SCH_1):PAGE111

TP_XDP_OBSDATA_B1 @BASEBOARD_FAB2_LIB.BASEBOARD_FAB2(SCH_1):TP_XDP_OBSDATA_B1
  J9A3   29   IO29 SCONN60_C21100002_SMLF-CONN,C2A    I26 @BASEBOARD_FAB2_LIB.BASEBOARD_FAB2(SCH_1):PAGE111

TP_XDP_OBSDATA_B2 @BASEBOARD_FAB2_LIB.BASEBOARD_FAB2(SCH_1):TP_XDP_OBSDATA_B2
  J9A3   33   IO33 SCONN60_C21100002_SMLF-CONN,C2A    I26 @BASEBOARD_FAB2_LIB.BASEBOARD_FAB2(SCH_1):PAGE111

TP_XDP_OBSDATA_B3 @BASEBOARD_FAB2_LIB.BASEBOARD_FAB2(SCH_1):TP_XDP_OBSDATA_B3
  J9A3   35   IO35 SCONN60_C21100002_SMLF-CONN,C2A    I26 @BASEBOARD_FAB2_LIB.BASEBOARD_FAB2(SCH_1):PAGE111

TP_XDP_OBSFN_B0 @BASEBOARD_FAB2_LIB.BASEBOARD_FAB2(SCH_1):TP_XDP_OBSFN_B0
  J9A3   21   IO21 SCONN60_C21100002_SMLF-CONN,C2A    I26 @BASEBOARD_FAB2_LIB.BASEBOARD_FAB2(SCH_1):PAGE111

TP_XDP_OBSFN_B1 @BASEBOARD_FAB2_LIB.BASEBOARD_FAB2(SCH_1):TP_XDP_OBSFN_B1
  J9A3   23   IO23 SCONN60_C21100002_SMLF-CONN,C2A    I26 @BASEBOARD_FAB2_LIB.BASEBOARD_FAB2(SCH_1):PAGE111

UART_BMC_RXD5 @BASEBOARD_FAB2_LIB.BASEBOARD_FAB2(SCH_1):UART_BMC_RXD5
  U9F1    2     B1 FSA3357_SM-IC,C63273-001    I75 @BASEBOARD_FAB2_LIB.BASEBOARD_FAB2(SCH_1):PAGE158
 R9F53    1      A RES_0402-0.0,5%,1/16W,CHIP,G21A    I53 @BASEBOARD_FAB2_LIB.BASEBOARD_FAB2(SCH_1):PAGE183
  U8D7   J5  PL10C LCMXO2_A_256BGA-IC,H63395-001   I179 @BASEBOARD_FAB2_LIB.BASEBOARD_FAB2(SCH_1):PAGE190
 U25W4   K2   RXD5 AST2520A1-GP-GP_ASIC2-GB1-AST2A   I117 @BASEBOARD_FAB2_LIB.BASEBOARD_FAB2(SCH_1):PAGE145

UART_BMC_TXD5 @BASEBOARD_FAB2_LIB.BASEBOARD_FAB2(SCH_1):UART_BMC_TXD5
  U9F2    2     B1 FSA3357_SM-IC,C63273-001    I74 @BASEBOARD_FAB2_LIB.BASEBOARD_FAB2(SCH_1):PAGE158
 R9F57    2      B RES_0402-0.0,5%,1/16W,CHIP,G21A    I48 @BASEBOARD_FAB2_LIB.BASEBOARD_FAB2(SCH_1):PAGE183
  U8D7   K6  PL10D LCMXO2_A_256BGA-IC,H63395-001   I179 @BASEBOARD_FAB2_LIB.BASEBOARD_FAB2(SCH_1):PAGE190
R25W116    2      B RES_0402-3.32K,1%,1/16W,CHIP,GA    I48 @BASEBOARD_FAB2_LIB.BASEBOARD_FAB2(SCH_1):PAGE151
 U25W4   K1   TXD5 AST2520A1-GP-GP_ASIC2-GB1-AST2A   I117 @BASEBOARD_FAB2_LIB.BASEBOARD_FAB2(SCH_1):PAGE145

UART_BRIDGE_RXD5 @BASEBOARD_FAB2_LIB.BASEBOARD_FAB2(SCH_1):UART_BRIDGE_RXD5
 EU9F3    4    RXB PI7C9X1172_QFN-IC,H66899-001     I1 @BASEBOARD_FAB2_LIB.BASEBOARD_FAB2(SCH_1):PAGE183
 R9F53    2      B RES_0402-0.0,5%,1/16W,CHIP,G21A    I53 @BASEBOARD_FAB2_LIB.BASEBOARD_FAB2(SCH_1):PAGE183

UART_BRIDGE_TXD5 @BASEBOARD_FAB2_LIB.BASEBOARD_FAB2(SCH_1):UART_BRIDGE_TXD5
 EU9F3    7    TXB PI7C9X1172_QFN-IC,H66899-001     I1 @BASEBOARD_FAB2_LIB.BASEBOARD_FAB2(SCH_1):PAGE183
 R9F57    1      A RES_0402-0.0,5%,1/16W,CHIP,G21A    I48 @BASEBOARD_FAB2_LIB.BASEBOARD_FAB2(SCH_1):PAGE183

UART_MUX_IN_R @BASEBOARD_FAB2_LIB.BASEBOARD_FAB2(SCH_1):UART_MUX_IN_R
  U9F1    7      A FSA3357_SM-IC,C63273-001    I75 @BASEBOARD_FAB2_LIB.BASEBOARD_FAB2(SCH_1):PAGE158
 R9F25    2      B RES_0402-100.0,1%,1/16W,CHIP,GA    I86 @BASEBOARD_FAB2_LIB.BASEBOARD_FAB2(SCH_1):PAGE158

UART_MUX_OUT_R @BASEBOARD_FAB2_LIB.BASEBOARD_FAB2(SCH_1):UART_MUX_OUT_R
  U9F2    7      A FSA3357_SM-IC,C63273-001    I74 @BASEBOARD_FAB2_LIB.BASEBOARD_FAB2(SCH_1):PAGE158
 R9F27    1      A RES_0402-0.0,5%,1/16W,CHIP,G21A    I91 @BASEBOARD_FAB2_LIB.BASEBOARD_FAB2(SCH_1):PAGE158

UART_SELECT_Q @BASEBOARD_FAB2_LIB.BASEBOARD_FAB2(SCH_1):UART_SELECT_Q
 R6W14    1      A RES_0402-5.11K,1%,1/16W,CHIP,GA    I33 @BASEBOARD_FAB2_LIB.BASEBOARD_FAB2(SCH_1):PAGE168
 R6W13    2      B RES_0402-15.0K,1%,1/16W,CHIP,GA    I34 @BASEBOARD_FAB2_LIB.BASEBOARD_FAB2(SCH_1):PAGE168
  Q6W3    1      B NPN_SM-MMBT3904,IC,C52245-001    I37 @BASEBOARD_FAB2_LIB.BASEBOARD_FAB2(SCH_1):PAGE168

UNNAMED_202_3D01R5F-GP_I75_2 @BASEBOARD_FAB2_LIB.BASEBOARD_FAB2(SCH_1):UNNAMED_202_3D01R5F-GP_I75_2
   CT3    2      2 SC2K2P50V3KX-GP_SMD-BCG6-SC2K2A    I76 @BASEBOARD_FAB2_LIB.BASEBOARD_FAB2(SCH_1):PAGE202
   RT2    2      2 3D01R5F-GP_SMD-RG5-3D01R5F-GP,A    I75 @BASEBOARD_FAB2_LIB.BASEBOARD_FAB2(SCH_1):PAGE202

UNNAMED_202_3D01R5F-GP_I83_2 @BASEBOARD_FAB2_LIB.BASEBOARD_FAB2(SCH_1):UNNAMED_202_3D01R5F-GP_I83_2
   CT5    2      2 SC2K2P50V3KX-GP_SMD-BCG6-SC2K2A    I82 @BASEBOARD_FAB2_LIB.BASEBOARD_FAB2(SCH_1):PAGE202
   RT4    2      2 3D01R5F-GP_SMD-RG5-3D01R5F-GP,A    I83 @BASEBOARD_FAB2_LIB.BASEBOARD_FAB2(SCH_1):PAGE202

UNNAMED_203_3D01R5F-GP_I102_2 @BASEBOARD_FAB2_LIB.BASEBOARD_FAB2(SCH_1):UNNAMED_203_3D01R5F-GP_I102_2
  CT38    2      2 SC2K2P50V3KX-GP_SMD-BCG6-SC2K2A   I101 @BASEBOARD_FAB2_LIB.BASEBOARD_FAB2(SCH_1):PAGE203
  RT26    2      2 3D01R5F-GP_SMD-RG5-3D01R5F-GP,A   I102 @BASEBOARD_FAB2_LIB.BASEBOARD_FAB2(SCH_1):PAGE203

UNNAMED_203_3D01R5F-GP_I105_2 @BASEBOARD_FAB2_LIB.BASEBOARD_FAB2(SCH_1):UNNAMED_203_3D01R5F-GP_I105_2
  CT41    2      2 SC2K2P50V3KX-GP_SMD-BCG6-SC2K2A   I106 @BASEBOARD_FAB2_LIB.BASEBOARD_FAB2(SCH_1):PAGE203
  RT27    2      2 3D01R5F-GP_SMD-RG5-3D01R5F-GP,A   I105 @BASEBOARD_FAB2_LIB.BASEBOARD_FAB2(SCH_1):PAGE203

UNNAMED_204_3D01R5F-GP_I91_2 @BASEBOARD_FAB2_LIB.BASEBOARD_FAB2(SCH_1):UNNAMED_204_3D01R5F-GP_I91_2
  CT35    2      2 SC2K2P50V3KX-GP_SMD-BCG6-SC2K2A    I90 @BASEBOARD_FAB2_LIB.BASEBOARD_FAB2(SCH_1):PAGE204
  RT24    2      2 3D01R5F-GP_SMD-RG5-3D01R5F-GP,A    I91 @BASEBOARD_FAB2_LIB.BASEBOARD_FAB2(SCH_1):PAGE204

UNNAMED_205_3D01R5F-GP_I68_2 @BASEBOARD_FAB2_LIB.BASEBOARD_FAB2(SCH_1):UNNAMED_205_3D01R5F-GP_I68_2
  CT59    2      2 SC2K2P50V3KX-GP_SMD-BCG6-SC2K2A    I64 @BASEBOARD_FAB2_LIB.BASEBOARD_FAB2(SCH_1):PAGE205
  RT39    2      2 3D01R5F-GP_SMD-RG5-3D01R5F-GP,A    I68 @BASEBOARD_FAB2_LIB.BASEBOARD_FAB2(SCH_1):PAGE205

UNNAMED_207_3D01R5F-GP_I76_2 @BASEBOARD_FAB2_LIB.BASEBOARD_FAB2(SCH_1):UNNAMED_207_3D01R5F-GP_I76_2
  CT23    2      2 SC2K2P50V3KX-GP_SMD-BCG6-SC2K2A    I77 @BASEBOARD_FAB2_LIB.BASEBOARD_FAB2(SCH_1):PAGE207
  RT16    2      2 3D01R5F-GP_SMD-RG5-3D01R5F-GP,A    I76 @BASEBOARD_FAB2_LIB.BASEBOARD_FAB2(SCH_1):PAGE207

UNNAMED_207_3D01R5F-GP_I85_2 @BASEBOARD_FAB2_LIB.BASEBOARD_FAB2(SCH_1):UNNAMED_207_3D01R5F-GP_I85_2
  CT27    2      2 SC2K2P50V3KX-GP_SMD-BCG6-SC2K2A    I84 @BASEBOARD_FAB2_LIB.BASEBOARD_FAB2(SCH_1):PAGE207
  RT18    2      2 3D01R5F-GP_SMD-RG5-3D01R5F-GP,A    I85 @BASEBOARD_FAB2_LIB.BASEBOARD_FAB2(SCH_1):PAGE207

UNNAMED_208_3D01R5F-GP_I86_2 @BASEBOARD_FAB2_LIB.BASEBOARD_FAB2(SCH_1):UNNAMED_208_3D01R5F-GP_I86_2
  CT18    2      2 SC2K2P50V3KX-GP_SMD-BCG6-SC2K2A    I84 @BASEBOARD_FAB2_LIB.BASEBOARD_FAB2(SCH_1):PAGE208
  RT12    2      2 3D01R5F-GP_SMD-RG5-3D01R5F-GP,A    I86 @BASEBOARD_FAB2_LIB.BASEBOARD_FAB2(SCH_1):PAGE208

UNNAMED_208_3D01R5F-GP_I94_2 @BASEBOARD_FAB2_LIB.BASEBOARD_FAB2(SCH_1):UNNAMED_208_3D01R5F-GP_I94_2
  CT20    2      2 SC2K2P50V3KX-GP_SMD-BCG6-SC2K2A    I92 @BASEBOARD_FAB2_LIB.BASEBOARD_FAB2(SCH_1):PAGE208
  RT13    2      2 3D01R5F-GP_SMD-RG5-3D01R5F-GP,A    I94 @BASEBOARD_FAB2_LIB.BASEBOARD_FAB2(SCH_1):PAGE208

UNNAMED_209_3D01R5F-GP_I66_2 @BASEBOARD_FAB2_LIB.BASEBOARD_FAB2(SCH_1):UNNAMED_209_3D01R5F-GP_I66_2
  CT14    2      2 SC2K2P50V3KX-GP_SMD-BCG6-SC2K2A    I64 @BASEBOARD_FAB2_LIB.BASEBOARD_FAB2(SCH_1):PAGE209
  RT10    2      2 3D01R5F-GP_SMD-RG5-3D01R5F-GP,A    I66 @BASEBOARD_FAB2_LIB.BASEBOARD_FAB2(SCH_1):PAGE209

UNNAMED_210_3D01R5F-GP_I59_2 @BASEBOARD_FAB2_LIB.BASEBOARD_FAB2(SCH_1):UNNAMED_210_3D01R5F-GP_I59_2
  CT56    2      2 SC2K2P50V3KX-GP_SMD-BCG6-SC2K2A    I57 @BASEBOARD_FAB2_LIB.BASEBOARD_FAB2(SCH_1):PAGE210
  RT38    2      2 3D01R5F-GP_SMD-RG5-3D01R5F-GP,A    I59 @BASEBOARD_FAB2_LIB.BASEBOARD_FAB2(SCH_1):PAGE210

UNNAMED_212_3D01R5F-GP_I112_2 @BASEBOARD_FAB2_LIB.BASEBOARD_FAB2(SCH_1):UNNAMED_212_3D01R5F-GP_I112_2
  CT72    2      2 SC2K2P50V3KX-GP_SMD-BCG6-SC2K2A   I111 @BASEBOARD_FAB2_LIB.BASEBOARD_FAB2(SCH_1):PAGE212
  RT48    2      2 3D01R5F-GP_SMD-RG5-3D01R5F-GP,A   I112 @BASEBOARD_FAB2_LIB.BASEBOARD_FAB2(SCH_1):PAGE212

UNNAMED_214_3D01R5F-GP_I132_2 @BASEBOARD_FAB2_LIB.BASEBOARD_FAB2(SCH_1):UNNAMED_214_3D01R5F-GP_I132_2
  CT62    2      2 SC2K2P50V3KX-GP_SMD-BCG6-SC2K2A   I131 @BASEBOARD_FAB2_LIB.BASEBOARD_FAB2(SCH_1):PAGE214
  RT42    2      2 3D01R5F-GP_SMD-RG5-3D01R5F-GP,A   I132 @BASEBOARD_FAB2_LIB.BASEBOARD_FAB2(SCH_1):PAGE214

UNNAMED_216_3D01R5F-GP_I114_2 @BASEBOARD_FAB2_LIB.BASEBOARD_FAB2(SCH_1):UNNAMED_216_3D01R5F-GP_I114_2
  CT50    2      2 SC2K2P50V3KX-GP_SMD-BCG6-SC2K2A   I124 @BASEBOARD_FAB2_LIB.BASEBOARD_FAB2(SCH_1):PAGE216
  RT34    2      2 3D01R5F-GP_SMD-RG5-3D01R5F-GP,A   I114 @BASEBOARD_FAB2_LIB.BASEBOARD_FAB2(SCH_1):PAGE216

UNNAMED_216_3D01R5F-GP_I123_2 @BASEBOARD_FAB2_LIB.BASEBOARD_FAB2(SCH_1):UNNAMED_216_3D01R5F-GP_I123_2
  CT53    2      2 SC2K2P50V3KX-GP_SMD-BCG6-SC2K2A   I119 @BASEBOARD_FAB2_LIB.BASEBOARD_FAB2(SCH_1):PAGE216
  RT35    2      2 3D01R5F-GP_SMD-RG5-3D01R5F-GP,A   I123 @BASEBOARD_FAB2_LIB.BASEBOARD_FAB2(SCH_1):PAGE216

UNNAMED_219_3D01R5F-GP_I123_2 @BASEBOARD_FAB2_LIB.BASEBOARD_FAB2(SCH_1):UNNAMED_219_3D01R5F-GP_I123_2
  CT47    2      2 SC2K2P50V3KX-GP_SMD-BCG6-SC2K2A   I121 @BASEBOARD_FAB2_LIB.BASEBOARD_FAB2(SCH_1):PAGE219
  RT32    2      2 3D01R5F-GP_SMD-RG5-3D01R5F-GP,A   I123 @BASEBOARD_FAB2_LIB.BASEBOARD_FAB2(SCH_1):PAGE219

UNNAMED_219_3D01R5F-GP_I126_2 @BASEBOARD_FAB2_LIB.BASEBOARD_FAB2(SCH_1):UNNAMED_219_3D01R5F-GP_I126_2
  CT44    2      2 SC2K2P50V3KX-GP_SMD-BCG6-SC2K2A   I127 @BASEBOARD_FAB2_LIB.BASEBOARD_FAB2(SCH_1):PAGE219
  RT29    2      2 3D01R5F-GP_SMD-RG5-3D01R5F-GP,A   I126 @BASEBOARD_FAB2_LIB.BASEBOARD_FAB2(SCH_1):PAGE219

UNNAMED_224_3D01R5F-GP_I119_2 @BASEBOARD_FAB2_LIB.BASEBOARD_FAB2(SCH_1):UNNAMED_224_3D01R5F-GP_I119_2
  CT29    2      2 SC2K2P50V3KX-GP_SMD-BCG6-SC2K2A   I121 @BASEBOARD_FAB2_LIB.BASEBOARD_FAB2(SCH_1):PAGE224
  RT20    2      2 3D01R5F-GP_SMD-RG5-3D01R5F-GP,A   I119 @BASEBOARD_FAB2_LIB.BASEBOARD_FAB2(SCH_1):PAGE224

UNNAMED_224_3D01R5F-GP_I129_2 @BASEBOARD_FAB2_LIB.BASEBOARD_FAB2(SCH_1):UNNAMED_224_3D01R5F-GP_I129_2
  CT33    2      2 SC2K2P50V3KX-GP_SMD-BCG6-SC2K2A   I127 @BASEBOARD_FAB2_LIB.BASEBOARD_FAB2(SCH_1):PAGE224
  RT22    2      2 3D01R5F-GP_SMD-RG5-3D01R5F-GP,A   I129 @BASEBOARD_FAB2_LIB.BASEBOARD_FAB2(SCH_1):PAGE224

UNNAMED_227_3D01R5F-GP_I124_1 @BASEBOARD_FAB2_LIB.BASEBOARD_FAB2(SCH_1):UNNAMED_227_3D01R5F-GP_I124_1
  CT11    2      2 SC2K2P50V3KX-GP_SMD-BCG6-SC2K2A   I116 @BASEBOARD_FAB2_LIB.BASEBOARD_FAB2(SCH_1):PAGE227
   RT7    1      1 3D01R5F-GP_SMD-RG5-3D01R5F-GP,A   I124 @BASEBOARD_FAB2_LIB.BASEBOARD_FAB2(SCH_1):PAGE227

UNNAMED_227_3D01R5F-GP_I125_1 @BASEBOARD_FAB2_LIB.BASEBOARD_FAB2(SCH_1):UNNAMED_227_3D01R5F-GP_I125_1
   CT9    2      2 SC2K2P50V3KX-GP_SMD-BCG6-SC2K2A   I111 @BASEBOARD_FAB2_LIB.BASEBOARD_FAB2(SCH_1):PAGE227
   RT6    1      1 3D01R5F-GP_SMD-RG5-3D01R5F-GP,A   I125 @BASEBOARD_FAB2_LIB.BASEBOARD_FAB2(SCH_1):PAGE227

UNNAMED_236_3D01R5F-GP_I132_2 @BASEBOARD_FAB2_LIB.BASEBOARD_FAB2(SCH_1):UNNAMED_236_3D01R5F-GP_I132_2
  CT65    2      2 SC2K2P50V3KX-GP_SMD-BCG6-SC2K2A   I131 @BASEBOARD_FAB2_LIB.BASEBOARD_FAB2(SCH_1):PAGE236
  RT43    2      2 3D01R5F-GP_SMD-RG5-3D01R5F-GP,A   I132 @BASEBOARD_FAB2_LIB.BASEBOARD_FAB2(SCH_1):PAGE236

UNNAMED_236_3D01R5F-GP_I137_2 @BASEBOARD_FAB2_LIB.BASEBOARD_FAB2(SCH_1):UNNAMED_236_3D01R5F-GP_I137_2
  CT68    2      2 SC2K2P50V3KX-GP_SMD-BCG6-SC2K2A   I140 @BASEBOARD_FAB2_LIB.BASEBOARD_FAB2(SCH_1):PAGE236
  RT45    2      2 3D01R5F-GP_SMD-RG5-3D01R5F-GP,A   I137 @BASEBOARD_FAB2_LIB.BASEBOARD_FAB2(SCH_1):PAGE236

UNNAMED_239_21K5R2F-GP_I99_2 @BASEBOARD_FAB2_LIB.BASEBOARD_FAB2(SCH_1):UNNAMED_239_21K5R2F-GP_I99_2
EU25F2    4 ADJ_NC RT9059_DFN-IC,H65765-001    I73 @BASEBOARD_FAB2_LIB.BASEBOARD_FAB2(SCH_1):PAGE239
 R9W32    2      B RES_0402-13K,1.0%,1/16W,CHIP,GA    I87 @BASEBOARD_FAB2_LIB.BASEBOARD_FAB2(SCH_1):PAGE239
 R9W31    2      2 21K5R2F-GP_RCL_GP-21K5R2F-GP,6A    I99 @BASEBOARD_FAB2_LIB.BASEBOARD_FAB2(SCH_1):PAGE239

UNNAMED_239_CAP_I84_A @BASEBOARD_FAB2_LIB.BASEBOARD_FAB2(SCH_1):UNNAMED_239_CAP_I84_A
EU25F2    5  PGOOD RT9059_DFN-IC,H65765-001    I73 @BASEBOARD_FAB2_LIB.BASEBOARD_FAB2(SCH_1):PAGE239
  R1W9    1      A RES_0402-22.1,1.0%,1/16W,CHIP,A    I77 @BASEBOARD_FAB2_LIB.BASEBOARD_FAB2(SCH_1):PAGE239
 R9W12    2      B RES_0402-10.0K,1%,1/16W,CHIP,GA    I79 @BASEBOARD_FAB2_LIB.BASEBOARD_FAB2(SCH_1):PAGE239
 C9W10    1      A CAP_0402LF-1000PF,50V,10%,X7R,A    I84 @BASEBOARD_FAB2_LIB.BASEBOARD_FAB2(SCH_1):PAGE239

UNNAMED_239_CAP_I91_A @BASEBOARD_FAB2_LIB.BASEBOARD_FAB2(SCH_1):UNNAMED_239_CAP_I91_A
EU25F2    6     EN RT9059_DFN-IC,H65765-001    I73 @BASEBOARD_FAB2_LIB.BASEBOARD_FAB2(SCH_1):PAGE239
  C9W6    1      A CAP_0402LF-1000PF,50V,10%,EMPTA    I91 @BASEBOARD_FAB2_LIB.BASEBOARD_FAB2(SCH_1):PAGE239

UNNAMED_239_OFFPAGE_I76_A @BASEBOARD_FAB2_LIB.BASEBOARD_FAB2(SCH_1):UNNAMED_239_OFFPAGE_I76_A
  R1W9    2      B RES_0402-22.1,1.0%,1/16W,CHIP,A    I77 @BASEBOARD_FAB2_LIB.BASEBOARD_FAB2(SCH_1):PAGE239

UPI_CPU0_CPU1_P0P0_DN<0> @BASEBOARD_FAB2_LIB.BASEBOARD_FAB2(SCH_1):UPI_CPU0_CPU1_P0P0_DN(0)
  U5D1  BG4 UPI0_TX_DN<19> SKX_EXT_B_BGA1-IC,TBD    I86 @BASEBOARD_FAB2_LIB.BASEBOARD_FAB2(SCH_1):PAGE33
  U2D1  AB9 UPI0_RX_DP<0> SKX_EXT_B_BGA1-IC,TBD   I132 @BASEBOARD_FAB2_LIB.BASEBOARD_FAB2(SCH_1):PAGE67

UPI_CPU0_CPU1_P0P0_DN<10> @BASEBOARD_FAB2_LIB.BASEBOARD_FAB2(SCH_1):UPI_CPU0_CPU1_P0P0_DN(10)
  U5D1  AL2 UPI0_TX_DN<9> SKX_EXT_B_BGA1-IC,TBD    I86 @BASEBOARD_FAB2_LIB.BASEBOARD_FAB2(SCH_1):PAGE33
  U2D1  AP7 UPI0_RX_DN<10> SKX_EXT_B_BGA1-IC,TBD   I132 @BASEBOARD_FAB2_LIB.BASEBOARD_FAB2(SCH_1):PAGE67

UPI_CPU0_CPU1_P0P0_DN<11> @BASEBOARD_FAB2_LIB.BASEBOARD_FAB2(SCH_1):UPI_CPU0_CPU1_P0P0_DN(11)
  U5D1  AH3 UPI0_TX_DN<8> SKX_EXT_B_BGA1-IC,TBD    I86 @BASEBOARD_FAB2_LIB.BASEBOARD_FAB2(SCH_1):PAGE33
  U2D1  AU8 UPI0_RX_DP<11> SKX_EXT_B_BGA1-IC,TBD   I132 @BASEBOARD_FAB2_LIB.BASEBOARD_FAB2(SCH_1):PAGE67

UPI_CPU0_CPU1_P0P0_DN<12> @BASEBOARD_FAB2_LIB.BASEBOARD_FAB2(SCH_1):UPI_CPU0_CPU1_P0P0_DN(12)
  U5D1  AE2 UPI0_TX_DN<7> SKX_EXT_B_BGA1-IC,TBD    I86 @BASEBOARD_FAB2_LIB.BASEBOARD_FAB2(SCH_1):PAGE33
  U2D1 AU10 UPI0_RX_DN<12> SKX_EXT_B_BGA1-IC,TBD   I132 @BASEBOARD_FAB2_LIB.BASEBOARD_FAB2(SCH_1):PAGE67

UPI_CPU0_CPU1_P0P0_DN<13> @BASEBOARD_FAB2_LIB.BASEBOARD_FAB2(SCH_1):UPI_CPU0_CPU1_P0P0_DN(13)
  U5D1  AG4 UPI0_TX_DN<6> SKX_EXT_B_BGA1-IC,TBD    I86 @BASEBOARD_FAB2_LIB.BASEBOARD_FAB2(SCH_1):PAGE33
  U2D1  BA8 UPI0_RX_DN<13> SKX_EXT_B_BGA1-IC,TBD   I132 @BASEBOARD_FAB2_LIB.BASEBOARD_FAB2(SCH_1):PAGE67

UPI_CPU0_CPU1_P0P0_DN<14> @BASEBOARD_FAB2_LIB.BASEBOARD_FAB2(SCH_1):UPI_CPU0_CPU1_P0P0_DN(14)
  U5D1  AC2 UPI0_TX_DN<5> SKX_EXT_B_BGA1-IC,TBD    I86 @BASEBOARD_FAB2_LIB.BASEBOARD_FAB2(SCH_1):PAGE33
  U2D1  BB7 UPI0_RX_DP<14> SKX_EXT_B_BGA1-IC,TBD   I132 @BASEBOARD_FAB2_LIB.BASEBOARD_FAB2(SCH_1):PAGE67

UPI_CPU0_CPU1_P0P0_DN<15> @BASEBOARD_FAB2_LIB.BASEBOARD_FAB2(SCH_1):UPI_CPU0_CPU1_P0P0_DN(15)
  U5D1  AB3 UPI0_TX_DN<4> SKX_EXT_B_BGA1-IC,TBD    I86 @BASEBOARD_FAB2_LIB.BASEBOARD_FAB2(SCH_1):PAGE33
  U2D1  BD7 UPI0_RX_DN<15> SKX_EXT_B_BGA1-IC,TBD   I132 @BASEBOARD_FAB2_LIB.BASEBOARD_FAB2(SCH_1):PAGE67

UPI_CPU0_CPU1_P0P0_DN<16> @BASEBOARD_FAB2_LIB.BASEBOARD_FAB2(SCH_1):UPI_CPU0_CPU1_P0P0_DN(16)
  U5D1   Y1 UPI0_TX_DN<3> SKX_EXT_B_BGA1-IC,TBD    I86 @BASEBOARD_FAB2_LIB.BASEBOARD_FAB2(SCH_1):PAGE33
  U2D1  AW8 UPI0_RX_DN<16> SKX_EXT_B_BGA1-IC,TBD   I132 @BASEBOARD_FAB2_LIB.BASEBOARD_FAB2(SCH_1):PAGE67

UPI_CPU0_CPU1_P0P0_DN<17> @BASEBOARD_FAB2_LIB.BASEBOARD_FAB2(SCH_1):UPI_CPU0_CPU1_P0P0_DN(17)
  U5D1   V3 UPI0_TX_DN<2> SKX_EXT_B_BGA1-IC,TBD    I86 @BASEBOARD_FAB2_LIB.BASEBOARD_FAB2(SCH_1):PAGE33
  U2D1  AY9 UPI0_RX_DN<17> SKX_EXT_B_BGA1-IC,TBD   I132 @BASEBOARD_FAB2_LIB.BASEBOARD_FAB2(SCH_1):PAGE67

UPI_CPU0_CPU1_P0P0_DN<18> @BASEBOARD_FAB2_LIB.BASEBOARD_FAB2(SCH_1):UPI_CPU0_CPU1_P0P0_DN(18)
  U5D1   P1 UPI0_TX_DN<1> SKX_EXT_B_BGA1-IC,TBD    I86 @BASEBOARD_FAB2_LIB.BASEBOARD_FAB2(SCH_1):PAGE33
  U2D1 BC10 UPI0_RX_DP<18> SKX_EXT_B_BGA1-IC,TBD   I132 @BASEBOARD_FAB2_LIB.BASEBOARD_FAB2(SCH_1):PAGE67

UPI_CPU0_CPU1_P0P0_DN<19> @BASEBOARD_FAB2_LIB.BASEBOARD_FAB2(SCH_1):UPI_CPU0_CPU1_P0P0_DN(19)
  U5D1   N2 UPI0_TX_DN<0> SKX_EXT_B_BGA1-IC,TBD    I86 @BASEBOARD_FAB2_LIB.BASEBOARD_FAB2(SCH_1):PAGE33
  U2D1 BA10 UPI0_RX_DP<19> SKX_EXT_B_BGA1-IC,TBD   I132 @BASEBOARD_FAB2_LIB.BASEBOARD_FAB2(SCH_1):PAGE67

UPI_CPU0_CPU1_P0P0_DN<1> @BASEBOARD_FAB2_LIB.BASEBOARD_FAB2(SCH_1):UPI_CPU0_CPU1_P0P0_DN(1)
  U5D1  BF3 UPI0_TX_DN<18> SKX_EXT_B_BGA1-IC,TBD    I86 @BASEBOARD_FAB2_LIB.BASEBOARD_FAB2(SCH_1):PAGE33
  U2D1  AA8 UPI0_RX_DN<1> SKX_EXT_B_BGA1-IC,TBD   I132 @BASEBOARD_FAB2_LIB.BASEBOARD_FAB2(SCH_1):PAGE67

UPI_CPU0_CPU1_P0P0_DN<2> @BASEBOARD_FAB2_LIB.BASEBOARD_FAB2(SCH_1):UPI_CPU0_CPU1_P0P0_DN(2)
  U5D1  BB3 UPI0_TX_DN<17> SKX_EXT_B_BGA1-IC,TBD    I86 @BASEBOARD_FAB2_LIB.BASEBOARD_FAB2(SCH_1):PAGE33
  U2D1  AB7 UPI0_RX_DN<2> SKX_EXT_B_BGA1-IC,TBD   I132 @BASEBOARD_FAB2_LIB.BASEBOARD_FAB2(SCH_1):PAGE67

UPI_CPU0_CPU1_P0P0_DN<3> @BASEBOARD_FAB2_LIB.BASEBOARD_FAB2(SCH_1):UPI_CPU0_CPU1_P0P0_DN(3)
  U5D1  BA4 UPI0_TX_DN<16> SKX_EXT_B_BGA1-IC,TBD    I86 @BASEBOARD_FAB2_LIB.BASEBOARD_FAB2(SCH_1):PAGE33
  U2D1  AC6 UPI0_RX_DP<3> SKX_EXT_B_BGA1-IC,TBD   I132 @BASEBOARD_FAB2_LIB.BASEBOARD_FAB2(SCH_1):PAGE67

UPI_CPU0_CPU1_P0P0_DN<4> @BASEBOARD_FAB2_LIB.BASEBOARD_FAB2(SCH_1):UPI_CPU0_CPU1_P0P0_DN(4)
  U5D1  AV5 UPI0_TX_DN<15> SKX_EXT_B_BGA1-IC,TBD    I86 @BASEBOARD_FAB2_LIB.BASEBOARD_FAB2(SCH_1):PAGE33
  U2D1  AG6 UPI0_RX_DP<4> SKX_EXT_B_BGA1-IC,TBD   I132 @BASEBOARD_FAB2_LIB.BASEBOARD_FAB2(SCH_1):PAGE67

UPI_CPU0_CPU1_P0P0_DN<5> @BASEBOARD_FAB2_LIB.BASEBOARD_FAB2(SCH_1):UPI_CPU0_CPU1_P0P0_DN(5)
  U5D1  AU4 UPI0_TX_DN<14> SKX_EXT_B_BGA1-IC,TBD    I86 @BASEBOARD_FAB2_LIB.BASEBOARD_FAB2(SCH_1):PAGE33
  U2D1  AF7 UPI0_RX_DP<5> SKX_EXT_B_BGA1-IC,TBD   I132 @BASEBOARD_FAB2_LIB.BASEBOARD_FAB2(SCH_1):PAGE67

UPI_CPU0_CPU1_P0P0_DN<6> @BASEBOARD_FAB2_LIB.BASEBOARD_FAB2(SCH_1):UPI_CPU0_CPU1_P0P0_DN(6)
  U5D1  AT3 UPI0_TX_DN<13> SKX_EXT_B_BGA1-IC,TBD    I86 @BASEBOARD_FAB2_LIB.BASEBOARD_FAB2(SCH_1):PAGE33
  U2D1  AH7 UPI0_RX_DP<6> SKX_EXT_B_BGA1-IC,TBD   I132 @BASEBOARD_FAB2_LIB.BASEBOARD_FAB2(SCH_1):PAGE67

UPI_CPU0_CPU1_P0P0_DN<7> @BASEBOARD_FAB2_LIB.BASEBOARD_FAB2(SCH_1):UPI_CPU0_CPU1_P0P0_DN(7)
  U5D1  AT1 UPI0_TX_DN<12> SKX_EXT_B_BGA1-IC,TBD    I86 @BASEBOARD_FAB2_LIB.BASEBOARD_FAB2(SCH_1):PAGE33
  U2D1  AK5 UPI0_RX_DP<7> SKX_EXT_B_BGA1-IC,TBD   I132 @BASEBOARD_FAB2_LIB.BASEBOARD_FAB2(SCH_1):PAGE67

UPI_CPU0_CPU1_P0P0_DN<8> @BASEBOARD_FAB2_LIB.BASEBOARD_FAB2(SCH_1):UPI_CPU0_CPU1_P0P0_DN(8)
  U5D1  AN4 UPI0_TX_DN<11> SKX_EXT_B_BGA1-IC,TBD    I86 @BASEBOARD_FAB2_LIB.BASEBOARD_FAB2(SCH_1):PAGE33
  U2D1  AM7 UPI0_RX_DP<8> SKX_EXT_B_BGA1-IC,TBD   I132 @BASEBOARD_FAB2_LIB.BASEBOARD_FAB2(SCH_1):PAGE67

UPI_CPU0_CPU1_P0P0_DN<9> @BASEBOARD_FAB2_LIB.BASEBOARD_FAB2(SCH_1):UPI_CPU0_CPU1_P0P0_DN(9)
  U5D1  AM3 UPI0_TX_DN<10> SKX_EXT_B_BGA1-IC,TBD    I86 @BASEBOARD_FAB2_LIB.BASEBOARD_FAB2(SCH_1):PAGE33
  U2D1  AL8 UPI0_RX_DP<9> SKX_EXT_B_BGA1-IC,TBD   I132 @BASEBOARD_FAB2_LIB.BASEBOARD_FAB2(SCH_1):PAGE67

UPI_CPU0_CPU1_P0P0_DP<0> @BASEBOARD_FAB2_LIB.BASEBOARD_FAB2(SCH_1):UPI_CPU0_CPU1_P0P0_DP(0)
  U5D1  BH3 UPI0_TX_DP<19> SKX_EXT_B_BGA1-IC,TBD    I86 @BASEBOARD_FAB2_LIB.BASEBOARD_FAB2(SCH_1):PAGE33
  U2D1 AC10 UPI0_RX_DN<0> SKX_EXT_B_BGA1-IC,TBD   I132 @BASEBOARD_FAB2_LIB.BASEBOARD_FAB2(SCH_1):PAGE67

UPI_CPU0_CPU1_P0P0_DP<10> @BASEBOARD_FAB2_LIB.BASEBOARD_FAB2(SCH_1):UPI_CPU0_CPU1_P0P0_DP(10)
  U5D1  AK1 UPI0_TX_DP<9> SKX_EXT_B_BGA1-IC,TBD    I86 @BASEBOARD_FAB2_LIB.BASEBOARD_FAB2(SCH_1):PAGE33
  U2D1  AN8 UPI0_RX_DP<10> SKX_EXT_B_BGA1-IC,TBD   I132 @BASEBOARD_FAB2_LIB.BASEBOARD_FAB2(SCH_1):PAGE67

UPI_CPU0_CPU1_P0P0_DP<11> @BASEBOARD_FAB2_LIB.BASEBOARD_FAB2(SCH_1):UPI_CPU0_CPU1_P0P0_DP(11)
  U5D1  AJ2 UPI0_TX_DP<8> SKX_EXT_B_BGA1-IC,TBD    I86 @BASEBOARD_FAB2_LIB.BASEBOARD_FAB2(SCH_1):PAGE33
  U2D1  AR8 UPI0_RX_DN<11> SKX_EXT_B_BGA1-IC,TBD   I132 @BASEBOARD_FAB2_LIB.BASEBOARD_FAB2(SCH_1):PAGE67

UPI_CPU0_CPU1_P0P0_DP<12> @BASEBOARD_FAB2_LIB.BASEBOARD_FAB2(SCH_1):UPI_CPU0_CPU1_P0P0_DP(12)
  U5D1  AG2 UPI0_TX_DP<7> SKX_EXT_B_BGA1-IC,TBD    I86 @BASEBOARD_FAB2_LIB.BASEBOARD_FAB2(SCH_1):PAGE33
  U2D1  AT9 UPI0_RX_DP<12> SKX_EXT_B_BGA1-IC,TBD   I132 @BASEBOARD_FAB2_LIB.BASEBOARD_FAB2(SCH_1):PAGE67

UPI_CPU0_CPU1_P0P0_DP<13> @BASEBOARD_FAB2_LIB.BASEBOARD_FAB2(SCH_1):UPI_CPU0_CPU1_P0P0_DP(13)
  U5D1  AF3 UPI0_TX_DP<6> SKX_EXT_B_BGA1-IC,TBD    I86 @BASEBOARD_FAB2_LIB.BASEBOARD_FAB2(SCH_1):PAGE33
  U2D1  AY7 UPI0_RX_DP<13> SKX_EXT_B_BGA1-IC,TBD   I132 @BASEBOARD_FAB2_LIB.BASEBOARD_FAB2(SCH_1):PAGE67

UPI_CPU0_CPU1_P0P0_DP<14> @BASEBOARD_FAB2_LIB.BASEBOARD_FAB2(SCH_1):UPI_CPU0_CPU1_P0P0_DP(14)
  U5D1  AD1 UPI0_TX_DP<5> SKX_EXT_B_BGA1-IC,TBD    I86 @BASEBOARD_FAB2_LIB.BASEBOARD_FAB2(SCH_1):PAGE33
  U2D1  BC6 UPI0_RX_DN<14> SKX_EXT_B_BGA1-IC,TBD   I132 @BASEBOARD_FAB2_LIB.BASEBOARD_FAB2(SCH_1):PAGE67

UPI_CPU0_CPU1_P0P0_DP<15> @BASEBOARD_FAB2_LIB.BASEBOARD_FAB2(SCH_1):UPI_CPU0_CPU1_P0P0_DP(15)
  U5D1  AA2 UPI0_TX_DP<4> SKX_EXT_B_BGA1-IC,TBD    I86 @BASEBOARD_FAB2_LIB.BASEBOARD_FAB2(SCH_1):PAGE33
  U2D1  BF7 UPI0_RX_DP<15> SKX_EXT_B_BGA1-IC,TBD   I132 @BASEBOARD_FAB2_LIB.BASEBOARD_FAB2(SCH_1):PAGE67

UPI_CPU0_CPU1_P0P0_DP<16> @BASEBOARD_FAB2_LIB.BASEBOARD_FAB2(SCH_1):UPI_CPU0_CPU1_P0P0_DP(16)
  U5D1   W2 UPI0_TX_DP<3> SKX_EXT_B_BGA1-IC,TBD    I86 @BASEBOARD_FAB2_LIB.BASEBOARD_FAB2(SCH_1):PAGE33
  U2D1  AV9 UPI0_RX_DP<16> SKX_EXT_B_BGA1-IC,TBD   I132 @BASEBOARD_FAB2_LIB.BASEBOARD_FAB2(SCH_1):PAGE67

UPI_CPU0_CPU1_P0P0_DP<17> @BASEBOARD_FAB2_LIB.BASEBOARD_FAB2(SCH_1):UPI_CPU0_CPU1_P0P0_DP(17)
  U5D1   Y3 UPI0_TX_DP<2> SKX_EXT_B_BGA1-IC,TBD    I86 @BASEBOARD_FAB2_LIB.BASEBOARD_FAB2(SCH_1):PAGE33
  U2D1  BB9 UPI0_RX_DP<17> SKX_EXT_B_BGA1-IC,TBD   I132 @BASEBOARD_FAB2_LIB.BASEBOARD_FAB2(SCH_1):PAGE67

UPI_CPU0_CPU1_P0P0_DP<18> @BASEBOARD_FAB2_LIB.BASEBOARD_FAB2(SCH_1):UPI_CPU0_CPU1_P0P0_DP(18)
  U5D1   T1 UPI0_TX_DP<1> SKX_EXT_B_BGA1-IC,TBD    I86 @BASEBOARD_FAB2_LIB.BASEBOARD_FAB2(SCH_1):PAGE33
  U2D1  BD9 UPI0_RX_DN<18> SKX_EXT_B_BGA1-IC,TBD   I132 @BASEBOARD_FAB2_LIB.BASEBOARD_FAB2(SCH_1):PAGE67

UPI_CPU0_CPU1_P0P0_DP<19> @BASEBOARD_FAB2_LIB.BASEBOARD_FAB2(SCH_1):UPI_CPU0_CPU1_P0P0_DP(19)
  U5D1   M1 UPI0_TX_DP<0> SKX_EXT_B_BGA1-IC,TBD    I86 @BASEBOARD_FAB2_LIB.BASEBOARD_FAB2(SCH_1):PAGE33
  U2D1 BB11 UPI0_RX_DN<19> SKX_EXT_B_BGA1-IC,TBD   I132 @BASEBOARD_FAB2_LIB.BASEBOARD_FAB2(SCH_1):PAGE67

UPI_CPU0_CPU1_P0P0_DP<1> @BASEBOARD_FAB2_LIB.BASEBOARD_FAB2(SCH_1):UPI_CPU0_CPU1_P0P0_DP(1)
  U5D1  BD3 UPI0_TX_DP<18> SKX_EXT_B_BGA1-IC,TBD    I86 @BASEBOARD_FAB2_LIB.BASEBOARD_FAB2(SCH_1):PAGE33
  U2D1  AC8 UPI0_RX_DP<1> SKX_EXT_B_BGA1-IC,TBD   I132 @BASEBOARD_FAB2_LIB.BASEBOARD_FAB2(SCH_1):PAGE67

UPI_CPU0_CPU1_P0P0_DP<2> @BASEBOARD_FAB2_LIB.BASEBOARD_FAB2(SCH_1):UPI_CPU0_CPU1_P0P0_DP(2)
  U5D1  BC2 UPI0_TX_DP<17> SKX_EXT_B_BGA1-IC,TBD    I86 @BASEBOARD_FAB2_LIB.BASEBOARD_FAB2(SCH_1):PAGE33
  U2D1  AA6 UPI0_RX_DP<2> SKX_EXT_B_BGA1-IC,TBD   I132 @BASEBOARD_FAB2_LIB.BASEBOARD_FAB2(SCH_1):PAGE67

UPI_CPU0_CPU1_P0P0_DP<3> @BASEBOARD_FAB2_LIB.BASEBOARD_FAB2(SCH_1):UPI_CPU0_CPU1_P0P0_DP(3)
  U5D1  AY3 UPI0_TX_DP<16> SKX_EXT_B_BGA1-IC,TBD    I86 @BASEBOARD_FAB2_LIB.BASEBOARD_FAB2(SCH_1):PAGE33
  U2D1  AD5 UPI0_RX_DN<3> SKX_EXT_B_BGA1-IC,TBD   I132 @BASEBOARD_FAB2_LIB.BASEBOARD_FAB2(SCH_1):PAGE67

UPI_CPU0_CPU1_P0P0_DP<4> @BASEBOARD_FAB2_LIB.BASEBOARD_FAB2(SCH_1):UPI_CPU0_CPU1_P0P0_DP(4)
  U5D1  AW4 UPI0_TX_DP<15> SKX_EXT_B_BGA1-IC,TBD    I86 @BASEBOARD_FAB2_LIB.BASEBOARD_FAB2(SCH_1):PAGE33
  U2D1  AE6 UPI0_RX_DN<4> SKX_EXT_B_BGA1-IC,TBD   I132 @BASEBOARD_FAB2_LIB.BASEBOARD_FAB2(SCH_1):PAGE67

UPI_CPU0_CPU1_P0P0_DP<5> @BASEBOARD_FAB2_LIB.BASEBOARD_FAB2(SCH_1):UPI_CPU0_CPU1_P0P0_DP(5)
  U5D1  AR4 UPI0_TX_DP<14> SKX_EXT_B_BGA1-IC,TBD    I86 @BASEBOARD_FAB2_LIB.BASEBOARD_FAB2(SCH_1):PAGE33
  U2D1  AG8 UPI0_RX_DN<5> SKX_EXT_B_BGA1-IC,TBD   I132 @BASEBOARD_FAB2_LIB.BASEBOARD_FAB2(SCH_1):PAGE67

UPI_CPU0_CPU1_P0P0_DP<6> @BASEBOARD_FAB2_LIB.BASEBOARD_FAB2(SCH_1):UPI_CPU0_CPU1_P0P0_DP(6)
  U5D1  AR2 UPI0_TX_DP<13> SKX_EXT_B_BGA1-IC,TBD    I86 @BASEBOARD_FAB2_LIB.BASEBOARD_FAB2(SCH_1):PAGE33
  U2D1  AJ6 UPI0_RX_DN<6> SKX_EXT_B_BGA1-IC,TBD   I132 @BASEBOARD_FAB2_LIB.BASEBOARD_FAB2(SCH_1):PAGE67

UPI_CPU0_CPU1_P0P0_DP<7> @BASEBOARD_FAB2_LIB.BASEBOARD_FAB2(SCH_1):UPI_CPU0_CPU1_P0P0_DP(7)
  U5D1  AP1 UPI0_TX_DP<12> SKX_EXT_B_BGA1-IC,TBD    I86 @BASEBOARD_FAB2_LIB.BASEBOARD_FAB2(SCH_1):PAGE33
  U2D1  AL6 UPI0_RX_DN<7> SKX_EXT_B_BGA1-IC,TBD   I132 @BASEBOARD_FAB2_LIB.BASEBOARD_FAB2(SCH_1):PAGE67

UPI_CPU0_CPU1_P0P0_DP<8> @BASEBOARD_FAB2_LIB.BASEBOARD_FAB2(SCH_1):UPI_CPU0_CPU1_P0P0_DP(8)
  U5D1  AP3 UPI0_TX_DP<11> SKX_EXT_B_BGA1-IC,TBD    I86 @BASEBOARD_FAB2_LIB.BASEBOARD_FAB2(SCH_1):PAGE33
  U2D1  AK7 UPI0_RX_DN<8> SKX_EXT_B_BGA1-IC,TBD   I132 @BASEBOARD_FAB2_LIB.BASEBOARD_FAB2(SCH_1):PAGE67

UPI_CPU0_CPU1_P0P0_DP<9> @BASEBOARD_FAB2_LIB.BASEBOARD_FAB2(SCH_1):UPI_CPU0_CPU1_P0P0_DP(9)
  U5D1  AK3 UPI0_TX_DP<10> SKX_EXT_B_BGA1-IC,TBD    I86 @BASEBOARD_FAB2_LIB.BASEBOARD_FAB2(SCH_1):PAGE33
  U2D1  AM9 UPI0_RX_DN<9> SKX_EXT_B_BGA1-IC,TBD   I132 @BASEBOARD_FAB2_LIB.BASEBOARD_FAB2(SCH_1):PAGE67

UPI_CPU0_CPU1_P1P1_DN<0> @BASEBOARD_FAB2_LIB.BASEBOARD_FAB2(SCH_1):UPI_CPU0_CPU1_P1P1_DN(0)
  U5D1  H21 UPI1_TX_DN<19> SKX_EXT_B_BGA1-IC,TBD    I86 @BASEBOARD_FAB2_LIB.BASEBOARD_FAB2(SCH_1):PAGE34
  U2D1   R6 UPI1_RX_DP<0> SKX_EXT_B_BGA1-IC,TBD   I125 @BASEBOARD_FAB2_LIB.BASEBOARD_FAB2(SCH_1):PAGE68

UPI_CPU0_CPU1_P1P1_DN<10> @BASEBOARD_FAB2_LIB.BASEBOARD_FAB2(SCH_1):UPI_CPU0_CPU1_P1P1_DN(10)
  U5D1  G10 UPI1_TX_DN<9> SKX_EXT_B_BGA1-IC,TBD    I86 @BASEBOARD_FAB2_LIB.BASEBOARD_FAB2(SCH_1):PAGE34
  U2D1  R16 UPI1_RX_DN<10> SKX_EXT_B_BGA1-IC,TBD   I125 @BASEBOARD_FAB2_LIB.BASEBOARD_FAB2(SCH_1):PAGE68

UPI_CPU0_CPU1_P1P1_DN<11> @BASEBOARD_FAB2_LIB.BASEBOARD_FAB2(SCH_1):UPI_CPU0_CPU1_P1P1_DN(11)
  U5D1  F11 UPI1_TX_DN<8> SKX_EXT_B_BGA1-IC,TBD    I86 @BASEBOARD_FAB2_LIB.BASEBOARD_FAB2(SCH_1):PAGE34
  U2D1  N16 UPI1_RX_DP<11> SKX_EXT_B_BGA1-IC,TBD   I125 @BASEBOARD_FAB2_LIB.BASEBOARD_FAB2(SCH_1):PAGE68

UPI_CPU0_CPU1_P1P1_DN<12> @BASEBOARD_FAB2_LIB.BASEBOARD_FAB2(SCH_1):UPI_CPU0_CPU1_P1P1_DN(12)
  U5D1   D9 UPI1_TX_DN<7> SKX_EXT_B_BGA1-IC,TBD    I86 @BASEBOARD_FAB2_LIB.BASEBOARD_FAB2(SCH_1):PAGE34
  U2D1  W16 UPI1_RX_DP<12> SKX_EXT_B_BGA1-IC,TBD   I125 @BASEBOARD_FAB2_LIB.BASEBOARD_FAB2(SCH_1):PAGE68

UPI_CPU0_CPU1_P1P1_DN<13> @BASEBOARD_FAB2_LIB.BASEBOARD_FAB2(SCH_1):UPI_CPU0_CPU1_P1P1_DN(13)
  U5D1   K9 UPI1_TX_DN<6> SKX_EXT_B_BGA1-IC,TBD    I86 @BASEBOARD_FAB2_LIB.BASEBOARD_FAB2(SCH_1):PAGE34
  U2D1  V17 UPI1_RX_DP<13> SKX_EXT_B_BGA1-IC,TBD   I125 @BASEBOARD_FAB2_LIB.BASEBOARD_FAB2(SCH_1):PAGE68

UPI_CPU0_CPU1_P1P1_DN<14> @BASEBOARD_FAB2_LIB.BASEBOARD_FAB2(SCH_1):UPI_CPU0_CPU1_P1P1_DN(14)
  U5D1   H7 UPI1_TX_DN<5> SKX_EXT_B_BGA1-IC,TBD    I86 @BASEBOARD_FAB2_LIB.BASEBOARD_FAB2(SCH_1):PAGE34
  U2D1  R20 UPI1_RX_DN<14> SKX_EXT_B_BGA1-IC,TBD   I125 @BASEBOARD_FAB2_LIB.BASEBOARD_FAB2(SCH_1):PAGE68

UPI_CPU0_CPU1_P1P1_DN<15> @BASEBOARD_FAB2_LIB.BASEBOARD_FAB2(SCH_1):UPI_CPU0_CPU1_P1P1_DN(15)
  U5D1   G6 UPI1_TX_DN<4> SKX_EXT_B_BGA1-IC,TBD    I86 @BASEBOARD_FAB2_LIB.BASEBOARD_FAB2(SCH_1):PAGE34
  U2D1  U18 UPI1_RX_DN<15> SKX_EXT_B_BGA1-IC,TBD   I125 @BASEBOARD_FAB2_LIB.BASEBOARD_FAB2(SCH_1):PAGE68

UPI_CPU0_CPU1_P1P1_DN<16> @BASEBOARD_FAB2_LIB.BASEBOARD_FAB2(SCH_1):UPI_CPU0_CPU1_P1P1_DN(16)
  U5D1   J6 UPI1_TX_DN<3> SKX_EXT_B_BGA1-IC,TBD    I86 @BASEBOARD_FAB2_LIB.BASEBOARD_FAB2(SCH_1):PAGE34
  U2D1  P21 UPI1_RX_DN<16> SKX_EXT_B_BGA1-IC,TBD   I125 @BASEBOARD_FAB2_LIB.BASEBOARD_FAB2(SCH_1):PAGE68

UPI_CPU0_CPU1_P1P1_DN<17> @BASEBOARD_FAB2_LIB.BASEBOARD_FAB2(SCH_1):UPI_CPU0_CPU1_P1P1_DN(17)
  U5D1   K5 UPI1_TX_DN<2> SKX_EXT_B_BGA1-IC,TBD    I86 @BASEBOARD_FAB2_LIB.BASEBOARD_FAB2(SCH_1):PAGE34
  U2D1  V19 UPI1_RX_DN<17> SKX_EXT_B_BGA1-IC,TBD   I125 @BASEBOARD_FAB2_LIB.BASEBOARD_FAB2(SCH_1):PAGE68

UPI_CPU0_CPU1_P1P1_DN<18> @BASEBOARD_FAB2_LIB.BASEBOARD_FAB2(SCH_1):UPI_CPU0_CPU1_P1P1_DN(18)
  U5D1   L4 UPI1_TX_DN<1> SKX_EXT_B_BGA1-IC,TBD    I86 @BASEBOARD_FAB2_LIB.BASEBOARD_FAB2(SCH_1):PAGE34
  U2D1  W20 UPI1_RX_DP<18> SKX_EXT_B_BGA1-IC,TBD   I125 @BASEBOARD_FAB2_LIB.BASEBOARD_FAB2(SCH_1):PAGE68

UPI_CPU0_CPU1_P1P1_DN<19> @BASEBOARD_FAB2_LIB.BASEBOARD_FAB2(SCH_1):UPI_CPU0_CPU1_P1P1_DN(19)
  U5D1   M3 UPI1_TX_DN<0> SKX_EXT_B_BGA1-IC,TBD    I86 @BASEBOARD_FAB2_LIB.BASEBOARD_FAB2(SCH_1):PAGE34
  U2D1 AA20 UPI1_RX_DP<19> SKX_EXT_B_BGA1-IC,TBD   I125 @BASEBOARD_FAB2_LIB.BASEBOARD_FAB2(SCH_1):PAGE68

UPI_CPU0_CPU1_P1P1_DN<1> @BASEBOARD_FAB2_LIB.BASEBOARD_FAB2(SCH_1):UPI_CPU0_CPU1_P1P1_DN(1)
  U5D1  F21 UPI1_TX_DN<18> SKX_EXT_B_BGA1-IC,TBD    I86 @BASEBOARD_FAB2_LIB.BASEBOARD_FAB2(SCH_1):PAGE34
  U2D1   P7 UPI1_RX_DN<1> SKX_EXT_B_BGA1-IC,TBD   I125 @BASEBOARD_FAB2_LIB.BASEBOARD_FAB2(SCH_1):PAGE68

UPI_CPU0_CPU1_P1P1_DN<2> @BASEBOARD_FAB2_LIB.BASEBOARD_FAB2(SCH_1):UPI_CPU0_CPU1_P1P1_DN(2)
  U5D1  J20 UPI1_TX_DN<17> SKX_EXT_B_BGA1-IC,TBD    I86 @BASEBOARD_FAB2_LIB.BASEBOARD_FAB2(SCH_1):PAGE34
  U2D1   V7 UPI1_RX_DN<2> SKX_EXT_B_BGA1-IC,TBD   I125 @BASEBOARD_FAB2_LIB.BASEBOARD_FAB2(SCH_1):PAGE68

UPI_CPU0_CPU1_P1P1_DN<3> @BASEBOARD_FAB2_LIB.BASEBOARD_FAB2(SCH_1):UPI_CPU0_CPU1_P1P1_DN(3)
  U5D1  G18 UPI1_TX_DN<16> SKX_EXT_B_BGA1-IC,TBD    I86 @BASEBOARD_FAB2_LIB.BASEBOARD_FAB2(SCH_1):PAGE34
  U2D1   T9 UPI1_RX_DN<3> SKX_EXT_B_BGA1-IC,TBD   I125 @BASEBOARD_FAB2_LIB.BASEBOARD_FAB2(SCH_1):PAGE68

UPI_CPU0_CPU1_P1P1_DN<4> @BASEBOARD_FAB2_LIB.BASEBOARD_FAB2(SCH_1):UPI_CPU0_CPU1_P1P1_DN(4)
  U5D1  K19 UPI1_TX_DN<15> SKX_EXT_B_BGA1-IC,TBD    I86 @BASEBOARD_FAB2_LIB.BASEBOARD_FAB2(SCH_1):PAGE34
  U2D1   P9 UPI1_RX_DN<4> SKX_EXT_B_BGA1-IC,TBD   I125 @BASEBOARD_FAB2_LIB.BASEBOARD_FAB2(SCH_1):PAGE68

UPI_CPU0_CPU1_P1P1_DN<5> @BASEBOARD_FAB2_LIB.BASEBOARD_FAB2(SCH_1):UPI_CPU0_CPU1_P1P1_DN(5)
  U5D1  H17 UPI1_TX_DN<14> SKX_EXT_B_BGA1-IC,TBD    I86 @BASEBOARD_FAB2_LIB.BASEBOARD_FAB2(SCH_1):PAGE34
  U2D1  R10 UPI1_RX_DN<5> SKX_EXT_B_BGA1-IC,TBD   I125 @BASEBOARD_FAB2_LIB.BASEBOARD_FAB2(SCH_1):PAGE68

UPI_CPU0_CPU1_P1P1_DN<6> @BASEBOARD_FAB2_LIB.BASEBOARD_FAB2(SCH_1):UPI_CPU0_CPU1_P1P1_DN(6)
  U5D1  F15 UPI1_TX_DN<13> SKX_EXT_B_BGA1-IC,TBD    I86 @BASEBOARD_FAB2_LIB.BASEBOARD_FAB2(SCH_1):PAGE34
  U2D1  U12 UPI1_RX_DN<6> SKX_EXT_B_BGA1-IC,TBD   I125 @BASEBOARD_FAB2_LIB.BASEBOARD_FAB2(SCH_1):PAGE68

UPI_CPU0_CPU1_P1P1_DN<7> @BASEBOARD_FAB2_LIB.BASEBOARD_FAB2(SCH_1):UPI_CPU0_CPU1_P1P1_DN(7)
  U5D1  D15 UPI1_TX_DN<12> SKX_EXT_B_BGA1-IC,TBD    I86 @BASEBOARD_FAB2_LIB.BASEBOARD_FAB2(SCH_1):PAGE34
  U2D1  L12 UPI1_RX_DN<7> SKX_EXT_B_BGA1-IC,TBD   I125 @BASEBOARD_FAB2_LIB.BASEBOARD_FAB2(SCH_1):PAGE68

UPI_CPU0_CPU1_P1P1_DN<8> @BASEBOARD_FAB2_LIB.BASEBOARD_FAB2(SCH_1):UPI_CPU0_CPU1_P1P1_DN(8)
  U5D1  G14 UPI1_TX_DN<11> SKX_EXT_B_BGA1-IC,TBD    I86 @BASEBOARD_FAB2_LIB.BASEBOARD_FAB2(SCH_1):PAGE34
  U2D1  M13 UPI1_RX_DP<8> SKX_EXT_B_BGA1-IC,TBD   I125 @BASEBOARD_FAB2_LIB.BASEBOARD_FAB2(SCH_1):PAGE68

UPI_CPU0_CPU1_P1P1_DN<9> @BASEBOARD_FAB2_LIB.BASEBOARD_FAB2(SCH_1):UPI_CPU0_CPU1_P1P1_DN(9)
  U5D1  E12 UPI1_TX_DN<10> SKX_EXT_B_BGA1-IC,TBD    I86 @BASEBOARD_FAB2_LIB.BASEBOARD_FAB2(SCH_1):PAGE34
  U2D1  R12 UPI1_RX_DN<9> SKX_EXT_B_BGA1-IC,TBD   I125 @BASEBOARD_FAB2_LIB.BASEBOARD_FAB2(SCH_1):PAGE68

UPI_CPU0_CPU1_P1P1_DP<0> @BASEBOARD_FAB2_LIB.BASEBOARD_FAB2(SCH_1):UPI_CPU0_CPU1_P1P1_DP(0)
  U5D1  K21 UPI1_TX_DP<19> SKX_EXT_B_BGA1-IC,TBD    I86 @BASEBOARD_FAB2_LIB.BASEBOARD_FAB2(SCH_1):PAGE34
  U2D1   T5 UPI1_RX_DN<0> SKX_EXT_B_BGA1-IC,TBD   I125 @BASEBOARD_FAB2_LIB.BASEBOARD_FAB2(SCH_1):PAGE68

UPI_CPU0_CPU1_P1P1_DP<10> @BASEBOARD_FAB2_LIB.BASEBOARD_FAB2(SCH_1):UPI_CPU0_CPU1_P1P1_DP(10)
  U5D1   H9 UPI1_TX_DP<9> SKX_EXT_B_BGA1-IC,TBD    I86 @BASEBOARD_FAB2_LIB.BASEBOARD_FAB2(SCH_1):PAGE34
  U2D1  T15 UPI1_RX_DP<10> SKX_EXT_B_BGA1-IC,TBD   I125 @BASEBOARD_FAB2_LIB.BASEBOARD_FAB2(SCH_1):PAGE68

UPI_CPU0_CPU1_P1P1_DP<11> @BASEBOARD_FAB2_LIB.BASEBOARD_FAB2(SCH_1):UPI_CPU0_CPU1_P1P1_DP(11)
  U5D1  E10 UPI1_TX_DP<8> SKX_EXT_B_BGA1-IC,TBD    I86 @BASEBOARD_FAB2_LIB.BASEBOARD_FAB2(SCH_1):PAGE34
  U2D1  P17 UPI1_RX_DN<11> SKX_EXT_B_BGA1-IC,TBD   I125 @BASEBOARD_FAB2_LIB.BASEBOARD_FAB2(SCH_1):PAGE68

UPI_CPU0_CPU1_P1P1_DP<12> @BASEBOARD_FAB2_LIB.BASEBOARD_FAB2(SCH_1):UPI_CPU0_CPU1_P1P1_DP(12)
  U5D1   F9 UPI1_TX_DP<7> SKX_EXT_B_BGA1-IC,TBD    I86 @BASEBOARD_FAB2_LIB.BASEBOARD_FAB2(SCH_1):PAGE34
  U2D1  U16 UPI1_RX_DN<12> SKX_EXT_B_BGA1-IC,TBD   I125 @BASEBOARD_FAB2_LIB.BASEBOARD_FAB2(SCH_1):PAGE68

UPI_CPU0_CPU1_P1P1_DP<13> @BASEBOARD_FAB2_LIB.BASEBOARD_FAB2(SCH_1):UPI_CPU0_CPU1_P1P1_DP(13)
  U5D1   J8 UPI1_TX_DP<6> SKX_EXT_B_BGA1-IC,TBD    I86 @BASEBOARD_FAB2_LIB.BASEBOARD_FAB2(SCH_1):PAGE34
  U2D1  W18 UPI1_RX_DN<13> SKX_EXT_B_BGA1-IC,TBD   I125 @BASEBOARD_FAB2_LIB.BASEBOARD_FAB2(SCH_1):PAGE68

UPI_CPU0_CPU1_P1P1_DP<14> @BASEBOARD_FAB2_LIB.BASEBOARD_FAB2(SCH_1):UPI_CPU0_CPU1_P1P1_DP(14)
  U5D1   K7 UPI1_TX_DP<5> SKX_EXT_B_BGA1-IC,TBD    I86 @BASEBOARD_FAB2_LIB.BASEBOARD_FAB2(SCH_1):PAGE34
  U2D1  P19 UPI1_RX_DP<14> SKX_EXT_B_BGA1-IC,TBD   I125 @BASEBOARD_FAB2_LIB.BASEBOARD_FAB2(SCH_1):PAGE68

UPI_CPU0_CPU1_P1P1_DP<15> @BASEBOARD_FAB2_LIB.BASEBOARD_FAB2(SCH_1):UPI_CPU0_CPU1_P1P1_DP(15)
  U5D1   F7 UPI1_TX_DP<4> SKX_EXT_B_BGA1-IC,TBD    I86 @BASEBOARD_FAB2_LIB.BASEBOARD_FAB2(SCH_1):PAGE34
  U2D1  T19 UPI1_RX_DP<15> SKX_EXT_B_BGA1-IC,TBD   I125 @BASEBOARD_FAB2_LIB.BASEBOARD_FAB2(SCH_1):PAGE68

UPI_CPU0_CPU1_P1P1_DP<16> @BASEBOARD_FAB2_LIB.BASEBOARD_FAB2(SCH_1):UPI_CPU0_CPU1_P1P1_DP(16)
  U5D1   H5 UPI1_TX_DP<3> SKX_EXT_B_BGA1-IC,TBD    I86 @BASEBOARD_FAB2_LIB.BASEBOARD_FAB2(SCH_1):PAGE34
  U2D1  T21 UPI1_RX_DP<16> SKX_EXT_B_BGA1-IC,TBD   I125 @BASEBOARD_FAB2_LIB.BASEBOARD_FAB2(SCH_1):PAGE68

UPI_CPU0_CPU1_P1P1_DP<17> @BASEBOARD_FAB2_LIB.BASEBOARD_FAB2(SCH_1):UPI_CPU0_CPU1_P1P1_DP(17)
  U5D1   M5 UPI1_TX_DP<2> SKX_EXT_B_BGA1-IC,TBD    I86 @BASEBOARD_FAB2_LIB.BASEBOARD_FAB2(SCH_1):PAGE34
  U2D1  Y19 UPI1_RX_DP<17> SKX_EXT_B_BGA1-IC,TBD   I125 @BASEBOARD_FAB2_LIB.BASEBOARD_FAB2(SCH_1):PAGE68

UPI_CPU0_CPU1_P1P1_DP<18> @BASEBOARD_FAB2_LIB.BASEBOARD_FAB2(SCH_1):UPI_CPU0_CPU1_P1P1_DP(18)
  U5D1   K3 UPI1_TX_DP<1> SKX_EXT_B_BGA1-IC,TBD    I86 @BASEBOARD_FAB2_LIB.BASEBOARD_FAB2(SCH_1):PAGE34
  U2D1  Y21 UPI1_RX_DN<18> SKX_EXT_B_BGA1-IC,TBD   I125 @BASEBOARD_FAB2_LIB.BASEBOARD_FAB2(SCH_1):PAGE68

UPI_CPU0_CPU1_P1P1_DP<19> @BASEBOARD_FAB2_LIB.BASEBOARD_FAB2(SCH_1):UPI_CPU0_CPU1_P1P1_DP(19)
  U5D1   P3 UPI1_TX_DP<0> SKX_EXT_B_BGA1-IC,TBD    I86 @BASEBOARD_FAB2_LIB.BASEBOARD_FAB2(SCH_1):PAGE34
  U2D1 AB19 UPI1_RX_DN<19> SKX_EXT_B_BGA1-IC,TBD   I125 @BASEBOARD_FAB2_LIB.BASEBOARD_FAB2(SCH_1):PAGE68

UPI_CPU0_CPU1_P1P1_DP<1> @BASEBOARD_FAB2_LIB.BASEBOARD_FAB2(SCH_1):UPI_CPU0_CPU1_P1P1_DP(1)
  U5D1  G20 UPI1_TX_DP<18> SKX_EXT_B_BGA1-IC,TBD    I86 @BASEBOARD_FAB2_LIB.BASEBOARD_FAB2(SCH_1):PAGE34
  U2D1   T7 UPI1_RX_DP<1> SKX_EXT_B_BGA1-IC,TBD   I125 @BASEBOARD_FAB2_LIB.BASEBOARD_FAB2(SCH_1):PAGE68

UPI_CPU0_CPU1_P1P1_DP<2> @BASEBOARD_FAB2_LIB.BASEBOARD_FAB2(SCH_1):UPI_CPU0_CPU1_P1P1_DP(2)
  U5D1  H19 UPI1_TX_DP<17> SKX_EXT_B_BGA1-IC,TBD    I86 @BASEBOARD_FAB2_LIB.BASEBOARD_FAB2(SCH_1):PAGE34
  U2D1   U8 UPI1_RX_DP<2> SKX_EXT_B_BGA1-IC,TBD   I125 @BASEBOARD_FAB2_LIB.BASEBOARD_FAB2(SCH_1):PAGE68

UPI_CPU0_CPU1_P1P1_DP<3> @BASEBOARD_FAB2_LIB.BASEBOARD_FAB2(SCH_1):UPI_CPU0_CPU1_P1P1_DP(3)
  U5D1  J18 UPI1_TX_DP<16> SKX_EXT_B_BGA1-IC,TBD    I86 @BASEBOARD_FAB2_LIB.BASEBOARD_FAB2(SCH_1):PAGE34
  U2D1   R8 UPI1_RX_DP<3> SKX_EXT_B_BGA1-IC,TBD   I125 @BASEBOARD_FAB2_LIB.BASEBOARD_FAB2(SCH_1):PAGE68

UPI_CPU0_CPU1_P1P1_DP<4> @BASEBOARD_FAB2_LIB.BASEBOARD_FAB2(SCH_1):UPI_CPU0_CPU1_P1P1_DP(4)
  U5D1  L18 UPI1_TX_DP<15> SKX_EXT_B_BGA1-IC,TBD    I86 @BASEBOARD_FAB2_LIB.BASEBOARD_FAB2(SCH_1):PAGE34
  U2D1  N10 UPI1_RX_DP<4> SKX_EXT_B_BGA1-IC,TBD   I125 @BASEBOARD_FAB2_LIB.BASEBOARD_FAB2(SCH_1):PAGE68

UPI_CPU0_CPU1_P1P1_DP<5> @BASEBOARD_FAB2_LIB.BASEBOARD_FAB2(SCH_1):UPI_CPU0_CPU1_P1P1_DP(5)
  U5D1  G16 UPI1_TX_DP<14> SKX_EXT_B_BGA1-IC,TBD    I86 @BASEBOARD_FAB2_LIB.BASEBOARD_FAB2(SCH_1):PAGE34
  U2D1  U10 UPI1_RX_DP<5> SKX_EXT_B_BGA1-IC,TBD   I125 @BASEBOARD_FAB2_LIB.BASEBOARD_FAB2(SCH_1):PAGE68

UPI_CPU0_CPU1_P1P1_DP<6> @BASEBOARD_FAB2_LIB.BASEBOARD_FAB2(SCH_1):UPI_CPU0_CPU1_P1P1_DP(6)
  U5D1  H15 UPI1_TX_DP<13> SKX_EXT_B_BGA1-IC,TBD    I86 @BASEBOARD_FAB2_LIB.BASEBOARD_FAB2(SCH_1):PAGE34
  U2D1  T11 UPI1_RX_DP<6> SKX_EXT_B_BGA1-IC,TBD   I125 @BASEBOARD_FAB2_LIB.BASEBOARD_FAB2(SCH_1):PAGE68

UPI_CPU0_CPU1_P1P1_DP<7> @BASEBOARD_FAB2_LIB.BASEBOARD_FAB2(SCH_1):UPI_CPU0_CPU1_P1P1_DP(7)
  U5D1  E14 UPI1_TX_DP<12> SKX_EXT_B_BGA1-IC,TBD    I86 @BASEBOARD_FAB2_LIB.BASEBOARD_FAB2(SCH_1):PAGE34
  U2D1  N12 UPI1_RX_DP<7> SKX_EXT_B_BGA1-IC,TBD   I125 @BASEBOARD_FAB2_LIB.BASEBOARD_FAB2(SCH_1):PAGE68

UPI_CPU0_CPU1_P1P1_DP<8> @BASEBOARD_FAB2_LIB.BASEBOARD_FAB2(SCH_1):UPI_CPU0_CPU1_P1P1_DP(8)
  U5D1  F13 UPI1_TX_DP<11> SKX_EXT_B_BGA1-IC,TBD    I86 @BASEBOARD_FAB2_LIB.BASEBOARD_FAB2(SCH_1):PAGE34
  U2D1  N14 UPI1_RX_DN<8> SKX_EXT_B_BGA1-IC,TBD   I125 @BASEBOARD_FAB2_LIB.BASEBOARD_FAB2(SCH_1):PAGE68

UPI_CPU0_CPU1_P1P1_DP<9> @BASEBOARD_FAB2_LIB.BASEBOARD_FAB2(SCH_1):UPI_CPU0_CPU1_P1P1_DP(9)
  U5D1  G12 UPI1_TX_DP<10> SKX_EXT_B_BGA1-IC,TBD    I86 @BASEBOARD_FAB2_LIB.BASEBOARD_FAB2(SCH_1):PAGE34
  U2D1  P13 UPI1_RX_DP<9> SKX_EXT_B_BGA1-IC,TBD   I125 @BASEBOARD_FAB2_LIB.BASEBOARD_FAB2(SCH_1):PAGE68

UPI_CPU1_CPU0_P0P0_DN<0> @BASEBOARD_FAB2_LIB.BASEBOARD_FAB2(SCH_1):UPI_CPU1_CPU0_P0P0_DN(0)
  U5D1 BB11 UPI0_RX_DN<19> SKX_EXT_B_BGA1-IC,TBD    I86 @BASEBOARD_FAB2_LIB.BASEBOARD_FAB2(SCH_1):PAGE33
  U2D1   M1 UPI0_TX_DP<0> SKX_EXT_B_BGA1-IC,TBD   I132 @BASEBOARD_FAB2_LIB.BASEBOARD_FAB2(SCH_1):PAGE67

UPI_CPU1_CPU0_P0P0_DN<10> @BASEBOARD_FAB2_LIB.BASEBOARD_FAB2(SCH_1):UPI_CPU1_CPU0_P0P0_DN(10)
  U5D1  AM9 UPI0_RX_DN<9> SKX_EXT_B_BGA1-IC,TBD    I86 @BASEBOARD_FAB2_LIB.BASEBOARD_FAB2(SCH_1):PAGE33
  U2D1  AK3 UPI0_TX_DP<10> SKX_EXT_B_BGA1-IC,TBD   I132 @BASEBOARD_FAB2_LIB.BASEBOARD_FAB2(SCH_1):PAGE67

UPI_CPU1_CPU0_P0P0_DN<11> @BASEBOARD_FAB2_LIB.BASEBOARD_FAB2(SCH_1):UPI_CPU1_CPU0_P0P0_DN(11)
  U5D1  AK7 UPI0_RX_DN<8> SKX_EXT_B_BGA1-IC,TBD    I86 @BASEBOARD_FAB2_LIB.BASEBOARD_FAB2(SCH_1):PAGE33
  U2D1  AP3 UPI0_TX_DP<11> SKX_EXT_B_BGA1-IC,TBD   I132 @BASEBOARD_FAB2_LIB.BASEBOARD_FAB2(SCH_1):PAGE67

UPI_CPU1_CPU0_P0P0_DN<12> @BASEBOARD_FAB2_LIB.BASEBOARD_FAB2(SCH_1):UPI_CPU1_CPU0_P0P0_DN(12)
  U5D1  AL6 UPI0_RX_DN<7> SKX_EXT_B_BGA1-IC,TBD    I86 @BASEBOARD_FAB2_LIB.BASEBOARD_FAB2(SCH_1):PAGE33
  U2D1  AP1 UPI0_TX_DP<12> SKX_EXT_B_BGA1-IC,TBD   I132 @BASEBOARD_FAB2_LIB.BASEBOARD_FAB2(SCH_1):PAGE67

UPI_CPU1_CPU0_P0P0_DN<13> @BASEBOARD_FAB2_LIB.BASEBOARD_FAB2(SCH_1):UPI_CPU1_CPU0_P0P0_DN(13)
  U5D1  AJ6 UPI0_RX_DN<6> SKX_EXT_B_BGA1-IC,TBD    I86 @BASEBOARD_FAB2_LIB.BASEBOARD_FAB2(SCH_1):PAGE33
  U2D1  AR2 UPI0_TX_DP<13> SKX_EXT_B_BGA1-IC,TBD   I132 @BASEBOARD_FAB2_LIB.BASEBOARD_FAB2(SCH_1):PAGE67

UPI_CPU1_CPU0_P0P0_DN<14> @BASEBOARD_FAB2_LIB.BASEBOARD_FAB2(SCH_1):UPI_CPU1_CPU0_P0P0_DN(14)
  U5D1  AG8 UPI0_RX_DN<5> SKX_EXT_B_BGA1-IC,TBD    I86 @BASEBOARD_FAB2_LIB.BASEBOARD_FAB2(SCH_1):PAGE33
  U2D1  AR4 UPI0_TX_DP<14> SKX_EXT_B_BGA1-IC,TBD   I132 @BASEBOARD_FAB2_LIB.BASEBOARD_FAB2(SCH_1):PAGE67

UPI_CPU1_CPU0_P0P0_DN<15> @BASEBOARD_FAB2_LIB.BASEBOARD_FAB2(SCH_1):UPI_CPU1_CPU0_P0P0_DN(15)
  U5D1  AE6 UPI0_RX_DN<4> SKX_EXT_B_BGA1-IC,TBD    I86 @BASEBOARD_FAB2_LIB.BASEBOARD_FAB2(SCH_1):PAGE33
  U2D1  AW4 UPI0_TX_DP<15> SKX_EXT_B_BGA1-IC,TBD   I132 @BASEBOARD_FAB2_LIB.BASEBOARD_FAB2(SCH_1):PAGE67

UPI_CPU1_CPU0_P0P0_DN<16> @BASEBOARD_FAB2_LIB.BASEBOARD_FAB2(SCH_1):UPI_CPU1_CPU0_P0P0_DN(16)
  U5D1  AD5 UPI0_RX_DN<3> SKX_EXT_B_BGA1-IC,TBD    I86 @BASEBOARD_FAB2_LIB.BASEBOARD_FAB2(SCH_1):PAGE33
  U2D1  AY3 UPI0_TX_DP<16> SKX_EXT_B_BGA1-IC,TBD   I132 @BASEBOARD_FAB2_LIB.BASEBOARD_FAB2(SCH_1):PAGE67

UPI_CPU1_CPU0_P0P0_DN<17> @BASEBOARD_FAB2_LIB.BASEBOARD_FAB2(SCH_1):UPI_CPU1_CPU0_P0P0_DN(17)
  U5D1  AB7 UPI0_RX_DN<2> SKX_EXT_B_BGA1-IC,TBD    I86 @BASEBOARD_FAB2_LIB.BASEBOARD_FAB2(SCH_1):PAGE33
  U2D1  BB3 UPI0_TX_DN<17> SKX_EXT_B_BGA1-IC,TBD   I132 @BASEBOARD_FAB2_LIB.BASEBOARD_FAB2(SCH_1):PAGE67

UPI_CPU1_CPU0_P0P0_DN<18> @BASEBOARD_FAB2_LIB.BASEBOARD_FAB2(SCH_1):UPI_CPU1_CPU0_P0P0_DN(18)
  U5D1  AA8 UPI0_RX_DN<1> SKX_EXT_B_BGA1-IC,TBD    I86 @BASEBOARD_FAB2_LIB.BASEBOARD_FAB2(SCH_1):PAGE33
  U2D1  BF3 UPI0_TX_DN<18> SKX_EXT_B_BGA1-IC,TBD   I132 @BASEBOARD_FAB2_LIB.BASEBOARD_FAB2(SCH_1):PAGE67

UPI_CPU1_CPU0_P0P0_DN<19> @BASEBOARD_FAB2_LIB.BASEBOARD_FAB2(SCH_1):UPI_CPU1_CPU0_P0P0_DN(19)
  U5D1 AC10 UPI0_RX_DN<0> SKX_EXT_B_BGA1-IC,TBD    I86 @BASEBOARD_FAB2_LIB.BASEBOARD_FAB2(SCH_1):PAGE33
  U2D1  BH3 UPI0_TX_DP<19> SKX_EXT_B_BGA1-IC,TBD   I132 @BASEBOARD_FAB2_LIB.BASEBOARD_FAB2(SCH_1):PAGE67

UPI_CPU1_CPU0_P0P0_DN<1> @BASEBOARD_FAB2_LIB.BASEBOARD_FAB2(SCH_1):UPI_CPU1_CPU0_P0P0_DN(1)
  U5D1  BD9 UPI0_RX_DN<18> SKX_EXT_B_BGA1-IC,TBD    I86 @BASEBOARD_FAB2_LIB.BASEBOARD_FAB2(SCH_1):PAGE33
  U2D1   T1 UPI0_TX_DP<1> SKX_EXT_B_BGA1-IC,TBD   I132 @BASEBOARD_FAB2_LIB.BASEBOARD_FAB2(SCH_1):PAGE67

UPI_CPU1_CPU0_P0P0_DN<2> @BASEBOARD_FAB2_LIB.BASEBOARD_FAB2(SCH_1):UPI_CPU1_CPU0_P0P0_DN(2)
  U5D1  AY9 UPI0_RX_DN<17> SKX_EXT_B_BGA1-IC,TBD    I86 @BASEBOARD_FAB2_LIB.BASEBOARD_FAB2(SCH_1):PAGE33
  U2D1   V3 UPI0_TX_DN<2> SKX_EXT_B_BGA1-IC,TBD   I132 @BASEBOARD_FAB2_LIB.BASEBOARD_FAB2(SCH_1):PAGE67

UPI_CPU1_CPU0_P0P0_DN<3> @BASEBOARD_FAB2_LIB.BASEBOARD_FAB2(SCH_1):UPI_CPU1_CPU0_P0P0_DN(3)
  U5D1  AW8 UPI0_RX_DN<16> SKX_EXT_B_BGA1-IC,TBD    I86 @BASEBOARD_FAB2_LIB.BASEBOARD_FAB2(SCH_1):PAGE33
  U2D1   Y1 UPI0_TX_DN<3> SKX_EXT_B_BGA1-IC,TBD   I132 @BASEBOARD_FAB2_LIB.BASEBOARD_FAB2(SCH_1):PAGE67

UPI_CPU1_CPU0_P0P0_DN<4> @BASEBOARD_FAB2_LIB.BASEBOARD_FAB2(SCH_1):UPI_CPU1_CPU0_P0P0_DN(4)
  U5D1  BD7 UPI0_RX_DN<15> SKX_EXT_B_BGA1-IC,TBD    I86 @BASEBOARD_FAB2_LIB.BASEBOARD_FAB2(SCH_1):PAGE33
  U2D1  AB3 UPI0_TX_DN<4> SKX_EXT_B_BGA1-IC,TBD   I132 @BASEBOARD_FAB2_LIB.BASEBOARD_FAB2(SCH_1):PAGE67

UPI_CPU1_CPU0_P0P0_DN<5> @BASEBOARD_FAB2_LIB.BASEBOARD_FAB2(SCH_1):UPI_CPU1_CPU0_P0P0_DN(5)
  U5D1  BC6 UPI0_RX_DN<14> SKX_EXT_B_BGA1-IC,TBD    I86 @BASEBOARD_FAB2_LIB.BASEBOARD_FAB2(SCH_1):PAGE33
  U2D1  AD1 UPI0_TX_DP<5> SKX_EXT_B_BGA1-IC,TBD   I132 @BASEBOARD_FAB2_LIB.BASEBOARD_FAB2(SCH_1):PAGE67

UPI_CPU1_CPU0_P0P0_DN<6> @BASEBOARD_FAB2_LIB.BASEBOARD_FAB2(SCH_1):UPI_CPU1_CPU0_P0P0_DN(6)
  U5D1  BA8 UPI0_RX_DN<13> SKX_EXT_B_BGA1-IC,TBD    I86 @BASEBOARD_FAB2_LIB.BASEBOARD_FAB2(SCH_1):PAGE33
  U2D1  AG4 UPI0_TX_DN<6> SKX_EXT_B_BGA1-IC,TBD   I132 @BASEBOARD_FAB2_LIB.BASEBOARD_FAB2(SCH_1):PAGE67

UPI_CPU1_CPU0_P0P0_DN<7> @BASEBOARD_FAB2_LIB.BASEBOARD_FAB2(SCH_1):UPI_CPU1_CPU0_P0P0_DN(7)
  U5D1 AU10 UPI0_RX_DN<12> SKX_EXT_B_BGA1-IC,TBD    I86 @BASEBOARD_FAB2_LIB.BASEBOARD_FAB2(SCH_1):PAGE33
  U2D1  AE2 UPI0_TX_DN<7> SKX_EXT_B_BGA1-IC,TBD   I132 @BASEBOARD_FAB2_LIB.BASEBOARD_FAB2(SCH_1):PAGE67

UPI_CPU1_CPU0_P0P0_DN<8> @BASEBOARD_FAB2_LIB.BASEBOARD_FAB2(SCH_1):UPI_CPU1_CPU0_P0P0_DN(8)
  U5D1  AR8 UPI0_RX_DN<11> SKX_EXT_B_BGA1-IC,TBD    I86 @BASEBOARD_FAB2_LIB.BASEBOARD_FAB2(SCH_1):PAGE33
  U2D1  AJ2 UPI0_TX_DP<8> SKX_EXT_B_BGA1-IC,TBD   I132 @BASEBOARD_FAB2_LIB.BASEBOARD_FAB2(SCH_1):PAGE67

UPI_CPU1_CPU0_P0P0_DN<9> @BASEBOARD_FAB2_LIB.BASEBOARD_FAB2(SCH_1):UPI_CPU1_CPU0_P0P0_DN(9)
  U5D1  AP7 UPI0_RX_DN<10> SKX_EXT_B_BGA1-IC,TBD    I86 @BASEBOARD_FAB2_LIB.BASEBOARD_FAB2(SCH_1):PAGE33
  U2D1  AL2 UPI0_TX_DN<9> SKX_EXT_B_BGA1-IC,TBD   I132 @BASEBOARD_FAB2_LIB.BASEBOARD_FAB2(SCH_1):PAGE67

UPI_CPU1_CPU0_P0P0_DP<0> @BASEBOARD_FAB2_LIB.BASEBOARD_FAB2(SCH_1):UPI_CPU1_CPU0_P0P0_DP(0)
  U5D1 BA10 UPI0_RX_DP<19> SKX_EXT_B_BGA1-IC,TBD    I86 @BASEBOARD_FAB2_LIB.BASEBOARD_FAB2(SCH_1):PAGE33
  U2D1   N2 UPI0_TX_DN<0> SKX_EXT_B_BGA1-IC,TBD   I132 @BASEBOARD_FAB2_LIB.BASEBOARD_FAB2(SCH_1):PAGE67

UPI_CPU1_CPU0_P0P0_DP<10> @BASEBOARD_FAB2_LIB.BASEBOARD_FAB2(SCH_1):UPI_CPU1_CPU0_P0P0_DP(10)
  U5D1  AL8 UPI0_RX_DP<9> SKX_EXT_B_BGA1-IC,TBD    I86 @BASEBOARD_FAB2_LIB.BASEBOARD_FAB2(SCH_1):PAGE33
  U2D1  AM3 UPI0_TX_DN<10> SKX_EXT_B_BGA1-IC,TBD   I132 @BASEBOARD_FAB2_LIB.BASEBOARD_FAB2(SCH_1):PAGE67

UPI_CPU1_CPU0_P0P0_DP<11> @BASEBOARD_FAB2_LIB.BASEBOARD_FAB2(SCH_1):UPI_CPU1_CPU0_P0P0_DP(11)
  U5D1  AM7 UPI0_RX_DP<8> SKX_EXT_B_BGA1-IC,TBD    I86 @BASEBOARD_FAB2_LIB.BASEBOARD_FAB2(SCH_1):PAGE33
  U2D1  AN4 UPI0_TX_DN<11> SKX_EXT_B_BGA1-IC,TBD   I132 @BASEBOARD_FAB2_LIB.BASEBOARD_FAB2(SCH_1):PAGE67

UPI_CPU1_CPU0_P0P0_DP<12> @BASEBOARD_FAB2_LIB.BASEBOARD_FAB2(SCH_1):UPI_CPU1_CPU0_P0P0_DP(12)
  U5D1  AK5 UPI0_RX_DP<7> SKX_EXT_B_BGA1-IC,TBD    I86 @BASEBOARD_FAB2_LIB.BASEBOARD_FAB2(SCH_1):PAGE33
  U2D1  AT1 UPI0_TX_DN<12> SKX_EXT_B_BGA1-IC,TBD   I132 @BASEBOARD_FAB2_LIB.BASEBOARD_FAB2(SCH_1):PAGE67

UPI_CPU1_CPU0_P0P0_DP<13> @BASEBOARD_FAB2_LIB.BASEBOARD_FAB2(SCH_1):UPI_CPU1_CPU0_P0P0_DP(13)
  U5D1  AH7 UPI0_RX_DP<6> SKX_EXT_B_BGA1-IC,TBD    I86 @BASEBOARD_FAB2_LIB.BASEBOARD_FAB2(SCH_1):PAGE33
  U2D1  AT3 UPI0_TX_DN<13> SKX_EXT_B_BGA1-IC,TBD   I132 @BASEBOARD_FAB2_LIB.BASEBOARD_FAB2(SCH_1):PAGE67

UPI_CPU1_CPU0_P0P0_DP<14> @BASEBOARD_FAB2_LIB.BASEBOARD_FAB2(SCH_1):UPI_CPU1_CPU0_P0P0_DP(14)
  U5D1  AF7 UPI0_RX_DP<5> SKX_EXT_B_BGA1-IC,TBD    I86 @BASEBOARD_FAB2_LIB.BASEBOARD_FAB2(SCH_1):PAGE33
  U2D1  AU4 UPI0_TX_DN<14> SKX_EXT_B_BGA1-IC,TBD   I132 @BASEBOARD_FAB2_LIB.BASEBOARD_FAB2(SCH_1):PAGE67

UPI_CPU1_CPU0_P0P0_DP<15> @BASEBOARD_FAB2_LIB.BASEBOARD_FAB2(SCH_1):UPI_CPU1_CPU0_P0P0_DP(15)
  U5D1  AG6 UPI0_RX_DP<4> SKX_EXT_B_BGA1-IC,TBD    I86 @BASEBOARD_FAB2_LIB.BASEBOARD_FAB2(SCH_1):PAGE33
  U2D1  AV5 UPI0_TX_DN<15> SKX_EXT_B_BGA1-IC,TBD   I132 @BASEBOARD_FAB2_LIB.BASEBOARD_FAB2(SCH_1):PAGE67

UPI_CPU1_CPU0_P0P0_DP<16> @BASEBOARD_FAB2_LIB.BASEBOARD_FAB2(SCH_1):UPI_CPU1_CPU0_P0P0_DP(16)
  U5D1  AC6 UPI0_RX_DP<3> SKX_EXT_B_BGA1-IC,TBD    I86 @BASEBOARD_FAB2_LIB.BASEBOARD_FAB2(SCH_1):PAGE33
  U2D1  BA4 UPI0_TX_DN<16> SKX_EXT_B_BGA1-IC,TBD   I132 @BASEBOARD_FAB2_LIB.BASEBOARD_FAB2(SCH_1):PAGE67

UPI_CPU1_CPU0_P0P0_DP<17> @BASEBOARD_FAB2_LIB.BASEBOARD_FAB2(SCH_1):UPI_CPU1_CPU0_P0P0_DP(17)
  U5D1  AA6 UPI0_RX_DP<2> SKX_EXT_B_BGA1-IC,TBD    I86 @BASEBOARD_FAB2_LIB.BASEBOARD_FAB2(SCH_1):PAGE33
  U2D1  BC2 UPI0_TX_DP<17> SKX_EXT_B_BGA1-IC,TBD   I132 @BASEBOARD_FAB2_LIB.BASEBOARD_FAB2(SCH_1):PAGE67

UPI_CPU1_CPU0_P0P0_DP<18> @BASEBOARD_FAB2_LIB.BASEBOARD_FAB2(SCH_1):UPI_CPU1_CPU0_P0P0_DP(18)
  U5D1  AC8 UPI0_RX_DP<1> SKX_EXT_B_BGA1-IC,TBD    I86 @BASEBOARD_FAB2_LIB.BASEBOARD_FAB2(SCH_1):PAGE33
  U2D1  BD3 UPI0_TX_DP<18> SKX_EXT_B_BGA1-IC,TBD   I132 @BASEBOARD_FAB2_LIB.BASEBOARD_FAB2(SCH_1):PAGE67

UPI_CPU1_CPU0_P0P0_DP<19> @BASEBOARD_FAB2_LIB.BASEBOARD_FAB2(SCH_1):UPI_CPU1_CPU0_P0P0_DP(19)
  U5D1  AB9 UPI0_RX_DP<0> SKX_EXT_B_BGA1-IC,TBD    I86 @BASEBOARD_FAB2_LIB.BASEBOARD_FAB2(SCH_1):PAGE33
  U2D1  BG4 UPI0_TX_DN<19> SKX_EXT_B_BGA1-IC,TBD   I132 @BASEBOARD_FAB2_LIB.BASEBOARD_FAB2(SCH_1):PAGE67

UPI_CPU1_CPU0_P0P0_DP<1> @BASEBOARD_FAB2_LIB.BASEBOARD_FAB2(SCH_1):UPI_CPU1_CPU0_P0P0_DP(1)
  U5D1 BC10 UPI0_RX_DP<18> SKX_EXT_B_BGA1-IC,TBD    I86 @BASEBOARD_FAB2_LIB.BASEBOARD_FAB2(SCH_1):PAGE33
  U2D1   P1 UPI0_TX_DN<1> SKX_EXT_B_BGA1-IC,TBD   I132 @BASEBOARD_FAB2_LIB.BASEBOARD_FAB2(SCH_1):PAGE67

UPI_CPU1_CPU0_P0P0_DP<2> @BASEBOARD_FAB2_LIB.BASEBOARD_FAB2(SCH_1):UPI_CPU1_CPU0_P0P0_DP(2)
  U5D1  BB9 UPI0_RX_DP<17> SKX_EXT_B_BGA1-IC,TBD    I86 @BASEBOARD_FAB2_LIB.BASEBOARD_FAB2(SCH_1):PAGE33
  U2D1   Y3 UPI0_TX_DP<2> SKX_EXT_B_BGA1-IC,TBD   I132 @BASEBOARD_FAB2_LIB.BASEBOARD_FAB2(SCH_1):PAGE67

UPI_CPU1_CPU0_P0P0_DP<3> @BASEBOARD_FAB2_LIB.BASEBOARD_FAB2(SCH_1):UPI_CPU1_CPU0_P0P0_DP(3)
  U5D1  AV9 UPI0_RX_DP<16> SKX_EXT_B_BGA1-IC,TBD    I86 @BASEBOARD_FAB2_LIB.BASEBOARD_FAB2(SCH_1):PAGE33
  U2D1   W2 UPI0_TX_DP<3> SKX_EXT_B_BGA1-IC,TBD   I132 @BASEBOARD_FAB2_LIB.BASEBOARD_FAB2(SCH_1):PAGE67

UPI_CPU1_CPU0_P0P0_DP<4> @BASEBOARD_FAB2_LIB.BASEBOARD_FAB2(SCH_1):UPI_CPU1_CPU0_P0P0_DP(4)
  U5D1  BF7 UPI0_RX_DP<15> SKX_EXT_B_BGA1-IC,TBD    I86 @BASEBOARD_FAB2_LIB.BASEBOARD_FAB2(SCH_1):PAGE33
  U2D1  AA2 UPI0_TX_DP<4> SKX_EXT_B_BGA1-IC,TBD   I132 @BASEBOARD_FAB2_LIB.BASEBOARD_FAB2(SCH_1):PAGE67

UPI_CPU1_CPU0_P0P0_DP<5> @BASEBOARD_FAB2_LIB.BASEBOARD_FAB2(SCH_1):UPI_CPU1_CPU0_P0P0_DP(5)
  U5D1  BB7 UPI0_RX_DP<14> SKX_EXT_B_BGA1-IC,TBD    I86 @BASEBOARD_FAB2_LIB.BASEBOARD_FAB2(SCH_1):PAGE33
  U2D1  AC2 UPI0_TX_DN<5> SKX_EXT_B_BGA1-IC,TBD   I132 @BASEBOARD_FAB2_LIB.BASEBOARD_FAB2(SCH_1):PAGE67

UPI_CPU1_CPU0_P0P0_DP<6> @BASEBOARD_FAB2_LIB.BASEBOARD_FAB2(SCH_1):UPI_CPU1_CPU0_P0P0_DP(6)
  U5D1  AY7 UPI0_RX_DP<13> SKX_EXT_B_BGA1-IC,TBD    I86 @BASEBOARD_FAB2_LIB.BASEBOARD_FAB2(SCH_1):PAGE33
  U2D1  AF3 UPI0_TX_DP<6> SKX_EXT_B_BGA1-IC,TBD   I132 @BASEBOARD_FAB2_LIB.BASEBOARD_FAB2(SCH_1):PAGE67

UPI_CPU1_CPU0_P0P0_DP<7> @BASEBOARD_FAB2_LIB.BASEBOARD_FAB2(SCH_1):UPI_CPU1_CPU0_P0P0_DP(7)
  U5D1  AT9 UPI0_RX_DP<12> SKX_EXT_B_BGA1-IC,TBD    I86 @BASEBOARD_FAB2_LIB.BASEBOARD_FAB2(SCH_1):PAGE33
  U2D1  AG2 UPI0_TX_DP<7> SKX_EXT_B_BGA1-IC,TBD   I132 @BASEBOARD_FAB2_LIB.BASEBOARD_FAB2(SCH_1):PAGE67

UPI_CPU1_CPU0_P0P0_DP<8> @BASEBOARD_FAB2_LIB.BASEBOARD_FAB2(SCH_1):UPI_CPU1_CPU0_P0P0_DP(8)
  U5D1  AU8 UPI0_RX_DP<11> SKX_EXT_B_BGA1-IC,TBD    I86 @BASEBOARD_FAB2_LIB.BASEBOARD_FAB2(SCH_1):PAGE33
  U2D1  AH3 UPI0_TX_DN<8> SKX_EXT_B_BGA1-IC,TBD   I132 @BASEBOARD_FAB2_LIB.BASEBOARD_FAB2(SCH_1):PAGE67

UPI_CPU1_CPU0_P0P0_DP<9> @BASEBOARD_FAB2_LIB.BASEBOARD_FAB2(SCH_1):UPI_CPU1_CPU0_P0P0_DP(9)
  U5D1  AN8 UPI0_RX_DP<10> SKX_EXT_B_BGA1-IC,TBD    I86 @BASEBOARD_FAB2_LIB.BASEBOARD_FAB2(SCH_1):PAGE33
  U2D1  AK1 UPI0_TX_DP<9> SKX_EXT_B_BGA1-IC,TBD   I132 @BASEBOARD_FAB2_LIB.BASEBOARD_FAB2(SCH_1):PAGE67

UPI_CPU1_CPU0_P1P1_DN<0> @BASEBOARD_FAB2_LIB.BASEBOARD_FAB2(SCH_1):UPI_CPU1_CPU0_P1P1_DN(0)
  U5D1 AB19 UPI1_RX_DN<19> SKX_EXT_B_BGA1-IC,TBD    I86 @BASEBOARD_FAB2_LIB.BASEBOARD_FAB2(SCH_1):PAGE34
  U2D1   P3 UPI1_TX_DP<0> SKX_EXT_B_BGA1-IC,TBD   I125 @BASEBOARD_FAB2_LIB.BASEBOARD_FAB2(SCH_1):PAGE68

UPI_CPU1_CPU0_P1P1_DN<10> @BASEBOARD_FAB2_LIB.BASEBOARD_FAB2(SCH_1):UPI_CPU1_CPU0_P1P1_DN(10)
  U5D1  R12 UPI1_RX_DN<9> SKX_EXT_B_BGA1-IC,TBD    I86 @BASEBOARD_FAB2_LIB.BASEBOARD_FAB2(SCH_1):PAGE34
  U2D1  E12 UPI1_TX_DN<10> SKX_EXT_B_BGA1-IC,TBD   I125 @BASEBOARD_FAB2_LIB.BASEBOARD_FAB2(SCH_1):PAGE68

UPI_CPU1_CPU0_P1P1_DN<11> @BASEBOARD_FAB2_LIB.BASEBOARD_FAB2(SCH_1):UPI_CPU1_CPU0_P1P1_DN(11)
  U5D1  N14 UPI1_RX_DN<8> SKX_EXT_B_BGA1-IC,TBD    I86 @BASEBOARD_FAB2_LIB.BASEBOARD_FAB2(SCH_1):PAGE34
  U2D1  F13 UPI1_TX_DP<11> SKX_EXT_B_BGA1-IC,TBD   I125 @BASEBOARD_FAB2_LIB.BASEBOARD_FAB2(SCH_1):PAGE68

UPI_CPU1_CPU0_P1P1_DN<12> @BASEBOARD_FAB2_LIB.BASEBOARD_FAB2(SCH_1):UPI_CPU1_CPU0_P1P1_DN(12)
  U5D1  L12 UPI1_RX_DN<7> SKX_EXT_B_BGA1-IC,TBD    I86 @BASEBOARD_FAB2_LIB.BASEBOARD_FAB2(SCH_1):PAGE34
  U2D1  D15 UPI1_TX_DN<12> SKX_EXT_B_BGA1-IC,TBD   I125 @BASEBOARD_FAB2_LIB.BASEBOARD_FAB2(SCH_1):PAGE68

UPI_CPU1_CPU0_P1P1_DN<13> @BASEBOARD_FAB2_LIB.BASEBOARD_FAB2(SCH_1):UPI_CPU1_CPU0_P1P1_DN(13)
  U5D1  U12 UPI1_RX_DN<6> SKX_EXT_B_BGA1-IC,TBD    I86 @BASEBOARD_FAB2_LIB.BASEBOARD_FAB2(SCH_1):PAGE34
  U2D1  F15 UPI1_TX_DN<13> SKX_EXT_B_BGA1-IC,TBD   I125 @BASEBOARD_FAB2_LIB.BASEBOARD_FAB2(SCH_1):PAGE68

UPI_CPU1_CPU0_P1P1_DN<14> @BASEBOARD_FAB2_LIB.BASEBOARD_FAB2(SCH_1):UPI_CPU1_CPU0_P1P1_DN(14)
  U5D1  R10 UPI1_RX_DN<5> SKX_EXT_B_BGA1-IC,TBD    I86 @BASEBOARD_FAB2_LIB.BASEBOARD_FAB2(SCH_1):PAGE34
  U2D1  H17 UPI1_TX_DN<14> SKX_EXT_B_BGA1-IC,TBD   I125 @BASEBOARD_FAB2_LIB.BASEBOARD_FAB2(SCH_1):PAGE68

UPI_CPU1_CPU0_P1P1_DN<15> @BASEBOARD_FAB2_LIB.BASEBOARD_FAB2(SCH_1):UPI_CPU1_CPU0_P1P1_DN(15)
  U5D1   P9 UPI1_RX_DN<4> SKX_EXT_B_BGA1-IC,TBD    I86 @BASEBOARD_FAB2_LIB.BASEBOARD_FAB2(SCH_1):PAGE34
  U2D1  K19 UPI1_TX_DN<15> SKX_EXT_B_BGA1-IC,TBD   I125 @BASEBOARD_FAB2_LIB.BASEBOARD_FAB2(SCH_1):PAGE68

UPI_CPU1_CPU0_P1P1_DN<16> @BASEBOARD_FAB2_LIB.BASEBOARD_FAB2(SCH_1):UPI_CPU1_CPU0_P1P1_DN(16)
  U5D1   T9 UPI1_RX_DN<3> SKX_EXT_B_BGA1-IC,TBD    I86 @BASEBOARD_FAB2_LIB.BASEBOARD_FAB2(SCH_1):PAGE34
  U2D1  G18 UPI1_TX_DN<16> SKX_EXT_B_BGA1-IC,TBD   I125 @BASEBOARD_FAB2_LIB.BASEBOARD_FAB2(SCH_1):PAGE68

UPI_CPU1_CPU0_P1P1_DN<17> @BASEBOARD_FAB2_LIB.BASEBOARD_FAB2(SCH_1):UPI_CPU1_CPU0_P1P1_DN(17)
  U5D1   V7 UPI1_RX_DN<2> SKX_EXT_B_BGA1-IC,TBD    I86 @BASEBOARD_FAB2_LIB.BASEBOARD_FAB2(SCH_1):PAGE34
  U2D1  J20 UPI1_TX_DN<17> SKX_EXT_B_BGA1-IC,TBD   I125 @BASEBOARD_FAB2_LIB.BASEBOARD_FAB2(SCH_1):PAGE68

UPI_CPU1_CPU0_P1P1_DN<18> @BASEBOARD_FAB2_LIB.BASEBOARD_FAB2(SCH_1):UPI_CPU1_CPU0_P1P1_DN(18)
  U5D1   P7 UPI1_RX_DN<1> SKX_EXT_B_BGA1-IC,TBD    I86 @BASEBOARD_FAB2_LIB.BASEBOARD_FAB2(SCH_1):PAGE34
  U2D1  G20 UPI1_TX_DP<18> SKX_EXT_B_BGA1-IC,TBD   I125 @BASEBOARD_FAB2_LIB.BASEBOARD_FAB2(SCH_1):PAGE68

UPI_CPU1_CPU0_P1P1_DN<19> @BASEBOARD_FAB2_LIB.BASEBOARD_FAB2(SCH_1):UPI_CPU1_CPU0_P1P1_DN(19)
  U5D1   T5 UPI1_RX_DN<0> SKX_EXT_B_BGA1-IC,TBD    I86 @BASEBOARD_FAB2_LIB.BASEBOARD_FAB2(SCH_1):PAGE34
  U2D1  K21 UPI1_TX_DP<19> SKX_EXT_B_BGA1-IC,TBD   I125 @BASEBOARD_FAB2_LIB.BASEBOARD_FAB2(SCH_1):PAGE68

UPI_CPU1_CPU0_P1P1_DN<1> @BASEBOARD_FAB2_LIB.BASEBOARD_FAB2(SCH_1):UPI_CPU1_CPU0_P1P1_DN(1)
  U5D1  Y21 UPI1_RX_DN<18> SKX_EXT_B_BGA1-IC,TBD    I86 @BASEBOARD_FAB2_LIB.BASEBOARD_FAB2(SCH_1):PAGE34
  U2D1   K3 UPI1_TX_DP<1> SKX_EXT_B_BGA1-IC,TBD   I125 @BASEBOARD_FAB2_LIB.BASEBOARD_FAB2(SCH_1):PAGE68

UPI_CPU1_CPU0_P1P1_DN<2> @BASEBOARD_FAB2_LIB.BASEBOARD_FAB2(SCH_1):UPI_CPU1_CPU0_P1P1_DN(2)
  U5D1  V19 UPI1_RX_DN<17> SKX_EXT_B_BGA1-IC,TBD    I86 @BASEBOARD_FAB2_LIB.BASEBOARD_FAB2(SCH_1):PAGE34
  U2D1   K5 UPI1_TX_DN<2> SKX_EXT_B_BGA1-IC,TBD   I125 @BASEBOARD_FAB2_LIB.BASEBOARD_FAB2(SCH_1):PAGE68

UPI_CPU1_CPU0_P1P1_DN<3> @BASEBOARD_FAB2_LIB.BASEBOARD_FAB2(SCH_1):UPI_CPU1_CPU0_P1P1_DN(3)
  U5D1  P21 UPI1_RX_DN<16> SKX_EXT_B_BGA1-IC,TBD    I86 @BASEBOARD_FAB2_LIB.BASEBOARD_FAB2(SCH_1):PAGE34
  U2D1   J6 UPI1_TX_DN<3> SKX_EXT_B_BGA1-IC,TBD   I125 @BASEBOARD_FAB2_LIB.BASEBOARD_FAB2(SCH_1):PAGE68

UPI_CPU1_CPU0_P1P1_DN<4> @BASEBOARD_FAB2_LIB.BASEBOARD_FAB2(SCH_1):UPI_CPU1_CPU0_P1P1_DN(4)
  U5D1  U18 UPI1_RX_DN<15> SKX_EXT_B_BGA1-IC,TBD    I86 @BASEBOARD_FAB2_LIB.BASEBOARD_FAB2(SCH_1):PAGE34
  U2D1   G6 UPI1_TX_DN<4> SKX_EXT_B_BGA1-IC,TBD   I125 @BASEBOARD_FAB2_LIB.BASEBOARD_FAB2(SCH_1):PAGE68

UPI_CPU1_CPU0_P1P1_DN<5> @BASEBOARD_FAB2_LIB.BASEBOARD_FAB2(SCH_1):UPI_CPU1_CPU0_P1P1_DN(5)
  U5D1  R20 UPI1_RX_DN<14> SKX_EXT_B_BGA1-IC,TBD    I86 @BASEBOARD_FAB2_LIB.BASEBOARD_FAB2(SCH_1):PAGE34
  U2D1   H7 UPI1_TX_DN<5> SKX_EXT_B_BGA1-IC,TBD   I125 @BASEBOARD_FAB2_LIB.BASEBOARD_FAB2(SCH_1):PAGE68

UPI_CPU1_CPU0_P1P1_DN<6> @BASEBOARD_FAB2_LIB.BASEBOARD_FAB2(SCH_1):UPI_CPU1_CPU0_P1P1_DN(6)
  U5D1  W18 UPI1_RX_DN<13> SKX_EXT_B_BGA1-IC,TBD    I86 @BASEBOARD_FAB2_LIB.BASEBOARD_FAB2(SCH_1):PAGE34
  U2D1   J8 UPI1_TX_DP<6> SKX_EXT_B_BGA1-IC,TBD   I125 @BASEBOARD_FAB2_LIB.BASEBOARD_FAB2(SCH_1):PAGE68

UPI_CPU1_CPU0_P1P1_DN<7> @BASEBOARD_FAB2_LIB.BASEBOARD_FAB2(SCH_1):UPI_CPU1_CPU0_P1P1_DN(7)
  U5D1  U16 UPI1_RX_DN<12> SKX_EXT_B_BGA1-IC,TBD    I86 @BASEBOARD_FAB2_LIB.BASEBOARD_FAB2(SCH_1):PAGE34
  U2D1   F9 UPI1_TX_DP<7> SKX_EXT_B_BGA1-IC,TBD   I125 @BASEBOARD_FAB2_LIB.BASEBOARD_FAB2(SCH_1):PAGE68

UPI_CPU1_CPU0_P1P1_DN<8> @BASEBOARD_FAB2_LIB.BASEBOARD_FAB2(SCH_1):UPI_CPU1_CPU0_P1P1_DN(8)
  U5D1  P17 UPI1_RX_DN<11> SKX_EXT_B_BGA1-IC,TBD    I86 @BASEBOARD_FAB2_LIB.BASEBOARD_FAB2(SCH_1):PAGE34
  U2D1  E10 UPI1_TX_DP<8> SKX_EXT_B_BGA1-IC,TBD   I125 @BASEBOARD_FAB2_LIB.BASEBOARD_FAB2(SCH_1):PAGE68

UPI_CPU1_CPU0_P1P1_DN<9> @BASEBOARD_FAB2_LIB.BASEBOARD_FAB2(SCH_1):UPI_CPU1_CPU0_P1P1_DN(9)
  U5D1  R16 UPI1_RX_DN<10> SKX_EXT_B_BGA1-IC,TBD    I86 @BASEBOARD_FAB2_LIB.BASEBOARD_FAB2(SCH_1):PAGE34
  U2D1  G10 UPI1_TX_DN<9> SKX_EXT_B_BGA1-IC,TBD   I125 @BASEBOARD_FAB2_LIB.BASEBOARD_FAB2(SCH_1):PAGE68

UPI_CPU1_CPU0_P1P1_DP<0> @BASEBOARD_FAB2_LIB.BASEBOARD_FAB2(SCH_1):UPI_CPU1_CPU0_P1P1_DP(0)
  U5D1 AA20 UPI1_RX_DP<19> SKX_EXT_B_BGA1-IC,TBD    I86 @BASEBOARD_FAB2_LIB.BASEBOARD_FAB2(SCH_1):PAGE34
  U2D1   M3 UPI1_TX_DN<0> SKX_EXT_B_BGA1-IC,TBD   I125 @BASEBOARD_FAB2_LIB.BASEBOARD_FAB2(SCH_1):PAGE68

UPI_CPU1_CPU0_P1P1_DP<10> @BASEBOARD_FAB2_LIB.BASEBOARD_FAB2(SCH_1):UPI_CPU1_CPU0_P1P1_DP(10)
  U5D1  P13 UPI1_RX_DP<9> SKX_EXT_B_BGA1-IC,TBD    I86 @BASEBOARD_FAB2_LIB.BASEBOARD_FAB2(SCH_1):PAGE34
  U2D1  G12 UPI1_TX_DP<10> SKX_EXT_B_BGA1-IC,TBD   I125 @BASEBOARD_FAB2_LIB.BASEBOARD_FAB2(SCH_1):PAGE68

UPI_CPU1_CPU0_P1P1_DP<11> @BASEBOARD_FAB2_LIB.BASEBOARD_FAB2(SCH_1):UPI_CPU1_CPU0_P1P1_DP(11)
  U5D1  M13 UPI1_RX_DP<8> SKX_EXT_B_BGA1-IC,TBD    I86 @BASEBOARD_FAB2_LIB.BASEBOARD_FAB2(SCH_1):PAGE34
  U2D1  G14 UPI1_TX_DN<11> SKX_EXT_B_BGA1-IC,TBD   I125 @BASEBOARD_FAB2_LIB.BASEBOARD_FAB2(SCH_1):PAGE68

UPI_CPU1_CPU0_P1P1_DP<12> @BASEBOARD_FAB2_LIB.BASEBOARD_FAB2(SCH_1):UPI_CPU1_CPU0_P1P1_DP(12)
  U5D1  N12 UPI1_RX_DP<7> SKX_EXT_B_BGA1-IC,TBD    I86 @BASEBOARD_FAB2_LIB.BASEBOARD_FAB2(SCH_1):PAGE34
  U2D1  E14 UPI1_TX_DP<12> SKX_EXT_B_BGA1-IC,TBD   I125 @BASEBOARD_FAB2_LIB.BASEBOARD_FAB2(SCH_1):PAGE68

UPI_CPU1_CPU0_P1P1_DP<13> @BASEBOARD_FAB2_LIB.BASEBOARD_FAB2(SCH_1):UPI_CPU1_CPU0_P1P1_DP(13)
  U5D1  T11 UPI1_RX_DP<6> SKX_EXT_B_BGA1-IC,TBD    I86 @BASEBOARD_FAB2_LIB.BASEBOARD_FAB2(SCH_1):PAGE34
  U2D1  H15 UPI1_TX_DP<13> SKX_EXT_B_BGA1-IC,TBD   I125 @BASEBOARD_FAB2_LIB.BASEBOARD_FAB2(SCH_1):PAGE68

UPI_CPU1_CPU0_P1P1_DP<14> @BASEBOARD_FAB2_LIB.BASEBOARD_FAB2(SCH_1):UPI_CPU1_CPU0_P1P1_DP(14)
  U5D1  U10 UPI1_RX_DP<5> SKX_EXT_B_BGA1-IC,TBD    I86 @BASEBOARD_FAB2_LIB.BASEBOARD_FAB2(SCH_1):PAGE34
  U2D1  G16 UPI1_TX_DP<14> SKX_EXT_B_BGA1-IC,TBD   I125 @BASEBOARD_FAB2_LIB.BASEBOARD_FAB2(SCH_1):PAGE68

UPI_CPU1_CPU0_P1P1_DP<15> @BASEBOARD_FAB2_LIB.BASEBOARD_FAB2(SCH_1):UPI_CPU1_CPU0_P1P1_DP(15)
  U5D1  N10 UPI1_RX_DP<4> SKX_EXT_B_BGA1-IC,TBD    I86 @BASEBOARD_FAB2_LIB.BASEBOARD_FAB2(SCH_1):PAGE34
  U2D1  L18 UPI1_TX_DP<15> SKX_EXT_B_BGA1-IC,TBD   I125 @BASEBOARD_FAB2_LIB.BASEBOARD_FAB2(SCH_1):PAGE68

UPI_CPU1_CPU0_P1P1_DP<16> @BASEBOARD_FAB2_LIB.BASEBOARD_FAB2(SCH_1):UPI_CPU1_CPU0_P1P1_DP(16)
  U5D1   R8 UPI1_RX_DP<3> SKX_EXT_B_BGA1-IC,TBD    I86 @BASEBOARD_FAB2_LIB.BASEBOARD_FAB2(SCH_1):PAGE34
  U2D1  J18 UPI1_TX_DP<16> SKX_EXT_B_BGA1-IC,TBD   I125 @BASEBOARD_FAB2_LIB.BASEBOARD_FAB2(SCH_1):PAGE68

UPI_CPU1_CPU0_P1P1_DP<17> @BASEBOARD_FAB2_LIB.BASEBOARD_FAB2(SCH_1):UPI_CPU1_CPU0_P1P1_DP(17)
  U5D1   U8 UPI1_RX_DP<2> SKX_EXT_B_BGA1-IC,TBD    I86 @BASEBOARD_FAB2_LIB.BASEBOARD_FAB2(SCH_1):PAGE34
  U2D1  H19 UPI1_TX_DP<17> SKX_EXT_B_BGA1-IC,TBD   I125 @BASEBOARD_FAB2_LIB.BASEBOARD_FAB2(SCH_1):PAGE68

UPI_CPU1_CPU0_P1P1_DP<18> @BASEBOARD_FAB2_LIB.BASEBOARD_FAB2(SCH_1):UPI_CPU1_CPU0_P1P1_DP(18)
  U5D1   T7 UPI1_RX_DP<1> SKX_EXT_B_BGA1-IC,TBD    I86 @BASEBOARD_FAB2_LIB.BASEBOARD_FAB2(SCH_1):PAGE34
  U2D1  F21 UPI1_TX_DN<18> SKX_EXT_B_BGA1-IC,TBD   I125 @BASEBOARD_FAB2_LIB.BASEBOARD_FAB2(SCH_1):PAGE68

UPI_CPU1_CPU0_P1P1_DP<19> @BASEBOARD_FAB2_LIB.BASEBOARD_FAB2(SCH_1):UPI_CPU1_CPU0_P1P1_DP(19)
  U5D1   R6 UPI1_RX_DP<0> SKX_EXT_B_BGA1-IC,TBD    I86 @BASEBOARD_FAB2_LIB.BASEBOARD_FAB2(SCH_1):PAGE34
  U2D1  H21 UPI1_TX_DN<19> SKX_EXT_B_BGA1-IC,TBD   I125 @BASEBOARD_FAB2_LIB.BASEBOARD_FAB2(SCH_1):PAGE68

UPI_CPU1_CPU0_P1P1_DP<1> @BASEBOARD_FAB2_LIB.BASEBOARD_FAB2(SCH_1):UPI_CPU1_CPU0_P1P1_DP(1)
  U5D1  W20 UPI1_RX_DP<18> SKX_EXT_B_BGA1-IC,TBD    I86 @BASEBOARD_FAB2_LIB.BASEBOARD_FAB2(SCH_1):PAGE34
  U2D1   L4 UPI1_TX_DN<1> SKX_EXT_B_BGA1-IC,TBD   I125 @BASEBOARD_FAB2_LIB.BASEBOARD_FAB2(SCH_1):PAGE68

UPI_CPU1_CPU0_P1P1_DP<2> @BASEBOARD_FAB2_LIB.BASEBOARD_FAB2(SCH_1):UPI_CPU1_CPU0_P1P1_DP(2)
  U5D1  Y19 UPI1_RX_DP<17> SKX_EXT_B_BGA1-IC,TBD    I86 @BASEBOARD_FAB2_LIB.BASEBOARD_FAB2(SCH_1):PAGE34
  U2D1   M5 UPI1_TX_DP<2> SKX_EXT_B_BGA1-IC,TBD   I125 @BASEBOARD_FAB2_LIB.BASEBOARD_FAB2(SCH_1):PAGE68

UPI_CPU1_CPU0_P1P1_DP<3> @BASEBOARD_FAB2_LIB.BASEBOARD_FAB2(SCH_1):UPI_CPU1_CPU0_P1P1_DP(3)
  U5D1  T21 UPI1_RX_DP<16> SKX_EXT_B_BGA1-IC,TBD    I86 @BASEBOARD_FAB2_LIB.BASEBOARD_FAB2(SCH_1):PAGE34
  U2D1   H5 UPI1_TX_DP<3> SKX_EXT_B_BGA1-IC,TBD   I125 @BASEBOARD_FAB2_LIB.BASEBOARD_FAB2(SCH_1):PAGE68

UPI_CPU1_CPU0_P1P1_DP<4> @BASEBOARD_FAB2_LIB.BASEBOARD_FAB2(SCH_1):UPI_CPU1_CPU0_P1P1_DP(4)
  U5D1  T19 UPI1_RX_DP<15> SKX_EXT_B_BGA1-IC,TBD    I86 @BASEBOARD_FAB2_LIB.BASEBOARD_FAB2(SCH_1):PAGE34
  U2D1   F7 UPI1_TX_DP<4> SKX_EXT_B_BGA1-IC,TBD   I125 @BASEBOARD_FAB2_LIB.BASEBOARD_FAB2(SCH_1):PAGE68

UPI_CPU1_CPU0_P1P1_DP<5> @BASEBOARD_FAB2_LIB.BASEBOARD_FAB2(SCH_1):UPI_CPU1_CPU0_P1P1_DP(5)
  U5D1  P19 UPI1_RX_DP<14> SKX_EXT_B_BGA1-IC,TBD    I86 @BASEBOARD_FAB2_LIB.BASEBOARD_FAB2(SCH_1):PAGE34
  U2D1   K7 UPI1_TX_DP<5> SKX_EXT_B_BGA1-IC,TBD   I125 @BASEBOARD_FAB2_LIB.BASEBOARD_FAB2(SCH_1):PAGE68

UPI_CPU1_CPU0_P1P1_DP<6> @BASEBOARD_FAB2_LIB.BASEBOARD_FAB2(SCH_1):UPI_CPU1_CPU0_P1P1_DP(6)
  U5D1  V17 UPI1_RX_DP<13> SKX_EXT_B_BGA1-IC,TBD    I86 @BASEBOARD_FAB2_LIB.BASEBOARD_FAB2(SCH_1):PAGE34
  U2D1   K9 UPI1_TX_DN<6> SKX_EXT_B_BGA1-IC,TBD   I125 @BASEBOARD_FAB2_LIB.BASEBOARD_FAB2(SCH_1):PAGE68

UPI_CPU1_CPU0_P1P1_DP<7> @BASEBOARD_FAB2_LIB.BASEBOARD_FAB2(SCH_1):UPI_CPU1_CPU0_P1P1_DP(7)
  U5D1  W16 UPI1_RX_DP<12> SKX_EXT_B_BGA1-IC,TBD    I86 @BASEBOARD_FAB2_LIB.BASEBOARD_FAB2(SCH_1):PAGE34
  U2D1   D9 UPI1_TX_DN<7> SKX_EXT_B_BGA1-IC,TBD   I125 @BASEBOARD_FAB2_LIB.BASEBOARD_FAB2(SCH_1):PAGE68

UPI_CPU1_CPU0_P1P1_DP<8> @BASEBOARD_FAB2_LIB.BASEBOARD_FAB2(SCH_1):UPI_CPU1_CPU0_P1P1_DP(8)
  U5D1  N16 UPI1_RX_DP<11> SKX_EXT_B_BGA1-IC,TBD    I86 @BASEBOARD_FAB2_LIB.BASEBOARD_FAB2(SCH_1):PAGE34
  U2D1  F11 UPI1_TX_DN<8> SKX_EXT_B_BGA1-IC,TBD   I125 @BASEBOARD_FAB2_LIB.BASEBOARD_FAB2(SCH_1):PAGE68

UPI_CPU1_CPU0_P1P1_DP<9> @BASEBOARD_FAB2_LIB.BASEBOARD_FAB2(SCH_1):UPI_CPU1_CPU0_P1P1_DP(9)
  U5D1  T15 UPI1_RX_DP<10> SKX_EXT_B_BGA1-IC,TBD    I86 @BASEBOARD_FAB2_LIB.BASEBOARD_FAB2(SCH_1):PAGE34
  U2D1   H9 UPI1_TX_DP<9> SKX_EXT_B_BGA1-IC,TBD   I125 @BASEBOARD_FAB2_LIB.BASEBOARD_FAB2(SCH_1):PAGE68

USB2_P01_DN @BASEBOARD_FAB2_LIB.BASEBOARD_FAB2(SCH_1):USB2_P01_DN
  U7C1 BY60 USB2N_1 LBG_CORE_QAT_EXT_D_BGA1-IC,H91A    I74 @BASEBOARD_FAB2_LIB.BASEBOARD_FAB2(SCH_1):PAGE115
  L1M2    1     A1 CHOKE_4PIN_SMLF-90 OHM,EMPTY,7A    I30 @BASEBOARD_FAB2_LIB.BASEBOARD_FAB2(SCH_1):PAGE176
  R1M6    1      A RES_0402-0.0,5%,1/16W,CHIP,G21A    I31 @BASEBOARD_FAB2_LIB.BASEBOARD_FAB2(SCH_1):PAGE176

USB2_P01_DP @BASEBOARD_FAB2_LIB.BASEBOARD_FAB2(SCH_1):USB2_P01_DP
  U7C1 BV60 USB2P_1 LBG_CORE_QAT_EXT_D_BGA1-IC,H91A    I74 @BASEBOARD_FAB2_LIB.BASEBOARD_FAB2(SCH_1):PAGE115
  R1M5    1      A RES_0402-0.0,5%,1/16W,CHIP,G21A    I16 @BASEBOARD_FAB2_LIB.BASEBOARD_FAB2(SCH_1):PAGE176
  L1M2    2     A2 CHOKE_4PIN_SMLF-90 OHM,EMPTY,7A    I30 @BASEBOARD_FAB2_LIB.BASEBOARD_FAB2(SCH_1):PAGE176

USB2_P01_ESD_DN @BASEBOARD_FAB2_LIB.BASEBOARD_FAB2(SCH_1):USB2_P01_ESD_DN
  L1M2    4     B2 CHOKE_4PIN_SMLF-90 OHM,EMPTY,7A    I30 @BASEBOARD_FAB2_LIB.BASEBOARD_FAB2(SCH_1):PAGE176
  R1M6    2      B RES_0402-0.0,5%,1/16W,CHIP,G21A    I31 @BASEBOARD_FAB2_LIB.BASEBOARD_FAB2(SCH_1):PAGE176
  J9B1    2     DN CONN9_H51826001_PIP2-CONN,H518A    I69 @BASEBOARD_FAB2_LIB.BASEBOARD_FAB2(SCH_1):PAGE176
 CR1M2    2    AC1 DIODEAC_DUAL_ARRAY_SM9-ESD3V3UA    I98 @BASEBOARD_FAB2_LIB.BASEBOARD_FAB2(SCH_1):PAGE176
 CR1M2    8   OUT1 DIODEAC_DUAL_ARRAY_SM9-ESD3V3UA    I98 @BASEBOARD_FAB2_LIB.BASEBOARD_FAB2(SCH_1):PAGE176

USB2_P01_ESD_DP @BASEBOARD_FAB2_LIB.BASEBOARD_FAB2(SCH_1):USB2_P01_ESD_DP
  R1M5    2      B RES_0402-0.0,5%,1/16W,CHIP,G21A    I16 @BASEBOARD_FAB2_LIB.BASEBOARD_FAB2(SCH_1):PAGE176
  L1M2    3     B1 CHOKE_4PIN_SMLF-90 OHM,EMPTY,7A    I30 @BASEBOARD_FAB2_LIB.BASEBOARD_FAB2(SCH_1):PAGE176
  J9B1    3     DP CONN9_H51826001_PIP2-CONN,H518A    I69 @BASEBOARD_FAB2_LIB.BASEBOARD_FAB2(SCH_1):PAGE176
 CR1M2    1    AC0 DIODEAC_DUAL_ARRAY_SM9-ESD3V3UA    I98 @BASEBOARD_FAB2_LIB.BASEBOARD_FAB2(SCH_1):PAGE176
 CR1M2    9   OUT0 DIODEAC_DUAL_ARRAY_SM9-ESD3V3UA    I98 @BASEBOARD_FAB2_LIB.BASEBOARD_FAB2(SCH_1):PAGE176

USB2_P02_DN @BASEBOARD_FAB2_LIB.BASEBOARD_FAB2(SCH_1):USB2_P02_DN
  U7C1 CA61 USB2N_2 LBG_CORE_QAT_EXT_D_BGA1-IC,H91A    I74 @BASEBOARD_FAB2_LIB.BASEBOARD_FAB2(SCH_1):PAGE115
 CONX8   59     59 SMC-CONN60A-22-GP_CONN-G7-SMC-A    I48 @BASEBOARD_FAB2_LIB.BASEBOARD_FAB2(SCH_1):PAGE245

USB2_P02_DP @BASEBOARD_FAB2_LIB.BASEBOARD_FAB2(SCH_1):USB2_P02_DP
  U7C1 BW61 USB2P_2 LBG_CORE_QAT_EXT_D_BGA1-IC,H91A    I74 @BASEBOARD_FAB2_LIB.BASEBOARD_FAB2(SCH_1):PAGE115
 CONX8   57     57 SMC-CONN60A-22-GP_CONN-G7-SMC-A    I48 @BASEBOARD_FAB2_LIB.BASEBOARD_FAB2(SCH_1):PAGE245

USB2_PCH_BMC_P5_DN @BASEBOARD_FAB2_LIB.BASEBOARD_FAB2(SCH_1):USB2_PCH_BMC_P5_DN
  U7C1 BY58 USB2N_5 LBG_CORE_QAT_EXT_D_BGA1-IC,H91A    I74 @BASEBOARD_FAB2_LIB.BASEBOARD_FAB2(SCH_1):PAGE115
 U25W4   A8 USB2A_DN AST2520A1-GP-GP_ASIC2-GB1-AST2A   I104 @BASEBOARD_FAB2_LIB.BASEBOARD_FAB2(SCH_1):PAGE146

USB2_PCH_BMC_P5_DP @BASEBOARD_FAB2_LIB.BASEBOARD_FAB2(SCH_1):USB2_PCH_BMC_P5_DP
  U7C1 BV58 USB2P_5 LBG_CORE_QAT_EXT_D_BGA1-IC,H91A    I74 @BASEBOARD_FAB2_LIB.BASEBOARD_FAB2(SCH_1):PAGE115
 U25W4   A7 USB2A_DP AST2520A1-GP-GP_ASIC2-GB1-AST2A   I104 @BASEBOARD_FAB2_LIB.BASEBOARD_FAB2(SCH_1):PAGE146

USB3_P01_RXN @BASEBOARD_FAB2_LIB.BASEBOARD_FAB2(SCH_1):USB3_P01_RXN
  U7C1 BK71 USB3_1_RXN LBG_CORE_QAT_EXT_D_BGA1-IC,H91A    I74 @BASEBOARD_FAB2_LIB.BASEBOARD_FAB2(SCH_1):PAGE115

USB3_P01_RXP @BASEBOARD_FAB2_LIB.BASEBOARD_FAB2(SCH_1):USB3_P01_RXP
  U7C1 BK69 USB3_1_RXP LBG_CORE_QAT_EXT_D_BGA1-IC,H91A    I74 @BASEBOARD_FAB2_LIB.BASEBOARD_FAB2(SCH_1):PAGE115

USB3_P01_TXN @BASEBOARD_FAB2_LIB.BASEBOARD_FAB2(SCH_1):USB3_P01_TXN
  U7C1 BL52 USB3_1_TXN LBG_CORE_QAT_EXT_D_BGA1-IC,H91A    I74 @BASEBOARD_FAB2_LIB.BASEBOARD_FAB2(SCH_1):PAGE115

USB3_P01_TXP @BASEBOARD_FAB2_LIB.BASEBOARD_FAB2(SCH_1):USB3_P01_TXP
  U7C1 BK54 USB3_1_TXP LBG_CORE_QAT_EXT_D_BGA1-IC,H91A    I74 @BASEBOARD_FAB2_LIB.BASEBOARD_FAB2(SCH_1):PAGE115

USB_PCH_BMC_P4_DN @BASEBOARD_FAB2_LIB.BASEBOARD_FAB2(SCH_1):USB_PCH_BMC_P4_DN
  U7C1 BY62 USB2N_4 LBG_CORE_QAT_EXT_D_BGA1-IC,H91A    I74 @BASEBOARD_FAB2_LIB.BASEBOARD_FAB2(SCH_1):PAGE115
 U25W4   A6 USB2B_DN AST2520A1-GP-GP_ASIC2-GB1-AST2A   I104 @BASEBOARD_FAB2_LIB.BASEBOARD_FAB2(SCH_1):PAGE146

USB_PCH_BMC_P4_DP @BASEBOARD_FAB2_LIB.BASEBOARD_FAB2(SCH_1):USB_PCH_BMC_P4_DP
  U7C1 BV62 USB2P_4 LBG_CORE_QAT_EXT_D_BGA1-IC,H91A    I74 @BASEBOARD_FAB2_LIB.BASEBOARD_FAB2(SCH_1):PAGE115
 R1U52    2      B RES_0402-1.5K,1%,1/16W,CHIP,G2A    I51 @BASEBOARD_FAB2_LIB.BASEBOARD_FAB2(SCH_1):PAGE146
 U25W4   B6 USB2B_DP AST2520A1-GP-GP_ASIC2-GB1-AST2A   I104 @BASEBOARD_FAB2_LIB.BASEBOARD_FAB2(SCH_1):PAGE146

UV_HIGH_SET_N @BASEBOARD_FAB2_LIB.BASEBOARD_FAB2(SCH_1):UV_HIGH_SET_N
  Q6W1    3    DRN FET_N_SOT23LF-2N7002,FET,C7925A   I225 @BASEBOARD_FAB2_LIB.BASEBOARD_FAB2(SCH_1):PAGE200
  R6W3    1      1 232KR2F-2-GP_SMD-RG1-232KR2F-2A   I239 @BASEBOARD_FAB2_LIB.BASEBOARD_FAB2(SCH_1):PAGE200

VCCBAT_TW12 @BASEBOARD_FAB2_LIB.BASEBOARD_FAB2(SCH_1):VCCBAT_TW12
R25W59    2      B RES_0402-0.0,5%,1/16W,CHIP,G21A    I16 @BASEBOARD_FAB2_LIB.BASEBOARD_FAB2(SCH_1):PAGE148
 U25W4   E4 BATVDD AST2520A1-GP-GP_ASIC2-GB1-AST2A    I28 @BASEBOARD_FAB2_LIB.BASEBOARD_FAB2(SCH_1):PAGE148

VCC_ADCAV3V3 @BASEBOARD_FAB2_LIB.BASEBOARD_FAB2(SCH_1):VCC_ADCAV3V3
C25W33    1      A CAP_0402-1.0UF,6.3V,10%,X6S,D9A    I59 @BASEBOARD_FAB2_LIB.BASEBOARD_FAB2(SCH_1):PAGE150
 FB2T3    2      2 HCB1608KF-800T30-GP_DISCRET-G9A    I76 @BASEBOARD_FAB2_LIB.BASEBOARD_FAB2(SCH_1):PAGE150
C25W32    1      A CAP_0402-1.0UF,6.3V,10%,X6S,D9A    I78 @BASEBOARD_FAB2_LIB.BASEBOARD_FAB2(SCH_1):PAGE150
C25W31    1      1 SCD1U16V2KX-3GP_SMD-BCG-SCD1U1A    I79 @BASEBOARD_FAB2_LIB.BASEBOARD_FAB2(SCH_1):PAGE150
 C25W7    2      B CAP_0402-0.1UF,16V,10%,EMPTY,AA    I36 @BASEBOARD_FAB2_LIB.BASEBOARD_FAB2(SCH_1):PAGE147
 U25W4   J6 ADCAV33 AST2520A1-GP-GP_ASIC2-GB1-AST2A    I28 @BASEBOARD_FAB2_LIB.BASEBOARD_FAB2(SCH_1):PAGE148

VCC_A_1V1 @BASEBOARD_FAB2_LIB.BASEBOARD_FAB2(SCH_1):VCC_A_1V1
C25W39    1      1 SC4D7U10V3KX-GP_SMD-BCG-SC4D7UA    I17 @BASEBOARD_FAB2_LIB.BASEBOARD_FAB2(SCH_1):PAGE150
C25W38    1      1 SCD1U16V2KX-3GP_SMD-BCG-SCD1U1A    I18 @BASEBOARD_FAB2_LIB.BASEBOARD_FAB2(SCH_1):PAGE150
C25W37    1      A CAP_0402-1.0UF,6.3V,10%,X6S,D9A    I35 @BASEBOARD_FAB2_LIB.BASEBOARD_FAB2(SCH_1):PAGE150
 FB2T7    2      2 HCB1608KF-800T30-GP_DISCRET-G9A    I39 @BASEBOARD_FAB2_LIB.BASEBOARD_FAB2(SCH_1):PAGE150
 U25W4   L5 VPLLAV110 AST2520A1-GP-GP_ASIC2-GB1-AST2A    I28 @BASEBOARD_FAB2_LIB.BASEBOARD_FAB2(SCH_1):PAGE148
 U25W4   L6 VPLLAV111 AST2520A1-GP-GP_ASIC2-GB1-AST2A    I28 @BASEBOARD_FAB2_LIB.BASEBOARD_FAB2(SCH_1):PAGE148

VCC_DACAV3V3 @BASEBOARD_FAB2_LIB.BASEBOARD_FAB2(SCH_1):VCC_DACAV3V3
C25W36    1      1 SC4D7U10V3KX-GP_SMD-BCG-SC4D7UA    I50 @BASEBOARD_FAB2_LIB.BASEBOARD_FAB2(SCH_1):PAGE150
C25W35    1      A CAP_0402-1.0UF,6.3V,10%,X6S,D9A    I51 @BASEBOARD_FAB2_LIB.BASEBOARD_FAB2(SCH_1):PAGE150
C25W34    1      1 SCD1U16V2KX-3GP_SMD-BCG-SCD1U1A    I53 @BASEBOARD_FAB2_LIB.BASEBOARD_FAB2(SCH_1):PAGE150
R25W93    2      2 0R3J-0-U-GP_RCL_GP-0R3J-0-U-GPA    I57 @BASEBOARD_FAB2_LIB.BASEBOARD_FAB2(SCH_1):PAGE150
 U25W4   K6 DACAV33 AST2520A1-GP-GP_ASIC2-GB1-AST2A    I28 @BASEBOARD_FAB2_LIB.BASEBOARD_FAB2(SCH_1):PAGE148
 U25W4   K5 DACDV33 AST2520A1-GP-GP_ASIC2-GB1-AST2A    I28 @BASEBOARD_FAB2_LIB.BASEBOARD_FAB2(SCH_1):PAGE148

VCC_D_3V3 @BASEBOARD_FAB2_LIB.BASEBOARD_FAB2(SCH_1):VCC_D_3V3
C25W47    1      1 SC4D7U10V3KX-GP_SMD-BCG-SC4D7UA    I54 @BASEBOARD_FAB2_LIB.BASEBOARD_FAB2(SCH_1):PAGE150
C25W46    1      A CAP_0805-10UF,16V,10%,X6S,C953A    I55 @BASEBOARD_FAB2_LIB.BASEBOARD_FAB2(SCH_1):PAGE150
C25W45    1      1 SCD1U16V2KX-3GP_SMD-BCG-SCD1U1A    I61 @BASEBOARD_FAB2_LIB.BASEBOARD_FAB2(SCH_1):PAGE150
C25W44    1      A CAP_0402-1.0UF,6.3V,10%,X6S,D9A    I62 @BASEBOARD_FAB2_LIB.BASEBOARD_FAB2(SCH_1):PAGE150
C25W43    1      A CAP_0402-1.0UF,6.3V,10%,X6S,D9A    I63 @BASEBOARD_FAB2_LIB.BASEBOARD_FAB2(SCH_1):PAGE150
C25W42    1      A CAP_0402-1.0UF,6.3V,10%,X6S,D9A    I80 @BASEBOARD_FAB2_LIB.BASEBOARD_FAB2(SCH_1):PAGE150
C25W41    1      A CAP_0402-1.0UF,6.3V,10%,X6S,D9A    I81 @BASEBOARD_FAB2_LIB.BASEBOARD_FAB2(SCH_1):PAGE150
C25W40    1      A CAP_0402-1.0UF,6.3V,10%,X6S,D9A    I82 @BASEBOARD_FAB2_LIB.BASEBOARD_FAB2(SCH_1):PAGE150
 FB2T4    2      2 HCB1608KF-800T30-GP_DISCRET-G9A    I84 @BASEBOARD_FAB2_LIB.BASEBOARD_FAB2(SCH_1):PAGE150
 U25W4  L16 PEAV33 AST2520A1-GP-GP_ASIC2-GB1-AST2A    I28 @BASEBOARD_FAB2_LIB.BASEBOARD_FAB2(SCH_1):PAGE148
 U25W4  F12 PV33D0 AST2520A1-GP-GP_ASIC2-GB1-AST2A    I28 @BASEBOARD_FAB2_LIB.BASEBOARD_FAB2(SCH_1):PAGE148
 U25W4  F13 PV33D1 AST2520A1-GP-GP_ASIC2-GB1-AST2A    I28 @BASEBOARD_FAB2_LIB.BASEBOARD_FAB2(SCH_1):PAGE148
 U25W4  F14 PV33D2 AST2520A1-GP-GP_ASIC2-GB1-AST2A    I28 @BASEBOARD_FAB2_LIB.BASEBOARD_FAB2(SCH_1):PAGE148
 U25W4  F15 PV33D3 AST2520A1-GP-GP_ASIC2-GB1-AST2A    I28 @BASEBOARD_FAB2_LIB.BASEBOARD_FAB2(SCH_1):PAGE148
 U25W4  G16 PV33D4 AST2520A1-GP-GP_ASIC2-GB1-AST2A    I28 @BASEBOARD_FAB2_LIB.BASEBOARD_FAB2(SCH_1):PAGE148
 U25W4  H17 PV33D5 AST2520A1-GP-GP_ASIC2-GB1-AST2A    I28 @BASEBOARD_FAB2_LIB.BASEBOARD_FAB2(SCH_1):PAGE148
 U25W4   K7 PV33D6 AST2520A1-GP-GP_ASIC2-GB1-AST2A    I28 @BASEBOARD_FAB2_LIB.BASEBOARD_FAB2(SCH_1):PAGE148
 U25W4  N17 PV33D7 AST2520A1-GP-GP_ASIC2-GB1-AST2A    I28 @BASEBOARD_FAB2_LIB.BASEBOARD_FAB2(SCH_1):PAGE148
 U25W4   N6 PV33D8 AST2520A1-GP-GP_ASIC2-GB1-AST2A    I28 @BASEBOARD_FAB2_LIB.BASEBOARD_FAB2(SCH_1):PAGE148
 U25W4  P17 PV33D9 AST2520A1-GP-GP_ASIC2-GB1-AST2A    I28 @BASEBOARD_FAB2_LIB.BASEBOARD_FAB2(SCH_1):PAGE148
 U25W4   P6 PV33D10 AST2520A1-GP-GP_ASIC2-GB1-AST2A    I28 @BASEBOARD_FAB2_LIB.BASEBOARD_FAB2(SCH_1):PAGE148
 U25W4  R17 PV33D11 AST2520A1-GP-GP_ASIC2-GB1-AST2A    I28 @BASEBOARD_FAB2_LIB.BASEBOARD_FAB2(SCH_1):PAGE148
 U25W4   R6 PV33D12 AST2520A1-GP-GP_ASIC2-GB1-AST2A    I28 @BASEBOARD_FAB2_LIB.BASEBOARD_FAB2(SCH_1):PAGE148
 U25W4  T15 PV33D14 AST2520A1-GP-GP_ASIC2-GB1-AST2A    I28 @BASEBOARD_FAB2_LIB.BASEBOARD_FAB2(SCH_1):PAGE148

VCC_D_PLL_3V3 @BASEBOARD_FAB2_LIB.BASEBOARD_FAB2(SCH_1):VCC_D_PLL_3V3
C25W65    1      1 SC4D7U10V3KX-GP_SMD-BCG-SC4D7UA     I2 @BASEBOARD_FAB2_LIB.BASEBOARD_FAB2(SCH_1):PAGE150
C25W64    1      1 SCD1U16V2KX-3GP_SMD-BCG-SCD1U1A    I24 @BASEBOARD_FAB2_LIB.BASEBOARD_FAB2(SCH_1):PAGE150
C25W63    1      A CAP_0402-1.0UF,6.3V,10%,X6S,D9A    I25 @BASEBOARD_FAB2_LIB.BASEBOARD_FAB2(SCH_1):PAGE150
 FB2T6    2      2 HCB1608KF-800T30-GP_DISCRET-G9A    I26 @BASEBOARD_FAB2_LIB.BASEBOARD_FAB2(SCH_1):PAGE150
 U25W4  T11 PV33D13 AST2520A1-GP-GP_ASIC2-GB1-AST2A    I28 @BASEBOARD_FAB2_LIB.BASEBOARD_FAB2(SCH_1):PAGE148

VCC_PA_3V3 @BASEBOARD_FAB2_LIB.BASEBOARD_FAB2(SCH_1):VCC_PA_3V3
C25W59    1      1 SC4D7U10V3KX-GP_SMD-BCG-SC4D7UA    I69 @BASEBOARD_FAB2_LIB.BASEBOARD_FAB2(SCH_1):PAGE150
C25W58    1      1 SCD1U16V2KX-3GP_SMD-BCG-SCD1U1A    I85 @BASEBOARD_FAB2_LIB.BASEBOARD_FAB2(SCH_1):PAGE150
C25W57    1      A CAP_0402-1.0UF,6.3V,10%,X6S,D9A    I86 @BASEBOARD_FAB2_LIB.BASEBOARD_FAB2(SCH_1):PAGE150
C25W56    1      A CAP_0402-1.0UF,6.3V,10%,X6S,D9A    I87 @BASEBOARD_FAB2_LIB.BASEBOARD_FAB2(SCH_1):PAGE150
 FB2T5    2      2 HCB1608KF-800T30-GP_DISCRET-G9A    I89 @BASEBOARD_FAB2_LIB.BASEBOARD_FAB2(SCH_1):PAGE150
 U25W4  Y17 PLLAV330 AST2520A1-GP-GP_ASIC2-GB1-AST2A    I28 @BASEBOARD_FAB2_LIB.BASEBOARD_FAB2(SCH_1):PAGE148
 U25W4  W17 PLLAV331 AST2520A1-GP-GP_ASIC2-GB1-AST2A    I28 @BASEBOARD_FAB2_LIB.BASEBOARD_FAB2(SCH_1):PAGE148

VCC_VA_3V3 @BASEBOARD_FAB2_LIB.BASEBOARD_FAB2(SCH_1):VCC_VA_3V3
C25W69    1      1 SC4D7U10V3KX-GP_SMD-BCG-SC4D7UA    I28 @BASEBOARD_FAB2_LIB.BASEBOARD_FAB2(SCH_1):PAGE150
C25W68    1      1 SCD1U16V2KX-3GP_SMD-BCG-SCD1U1A    I30 @BASEBOARD_FAB2_LIB.BASEBOARD_FAB2(SCH_1):PAGE150
C25W67    1      A CAP_0402-1.0UF,6.3V,10%,X6S,D9A    I31 @BASEBOARD_FAB2_LIB.BASEBOARD_FAB2(SCH_1):PAGE150
 FB2T1    2      2 HCB1608KF-800T30-GP_DISCRET-G9A    I32 @BASEBOARD_FAB2_LIB.BASEBOARD_FAB2(SCH_1):PAGE150
C25W66    1      A CAP_0402-1.0UF,6.3V,10%,X6S,D9A    I33 @BASEBOARD_FAB2_LIB.BASEBOARD_FAB2(SCH_1):PAGE150
 U25W4   J7 VPLLAV330 AST2520A1-GP-GP_ASIC2-GB1-AST2A    I28 @BASEBOARD_FAB2_LIB.BASEBOARD_FAB2(SCH_1):PAGE148
 U25W4   H7 VPLLAV331 AST2520A1-GP-GP_ASIC2-GB1-AST2A    I28 @BASEBOARD_FAB2_LIB.BASEBOARD_FAB2(SCH_1):PAGE148

VID_PCH_CORE_PVNN_AUX_VID_0 @BASEBOARD_FAB2_LIB.BASEBOARD_FAB2(SCH_1):VID_PCH_CORE_PVNN_AUX_VID_0
  U7C1  BL7 GPP_B0_CORE_VID0 LBG_CORE_QAT_EXT_D_BGA1-IC,H91A   I115 @BASEBOARD_FAB2_LIB.BASEBOARD_FAB2(SCH_1):PAGE119
 EU8A1   13    MP0 PXE1110B_QFN-IC,H89187-001   I229 @BASEBOARD_FAB2_LIB.BASEBOARD_FAB2(SCH_1):PAGE235
 R2L26    2      B RES_0402-100.0K,1%,1/16W,EMPTYA   I236 @BASEBOARD_FAB2_LIB.BASEBOARD_FAB2(SCH_1):PAGE235

VID_PCH_CORE_PVNN_AUX_VID_1 @BASEBOARD_FAB2_LIB.BASEBOARD_FAB2(SCH_1):VID_PCH_CORE_PVNN_AUX_VID_1
  U7C1  BH9 GPP_B1_CORE_VID1 LBG_CORE_QAT_EXT_D_BGA1-IC,H91A   I115 @BASEBOARD_FAB2_LIB.BASEBOARD_FAB2(SCH_1):PAGE119
 EU8A1   14    MP1 PXE1110B_QFN-IC,H89187-001   I229 @BASEBOARD_FAB2_LIB.BASEBOARD_FAB2(SCH_1):PAGE235
 R2L25    2      B RES_0402-100.0K,1%,1/16W,EMPTYA   I235 @BASEBOARD_FAB2_LIB.BASEBOARD_FAB2(SCH_1):PAGE235

VREF_2V2 @BASEBOARD_FAB2_LIB.BASEBOARD_FAB2(SCH_1):VREF_2V2
  R3W9    1      A RES_0402-10.0K,1%,1/16W,CHIP,GA     I7 @BASEBOARD_FAB2_LIB.BASEBOARD_FAB2(SCH_1):PAGE249
  R3W7    2      B RES_0402-4.75K,1%,1/16W,CHIP,GA     I8 @BASEBOARD_FAB2_LIB.BASEBOARD_FAB2(SCH_1):PAGE249
  Q9W4    3    -IN LMV331IDCKRG4-GP_DISCRET-G-LMVA    I15 @BASEBOARD_FAB2_LIB.BASEBOARD_FAB2(SCH_1):PAGE249

VR_COMP_PVPP_ABC @BASEBOARD_FAB2_LIB.BASEBOARD_FAB2(SCH_1):VR_COMP_PVPP_ABC
 R7F17    2      B RES_0402-1.0K,0.1%,1/16W,CHIP,A   I218 @BASEBOARD_FAB2_LIB.BASEBOARD_FAB2(SCH_1):PAGE231
 C7F13    1      A CAP_0402LF-2200PF,50V,10%,X7R,A   I219 @BASEBOARD_FAB2_LIB.BASEBOARD_FAB2(SCH_1):PAGE231

VR_COMP_PVPP_ABC_3 @BASEBOARD_FAB2_LIB.BASEBOARD_FAB2(SCH_1):VR_COMP_PVPP_ABC_3
 EU7F1    3   COMP NCP3232L_SM-IC,H86355-001   I193 @BASEBOARD_FAB2_LIB.BASEBOARD_FAB2(SCH_1):PAGE231
  C7F9    2      B CAP_0402LF-100.0PF,50V,5%,COG,A   I199 @BASEBOARD_FAB2_LIB.BASEBOARD_FAB2(SCH_1):PAGE231
 C7F12    2      B CAP_0402LF-2200PF,50V,10%,X7R,A   I200 @BASEBOARD_FAB2_LIB.BASEBOARD_FAB2(SCH_1):PAGE231

VR_COMP_PVPP_DEF @BASEBOARD_FAB2_LIB.BASEBOARD_FAB2(SCH_1):VR_COMP_PVPP_DEF
 R7B18    2      B RES_0402-1.0K,0.1%,1/16W,CHIP,A   I298 @BASEBOARD_FAB2_LIB.BASEBOARD_FAB2(SCH_1):PAGE232
 C7B13    1      A CAP_0402LF-2200PF,50V,10%,X7R,A   I302 @BASEBOARD_FAB2_LIB.BASEBOARD_FAB2(SCH_1):PAGE232

VR_COMP_PVPP_DEF_3 @BASEBOARD_FAB2_LIB.BASEBOARD_FAB2(SCH_1):VR_COMP_PVPP_DEF_3
 EU7B1    3   COMP NCP3232L_SM-IC,H86355-001   I214 @BASEBOARD_FAB2_LIB.BASEBOARD_FAB2(SCH_1):PAGE232
 C7B10    2      B CAP_0402LF-100.0PF,50V,5%,COG,A   I301 @BASEBOARD_FAB2_LIB.BASEBOARD_FAB2(SCH_1):PAGE232
 C7B14    2      B CAP_0402LF-2200PF,50V,10%,X7R,A   I306 @BASEBOARD_FAB2_LIB.BASEBOARD_FAB2(SCH_1):PAGE232

VR_COMP_PVPP_GHJ @BASEBOARD_FAB2_LIB.BASEBOARD_FAB2(SCH_1):VR_COMP_PVPP_GHJ
 R4G10    2      B RES_0402-1.0K,0.1%,1/16W,CHIP,A   I266 @BASEBOARD_FAB2_LIB.BASEBOARD_FAB2(SCH_1):PAGE233
 C4G11    1      A CAP_0402LF-2200PF,50V,10%,X7R,A   I267 @BASEBOARD_FAB2_LIB.BASEBOARD_FAB2(SCH_1):PAGE233

VR_COMP_PVPP_GHJ_3 @BASEBOARD_FAB2_LIB.BASEBOARD_FAB2(SCH_1):VR_COMP_PVPP_GHJ_3
 EU4G1    3   COMP NCP3232L_SM-IC,H86355-001   I225 @BASEBOARD_FAB2_LIB.BASEBOARD_FAB2(SCH_1):PAGE233
  C4G6    2      B CAP_0402LF-100.0PF,50V,5%,COG,A   I273 @BASEBOARD_FAB2_LIB.BASEBOARD_FAB2(SCH_1):PAGE233
 C4G10    2      B CAP_0402LF-2200PF,50V,10%,X7R,A   I274 @BASEBOARD_FAB2_LIB.BASEBOARD_FAB2(SCH_1):PAGE233

VR_COMP_PVPP_KLM @BASEBOARD_FAB2_LIB.BASEBOARD_FAB2(SCH_1):VR_COMP_PVPP_KLM
  C4B7    1      A CAP_0402LF-2200PF,50V,10%,X7R,A   I218 @BASEBOARD_FAB2_LIB.BASEBOARD_FAB2(SCH_1):PAGE234
  R4B9    2      B RES_0402-1.0K,0.1%,1/16W,CHIP,A   I219 @BASEBOARD_FAB2_LIB.BASEBOARD_FAB2(SCH_1):PAGE234

VR_COMP_PVPP_KLM_3 @BASEBOARD_FAB2_LIB.BASEBOARD_FAB2(SCH_1):VR_COMP_PVPP_KLM_3
 EU4A3    3   COMP NCP3232L_SM-IC,H86355-001   I184 @BASEBOARD_FAB2_LIB.BASEBOARD_FAB2(SCH_1):PAGE234
  C4B9    2      B CAP_0402LF-2200PF,50V,10%,X7R,A   I211 @BASEBOARD_FAB2_LIB.BASEBOARD_FAB2(SCH_1):PAGE234
  C4B4    2      B CAP_0402LF-100.0PF,50V,5%,COG,A   I212 @BASEBOARD_FAB2_LIB.BASEBOARD_FAB2(SCH_1):PAGE234

VR_COMP_RC_PVPP_ABC @BASEBOARD_FAB2_LIB.BASEBOARD_FAB2(SCH_1):VR_COMP_RC_PVPP_ABC
 C7F12    1      A CAP_0402LF-2200PF,50V,10%,X7R,A   I200 @BASEBOARD_FAB2_LIB.BASEBOARD_FAB2(SCH_1):PAGE231
 R7F18    1      A RES_0402-7.87K,1.0%,1/16W,CHIPA   I201 @BASEBOARD_FAB2_LIB.BASEBOARD_FAB2(SCH_1):PAGE231

VR_COMP_RC_PVPP_DEF @BASEBOARD_FAB2_LIB.BASEBOARD_FAB2(SCH_1):VR_COMP_RC_PVPP_DEF
 R7B16    1      A RES_0402-7.87K,1.0%,1/16W,CHIPA   I300 @BASEBOARD_FAB2_LIB.BASEBOARD_FAB2(SCH_1):PAGE232
 C7B14    1      A CAP_0402LF-2200PF,50V,10%,X7R,A   I306 @BASEBOARD_FAB2_LIB.BASEBOARD_FAB2(SCH_1):PAGE232

VR_COMP_RC_PVPP_GHJ @BASEBOARD_FAB2_LIB.BASEBOARD_FAB2(SCH_1):VR_COMP_RC_PVPP_GHJ
 R4G13    1      A RES_0402-7.87K,1.0%,1/16W,CHIPA   I272 @BASEBOARD_FAB2_LIB.BASEBOARD_FAB2(SCH_1):PAGE233
 C4G10    1      A CAP_0402LF-2200PF,50V,10%,X7R,A   I274 @BASEBOARD_FAB2_LIB.BASEBOARD_FAB2(SCH_1):PAGE233

VR_COMP_RC_PVPP_KLM @BASEBOARD_FAB2_LIB.BASEBOARD_FAB2(SCH_1):VR_COMP_RC_PVPP_KLM
  C4B9    1      A CAP_0402LF-2200PF,50V,10%,X7R,A   I211 @BASEBOARD_FAB2_LIB.BASEBOARD_FAB2(SCH_1):PAGE234
  R4B8    1      A RES_0402-7.87K,1.0%,1/16W,CHIPA   I213 @BASEBOARD_FAB2_LIB.BASEBOARD_FAB2(SCH_1):PAGE234

VR_FB_PVPP_ABC @BASEBOARD_FAB2_LIB.BASEBOARD_FAB2(SCH_1):VR_FB_PVPP_ABC
 R7F11    1      A RES_0402-6.34K,1%,1/16W,CHIP,GA   I166 @BASEBOARD_FAB2_LIB.BASEBOARD_FAB2(SCH_1):PAGE231
 R7F13    2      B RES_0402-20.0K,1%,1/16W,CHIP,GA   I167 @BASEBOARD_FAB2_LIB.BASEBOARD_FAB2(SCH_1):PAGE231
 EU7F1    2     FB NCP3232L_SM-IC,H86355-001   I193 @BASEBOARD_FAB2_LIB.BASEBOARD_FAB2(SCH_1):PAGE231
  C7F9    1      A CAP_0402LF-100.0PF,50V,5%,COG,A   I199 @BASEBOARD_FAB2_LIB.BASEBOARD_FAB2(SCH_1):PAGE231
 R7F18    2      B RES_0402-7.87K,1.0%,1/16W,CHIPA   I201 @BASEBOARD_FAB2_LIB.BASEBOARD_FAB2(SCH_1):PAGE231
 C7F13    2      B CAP_0402LF-2200PF,50V,10%,X7R,A   I219 @BASEBOARD_FAB2_LIB.BASEBOARD_FAB2(SCH_1):PAGE231

VR_FB_PVPP_DEF @BASEBOARD_FAB2_LIB.BASEBOARD_FAB2(SCH_1):VR_FB_PVPP_DEF
 EU7B1    2     FB NCP3232L_SM-IC,H86355-001   I214 @BASEBOARD_FAB2_LIB.BASEBOARD_FAB2(SCH_1):PAGE232
 R7B16    2      B RES_0402-7.87K,1.0%,1/16W,CHIPA   I300 @BASEBOARD_FAB2_LIB.BASEBOARD_FAB2(SCH_1):PAGE232
 C7B10    1      A CAP_0402LF-100.0PF,50V,5%,COG,A   I301 @BASEBOARD_FAB2_LIB.BASEBOARD_FAB2(SCH_1):PAGE232
 C7B13    2      B CAP_0402LF-2200PF,50V,10%,X7R,A   I302 @BASEBOARD_FAB2_LIB.BASEBOARD_FAB2(SCH_1):PAGE232
 R7B15    2      B RES_0402-20.0K,1%,1/16W,CHIP,GA   I303 @BASEBOARD_FAB2_LIB.BASEBOARD_FAB2(SCH_1):PAGE232
 R7B13    1      A RES_0402-6.34K,1%,1/16W,CHIP,GA   I304 @BASEBOARD_FAB2_LIB.BASEBOARD_FAB2(SCH_1):PAGE232

VR_FB_PVPP_GHJ @BASEBOARD_FAB2_LIB.BASEBOARD_FAB2(SCH_1):VR_FB_PVPP_GHJ
 EU4G1    2     FB NCP3232L_SM-IC,H86355-001   I225 @BASEBOARD_FAB2_LIB.BASEBOARD_FAB2(SCH_1):PAGE233
 C4G11    2      B CAP_0402LF-2200PF,50V,10%,X7R,A   I267 @BASEBOARD_FAB2_LIB.BASEBOARD_FAB2(SCH_1):PAGE233
  R4G9    1      A RES_0402-6.34K,1%,1/16W,CHIP,GA   I269 @BASEBOARD_FAB2_LIB.BASEBOARD_FAB2(SCH_1):PAGE233
  R4G7    2      B RES_0402-20.0K,1%,1/16W,CHIP,GA   I270 @BASEBOARD_FAB2_LIB.BASEBOARD_FAB2(SCH_1):PAGE233
 R4G13    2      B RES_0402-7.87K,1.0%,1/16W,CHIPA   I272 @BASEBOARD_FAB2_LIB.BASEBOARD_FAB2(SCH_1):PAGE233
  C4G6    1      A CAP_0402LF-100.0PF,50V,5%,COG,A   I273 @BASEBOARD_FAB2_LIB.BASEBOARD_FAB2(SCH_1):PAGE233

VR_FB_PVPP_KLM @BASEBOARD_FAB2_LIB.BASEBOARD_FAB2(SCH_1):VR_FB_PVPP_KLM
 EU4A3    2     FB NCP3232L_SM-IC,H86355-001   I184 @BASEBOARD_FAB2_LIB.BASEBOARD_FAB2(SCH_1):PAGE234
  C4B4    1      A CAP_0402LF-100.0PF,50V,5%,COG,A   I212 @BASEBOARD_FAB2_LIB.BASEBOARD_FAB2(SCH_1):PAGE234
  R4B8    2      B RES_0402-7.87K,1.0%,1/16W,CHIPA   I213 @BASEBOARD_FAB2_LIB.BASEBOARD_FAB2(SCH_1):PAGE234
  R4B5    2      B RES_0402-20.0K,1%,1/16W,CHIP,GA   I215 @BASEBOARD_FAB2_LIB.BASEBOARD_FAB2(SCH_1):PAGE234
  R4B4    1      A RES_0402-6.34K,1%,1/16W,CHIP,GA   I216 @BASEBOARD_FAB2_LIB.BASEBOARD_FAB2(SCH_1):PAGE234
  C4B7    2      B CAP_0402LF-2200PF,50V,10%,X7R,A   I218 @BASEBOARD_FAB2_LIB.BASEBOARD_FAB2(SCH_1):PAGE234

VR_FET_SW_P12V_PVCCIN_CPU0_R @BASEBOARD_FAB2_LIB.BASEBOARD_FAB2(SCH_1):VR_FET_SW_P12V_PVCCIN_CPU0_R
  R4C6    1      A RES_2010-0.001,1%,1W,CHIP,E309A    I45 @BASEBOARD_FAB2_LIB.BASEBOARD_FAB2(SCH_1):PAGE204
  L4C1    2    INB INDUCTOR_SM-100NH,IND,D92183-0A    I46 @BASEBOARD_FAB2_LIB.BASEBOARD_FAB2(SCH_1):PAGE204
  C4C2    1      A CAP_A_0402V-0.1UF,16V,10%,EMPTA    I51 @BASEBOARD_FAB2_LIB.BASEBOARD_FAB2(SCH_1):PAGE204
  U4C1    4    RSP ADM4073_SM-EMPTY,G12194-001    I53 @BASEBOARD_FAB2_LIB.BASEBOARD_FAB2(SCH_1):PAGE204
  U4C1    3    VCC ADM4073_SM-EMPTY,G12194-001    I53 @BASEBOARD_FAB2_LIB.BASEBOARD_FAB2(SCH_1):PAGE204

VR_FET_SW_P12V_PVCCIN_CPU1_R @BASEBOARD_FAB2_LIB.BASEBOARD_FAB2(SCH_1):VR_FET_SW_P12V_PVCCIN_CPU1_R
 C1B16    1      A CAP_A_0402V-0.1UF,16V,10%,EMPTA    I30 @BASEBOARD_FAB2_LIB.BASEBOARD_FAB2(SCH_1):PAGE209
  L1B2    2    INB INDUCTOR_SM-100NH,IND,D92183-0A    I32 @BASEBOARD_FAB2_LIB.BASEBOARD_FAB2(SCH_1):PAGE209
 R1B20    1      A RES_2010-0.001,1%,1W,CHIP,E309A    I39 @BASEBOARD_FAB2_LIB.BASEBOARD_FAB2(SCH_1):PAGE209
  U1B3    4    RSP ADM4073_SM-EMPTY,G12194-001    I52 @BASEBOARD_FAB2_LIB.BASEBOARD_FAB2(SCH_1):PAGE209
  U1B3    3    VCC ADM4073_SM-EMPTY,G12194-001    I52 @BASEBOARD_FAB2_LIB.BASEBOARD_FAB2(SCH_1):PAGE209

VR_FET_SW_P12V_STBY_P3V3_STBY @BASEBOARD_FAB2_LIB.BASEBOARD_FAB2(SCH_1):VR_FET_SW_P12V_STBY_P3V3_STBY
 FB9E1    2      B FERRITE_SM-22,FB,656554-051   I132 @BASEBOARD_FAB2_LIB.BASEBOARD_FAB2(SCH_1):PAGE240
  C9F1    1      A CAP_1210-47UF,16V,20%,X6S,D384A   I134 @BASEBOARD_FAB2_LIB.BASEBOARD_FAB2(SCH_1):PAGE240
 C8E11    1      A CAP_1210-47UF,16V,20%,X6S,D384A   I135 @BASEBOARD_FAB2_LIB.BASEBOARD_FAB2(SCH_1):PAGE240
 C8E10    1      A CAP_1206LF-22UF,16V,10%,X6S,D3A   I137 @BASEBOARD_FAB2_LIB.BASEBOARD_FAB2(SCH_1):PAGE240
 C8E14    1      A CAP_0402-1.0UF,16V,10%,X6S,D97A   I139 @BASEBOARD_FAB2_LIB.BASEBOARD_FAB2(SCH_1):PAGE240
 EU8E1    2    VIN CSD87384M_SM-IC,H66258-001   I170 @BASEBOARD_FAB2_LIB.BASEBOARD_FAB2(SCH_1):PAGE240

VR_FET_SW_P12V_STBY_PVCCIN_CPU0 @BASEBOARD_FAB2_LIB.BASEBOARD_FAB2(SCH_1):VR_FET_SW_P12V_STBY_PVCCIN_CPU0
 R4D27    1      A RES_0402-100.0K,1%,1/16W,CHIP,B    I54 @BASEBOARD_FAB2_LIB.BASEBOARD_FAB2(SCH_1):PAGE201
 C4E20    1      A CAP_A_0402V-0.1UF,16V,10%,X7R,A    I35 @BASEBOARD_FAB2_LIB.BASEBOARD_FAB2(SCH_1):PAGE202
 C4E19    1      A CAP_0402-1.0UF,16V,10%,X6S,D97A    I36 @BASEBOARD_FAB2_LIB.BASEBOARD_FAB2(SCH_1):PAGE202
 C6R11    1      A CAP_0805-10UF,16V,10%,X6S,C953A    I37 @BASEBOARD_FAB2_LIB.BASEBOARD_FAB2(SCH_1):PAGE202
 C6P13    1      A CAP_0805-10UF,16V,10%,X6S,C953A    I38 @BASEBOARD_FAB2_LIB.BASEBOARD_FAB2(SCH_1):PAGE202
 C6R13    1      A CAP_0805-10UF,16V,10%,X6S,C953A    I42 @BASEBOARD_FAB2_LIB.BASEBOARD_FAB2(SCH_1):PAGE202
 C4D49    1      A CAP_A_0402V-0.1UF,16V,10%,X7R,A    I46 @BASEBOARD_FAB2_LIB.BASEBOARD_FAB2(SCH_1):PAGE202
 C4D48    1      A CAP_0402-1.0UF,16V,10%,X6S,D97A    I47 @BASEBOARD_FAB2_LIB.BASEBOARD_FAB2(SCH_1):PAGE202
  C6R4    1      A CAP_0805-10UF,16V,10%,X6S,C953A    I48 @BASEBOARD_FAB2_LIB.BASEBOARD_FAB2(SCH_1):PAGE202
 C6P22    1      A CAP_0805-10UF,16V,10%,X6S,C953A    I49 @BASEBOARD_FAB2_LIB.BASEBOARD_FAB2(SCH_1):PAGE202
  C6N8    1      A CAP_0805-10UF,16V,10%,X6S,C953A    I51 @BASEBOARD_FAB2_LIB.BASEBOARD_FAB2(SCH_1):PAGE202
 EU4E1   25 VIN<0> IR354XX_SM-IR35411,IC,H73688-0A    I63 @BASEBOARD_FAB2_LIB.BASEBOARD_FAB2(SCH_1):PAGE202
 EU4E1   30 VIN<1> IR354XX_SM-IR35411,IC,H73688-0A    I63 @BASEBOARD_FAB2_LIB.BASEBOARD_FAB2(SCH_1):PAGE202
 EU4D6   25 VIN<0> IR354XX_SM-IR35411,IC,H73688-0A    I64 @BASEBOARD_FAB2_LIB.BASEBOARD_FAB2(SCH_1):PAGE202
 EU4D6   30 VIN<1> IR354XX_SM-IR35411,IC,H73688-0A    I64 @BASEBOARD_FAB2_LIB.BASEBOARD_FAB2(SCH_1):PAGE202
 C6P24    1      A CAP_0805-10UF,16V,10%,X6S,C953A     I1 @BASEBOARD_FAB2_LIB.BASEBOARD_FAB2(SCH_1):PAGE203
  C6R6    1      A CAP_0805-10UF,16V,10%,X6S,C953A     I2 @BASEBOARD_FAB2_LIB.BASEBOARD_FAB2(SCH_1):PAGE203
 C4D35    1      A CAP_A_0402V-0.1UF,16V,10%,X7R,A    I46 @BASEBOARD_FAB2_LIB.BASEBOARD_FAB2(SCH_1):PAGE203
 C4D30    1      A CAP_0402-1.0UF,16V,10%,X6S,D97A    I47 @BASEBOARD_FAB2_LIB.BASEBOARD_FAB2(SCH_1):PAGE203
 C4D11    1      A CAP_A_0402V-0.1UF,16V,10%,X7R,A    I52 @BASEBOARD_FAB2_LIB.BASEBOARD_FAB2(SCH_1):PAGE203
 C4D10    1      A CAP_0402-1.0UF,16V,10%,X6S,D97A    I53 @BASEBOARD_FAB2_LIB.BASEBOARD_FAB2(SCH_1):PAGE203
 C6P19    1      A CAP_0805-10UF,16V,10%,X6S,C953A    I54 @BASEBOARD_FAB2_LIB.BASEBOARD_FAB2(SCH_1):PAGE203
 C6P20    1      A CAP_0805-10UF,16V,10%,X6S,C953A    I57 @BASEBOARD_FAB2_LIB.BASEBOARD_FAB2(SCH_1):PAGE203
 C6P15    1      A CAP_0805-10UF,16V,10%,X6S,C953A    I58 @BASEBOARD_FAB2_LIB.BASEBOARD_FAB2(SCH_1):PAGE203
  C6P7    1      A CAP_0805-10UF,16V,10%,X6S,C953A    I59 @BASEBOARD_FAB2_LIB.BASEBOARD_FAB2(SCH_1):PAGE203
 EU4D3   25 VIN<0> IR354XX_SM-IR35411,IC,H73688-0A    I70 @BASEBOARD_FAB2_LIB.BASEBOARD_FAB2(SCH_1):PAGE203
 EU4D3   30 VIN<1> IR354XX_SM-IR35411,IC,H73688-0A    I70 @BASEBOARD_FAB2_LIB.BASEBOARD_FAB2(SCH_1):PAGE203
 EU4D1   25 VIN<0> IR354XX_SM-IR35411,IC,H73688-0A    I71 @BASEBOARD_FAB2_LIB.BASEBOARD_FAB2(SCH_1):PAGE203
 EU4D1   30 VIN<1> IR354XX_SM-IR35411,IC,H73688-0A    I71 @BASEBOARD_FAB2_LIB.BASEBOARD_FAB2(SCH_1):PAGE203
 C4C19    1      A CAP_A_0402V-0.1UF,16V,10%,X7R,A    I35 @BASEBOARD_FAB2_LIB.BASEBOARD_FAB2(SCH_1):PAGE204
 C4C18    1      A CAP_0402-1.0UF,16V,10%,X6S,D97A    I36 @BASEBOARD_FAB2_LIB.BASEBOARD_FAB2(SCH_1):PAGE204
 C6N10    1      A CAP_0805-10UF,16V,10%,X6S,C953A    I37 @BASEBOARD_FAB2_LIB.BASEBOARD_FAB2(SCH_1):PAGE204
 C6P17    1      A CAP_0805-10UF,16V,10%,X6S,C953A    I38 @BASEBOARD_FAB2_LIB.BASEBOARD_FAB2(SCH_1):PAGE204
 C6N11    1      A CAP_0805-10UF,16V,10%,X6S,C953A    I42 @BASEBOARD_FAB2_LIB.BASEBOARD_FAB2(SCH_1):PAGE204
  R4C6    2      B RES_2010-0.001,1%,1W,CHIP,E309A    I45 @BASEBOARD_FAB2_LIB.BASEBOARD_FAB2(SCH_1):PAGE204
  C4D2    1      A CAPP_2626-270UF,16V,20%,OSCON,A    I48 @BASEBOARD_FAB2_LIB.BASEBOARD_FAB2(SCH_1):PAGE204
 C4E16    1      A CAPP_2626-270UF,16V,20%,OSCON,A    I50 @BASEBOARD_FAB2_LIB.BASEBOARD_FAB2(SCH_1):PAGE204
  U4C1    5    RSN ADM4073_SM-EMPTY,G12194-001    I53 @BASEBOARD_FAB2_LIB.BASEBOARD_FAB2(SCH_1):PAGE204
 C4C12    1      A CAPP_2626-270UF,16V,20%,OSCON,A    I67 @BASEBOARD_FAB2_LIB.BASEBOARD_FAB2(SCH_1):PAGE204
 EU4C2   25 VIN<0> IR354XX_SM-IR35411,IC,H73688-0A    I71 @BASEBOARD_FAB2_LIB.BASEBOARD_FAB2(SCH_1):PAGE204
 EU4C2   30 VIN<1> IR354XX_SM-IR35411,IC,H73688-0A    I71 @BASEBOARD_FAB2_LIB.BASEBOARD_FAB2(SCH_1):PAGE204
 C4C10    1      A CAP_A_0402V-0.1UF,16V,10%,X7R,A    I31 @BASEBOARD_FAB2_LIB.BASEBOARD_FAB2(SCH_1):PAGE205
  C4C9    1      A CAP_0402-1.0UF,16V,10%,X6S,D97A    I32 @BASEBOARD_FAB2_LIB.BASEBOARD_FAB2(SCH_1):PAGE205
  C6N2    1      A CAP_0805-10UF,16V,10%,X6S,C953A    I33 @BASEBOARD_FAB2_LIB.BASEBOARD_FAB2(SCH_1):PAGE205
  C6N3    1      A CAP_0805-10UF,16V,10%,X6S,C953A    I34 @BASEBOARD_FAB2_LIB.BASEBOARD_FAB2(SCH_1):PAGE205
  C6N6    1      A CAP_0805-10UF,16V,10%,X6S,C953A    I35 @BASEBOARD_FAB2_LIB.BASEBOARD_FAB2(SCH_1):PAGE205
 EU4C1   25 VIN<0> IR354XX_SM-IR35412,IC,H73684-0A    I46 @BASEBOARD_FAB2_LIB.BASEBOARD_FAB2(SCH_1):PAGE205
 EU4C1   30 VIN<1> IR354XX_SM-IR35412,IC,H73684-0A    I46 @BASEBOARD_FAB2_LIB.BASEBOARD_FAB2(SCH_1):PAGE205
 R4D60    1      A RES_0402-100.0K,1%,1/16W,CHIP,B    I31 @BASEBOARD_FAB2_LIB.BASEBOARD_FAB2(SCH_1):PAGE213
  C4E9    1      A CAP_1210-100UF,16V,20%,X5R,644A     I8 @BASEBOARD_FAB2_LIB.BASEBOARD_FAB2(SCH_1):PAGE214
  C4E8    1      A CAP_1210-100UF,16V,20%,X5R,644A    I29 @BASEBOARD_FAB2_LIB.BASEBOARD_FAB2(SCH_1):PAGE214
 C4E14    1      A CAP_1210-100UF,16V,20%,X5R,644A    I31 @BASEBOARD_FAB2_LIB.BASEBOARD_FAB2(SCH_1):PAGE214
 C4E13    1      A CAP_A_0402V-0.1UF,16V,10%,X7R,A    I77 @BASEBOARD_FAB2_LIB.BASEBOARD_FAB2(SCH_1):PAGE214
 C4E15    1      A CAP_0402-1.0UF,16V,10%,X6S,D97A    I79 @BASEBOARD_FAB2_LIB.BASEBOARD_FAB2(SCH_1):PAGE214
 C6R14    1      A CAP_0805-10UF,16V,10%,X6S,C953A    I80 @BASEBOARD_FAB2_LIB.BASEBOARD_FAB2(SCH_1):PAGE214
 C6R10    1      A CAP_0805-10UF,16V,10%,X6S,C953A    I81 @BASEBOARD_FAB2_LIB.BASEBOARD_FAB2(SCH_1):PAGE214
  C6R8    1      A CAP_0805-10UF,16V,10%,X6S,C953A    I83 @BASEBOARD_FAB2_LIB.BASEBOARD_FAB2(SCH_1):PAGE214
 EU4E2   25 VIN<0> IR354XX_SM-IR35412,IC,H73684-0A   I126 @BASEBOARD_FAB2_LIB.BASEBOARD_FAB2(SCH_1):PAGE214
 EU4E2   30 VIN<1> IR354XX_SM-IR35412,IC,H73684-0A   I126 @BASEBOARD_FAB2_LIB.BASEBOARD_FAB2(SCH_1):PAGE214

VR_FET_SW_P12V_STBY_PVCCIN_CPU1 @BASEBOARD_FAB2_LIB.BASEBOARD_FAB2(SCH_1):VR_FET_SW_P12V_STBY_PVCCIN_CPU1
 R1C13    1      A RES_0402-100.0K,1%,1/16W,CHIP,B    I49 @BASEBOARD_FAB2_LIB.BASEBOARD_FAB2(SCH_1):PAGE206
 EU1E2   25 VIN<0> IR354XX_SM-IR35411,IC,H73688-0A    I20 @BASEBOARD_FAB2_LIB.BASEBOARD_FAB2(SCH_1):PAGE207
 EU1E2   30 VIN<1> IR354XX_SM-IR35411,IC,H73688-0A    I20 @BASEBOARD_FAB2_LIB.BASEBOARD_FAB2(SCH_1):PAGE207
 EU1D4   25 VIN<0> IR354XX_SM-IR35411,IC,H73688-0A    I24 @BASEBOARD_FAB2_LIB.BASEBOARD_FAB2(SCH_1):PAGE207
 EU1D4   30 VIN<1> IR354XX_SM-IR35411,IC,H73688-0A    I24 @BASEBOARD_FAB2_LIB.BASEBOARD_FAB2(SCH_1):PAGE207
 C1E14    1      A CAP_A_0402V-0.1UF,16V,10%,X7R,A    I33 @BASEBOARD_FAB2_LIB.BASEBOARD_FAB2(SCH_1):PAGE207
 C1E13    1      A CAP_0402-1.0UF,16V,10%,X6S,D97A    I34 @BASEBOARD_FAB2_LIB.BASEBOARD_FAB2(SCH_1):PAGE207
 C1D34    1      A CAP_A_0402V-0.1UF,16V,10%,X7R,A    I41 @BASEBOARD_FAB2_LIB.BASEBOARD_FAB2(SCH_1):PAGE207
 C1D35    1      A CAP_0402-1.0UF,16V,10%,X6S,D97A    I42 @BASEBOARD_FAB2_LIB.BASEBOARD_FAB2(SCH_1):PAGE207
  C9R7    1      A CAP_0805-10UF,16V,10%,X6S,C953A    I43 @BASEBOARD_FAB2_LIB.BASEBOARD_FAB2(SCH_1):PAGE207
 C9R10    1      A CAP_0805-10UF,16V,10%,X6S,C953A    I44 @BASEBOARD_FAB2_LIB.BASEBOARD_FAB2(SCH_1):PAGE207
 C9R11    1      A CAP_0805-10UF,16V,10%,X6S,C953A    I48 @BASEBOARD_FAB2_LIB.BASEBOARD_FAB2(SCH_1):PAGE207
 C9P22    1      A CAP_0805-10UF,16V,10%,X6S,C953A    I50 @BASEBOARD_FAB2_LIB.BASEBOARD_FAB2(SCH_1):PAGE207
 C9P25    1      A CAP_0805-10UF,16V,10%,X6S,C953A    I51 @BASEBOARD_FAB2_LIB.BASEBOARD_FAB2(SCH_1):PAGE207
 C9P26    1      A CAP_0805-10UF,16V,10%,X6S,C953A    I54 @BASEBOARD_FAB2_LIB.BASEBOARD_FAB2(SCH_1):PAGE207
 EU1D3   25 VIN<0> IR354XX_SM-IR35411,IC,H73688-0A    I27 @BASEBOARD_FAB2_LIB.BASEBOARD_FAB2(SCH_1):PAGE208
 EU1D3   30 VIN<1> IR354XX_SM-IR35411,IC,H73688-0A    I27 @BASEBOARD_FAB2_LIB.BASEBOARD_FAB2(SCH_1):PAGE208
 C1D28    1      A CAP_A_0402V-0.1UF,16V,10%,X7R,A    I44 @BASEBOARD_FAB2_LIB.BASEBOARD_FAB2(SCH_1):PAGE208
 C1D23    1      A CAP_0402-1.0UF,16V,10%,X6S,D97A    I45 @BASEBOARD_FAB2_LIB.BASEBOARD_FAB2(SCH_1):PAGE208
 C1D13    1      A CAP_A_0402V-0.1UF,16V,10%,X7R,A    I51 @BASEBOARD_FAB2_LIB.BASEBOARD_FAB2(SCH_1):PAGE208
 C1D12    1      A CAP_0402-1.0UF,16V,10%,X6S,D97A    I52 @BASEBOARD_FAB2_LIB.BASEBOARD_FAB2(SCH_1):PAGE208
  C9P4    1      A CAP_0805-10UF,16V,10%,X6S,C953A    I53 @BASEBOARD_FAB2_LIB.BASEBOARD_FAB2(SCH_1):PAGE208
  C9P7    1      A CAP_0805-10UF,16V,10%,X6S,C953A    I54 @BASEBOARD_FAB2_LIB.BASEBOARD_FAB2(SCH_1):PAGE208
  C9P9    1      A CAP_0805-10UF,16V,10%,X6S,C953A    I55 @BASEBOARD_FAB2_LIB.BASEBOARD_FAB2(SCH_1):PAGE208
 C9P24    1      A CAP_0805-10UF,16V,10%,X6S,C953A    I58 @BASEBOARD_FAB2_LIB.BASEBOARD_FAB2(SCH_1):PAGE208
  C9P1    1      A CAP_0805-10UF,16V,10%,X6S,C953A    I59 @BASEBOARD_FAB2_LIB.BASEBOARD_FAB2(SCH_1):PAGE208
  C9P2    1      A CAP_0805-10UF,16V,10%,X6S,C953A    I60 @BASEBOARD_FAB2_LIB.BASEBOARD_FAB2(SCH_1):PAGE208
 EU1D1   25 VIN<0> IR354XX_SM-IR35411,IC,H73688-0A    I71 @BASEBOARD_FAB2_LIB.BASEBOARD_FAB2(SCH_1):PAGE208
 EU1D1   30 VIN<1> IR354XX_SM-IR35411,IC,H73688-0A    I71 @BASEBOARD_FAB2_LIB.BASEBOARD_FAB2(SCH_1):PAGE208
 C9N27    1      A CAP_0805-10UF,16V,10%,X6S,C953A     I5 @BASEBOARD_FAB2_LIB.BASEBOARD_FAB2(SCH_1):PAGE209
 C9N26    1      A CAP_0805-10UF,16V,10%,X6S,C953A     I7 @BASEBOARD_FAB2_LIB.BASEBOARD_FAB2(SCH_1):PAGE209
 C9N25    1      A CAP_0805-10UF,16V,10%,X6S,C953A     I8 @BASEBOARD_FAB2_LIB.BASEBOARD_FAB2(SCH_1):PAGE209
 C1C26    1      A CAP_0402-1.0UF,16V,10%,X6S,D97A    I16 @BASEBOARD_FAB2_LIB.BASEBOARD_FAB2(SCH_1):PAGE209
 C1C25    1      A CAP_A_0402V-0.1UF,16V,10%,X7R,A    I17 @BASEBOARD_FAB2_LIB.BASEBOARD_FAB2(SCH_1):PAGE209
  C1C1    1      A CAPP_2626-270UF,16V,20%,OSCON,A    I35 @BASEBOARD_FAB2_LIB.BASEBOARD_FAB2(SCH_1):PAGE209
 C1E18    1      A CAPP_2626-270UF,16V,20%,OSCON,A    I37 @BASEBOARD_FAB2_LIB.BASEBOARD_FAB2(SCH_1):PAGE209
  C1C2    1      A CAPP_2626-270UF,16V,20%,OSCON,A    I38 @BASEBOARD_FAB2_LIB.BASEBOARD_FAB2(SCH_1):PAGE209
 R1B20    2      B RES_2010-0.001,1%,1W,CHIP,E309A    I39 @BASEBOARD_FAB2_LIB.BASEBOARD_FAB2(SCH_1):PAGE209
  U1B3    5    RSN ADM4073_SM-EMPTY,G12194-001    I52 @BASEBOARD_FAB2_LIB.BASEBOARD_FAB2(SCH_1):PAGE209
 EU1C3   25 VIN<0> IR354XX_SM-IR35411,IC,H73688-0A    I56 @BASEBOARD_FAB2_LIB.BASEBOARD_FAB2(SCH_1):PAGE209
 EU1C3   30 VIN<1> IR354XX_SM-IR35411,IC,H73688-0A    I56 @BASEBOARD_FAB2_LIB.BASEBOARD_FAB2(SCH_1):PAGE209
 C1C17    1      A CAP_A_0402V-0.1UF,16V,10%,X7R,A    I27 @BASEBOARD_FAB2_LIB.BASEBOARD_FAB2(SCH_1):PAGE210
 C1C15    1      A CAP_0402-1.0UF,16V,10%,X6S,D97A    I28 @BASEBOARD_FAB2_LIB.BASEBOARD_FAB2(SCH_1):PAGE210
 C9N13    1      A CAP_0805-10UF,16V,10%,X6S,C953A    I35 @BASEBOARD_FAB2_LIB.BASEBOARD_FAB2(SCH_1):PAGE210
 C9N19    1      A CAP_0805-10UF,16V,10%,X6S,C953A    I36 @BASEBOARD_FAB2_LIB.BASEBOARD_FAB2(SCH_1):PAGE210
 C9N21    1      A CAP_0805-10UF,16V,10%,X6S,C953A    I38 @BASEBOARD_FAB2_LIB.BASEBOARD_FAB2(SCH_1):PAGE210
 EU1C1   25 VIN<0> IR354XX_SM-IR35412,IC,H73684-0A    I51 @BASEBOARD_FAB2_LIB.BASEBOARD_FAB2(SCH_1):PAGE210
 EU1C1   30 VIN<1> IR354XX_SM-IR35412,IC,H73684-0A    I51 @BASEBOARD_FAB2_LIB.BASEBOARD_FAB2(SCH_1):PAGE210

VR_FET_SW_P12V_STBY_PVCCIO_CPU0 @BASEBOARD_FAB2_LIB.BASEBOARD_FAB2(SCH_1):VR_FET_SW_P12V_STBY_PVCCIO_CPU0
 R3P12    1      A RES_0402-100.0K,1%,1/16W,CHIP,B    I31 @BASEBOARD_FAB2_LIB.BASEBOARD_FAB2(SCH_1):PAGE211
 C7C11    1      A CAP_A_0402V-0.1UF,16V,10%,X7R,A    I38 @BASEBOARD_FAB2_LIB.BASEBOARD_FAB2(SCH_1):PAGE212
 C7C12    1      A CAP_0402-1.0UF,16V,10%,X6S,D97A    I39 @BASEBOARD_FAB2_LIB.BASEBOARD_FAB2(SCH_1):PAGE212
 C3N36    1      A CAP_0805-10UF,16V,10%,X6S,C953A    I40 @BASEBOARD_FAB2_LIB.BASEBOARD_FAB2(SCH_1):PAGE212
 C3N33    1      A CAP_0805-10UF,16V,10%,X6S,C953A    I41 @BASEBOARD_FAB2_LIB.BASEBOARD_FAB2(SCH_1):PAGE212
 C3N34    1      A CAP_0805-10UF,16V,10%,X6S,C953A    I43 @BASEBOARD_FAB2_LIB.BASEBOARD_FAB2(SCH_1):PAGE212
  C7C8    1      A CAP_1210-100UF,16V,20%,X5R,644A    I51 @BASEBOARD_FAB2_LIB.BASEBOARD_FAB2(SCH_1):PAGE212
  C7C7    1      A CAP_1210-100UF,16V,20%,X5R,644A    I54 @BASEBOARD_FAB2_LIB.BASEBOARD_FAB2(SCH_1):PAGE212
  L7C1    2    INB INDUCTOR_SM-100NH,IND,D92183-0B    I56 @BASEBOARD_FAB2_LIB.BASEBOARD_FAB2(SCH_1):PAGE212
 EU7C1   25 VIN<0> IR354XX_SM-IR35412,IC,H73684-0A   I101 @BASEBOARD_FAB2_LIB.BASEBOARD_FAB2(SCH_1):PAGE212
 EU7C1   30 VIN<1> IR354XX_SM-IR35412,IC,H73684-0A   I101 @BASEBOARD_FAB2_LIB.BASEBOARD_FAB2(SCH_1):PAGE212

VR_FET_SW_P12V_STBY_PVDDQ_ABC @BASEBOARD_FAB2_LIB.BASEBOARD_FAB2(SCH_1):VR_FET_SW_P12V_STBY_PVDDQ_ABC
 R7F34    1      A RES_0402-100.0K,1%,1/16W,CHIP,B   I336 @BASEBOARD_FAB2_LIB.BASEBOARD_FAB2(SCH_1):PAGE215
  C3U2    1      A CAP_0805-10UF,16V,10%,X6S,C953A    I45 @BASEBOARD_FAB2_LIB.BASEBOARD_FAB2(SCH_1):PAGE216
  C3U3    1      A CAP_0805-10UF,16V,10%,X6S,C953A    I46 @BASEBOARD_FAB2_LIB.BASEBOARD_FAB2(SCH_1):PAGE216
  C3U4    1      A CAP_0805-10UF,16V,10%,X6S,C953A    I47 @BASEBOARD_FAB2_LIB.BASEBOARD_FAB2(SCH_1):PAGE216
 C7G37    1      A CAP_0402-1.0UF,16V,10%,X6S,D97A    I48 @BASEBOARD_FAB2_LIB.BASEBOARD_FAB2(SCH_1):PAGE216
 C7G29    1      A CAP_A_0402V-0.1UF,16V,10%,X7R,A    I51 @BASEBOARD_FAB2_LIB.BASEBOARD_FAB2(SCH_1):PAGE216
 C7G36    1      A CAP_A_0402V-0.1UF,16V,10%,X7R,A    I78 @BASEBOARD_FAB2_LIB.BASEBOARD_FAB2(SCH_1):PAGE216
 C7G30    1      A CAP_0402-1.0UF,16V,10%,X6S,D97A    I79 @BASEBOARD_FAB2_LIB.BASEBOARD_FAB2(SCH_1):PAGE216
  C3U9    1      A CAP_0805-10UF,16V,10%,X6S,C953A    I80 @BASEBOARD_FAB2_LIB.BASEBOARD_FAB2(SCH_1):PAGE216
  C3U7    1      A CAP_0805-10UF,16V,10%,X6S,C953A    I81 @BASEBOARD_FAB2_LIB.BASEBOARD_FAB2(SCH_1):PAGE216
  C3U6    1      A CAP_0805-10UF,16V,10%,X6S,C953A    I84 @BASEBOARD_FAB2_LIB.BASEBOARD_FAB2(SCH_1):PAGE216
 EU7G2   25 VIN<0> IR354XX_SM-IR35411,IC,H73688-0A   I102 @BASEBOARD_FAB2_LIB.BASEBOARD_FAB2(SCH_1):PAGE216
 EU7G2   30 VIN<1> IR354XX_SM-IR35411,IC,H73688-0A   I102 @BASEBOARD_FAB2_LIB.BASEBOARD_FAB2(SCH_1):PAGE216
 EU7G3   25 VIN<0> IR354XX_SM-IR35411,IC,H73688-0A   I103 @BASEBOARD_FAB2_LIB.BASEBOARD_FAB2(SCH_1):PAGE216
 EU7G3   30 VIN<1> IR354XX_SM-IR35411,IC,H73688-0A   I103 @BASEBOARD_FAB2_LIB.BASEBOARD_FAB2(SCH_1):PAGE216
  L7F2    2    INB INDUCTOR_SM-100NH,IND,D92183-0B   I124 @BASEBOARD_FAB2_LIB.BASEBOARD_FAB2(SCH_1):PAGE217
  C7G2    1      A CAPP_2626-270UF,16V,20%,OSCON,A   I175 @BASEBOARD_FAB2_LIB.BASEBOARD_FAB2(SCH_1):PAGE217

VR_FET_SW_P12V_STBY_PVDDQ_DEF @BASEBOARD_FAB2_LIB.BASEBOARD_FAB2(SCH_1):VR_FET_SW_P12V_STBY_PVDDQ_DEF
 R3L12    1      A RES_0402-100.0K,1%,1/16W,CHIP,B    I53 @BASEBOARD_FAB2_LIB.BASEBOARD_FAB2(SCH_1):PAGE218
  C3L2    1      A CAP_0805-10UF,16V,10%,X6S,C953A    I45 @BASEBOARD_FAB2_LIB.BASEBOARD_FAB2(SCH_1):PAGE219
  C3L4    1      A CAP_0805-10UF,16V,10%,X6S,C953A    I46 @BASEBOARD_FAB2_LIB.BASEBOARD_FAB2(SCH_1):PAGE219
 C3L13    1      A CAP_0805-10UF,16V,10%,X6S,C953A    I47 @BASEBOARD_FAB2_LIB.BASEBOARD_FAB2(SCH_1):PAGE219
 C7A11    1      A CAP_0402-1.0UF,16V,10%,X6S,D97A    I48 @BASEBOARD_FAB2_LIB.BASEBOARD_FAB2(SCH_1):PAGE219
  C7A5    1      A CAP_A_0402V-0.1UF,16V,10%,X7R,A    I51 @BASEBOARD_FAB2_LIB.BASEBOARD_FAB2(SCH_1):PAGE219
 C7A20    1      A CAP_A_0402V-0.1UF,16V,10%,X7R,A    I78 @BASEBOARD_FAB2_LIB.BASEBOARD_FAB2(SCH_1):PAGE219
 C7A21    1      A CAP_0402-1.0UF,16V,10%,X6S,D97A    I79 @BASEBOARD_FAB2_LIB.BASEBOARD_FAB2(SCH_1):PAGE219
 C3L17    1      A CAP_0805-10UF,16V,10%,X6S,C953A    I80 @BASEBOARD_FAB2_LIB.BASEBOARD_FAB2(SCH_1):PAGE219
 C3L16    1      A CAP_0805-10UF,16V,10%,X6S,C953A    I81 @BASEBOARD_FAB2_LIB.BASEBOARD_FAB2(SCH_1):PAGE219
 C3L15    1      A CAP_0805-10UF,16V,10%,X6S,C953A    I84 @BASEBOARD_FAB2_LIB.BASEBOARD_FAB2(SCH_1):PAGE219
 EU7A1   25 VIN<0> IR354XX_SM-IR35411,IC,H73688-0A   I106 @BASEBOARD_FAB2_LIB.BASEBOARD_FAB2(SCH_1):PAGE219
 EU7A1   30 VIN<1> IR354XX_SM-IR35411,IC,H73688-0A   I106 @BASEBOARD_FAB2_LIB.BASEBOARD_FAB2(SCH_1):PAGE219
 EU7A4   25 VIN<0> IR354XX_SM-IR35411,IC,H73688-0A   I107 @BASEBOARD_FAB2_LIB.BASEBOARD_FAB2(SCH_1):PAGE219
 EU7A4   30 VIN<1> IR354XX_SM-IR35411,IC,H73688-0A   I107 @BASEBOARD_FAB2_LIB.BASEBOARD_FAB2(SCH_1):PAGE219
  L7A5    2    INB INDUCTOR_SM-100NH,IND,D92183-0B   I124 @BASEBOARD_FAB2_LIB.BASEBOARD_FAB2(SCH_1):PAGE220
 C7A19    1      A CAPP_2626-270UF,16V,20%,OSCON,A   I175 @BASEBOARD_FAB2_LIB.BASEBOARD_FAB2(SCH_1):PAGE220
  R8A4    1      A RES_0402-100.0K,1%,1/16W,CHIP,B   I165 @BASEBOARD_FAB2_LIB.BASEBOARD_FAB2(SCH_1):PAGE235
 C7A39    1      A CAP_A_0402V-0.1UF,16V,10%,X7R,A    I20 @BASEBOARD_FAB2_LIB.BASEBOARD_FAB2(SCH_1):PAGE236
  C7A7    1      A CAP_0402-1.0UF,16V,10%,X6S,D97A    I22 @BASEBOARD_FAB2_LIB.BASEBOARD_FAB2(SCH_1):PAGE236
 C3L12    1      A CAP_0805-10UF,16V,10%,X6S,C953A    I23 @BASEBOARD_FAB2_LIB.BASEBOARD_FAB2(SCH_1):PAGE236
 C3L11    1      A CAP_0805-10UF,16V,10%,X6S,C953A    I24 @BASEBOARD_FAB2_LIB.BASEBOARD_FAB2(SCH_1):PAGE236
  C3L8    1      A CAP_0805-10UF,16V,10%,X6S,C953A    I26 @BASEBOARD_FAB2_LIB.BASEBOARD_FAB2(SCH_1):PAGE236
  C3L9    1      A CAP_0805-10UF,16V,10%,X6S,C953A    I29 @BASEBOARD_FAB2_LIB.BASEBOARD_FAB2(SCH_1):PAGE236
  C3L7    1      A CAP_0805-10UF,16V,10%,X6S,C953A    I31 @BASEBOARD_FAB2_LIB.BASEBOARD_FAB2(SCH_1):PAGE236
 C3L10    1      A CAP_0805-10UF,16V,10%,X6S,C953A    I32 @BASEBOARD_FAB2_LIB.BASEBOARD_FAB2(SCH_1):PAGE236
  C7A9    1      A CAP_0402-1.0UF,16V,10%,X6S,D97A    I33 @BASEBOARD_FAB2_LIB.BASEBOARD_FAB2(SCH_1):PAGE236
 C7A40    1      A CAP_A_0402V-0.1UF,16V,10%,X7R,A    I35 @BASEBOARD_FAB2_LIB.BASEBOARD_FAB2(SCH_1):PAGE236
 C7A13    1      A CAP_1210-100UF,16V,20%,X5R,644A    I63 @BASEBOARD_FAB2_LIB.BASEBOARD_FAB2(SCH_1):PAGE236
 C7A14    1      A CAP_1210-100UF,16V,20%,X5R,644A    I65 @BASEBOARD_FAB2_LIB.BASEBOARD_FAB2(SCH_1):PAGE236
 EU7A3   25 VIN<0> IR354XX_SM-IR35412,IC,H73684-0A   I116 @BASEBOARD_FAB2_LIB.BASEBOARD_FAB2(SCH_1):PAGE236
 EU7A3   30 VIN<1> IR354XX_SM-IR35412,IC,H73684-0A   I116 @BASEBOARD_FAB2_LIB.BASEBOARD_FAB2(SCH_1):PAGE236
 EU7A2   25 VIN<0> IR354XX_SM-IR35412,IC,H73684-0A   I117 @BASEBOARD_FAB2_LIB.BASEBOARD_FAB2(SCH_1):PAGE236
 EU7A2   30 VIN<1> IR354XX_SM-IR35412,IC,H73684-0A   I117 @BASEBOARD_FAB2_LIB.BASEBOARD_FAB2(SCH_1):PAGE236

VR_FET_SW_P12V_STBY_PVDDQ_GHJ @BASEBOARD_FAB2_LIB.BASEBOARD_FAB2(SCH_1):VR_FET_SW_P12V_STBY_PVDDQ_GHJ
 R9U11    1      A RES_0402-100.0K,1%,1/16W,CHIP,B    I57 @BASEBOARD_FAB2_LIB.BASEBOARD_FAB2(SCH_1):PAGE223
  C9U6    1      A CAP_0805-10UF,16V,10%,X6S,C953A    I45 @BASEBOARD_FAB2_LIB.BASEBOARD_FAB2(SCH_1):PAGE224
  C9U4    1      A CAP_0805-10UF,16V,10%,X6S,C953A    I46 @BASEBOARD_FAB2_LIB.BASEBOARD_FAB2(SCH_1):PAGE224
  C9T4    1      A CAP_0805-10UF,16V,10%,X6S,C953A    I47 @BASEBOARD_FAB2_LIB.BASEBOARD_FAB2(SCH_1):PAGE224
 C1F27    1      A CAP_0402-1.0UF,16V,10%,X6S,D97A    I48 @BASEBOARD_FAB2_LIB.BASEBOARD_FAB2(SCH_1):PAGE224
 C1G14    1      A CAP_A_0402V-0.1UF,16V,10%,X7R,A    I51 @BASEBOARD_FAB2_LIB.BASEBOARD_FAB2(SCH_1):PAGE224
 C1F28    1      A CAP_A_0402V-0.1UF,16V,10%,X7R,A    I78 @BASEBOARD_FAB2_LIB.BASEBOARD_FAB2(SCH_1):PAGE224
 C1G13    1      A CAP_0402-1.0UF,16V,10%,X6S,D97A    I79 @BASEBOARD_FAB2_LIB.BASEBOARD_FAB2(SCH_1):PAGE224
  C9U3    1      A CAP_0805-10UF,16V,10%,X6S,C953A    I80 @BASEBOARD_FAB2_LIB.BASEBOARD_FAB2(SCH_1):PAGE224
  C9T6    1      A CAP_0805-10UF,16V,10%,X6S,C953A    I81 @BASEBOARD_FAB2_LIB.BASEBOARD_FAB2(SCH_1):PAGE224
  C9T9    1      A CAP_0805-10UF,16V,10%,X6S,C953A    I84 @BASEBOARD_FAB2_LIB.BASEBOARD_FAB2(SCH_1):PAGE224
 EU1G1   25 VIN<0> IR354XX_SM-IR35411,IC,H73688-0A   I110 @BASEBOARD_FAB2_LIB.BASEBOARD_FAB2(SCH_1):PAGE224
 EU1G1   30 VIN<1> IR354XX_SM-IR35411,IC,H73688-0A   I110 @BASEBOARD_FAB2_LIB.BASEBOARD_FAB2(SCH_1):PAGE224
 EU1F1   25 VIN<0> IR354XX_SM-IR35411,IC,H73688-0A   I111 @BASEBOARD_FAB2_LIB.BASEBOARD_FAB2(SCH_1):PAGE224
 EU1F1   30 VIN<1> IR354XX_SM-IR35411,IC,H73688-0A   I111 @BASEBOARD_FAB2_LIB.BASEBOARD_FAB2(SCH_1):PAGE224
  L1F1    2    INB INDUCTOR_SM-100NH,IND,D92183-0B   I124 @BASEBOARD_FAB2_LIB.BASEBOARD_FAB2(SCH_1):PAGE225
 C1G15    1      A CAP_1210-47UF,16V,20%,X6S,D384A   I192 @BASEBOARD_FAB2_LIB.BASEBOARD_FAB2(SCH_1):PAGE225
 C1G12    1      A CAP_1210-47UF,16V,20%,X6S,D384A   I193 @BASEBOARD_FAB2_LIB.BASEBOARD_FAB2(SCH_1):PAGE225
  C1G2    1      A CAP_1210-47UF,16V,20%,X6S,D384A   I194 @BASEBOARD_FAB2_LIB.BASEBOARD_FAB2(SCH_1):PAGE225
  C1G7    1      A CAP_1210-47UF,16V,20%,X6S,D384A   I195 @BASEBOARD_FAB2_LIB.BASEBOARD_FAB2(SCH_1):PAGE225

VR_FET_SW_P12V_STBY_PVDDQ_KLM @BASEBOARD_FAB2_LIB.BASEBOARD_FAB2(SCH_1):VR_FET_SW_P12V_STBY_PVDDQ_KLM
  R9M8    1      A RES_0402-100.0K,1%,1/16W,CHIP,B    I57 @BASEBOARD_FAB2_LIB.BASEBOARD_FAB2(SCH_1):PAGE226
 C9L11    1      A CAP_0805-10UF,16V,10%,X6S,C953A    I45 @BASEBOARD_FAB2_LIB.BASEBOARD_FAB2(SCH_1):PAGE227
 C9L10    1      A CAP_0805-10UF,16V,10%,X6S,C953A    I46 @BASEBOARD_FAB2_LIB.BASEBOARD_FAB2(SCH_1):PAGE227
  C9L6    1      A CAP_0805-10UF,16V,10%,X6S,C953A    I47 @BASEBOARD_FAB2_LIB.BASEBOARD_FAB2(SCH_1):PAGE227
 C1A19    1      A CAP_0402-1.0UF,16V,10%,X6S,D97A    I48 @BASEBOARD_FAB2_LIB.BASEBOARD_FAB2(SCH_1):PAGE227
 C1A10    1      A CAP_A_0402V-0.1UF,16V,10%,X7R,A    I51 @BASEBOARD_FAB2_LIB.BASEBOARD_FAB2(SCH_1):PAGE227
 C1A20    1      A CAP_A_0402V-0.1UF,16V,10%,X7R,A    I78 @BASEBOARD_FAB2_LIB.BASEBOARD_FAB2(SCH_1):PAGE227
  C1A9    1      A CAP_0402-1.0UF,16V,10%,X6S,D97A    I79 @BASEBOARD_FAB2_LIB.BASEBOARD_FAB2(SCH_1):PAGE227
  C9L5    1      A CAP_0805-10UF,16V,10%,X6S,C953A    I80 @BASEBOARD_FAB2_LIB.BASEBOARD_FAB2(SCH_1):PAGE227
 C9L13    1      A CAP_0805-10UF,16V,10%,X6S,C953A    I81 @BASEBOARD_FAB2_LIB.BASEBOARD_FAB2(SCH_1):PAGE227
 C9L14    1      A CAP_0805-10UF,16V,10%,X6S,C953A    I84 @BASEBOARD_FAB2_LIB.BASEBOARD_FAB2(SCH_1):PAGE227
 EU1A2   25 VIN<0> IR354XX_SM-IR35411,IC,H73688-0A   I101 @BASEBOARD_FAB2_LIB.BASEBOARD_FAB2(SCH_1):PAGE227
 EU1A2   30 VIN<1> IR354XX_SM-IR35411,IC,H73688-0A   I101 @BASEBOARD_FAB2_LIB.BASEBOARD_FAB2(SCH_1):PAGE227
 EU1A1   25 VIN<0> IR354XX_SM-IR35411,IC,H73688-0A   I102 @BASEBOARD_FAB2_LIB.BASEBOARD_FAB2(SCH_1):PAGE227
 EU1A1   30 VIN<1> IR354XX_SM-IR35411,IC,H73688-0A   I102 @BASEBOARD_FAB2_LIB.BASEBOARD_FAB2(SCH_1):PAGE227
  L1B1    2    INB INDUCTOR_SM-100NH,IND,D92183-0B   I124 @BASEBOARD_FAB2_LIB.BASEBOARD_FAB2(SCH_1):PAGE228
 C1B10    1      A CAPP_2626-270UF,16V,20%,OSCON,A   I175 @BASEBOARD_FAB2_LIB.BASEBOARD_FAB2(SCH_1):PAGE228

VR_FET_SW_P12V_STBY_PVPP_ABC @BASEBOARD_FAB2_LIB.BASEBOARD_FAB2(SCH_1):VR_FET_SW_P12V_STBY_PVPP_ABC
  C7F7    1      A CAP_1210-47UF,16V,20%,X6S,D384A   I151 @BASEBOARD_FAB2_LIB.BASEBOARD_FAB2(SCH_1):PAGE231
 C3T10    1      A CAP_0402-1.0UF,16V,10%,X6S,D97A   I161 @BASEBOARD_FAB2_LIB.BASEBOARD_FAB2(SCH_1):PAGE231
 FB7F1    2      B FERRITE_SM-22,FB,656554-051   I162 @BASEBOARD_FAB2_LIB.BASEBOARD_FAB2(SCH_1):PAGE231
 EU7F1   39    VCC NCP3232L_SM-IC,H86355-001   I193 @BASEBOARD_FAB2_LIB.BASEBOARD_FAB2(SCH_1):PAGE231
 EU7F1    8 VIN<0> NCP3232L_SM-IC,H86355-001   I193 @BASEBOARD_FAB2_LIB.BASEBOARD_FAB2(SCH_1):PAGE231
 EU7F1    9 VIN<1> NCP3232L_SM-IC,H86355-001   I193 @BASEBOARD_FAB2_LIB.BASEBOARD_FAB2(SCH_1):PAGE231
 EU7F1   10 VIN<2> NCP3232L_SM-IC,H86355-001   I193 @BASEBOARD_FAB2_LIB.BASEBOARD_FAB2(SCH_1):PAGE231
 EU7F1   11 VIN<3> NCP3232L_SM-IC,H86355-001   I193 @BASEBOARD_FAB2_LIB.BASEBOARD_FAB2(SCH_1):PAGE231
 EU7F1   12 VIN<4> NCP3232L_SM-IC,H86355-001   I193 @BASEBOARD_FAB2_LIB.BASEBOARD_FAB2(SCH_1):PAGE231
 EU7F1   13 VIN<5> NCP3232L_SM-IC,H86355-001   I193 @BASEBOARD_FAB2_LIB.BASEBOARD_FAB2(SCH_1):PAGE231
 EU7F1   14 VIN<6> NCP3232L_SM-IC,H86355-001   I193 @BASEBOARD_FAB2_LIB.BASEBOARD_FAB2(SCH_1):PAGE231
 EU7F1   42 VIN<7> NCP3232L_SM-IC,H86355-001   I193 @BASEBOARD_FAB2_LIB.BASEBOARD_FAB2(SCH_1):PAGE231
  C7F6    1      A CAP_A_0402V-0.1UF,16V,10%,X7R,A   I205 @BASEBOARD_FAB2_LIB.BASEBOARD_FAB2(SCH_1):PAGE231
  C7F5    1      A CAP_0805-10UF,16V,10%,X6S,C953A   I209 @BASEBOARD_FAB2_LIB.BASEBOARD_FAB2(SCH_1):PAGE231
  C3T8    1      A CAP_0805-10UF,16V,10%,X6S,C953A   I210 @BASEBOARD_FAB2_LIB.BASEBOARD_FAB2(SCH_1):PAGE231
 C3T14    1      A CAP_0805-10UF,16V,10%,X6S,C953A   I211 @BASEBOARD_FAB2_LIB.BASEBOARD_FAB2(SCH_1):PAGE231
 C3T12    1      A CAP_0805-10UF,16V,10%,X6S,C953A   I215 @BASEBOARD_FAB2_LIB.BASEBOARD_FAB2(SCH_1):PAGE231

VR_FET_SW_P12V_STBY_PVPP_DEF @BASEBOARD_FAB2_LIB.BASEBOARD_FAB2(SCH_1):VR_FET_SW_P12V_STBY_PVPP_DEF
 FB7B1    2      B FERRITE_SM-22,FB,656554-051   I200 @BASEBOARD_FAB2_LIB.BASEBOARD_FAB2(SCH_1):PAGE232
  C7B8    1      A CAP_1210-47UF,16V,20%,X6S,D384A   I202 @BASEBOARD_FAB2_LIB.BASEBOARD_FAB2(SCH_1):PAGE232
  C3M9    1      A CAP_0402-1.0UF,16V,10%,X6S,D97A   I207 @BASEBOARD_FAB2_LIB.BASEBOARD_FAB2(SCH_1):PAGE232
 EU7B1   39    VCC NCP3232L_SM-IC,H86355-001   I214 @BASEBOARD_FAB2_LIB.BASEBOARD_FAB2(SCH_1):PAGE232
 EU7B1    8 VIN<0> NCP3232L_SM-IC,H86355-001   I214 @BASEBOARD_FAB2_LIB.BASEBOARD_FAB2(SCH_1):PAGE232
 EU7B1    9 VIN<1> NCP3232L_SM-IC,H86355-001   I214 @BASEBOARD_FAB2_LIB.BASEBOARD_FAB2(SCH_1):PAGE232
 EU7B1   10 VIN<2> NCP3232L_SM-IC,H86355-001   I214 @BASEBOARD_FAB2_LIB.BASEBOARD_FAB2(SCH_1):PAGE232
 EU7B1   11 VIN<3> NCP3232L_SM-IC,H86355-001   I214 @BASEBOARD_FAB2_LIB.BASEBOARD_FAB2(SCH_1):PAGE232
 EU7B1   12 VIN<4> NCP3232L_SM-IC,H86355-001   I214 @BASEBOARD_FAB2_LIB.BASEBOARD_FAB2(SCH_1):PAGE232
 EU7B1   13 VIN<5> NCP3232L_SM-IC,H86355-001   I214 @BASEBOARD_FAB2_LIB.BASEBOARD_FAB2(SCH_1):PAGE232
 EU7B1   14 VIN<6> NCP3232L_SM-IC,H86355-001   I214 @BASEBOARD_FAB2_LIB.BASEBOARD_FAB2(SCH_1):PAGE232
 EU7B1   42 VIN<7> NCP3232L_SM-IC,H86355-001   I214 @BASEBOARD_FAB2_LIB.BASEBOARD_FAB2(SCH_1):PAGE232
  C7B6    1      A CAP_A_0402V-0.1UF,16V,10%,X7R,A   I252 @BASEBOARD_FAB2_LIB.BASEBOARD_FAB2(SCH_1):PAGE232
  C3M8    1      A CAP_0805-10UF,16V,10%,X6S,C953A   I259 @BASEBOARD_FAB2_LIB.BASEBOARD_FAB2(SCH_1):PAGE232
 C3M15    1      A CAP_0805-10UF,16V,10%,X6S,C953A   I260 @BASEBOARD_FAB2_LIB.BASEBOARD_FAB2(SCH_1):PAGE232
 C3M16    1      A CAP_0805-10UF,16V,10%,X6S,C953A   I261 @BASEBOARD_FAB2_LIB.BASEBOARD_FAB2(SCH_1):PAGE232
  C7B5    1      A CAP_0805-10UF,16V,10%,X6S,C953A   I262 @BASEBOARD_FAB2_LIB.BASEBOARD_FAB2(SCH_1):PAGE232

VR_FET_SW_P12V_STBY_PVPP_GHJ @BASEBOARD_FAB2_LIB.BASEBOARD_FAB2(SCH_1):VR_FET_SW_P12V_STBY_PVPP_GHJ
  C4G5    1      A CAP_1210-47UF,16V,20%,X6S,D384A   I189 @BASEBOARD_FAB2_LIB.BASEBOARD_FAB2(SCH_1):PAGE233
  C4G4    1      A CAP_0402-1.0UF,16V,10%,X6S,D97A   I196 @BASEBOARD_FAB2_LIB.BASEBOARD_FAB2(SCH_1):PAGE233
 FB4G1    2      B FERRITE_SM-22,FB,656554-051   I198 @BASEBOARD_FAB2_LIB.BASEBOARD_FAB2(SCH_1):PAGE233
 EU4G1   39    VCC NCP3232L_SM-IC,H86355-001   I225 @BASEBOARD_FAB2_LIB.BASEBOARD_FAB2(SCH_1):PAGE233
 EU4G1    8 VIN<0> NCP3232L_SM-IC,H86355-001   I225 @BASEBOARD_FAB2_LIB.BASEBOARD_FAB2(SCH_1):PAGE233
 EU4G1    9 VIN<1> NCP3232L_SM-IC,H86355-001   I225 @BASEBOARD_FAB2_LIB.BASEBOARD_FAB2(SCH_1):PAGE233
 EU4G1   10 VIN<2> NCP3232L_SM-IC,H86355-001   I225 @BASEBOARD_FAB2_LIB.BASEBOARD_FAB2(SCH_1):PAGE233
 EU4G1   11 VIN<3> NCP3232L_SM-IC,H86355-001   I225 @BASEBOARD_FAB2_LIB.BASEBOARD_FAB2(SCH_1):PAGE233
 EU4G1   12 VIN<4> NCP3232L_SM-IC,H86355-001   I225 @BASEBOARD_FAB2_LIB.BASEBOARD_FAB2(SCH_1):PAGE233
 EU4G1   13 VIN<5> NCP3232L_SM-IC,H86355-001   I225 @BASEBOARD_FAB2_LIB.BASEBOARD_FAB2(SCH_1):PAGE233
 EU4G1   14 VIN<6> NCP3232L_SM-IC,H86355-001   I225 @BASEBOARD_FAB2_LIB.BASEBOARD_FAB2(SCH_1):PAGE233
 EU4G1   42 VIN<7> NCP3232L_SM-IC,H86355-001   I225 @BASEBOARD_FAB2_LIB.BASEBOARD_FAB2(SCH_1):PAGE233
  C6U5    1      A CAP_A_0402V-0.1UF,16V,10%,X7R,A   I242 @BASEBOARD_FAB2_LIB.BASEBOARD_FAB2(SCH_1):PAGE233
  C6U4    1      A CAP_0805-10UF,16V,10%,X6S,C953A   I248 @BASEBOARD_FAB2_LIB.BASEBOARD_FAB2(SCH_1):PAGE233
  C4G2    1      A CAP_0805-10UF,16V,10%,X6S,C953A   I253 @BASEBOARD_FAB2_LIB.BASEBOARD_FAB2(SCH_1):PAGE233
  C6U7    1      A CAP_0805-10UF,16V,10%,X6S,C953A   I254 @BASEBOARD_FAB2_LIB.BASEBOARD_FAB2(SCH_1):PAGE233
  C6U8    1      A CAP_0805-10UF,16V,10%,X6S,C953A   I255 @BASEBOARD_FAB2_LIB.BASEBOARD_FAB2(SCH_1):PAGE233

VR_FET_SW_P12V_STBY_PVPP_KLM @BASEBOARD_FAB2_LIB.BASEBOARD_FAB2(SCH_1):VR_FET_SW_P12V_STBY_PVPP_KLM
  C4B1    1      A CAP_1210-47UF,16V,20%,X6S,D384A   I130 @BASEBOARD_FAB2_LIB.BASEBOARD_FAB2(SCH_1):PAGE234
 C6L11    1      A CAP_0402-1.0UF,16V,10%,X6S,D97A   I152 @BASEBOARD_FAB2_LIB.BASEBOARD_FAB2(SCH_1):PAGE234
 FB4A1    2      B FERRITE_SM-22,FB,656554-051   I154 @BASEBOARD_FAB2_LIB.BASEBOARD_FAB2(SCH_1):PAGE234
 EU4A3   39    VCC NCP3232L_SM-IC,H86355-001   I184 @BASEBOARD_FAB2_LIB.BASEBOARD_FAB2(SCH_1):PAGE234
 EU4A3    8 VIN<0> NCP3232L_SM-IC,H86355-001   I184 @BASEBOARD_FAB2_LIB.BASEBOARD_FAB2(SCH_1):PAGE234
 EU4A3    9 VIN<1> NCP3232L_SM-IC,H86355-001   I184 @BASEBOARD_FAB2_LIB.BASEBOARD_FAB2(SCH_1):PAGE234
 EU4A3   10 VIN<2> NCP3232L_SM-IC,H86355-001   I184 @BASEBOARD_FAB2_LIB.BASEBOARD_FAB2(SCH_1):PAGE234
 EU4A3   11 VIN<3> NCP3232L_SM-IC,H86355-001   I184 @BASEBOARD_FAB2_LIB.BASEBOARD_FAB2(SCH_1):PAGE234
 EU4A3   12 VIN<4> NCP3232L_SM-IC,H86355-001   I184 @BASEBOARD_FAB2_LIB.BASEBOARD_FAB2(SCH_1):PAGE234
 EU4A3   13 VIN<5> NCP3232L_SM-IC,H86355-001   I184 @BASEBOARD_FAB2_LIB.BASEBOARD_FAB2(SCH_1):PAGE234
 EU4A3   14 VIN<6> NCP3232L_SM-IC,H86355-001   I184 @BASEBOARD_FAB2_LIB.BASEBOARD_FAB2(SCH_1):PAGE234
 EU4A3   42 VIN<7> NCP3232L_SM-IC,H86355-001   I184 @BASEBOARD_FAB2_LIB.BASEBOARD_FAB2(SCH_1):PAGE234
 C4A20    1      A CAP_A_0402V-0.1UF,16V,10%,X7R,A   I199 @BASEBOARD_FAB2_LIB.BASEBOARD_FAB2(SCH_1):PAGE234
 C6L10    1      A CAP_0805-10UF,16V,10%,X6S,C953A   I202 @BASEBOARD_FAB2_LIB.BASEBOARD_FAB2(SCH_1):PAGE234
  C6M3    1      A CAP_0805-10UF,16V,10%,X6S,C953A   I203 @BASEBOARD_FAB2_LIB.BASEBOARD_FAB2(SCH_1):PAGE234
  C6M5    1      A CAP_0805-10UF,16V,10%,X6S,C953A   I204 @BASEBOARD_FAB2_LIB.BASEBOARD_FAB2(SCH_1):PAGE234
 C4A19    1      A CAP_0805-10UF,16V,10%,X6S,C953A   I205 @BASEBOARD_FAB2_LIB.BASEBOARD_FAB2(SCH_1):PAGE234

VR_FET_SW_P5V_STBY_PVIN @BASEBOARD_FAB2_LIB.BASEBOARD_FAB2(SCH_1):VR_FET_SW_P5V_STBY_PVIN
 R7E17    1      A RES_0402-0.0,5%,1/16W,CHIP,G21A    I37 @BASEBOARD_FAB2_LIB.BASEBOARD_FAB2(SCH_1):PAGE241
 C7E11    1      A CAP_1206LF-22UF,16V,10%,X6S,D3A    I39 @BASEBOARD_FAB2_LIB.BASEBOARD_FAB2(SCH_1):PAGE241
 C7E13    1      A CAP_1210-47UF,16V,20%,X6S,D384A    I45 @BASEBOARD_FAB2_LIB.BASEBOARD_FAB2(SCH_1):PAGE241
 C7E12    1      A CAP_1210-47UF,16V,20%,X6S,D384A    I47 @BASEBOARD_FAB2_LIB.BASEBOARD_FAB2(SCH_1):PAGE241
 FB7E1    2      B FERRITE_SM-22,FB,656554-051    I82 @BASEBOARD_FAB2_LIB.BASEBOARD_FAB2(SCH_1):PAGE241
 EU7E2    4 PVIN<0> TPS54821_LCC-IC,H63269-001    I83 @BASEBOARD_FAB2_LIB.BASEBOARD_FAB2(SCH_1):PAGE241
 EU7E2    5 PVIN<1> TPS54821_LCC-IC,H63269-001    I83 @BASEBOARD_FAB2_LIB.BASEBOARD_FAB2(SCH_1):PAGE241

VR_P1V05_PCH_BIREF1 @BASEBOARD_FAB2_LIB.BASEBOARD_FAB2(SCH_1):VR_P1V05_PCH_BIREF1
  R2L7    2      B RES_0402-0.0,5%,1/16W,CHIP,G21A   I225 @BASEBOARD_FAB2_LIB.BASEBOARD_FAB2(SCH_1):PAGE235
 EU8A1   25 BIREF1 PXE1110B_QFN-IC,H89187-001   I229 @BASEBOARD_FAB2_LIB.BASEBOARD_FAB2(SCH_1):PAGE235
 EU7A2   39  REFIN IR354XX_SM-IR35412,IC,H73684-0A   I117 @BASEBOARD_FAB2_LIB.BASEBOARD_FAB2(SCH_1):PAGE236
  CT67    1      A CAP_A_0402V-0.1UF,16V,10%,X7R,A   I124 @BASEBOARD_FAB2_LIB.BASEBOARD_FAB2(SCH_1):PAGE236

VR_P1V05_PCH_STBY_AVSP @BASEBOARD_FAB2_LIB.BASEBOARD_FAB2(SCH_1):VR_P1V05_PCH_STBY_AVSP
  C2L2    1      A CAP_0402LF-220PF,50V,10%,X7R,AA   I153 @BASEBOARD_FAB2_LIB.BASEBOARD_FAB2(SCH_1):PAGE235
  R2L8    2      B RES_0603-10.0,1%,1/10W,CHIP,G2A   I154 @BASEBOARD_FAB2_LIB.BASEBOARD_FAB2(SCH_1):PAGE235
 EU8A1   29  BVSEN PXE1110B_QFN-IC,H89187-001   I229 @BASEBOARD_FAB2_LIB.BASEBOARD_FAB2(SCH_1):PAGE235

VR_P1V05_PCH_STBY_OCSET @BASEBOARD_FAB2_LIB.BASEBOARD_FAB2(SCH_1):VR_P1V05_PCH_STBY_OCSET
 EU7A2   37  OCSET IR354XX_SM-IR35412,IC,H73684-0A   I117 @BASEBOARD_FAB2_LIB.BASEBOARD_FAB2(SCH_1):PAGE236
 R3L14    1      A RES_0402-68.1K,1%,1/16W,EMPTY,A   I120 @BASEBOARD_FAB2_LIB.BASEBOARD_FAB2(SCH_1):PAGE236

VR_P1V05_PCH_STBY_PH1_BOOT @BASEBOARD_FAB2_LIB.BASEBOARD_FAB2(SCH_1):VR_P1V05_PCH_STBY_PH1_BOOT
 C7A44    1      A CAP_0402-0.220UF,16V,10%,X7R,AA    I34 @BASEBOARD_FAB2_LIB.BASEBOARD_FAB2(SCH_1):PAGE236
  RT46    1      A RES_0402-0.0,5%,1/16W,CHIP,G21A   I142 @BASEBOARD_FAB2_LIB.BASEBOARD_FAB2(SCH_1):PAGE236

VR_P1V05_PCH_STBY_PH1_BOOT_R @BASEBOARD_FAB2_LIB.BASEBOARD_FAB2(SCH_1):VR_P1V05_PCH_STBY_PH1_BOOT_R
 EU7A2   33  BOOST IR354XX_SM-IR35412,IC,H73684-0A   I117 @BASEBOARD_FAB2_LIB.BASEBOARD_FAB2(SCH_1):PAGE236
  RT46    2      B RES_0402-0.0,5%,1/16W,CHIP,G21A   I142 @BASEBOARD_FAB2_LIB.BASEBOARD_FAB2(SCH_1):PAGE236

VR_P1V05_PCH_STBY_PH1_PHASE @BASEBOARD_FAB2_LIB.BASEBOARD_FAB2(SCH_1):VR_P1V05_PCH_STBY_PH1_PHASE
 C7A44    2      B CAP_0402-0.220UF,16V,10%,X7R,AA    I34 @BASEBOARD_FAB2_LIB.BASEBOARD_FAB2(SCH_1):PAGE236
 EU7A2   32  PHASE IR354XX_SM-IR35412,IC,H73684-0A   I117 @BASEBOARD_FAB2_LIB.BASEBOARD_FAB2(SCH_1):PAGE236

VR_P1V05_PCH_STBY_PH1_PHASE_SW @BASEBOARD_FAB2_LIB.BASEBOARD_FAB2(SCH_1):VR_P1V05_PCH_STBY_PH1_PHASE_SW
  L7A4    1    INA INDUCTOR_SM-0.3UH,IND,D92183-0A    I45 @BASEBOARD_FAB2_LIB.BASEBOARD_FAB2(SCH_1):PAGE236
 EU7A2   10     SW IR354XX_SM-IR35412,IC,H73684-0A   I117 @BASEBOARD_FAB2_LIB.BASEBOARD_FAB2(SCH_1):PAGE236
  CT68    1      1 SC2K2P50V3KX-GP_SMD-BCG6-SC2K2A   I140 @BASEBOARD_FAB2_LIB.BASEBOARD_FAB2(SCH_1):PAGE236

VR_P1V05_PCH_STBY_PH1_VCIN @BASEBOARD_FAB2_LIB.BASEBOARD_FAB2(SCH_1):VR_P1V05_PCH_STBY_PH1_VCIN
 C7A10    1      A CAP_0402-1.0UF,16V,10%,X6S,D97A    I36 @BASEBOARD_FAB2_LIB.BASEBOARD_FAB2(SCH_1):PAGE236
  R3L4    1      A RES_0402-1.0,1%,1/16W,CHIP,G21A    I41 @BASEBOARD_FAB2_LIB.BASEBOARD_FAB2(SCH_1):PAGE236
 EU7A2    3    VCC IR354XX_SM-IR35412,IC,H73684-0A   I117 @BASEBOARD_FAB2_LIB.BASEBOARD_FAB2(SCH_1):PAGE236

VR_P1V05_PCH_STBY_PWM1 @BASEBOARD_FAB2_LIB.BASEBOARD_FAB2(SCH_1):VR_P1V05_PCH_STBY_PWM1
 EU8A1    3  BPWM1 PXE1110B_QFN-IC,H89187-001   I229 @BASEBOARD_FAB2_LIB.BASEBOARD_FAB2(SCH_1):PAGE235
 EU7A2   34    PWM IR354XX_SM-IR35412,IC,H73684-0A   I117 @BASEBOARD_FAB2_LIB.BASEBOARD_FAB2(SCH_1):PAGE236

VR_P1V26_BMC_STBY_FB @BASEBOARD_FAB2_LIB.BASEBOARD_FAB2(SCH_1):VR_P1V26_BMC_STBY_FB
  R9F8    2      B RES_0402-10.0K,1%,1/16W,CHIP,GA    I14 @BASEBOARD_FAB2_LIB.BASEBOARD_FAB2(SCH_1):PAGE238
 EU9F1    4 ADJ_NC RT9059_DFN-IC,H65765-001    I40 @BASEBOARD_FAB2_LIB.BASEBOARD_FAB2(SCH_1):PAGE238
  R9F6    2      2 4K42R2F-GP_SMD-RG-4K42R2F-GP,6A    I45 @BASEBOARD_FAB2_LIB.BASEBOARD_FAB2(SCH_1):PAGE238

VR_P1V538_BMC_STBY_FB @BASEBOARD_FAB2_LIB.BASEBOARD_FAB2(SCH_1):VR_P1V538_BMC_STBY_FB
 R9F32    2      B RES_0402-13K,1.0%,1/16W,CHIP,GA    I15 @BASEBOARD_FAB2_LIB.BASEBOARD_FAB2(SCH_1):PAGE239
 EU9F2    4 ADJ_NC RT9059_DFN-IC,H65765-001    I70 @BASEBOARD_FAB2_LIB.BASEBOARD_FAB2(SCH_1):PAGE239
 R9F31    2      2 5K1R2F-2-GP_SMD-RG-5K1R2F-2-GPA    I98 @BASEBOARD_FAB2_LIB.BASEBOARD_FAB2(SCH_1):PAGE239

VR_P1V8_PCH_STBY_FB @BASEBOARD_FAB2_LIB.BASEBOARD_FAB2(SCH_1):VR_P1V8_PCH_STBY_FB
 R2L19    1      A RES_0402-49.9K,1%,1/16W,CHIP,GA    I80 @BASEBOARD_FAB2_LIB.BASEBOARD_FAB2(SCH_1):PAGE237
 R2L20    2      B RES_0402-63.4K,1.0%,1/16W,CHIPA    I81 @BASEBOARD_FAB2_LIB.BASEBOARD_FAB2(SCH_1):PAGE237
 EU8A2    4 ADJ_NC RT9059_DFN-IC,H65765-001    I86 @BASEBOARD_FAB2_LIB.BASEBOARD_FAB2(SCH_1):PAGE237

VR_P3V3_STBY_BOOT @BASEBOARD_FAB2_LIB.BASEBOARD_FAB2(SCH_1):VR_P3V3_STBY_BOOT
 EU8F1    4   BOOT RT8240_QFN-IC,H66262-001   I125 @BASEBOARD_FAB2_LIB.BASEBOARD_FAB2(SCH_1):PAGE240
 R8E35    1      A RES_0402-0.0,5%,1/16W,CHIP,G21A   I127 @BASEBOARD_FAB2_LIB.BASEBOARD_FAB2(SCH_1):PAGE240

VR_P3V3_STBY_BOOT_R @BASEBOARD_FAB2_LIB.BASEBOARD_FAB2(SCH_1):VR_P3V3_STBY_BOOT_R
 R8E35    2      B RES_0402-0.0,5%,1/16W,CHIP,G21A   I127 @BASEBOARD_FAB2_LIB.BASEBOARD_FAB2(SCH_1):PAGE240
 C8E12    2      B CAP_0603LF-0.1UF,25V,10%,X7R,6A   I129 @BASEBOARD_FAB2_LIB.BASEBOARD_FAB2(SCH_1):PAGE240

VR_P3V3_STBY_EN @BASEBOARD_FAB2_LIB.BASEBOARD_FAB2(SCH_1):VR_P3V3_STBY_EN
 EU8F1    8     EN RT8240_QFN-IC,H66262-001   I125 @BASEBOARD_FAB2_LIB.BASEBOARD_FAB2(SCH_1):PAGE240
  R8F2    2      B RES_0402-0.0,5%,1/16W,CHIP,G21A   I176 @BASEBOARD_FAB2_LIB.BASEBOARD_FAB2(SCH_1):PAGE240
 R8E40    2      B RES_0402-100.0K,1%,1/16W,EMPTYA   I177 @BASEBOARD_FAB2_LIB.BASEBOARD_FAB2(SCH_1):PAGE240

VR_P3V3_STBY_LGATE @BASEBOARD_FAB2_LIB.BASEBOARD_FAB2(SCH_1):VR_P3V3_STBY_LGATE
 EU8F1    1  LGATE RT8240_QFN-IC,H66262-001   I125 @BASEBOARD_FAB2_LIB.BASEBOARD_FAB2(SCH_1):PAGE240
 EU8E1    4     BG CSD87384M_SM-IC,H66258-001   I170 @BASEBOARD_FAB2_LIB.BASEBOARD_FAB2(SCH_1):PAGE240

VR_P3V3_STBY_OCSELECT @BASEBOARD_FAB2_LIB.BASEBOARD_FAB2(SCH_1):VR_P3V3_STBY_OCSELECT
  R8F9    1      A RES_0402-64.9K,1%,1/16W,CHIP,GA   I106 @BASEBOARD_FAB2_LIB.BASEBOARD_FAB2(SCH_1):PAGE240
 EU8F1   10     CS RT8240_QFN-IC,H66262-001   I125 @BASEBOARD_FAB2_LIB.BASEBOARD_FAB2(SCH_1):PAGE240

VR_P3V3_STBY_PHASE @BASEBOARD_FAB2_LIB.BASEBOARD_FAB2(SCH_1):VR_P3V3_STBY_PHASE
 EU8F1    2  PHASE RT8240_QFN-IC,H66262-001   I125 @BASEBOARD_FAB2_LIB.BASEBOARD_FAB2(SCH_1):PAGE240
 C8E12    1      A CAP_0603LF-0.1UF,25V,10%,X7R,6A   I129 @BASEBOARD_FAB2_LIB.BASEBOARD_FAB2(SCH_1):PAGE240
  C8F3    1      A CAP_0402LF-3300PF,50V,10%,EMPTA   I163 @BASEBOARD_FAB2_LIB.BASEBOARD_FAB2(SCH_1):PAGE240
 EU8E1    5    VSW CSD87384M_SM-IC,H66258-001   I170 @BASEBOARD_FAB2_LIB.BASEBOARD_FAB2(SCH_1):PAGE240
  L8F1    1    INA INDUCTOR_SM-1.00UH,IND,E98679-A   I173 @BASEBOARD_FAB2_LIB.BASEBOARD_FAB2(SCH_1):PAGE240

VR_P3V3_STBY_SNUB @BASEBOARD_FAB2_LIB.BASEBOARD_FAB2(SCH_1):VR_P3V3_STBY_SNUB
  R8F3    1      A RES_0402-2.2,5%,1/16W,EMPTY,G2A   I148 @BASEBOARD_FAB2_LIB.BASEBOARD_FAB2(SCH_1):PAGE240
  C8F3    2      B CAP_0402LF-3300PF,50V,10%,EMPTA   I163 @BASEBOARD_FAB2_LIB.BASEBOARD_FAB2(SCH_1):PAGE240

VR_P3V3_STBY_UGATE @BASEBOARD_FAB2_LIB.BASEBOARD_FAB2(SCH_1):VR_P3V3_STBY_UGATE
 EU8F1    3  UGATE RT8240_QFN-IC,H66262-001   I125 @BASEBOARD_FAB2_LIB.BASEBOARD_FAB2(SCH_1):PAGE240
 EU8E1    1     TG CSD87384M_SM-IC,H66258-001   I170 @BASEBOARD_FAB2_LIB.BASEBOARD_FAB2(SCH_1):PAGE240

VR_P5V_STBY_BOOT @BASEBOARD_FAB2_LIB.BASEBOARD_FAB2(SCH_1):VR_P5V_STBY_BOOT
  C8E6    1      A CAP_0603LF-0.1UF,25V,10%,X7R,6A    I12 @BASEBOARD_FAB2_LIB.BASEBOARD_FAB2(SCH_1):PAGE241
 EU7E2   13   BOOT TPS54821_LCC-IC,H63269-001    I83 @BASEBOARD_FAB2_LIB.BASEBOARD_FAB2(SCH_1):PAGE241

VR_P5V_STBY_COMP @BASEBOARD_FAB2_LIB.BASEBOARD_FAB2(SCH_1):VR_P5V_STBY_COMP
 C8E16    1      A CAP_0402LF-270PF,50V,10%,X7R,AA    I53 @BASEBOARD_FAB2_LIB.BASEBOARD_FAB2(SCH_1):PAGE241
 R8E39    1      A RES_0402-24.9K,1%,1/16W,CHIP,GA    I54 @BASEBOARD_FAB2_LIB.BASEBOARD_FAB2(SCH_1):PAGE241
 EU7E2    8   COMP TPS54821_LCC-IC,H63269-001    I83 @BASEBOARD_FAB2_LIB.BASEBOARD_FAB2(SCH_1):PAGE241

VR_P5V_STBY_EN @BASEBOARD_FAB2_LIB.BASEBOARD_FAB2(SCH_1):VR_P5V_STBY_EN
 EU7E2   10     EN TPS54821_LCC-IC,H63269-001    I83 @BASEBOARD_FAB2_LIB.BASEBOARD_FAB2(SCH_1):PAGE241
 R8E33    2      B RES_0402-0.0,5%,1/16W,CHIP,G21A    I91 @BASEBOARD_FAB2_LIB.BASEBOARD_FAB2(SCH_1):PAGE241

VR_P5V_STBY_PHASE @BASEBOARD_FAB2_LIB.BASEBOARD_FAB2(SCH_1):VR_P5V_STBY_PHASE
  C8E6    2      B CAP_0603LF-0.1UF,25V,10%,X7R,6A    I12 @BASEBOARD_FAB2_LIB.BASEBOARD_FAB2(SCH_1):PAGE241
 EU7E2   11  PH<0> TPS54821_LCC-IC,H63269-001    I83 @BASEBOARD_FAB2_LIB.BASEBOARD_FAB2(SCH_1):PAGE241
 EU7E2   12  PH<1> TPS54821_LCC-IC,H63269-001    I83 @BASEBOARD_FAB2_LIB.BASEBOARD_FAB2(SCH_1):PAGE241
  L8E1    1    INA INDUCTOR_SM-2.2UH,IND,E98761-0A    I90 @BASEBOARD_FAB2_LIB.BASEBOARD_FAB2(SCH_1):PAGE241

VR_P5V_STBY_RC_COMP @BASEBOARD_FAB2_LIB.BASEBOARD_FAB2(SCH_1):VR_P5V_STBY_RC_COMP
 R8E39    2      B RES_0402-24.9K,1%,1/16W,CHIP,GA    I54 @BASEBOARD_FAB2_LIB.BASEBOARD_FAB2(SCH_1):PAGE241
  C8F1    1      A CAP_0402LF-2200PF,50V,10%,X7R,A    I57 @BASEBOARD_FAB2_LIB.BASEBOARD_FAB2(SCH_1):PAGE241

VR_P5V_STBY_RT @BASEBOARD_FAB2_LIB.BASEBOARD_FAB2(SCH_1):VR_P5V_STBY_RT
 R7E14    1      A RES_0402-75K,1%,1/16W,CHIP,G21A    I18 @BASEBOARD_FAB2_LIB.BASEBOARD_FAB2(SCH_1):PAGE241
 EU7E2    1 RT_CLK TPS54821_LCC-IC,H63269-001    I83 @BASEBOARD_FAB2_LIB.BASEBOARD_FAB2(SCH_1):PAGE241

VR_P5V_STBY_SS @BASEBOARD_FAB2_LIB.BASEBOARD_FAB2(SCH_1):VR_P5V_STBY_SS
 C8E15    1      A CAP_0402LF-0.022UF,16V,10%,X7RA    I63 @BASEBOARD_FAB2_LIB.BASEBOARD_FAB2(SCH_1):PAGE241
 EU7E2    9  SS_TR TPS54821_LCC-IC,H63269-001    I83 @BASEBOARD_FAB2_LIB.BASEBOARD_FAB2(SCH_1):PAGE241

VR_P5V_STBY_VIN @BASEBOARD_FAB2_LIB.BASEBOARD_FAB2(SCH_1):VR_P5V_STBY_VIN
 C7E14    1      A CAP_0402-1.0UF,16V,10%,X6S,D97A    I30 @BASEBOARD_FAB2_LIB.BASEBOARD_FAB2(SCH_1):PAGE241
 R7E17    2      B RES_0402-0.0,5%,1/16W,CHIP,G21A    I37 @BASEBOARD_FAB2_LIB.BASEBOARD_FAB2(SCH_1):PAGE241
 EU7E2    6    VIN TPS54821_LCC-IC,H63269-001    I83 @BASEBOARD_FAB2_LIB.BASEBOARD_FAB2(SCH_1):PAGE241

VR_P5V_STBY_VSENSE @BASEBOARD_FAB2_LIB.BASEBOARD_FAB2(SCH_1):VR_P5V_STBY_VSENSE
  R7F1    2      B RES_0402-10.0K,1%,1/16W,CHIP,GA    I50 @BASEBOARD_FAB2_LIB.BASEBOARD_FAB2(SCH_1):PAGE241
 R7E16    1      A RES_0402-1.37K,1%,1/16W,CHIP,GA    I51 @BASEBOARD_FAB2_LIB.BASEBOARD_FAB2(SCH_1):PAGE241
 EU7E2    7 VSENSE TPS54821_LCC-IC,H63269-001    I83 @BASEBOARD_FAB2_LIB.BASEBOARD_FAB2(SCH_1):PAGE241

VR_P5V_STBY_VSENSE_R @BASEBOARD_FAB2_LIB.BASEBOARD_FAB2(SCH_1):VR_P5V_STBY_VSENSE_R
  R7F1    1      A RES_0402-10.0K,1%,1/16W,CHIP,GA    I50 @BASEBOARD_FAB2_LIB.BASEBOARD_FAB2(SCH_1):PAGE241
 R8E37    1      A RES_0402-0.0,5%,1/16W,CHIP,G21A    I78 @BASEBOARD_FAB2_LIB.BASEBOARD_FAB2(SCH_1):PAGE241

VR_PVCCIN_CPU0_AIREF1 @BASEBOARD_FAB2_LIB.BASEBOARD_FAB2(SCH_1):VR_PVCCIN_CPU0_AIREF1
 R6P43    2      B RES_0402-0.0,5%,1/16W,CHIP,G21A   I150 @BASEBOARD_FAB2_LIB.BASEBOARD_FAB2(SCH_1):PAGE201
 EU4D4   23 AIREF1 PXE1610B_QFN-IC,H79206-001   I155 @BASEBOARD_FAB2_LIB.BASEBOARD_FAB2(SCH_1):PAGE201
 EU4E1   39  REFIN IR354XX_SM-IR35411,IC,H73688-0A    I63 @BASEBOARD_FAB2_LIB.BASEBOARD_FAB2(SCH_1):PAGE202
   CT1    1      A CAP_A_0402V-0.1UF,16V,10%,X7R,A    I70 @BASEBOARD_FAB2_LIB.BASEBOARD_FAB2(SCH_1):PAGE202

VR_PVCCIN_CPU0_AIREF2 @BASEBOARD_FAB2_LIB.BASEBOARD_FAB2(SCH_1):VR_PVCCIN_CPU0_AIREF2
 R6P42    2      B RES_0402-0.0,5%,1/16W,CHIP,G21A   I139 @BASEBOARD_FAB2_LIB.BASEBOARD_FAB2(SCH_1):PAGE201
 EU4D4   25 AIREF2 PXE1610B_QFN-IC,H79206-001   I155 @BASEBOARD_FAB2_LIB.BASEBOARD_FAB2(SCH_1):PAGE201
 EU4D6   39  REFIN IR354XX_SM-IR35411,IC,H73688-0A    I64 @BASEBOARD_FAB2_LIB.BASEBOARD_FAB2(SCH_1):PAGE202
   CT6    1      A CAP_A_0402V-0.1UF,16V,10%,X7R,A    I81 @BASEBOARD_FAB2_LIB.BASEBOARD_FAB2(SCH_1):PAGE202

VR_PVCCIN_CPU0_AIREF3 @BASEBOARD_FAB2_LIB.BASEBOARD_FAB2(SCH_1):VR_PVCCIN_CPU0_AIREF3
 R6P38    2      B RES_0402-0.0,5%,1/16W,CHIP,G21A   I147 @BASEBOARD_FAB2_LIB.BASEBOARD_FAB2(SCH_1):PAGE201
 EU4D4   27 AIREF3 PXE1610B_QFN-IC,H79206-001   I155 @BASEBOARD_FAB2_LIB.BASEBOARD_FAB2(SCH_1):PAGE201
 EU4D3   39  REFIN IR354XX_SM-IR35411,IC,H73688-0A    I70 @BASEBOARD_FAB2_LIB.BASEBOARD_FAB2(SCH_1):PAGE203
  CT39    1      A CAP_A_0402V-0.1UF,16V,10%,X7R,A    I96 @BASEBOARD_FAB2_LIB.BASEBOARD_FAB2(SCH_1):PAGE203

VR_PVCCIN_CPU0_AIREF4 @BASEBOARD_FAB2_LIB.BASEBOARD_FAB2(SCH_1):VR_PVCCIN_CPU0_AIREF4
 R6P34    2      B RES_0402-0.0,5%,1/16W,CHIP,G21A   I148 @BASEBOARD_FAB2_LIB.BASEBOARD_FAB2(SCH_1):PAGE201
 EU4D4   29 AIREF4 PXE1610B_QFN-IC,H79206-001   I155 @BASEBOARD_FAB2_LIB.BASEBOARD_FAB2(SCH_1):PAGE201
 EU4D1   39  REFIN IR354XX_SM-IR35411,IC,H73688-0A    I71 @BASEBOARD_FAB2_LIB.BASEBOARD_FAB2(SCH_1):PAGE203
  CT40    1      A CAP_A_0402V-0.1UF,16V,10%,X7R,A    I93 @BASEBOARD_FAB2_LIB.BASEBOARD_FAB2(SCH_1):PAGE203

VR_PVCCIN_CPU0_AIREF5 @BASEBOARD_FAB2_LIB.BASEBOARD_FAB2(SCH_1):VR_PVCCIN_CPU0_AIREF5
 R6P30    2      B RES_0402-0.0,5%,1/16W,CHIP,G21A   I149 @BASEBOARD_FAB2_LIB.BASEBOARD_FAB2(SCH_1):PAGE201
 EU4D4   31 AIREF5 PXE1610B_QFN-IC,H79206-001   I155 @BASEBOARD_FAB2_LIB.BASEBOARD_FAB2(SCH_1):PAGE201
 EU4C2   39  REFIN IR354XX_SM-IR35411,IC,H73688-0A    I71 @BASEBOARD_FAB2_LIB.BASEBOARD_FAB2(SCH_1):PAGE204
  CT36    1      A CAP_A_0402V-0.1UF,16V,10%,X7R,A    I85 @BASEBOARD_FAB2_LIB.BASEBOARD_FAB2(SCH_1):PAGE204

VR_PVCCIN_CPU0_AVINSEN @BASEBOARD_FAB2_LIB.BASEBOARD_FAB2(SCH_1):VR_PVCCIN_CPU0_AVINSEN
 R4D27    2      B RES_0402-100.0K,1%,1/16W,CHIP,B    I54 @BASEBOARD_FAB2_LIB.BASEBOARD_FAB2(SCH_1):PAGE201
 R4D32    1      A RES_0402-1.5K,1%,1/16W,CHIP,G2A    I55 @BASEBOARD_FAB2_LIB.BASEBOARD_FAB2(SCH_1):PAGE201
 C4D20    1      A CAP_0402LF-1000PF,50V,10%,X7R,A    I60 @BASEBOARD_FAB2_LIB.BASEBOARD_FAB2(SCH_1):PAGE201
 EU4D4   45 VINSEN PXE1610B_QFN-IC,H79206-001   I155 @BASEBOARD_FAB2_LIB.BASEBOARD_FAB2(SCH_1):PAGE201

VR_PVCCIN_CPU0_PH1_BOOT @BASEBOARD_FAB2_LIB.BASEBOARD_FAB2(SCH_1):VR_PVCCIN_CPU0_PH1_BOOT
 C4E17    1      A CAP_0402-0.220UF,16V,10%,X7R,AA    I22 @BASEBOARD_FAB2_LIB.BASEBOARD_FAB2(SCH_1):PAGE202
   RT1    1      A RES_0402-0.0,5%,1/16W,CHIP,G21A    I88 @BASEBOARD_FAB2_LIB.BASEBOARD_FAB2(SCH_1):PAGE202

VR_PVCCIN_CPU0_PH1_BOOT_R @BASEBOARD_FAB2_LIB.BASEBOARD_FAB2(SCH_1):VR_PVCCIN_CPU0_PH1_BOOT_R
 EU4E1   33  BOOST IR354XX_SM-IR35411,IC,H73688-0A    I63 @BASEBOARD_FAB2_LIB.BASEBOARD_FAB2(SCH_1):PAGE202
   RT1    2      B RES_0402-0.0,5%,1/16W,CHIP,G21A    I88 @BASEBOARD_FAB2_LIB.BASEBOARD_FAB2(SCH_1):PAGE202

VR_PVCCIN_CPU0_PH1_OCSET @BASEBOARD_FAB2_LIB.BASEBOARD_FAB2(SCH_1):VR_PVCCIN_CPU0_PH1_OCSET
 EU4E1   37  OCSET IR354XX_SM-IR35411,IC,H73688-0A    I63 @BASEBOARD_FAB2_LIB.BASEBOARD_FAB2(SCH_1):PAGE202
 R4E22    1      A RES_0402-68.1K,1%,1/16W,EMPTY,A    I65 @BASEBOARD_FAB2_LIB.BASEBOARD_FAB2(SCH_1):PAGE202

VR_PVCCIN_CPU0_PH1_PHASE @BASEBOARD_FAB2_LIB.BASEBOARD_FAB2(SCH_1):VR_PVCCIN_CPU0_PH1_PHASE
 C4E17    2      B CAP_0402-0.220UF,16V,10%,X7R,AA    I22 @BASEBOARD_FAB2_LIB.BASEBOARD_FAB2(SCH_1):PAGE202
 EU4E1   32  PHASE IR354XX_SM-IR35411,IC,H73688-0A    I63 @BASEBOARD_FAB2_LIB.BASEBOARD_FAB2(SCH_1):PAGE202

VR_PVCCIN_CPU0_PH1_VCIN @BASEBOARD_FAB2_LIB.BASEBOARD_FAB2(SCH_1):VR_PVCCIN_CPU0_PH1_VCIN
  R6R2    1      A RES_0402-1.0,1%,1/16W,CHIP,G21A    I33 @BASEBOARD_FAB2_LIB.BASEBOARD_FAB2(SCH_1):PAGE202
 C4E10    1      A CAP_0402-1.0UF,16V,10%,X6S,D97A    I34 @BASEBOARD_FAB2_LIB.BASEBOARD_FAB2(SCH_1):PAGE202
 EU4E1    3    VCC IR354XX_SM-IR35411,IC,H73688-0A    I63 @BASEBOARD_FAB2_LIB.BASEBOARD_FAB2(SCH_1):PAGE202

VR_PVCCIN_CPU0_PH2_BOOT @BASEBOARD_FAB2_LIB.BASEBOARD_FAB2(SCH_1):VR_PVCCIN_CPU0_PH2_BOOT
 C4D50    1      A CAP_0402-0.220UF,16V,10%,X7R,AA    I32 @BASEBOARD_FAB2_LIB.BASEBOARD_FAB2(SCH_1):PAGE202
   RT3    1      A RES_0402-0.0,5%,1/16W,CHIP,G21A    I89 @BASEBOARD_FAB2_LIB.BASEBOARD_FAB2(SCH_1):PAGE202

VR_PVCCIN_CPU0_PH2_BOOT_R @BASEBOARD_FAB2_LIB.BASEBOARD_FAB2(SCH_1):VR_PVCCIN_CPU0_PH2_BOOT_R
 EU4D6   33  BOOST IR354XX_SM-IR35411,IC,H73688-0A    I64 @BASEBOARD_FAB2_LIB.BASEBOARD_FAB2(SCH_1):PAGE202
   RT3    2      B RES_0402-0.0,5%,1/16W,CHIP,G21A    I89 @BASEBOARD_FAB2_LIB.BASEBOARD_FAB2(SCH_1):PAGE202

VR_PVCCIN_CPU0_PH2_OCSET @BASEBOARD_FAB2_LIB.BASEBOARD_FAB2(SCH_1):VR_PVCCIN_CPU0_PH2_OCSET
 EU4D6   37  OCSET IR354XX_SM-IR35411,IC,H73688-0A    I64 @BASEBOARD_FAB2_LIB.BASEBOARD_FAB2(SCH_1):PAGE202
 R4E19    1      A RES_0402-68.1K,1%,1/16W,EMPTY,A    I67 @BASEBOARD_FAB2_LIB.BASEBOARD_FAB2(SCH_1):PAGE202

VR_PVCCIN_CPU0_PH2_PHASE @BASEBOARD_FAB2_LIB.BASEBOARD_FAB2(SCH_1):VR_PVCCIN_CPU0_PH2_PHASE
 C4D50    2      B CAP_0402-0.220UF,16V,10%,X7R,AA    I32 @BASEBOARD_FAB2_LIB.BASEBOARD_FAB2(SCH_1):PAGE202
 EU4D6   32  PHASE IR354XX_SM-IR35411,IC,H73688-0A    I64 @BASEBOARD_FAB2_LIB.BASEBOARD_FAB2(SCH_1):PAGE202

VR_PVCCIN_CPU0_PH2_VCIN @BASEBOARD_FAB2_LIB.BASEBOARD_FAB2(SCH_1):VR_PVCCIN_CPU0_PH2_VCIN
  R6R6    1      A RES_0402-1.0,1%,1/16W,CHIP,G21A    I39 @BASEBOARD_FAB2_LIB.BASEBOARD_FAB2(SCH_1):PAGE202
 C4E26    1      A CAP_0402-1.0UF,16V,10%,X6S,D97A    I45 @BASEBOARD_FAB2_LIB.BASEBOARD_FAB2(SCH_1):PAGE202
 EU4D6    3    VCC IR354XX_SM-IR35411,IC,H73688-0A    I64 @BASEBOARD_FAB2_LIB.BASEBOARD_FAB2(SCH_1):PAGE202

VR_PVCCIN_CPU0_PH3_BOOT @BASEBOARD_FAB2_LIB.BASEBOARD_FAB2(SCH_1):VR_PVCCIN_CPU0_PH3_BOOT
 C4D28    1      A CAP_0402-0.220UF,16V,10%,X7R,AA    I42 @BASEBOARD_FAB2_LIB.BASEBOARD_FAB2(SCH_1):PAGE203
  RT25    1      A RES_0402-0.0,5%,1/16W,CHIP,G21A   I110 @BASEBOARD_FAB2_LIB.BASEBOARD_FAB2(SCH_1):PAGE203

VR_PVCCIN_CPU0_PH3_BOOT_R @BASEBOARD_FAB2_LIB.BASEBOARD_FAB2(SCH_1):VR_PVCCIN_CPU0_PH3_BOOT_R
 EU4D3   33  BOOST IR354XX_SM-IR35411,IC,H73688-0A    I70 @BASEBOARD_FAB2_LIB.BASEBOARD_FAB2(SCH_1):PAGE203
  RT25    2      B RES_0402-0.0,5%,1/16W,CHIP,G21A   I110 @BASEBOARD_FAB2_LIB.BASEBOARD_FAB2(SCH_1):PAGE203

VR_PVCCIN_CPU0_PH3_OCSET @BASEBOARD_FAB2_LIB.BASEBOARD_FAB2(SCH_1):VR_PVCCIN_CPU0_PH3_OCSET
 EU4D3   37  OCSET IR354XX_SM-IR35411,IC,H73688-0A    I70 @BASEBOARD_FAB2_LIB.BASEBOARD_FAB2(SCH_1):PAGE203
 R4D72    1      A RES_0402-68.1K,1%,1/16W,EMPTY,A    I89 @BASEBOARD_FAB2_LIB.BASEBOARD_FAB2(SCH_1):PAGE203

VR_PVCCIN_CPU0_PH3_PHASE @BASEBOARD_FAB2_LIB.BASEBOARD_FAB2(SCH_1):VR_PVCCIN_CPU0_PH3_PHASE
 C4D28    2      B CAP_0402-0.220UF,16V,10%,X7R,AA    I42 @BASEBOARD_FAB2_LIB.BASEBOARD_FAB2(SCH_1):PAGE203
 EU4D3   32  PHASE IR354XX_SM-IR35411,IC,H73688-0A    I70 @BASEBOARD_FAB2_LIB.BASEBOARD_FAB2(SCH_1):PAGE203

VR_PVCCIN_CPU0_PH3_VCIN @BASEBOARD_FAB2_LIB.BASEBOARD_FAB2(SCH_1):VR_PVCCIN_CPU0_PH3_VCIN
 R6P19    1      A RES_0402-1.0,1%,1/16W,CHIP,G21A    I38 @BASEBOARD_FAB2_LIB.BASEBOARD_FAB2(SCH_1):PAGE203
 C4D16    1      A CAP_0402-1.0UF,16V,10%,X6S,D97A    I45 @BASEBOARD_FAB2_LIB.BASEBOARD_FAB2(SCH_1):PAGE203
 EU4D3    3    VCC IR354XX_SM-IR35411,IC,H73688-0A    I70 @BASEBOARD_FAB2_LIB.BASEBOARD_FAB2(SCH_1):PAGE203

VR_PVCCIN_CPU0_PH4_BOOT @BASEBOARD_FAB2_LIB.BASEBOARD_FAB2(SCH_1):VR_PVCCIN_CPU0_PH4_BOOT
  C4D9    1      A CAP_0402-0.220UF,16V,10%,X7R,AA     I3 @BASEBOARD_FAB2_LIB.BASEBOARD_FAB2(SCH_1):PAGE203
  RT28    1      A RES_0402-0.0,5%,1/16W,CHIP,G21A   I111 @BASEBOARD_FAB2_LIB.BASEBOARD_FAB2(SCH_1):PAGE203

VR_PVCCIN_CPU0_PH4_BOOT_R @BASEBOARD_FAB2_LIB.BASEBOARD_FAB2(SCH_1):VR_PVCCIN_CPU0_PH4_BOOT_R
 EU4D1   33  BOOST IR354XX_SM-IR35411,IC,H73688-0A    I71 @BASEBOARD_FAB2_LIB.BASEBOARD_FAB2(SCH_1):PAGE203
  RT28    2      B RES_0402-0.0,5%,1/16W,CHIP,G21A   I111 @BASEBOARD_FAB2_LIB.BASEBOARD_FAB2(SCH_1):PAGE203

VR_PVCCIN_CPU0_PH4_OCSET @BASEBOARD_FAB2_LIB.BASEBOARD_FAB2(SCH_1):VR_PVCCIN_CPU0_PH4_OCSET
 EU4D1   37  OCSET IR354XX_SM-IR35411,IC,H73688-0A    I71 @BASEBOARD_FAB2_LIB.BASEBOARD_FAB2(SCH_1):PAGE203
 R4D71    1      A RES_0402-68.1K,1%,1/16W,EMPTY,A    I91 @BASEBOARD_FAB2_LIB.BASEBOARD_FAB2(SCH_1):PAGE203

VR_PVCCIN_CPU0_PH4_PHASE @BASEBOARD_FAB2_LIB.BASEBOARD_FAB2(SCH_1):VR_PVCCIN_CPU0_PH4_PHASE
  C4D9    2      B CAP_0402-0.220UF,16V,10%,X7R,AA     I3 @BASEBOARD_FAB2_LIB.BASEBOARD_FAB2(SCH_1):PAGE203
 EU4D1   32  PHASE IR354XX_SM-IR35411,IC,H73688-0A    I71 @BASEBOARD_FAB2_LIB.BASEBOARD_FAB2(SCH_1):PAGE203

VR_PVCCIN_CPU0_PH4_VCIN @BASEBOARD_FAB2_LIB.BASEBOARD_FAB2(SCH_1):VR_PVCCIN_CPU0_PH4_VCIN
 R6P10    1      A RES_0402-1.0,1%,1/16W,CHIP,G21A    I50 @BASEBOARD_FAB2_LIB.BASEBOARD_FAB2(SCH_1):PAGE203
  C4D7    1      A CAP_0402-1.0UF,16V,10%,X6S,D97A    I51 @BASEBOARD_FAB2_LIB.BASEBOARD_FAB2(SCH_1):PAGE203
 EU4D1    3    VCC IR354XX_SM-IR35411,IC,H73688-0A    I71 @BASEBOARD_FAB2_LIB.BASEBOARD_FAB2(SCH_1):PAGE203

VR_PVCCIN_CPU0_PH5_BOOT @BASEBOARD_FAB2_LIB.BASEBOARD_FAB2(SCH_1):VR_PVCCIN_CPU0_PH5_BOOT
 C4C17    1      A CAP_0402-0.220UF,16V,10%,X7R,AA    I22 @BASEBOARD_FAB2_LIB.BASEBOARD_FAB2(SCH_1):PAGE204
  RT23    1      A RES_0402-0.0,5%,1/16W,CHIP,G21A    I93 @BASEBOARD_FAB2_LIB.BASEBOARD_FAB2(SCH_1):PAGE204

VR_PVCCIN_CPU0_PH5_BOOT_R @BASEBOARD_FAB2_LIB.BASEBOARD_FAB2(SCH_1):VR_PVCCIN_CPU0_PH5_BOOT_R
 EU4C2   33  BOOST IR354XX_SM-IR35411,IC,H73688-0A    I71 @BASEBOARD_FAB2_LIB.BASEBOARD_FAB2(SCH_1):PAGE204
  RT23    2      B RES_0402-0.0,5%,1/16W,CHIP,G21A    I93 @BASEBOARD_FAB2_LIB.BASEBOARD_FAB2(SCH_1):PAGE204

VR_PVCCIN_CPU0_PH5_OCSET @BASEBOARD_FAB2_LIB.BASEBOARD_FAB2(SCH_1):VR_PVCCIN_CPU0_PH5_OCSET
 EU4C2   37  OCSET IR354XX_SM-IR35411,IC,H73688-0A    I71 @BASEBOARD_FAB2_LIB.BASEBOARD_FAB2(SCH_1):PAGE204
 R4D68    1      A RES_0402-68.1K,1%,1/16W,EMPTY,A    I83 @BASEBOARD_FAB2_LIB.BASEBOARD_FAB2(SCH_1):PAGE204

VR_PVCCIN_CPU0_PH5_PHASE @BASEBOARD_FAB2_LIB.BASEBOARD_FAB2(SCH_1):VR_PVCCIN_CPU0_PH5_PHASE
 C4C17    2      B CAP_0402-0.220UF,16V,10%,X7R,AA    I22 @BASEBOARD_FAB2_LIB.BASEBOARD_FAB2(SCH_1):PAGE204
 EU4C2   32  PHASE IR354XX_SM-IR35411,IC,H73688-0A    I71 @BASEBOARD_FAB2_LIB.BASEBOARD_FAB2(SCH_1):PAGE204

VR_PVCCIN_CPU0_PH5_VCIN @BASEBOARD_FAB2_LIB.BASEBOARD_FAB2(SCH_1):VR_PVCCIN_CPU0_PH5_VCIN
 R6P47    1      A RES_0402-1.0,1%,1/16W,CHIP,G21A    I33 @BASEBOARD_FAB2_LIB.BASEBOARD_FAB2(SCH_1):PAGE204
 C4D46    1      A CAP_0402-1.0UF,16V,10%,X6S,D97A    I34 @BASEBOARD_FAB2_LIB.BASEBOARD_FAB2(SCH_1):PAGE204
 EU4C2    3    VCC IR354XX_SM-IR35411,IC,H73688-0A    I71 @BASEBOARD_FAB2_LIB.BASEBOARD_FAB2(SCH_1):PAGE204

VR_PVCCIN_CPU0_PHASE1 @BASEBOARD_FAB2_LIB.BASEBOARD_FAB2(SCH_1):VR_PVCCIN_CPU0_PHASE1
  L4E1    1    INA INDUCTOR_SM-0.12UH,IND,D92183-A     I5 @BASEBOARD_FAB2_LIB.BASEBOARD_FAB2(SCH_1):PAGE202
 EU4E1   10     SW IR354XX_SM-IR35411,IC,H73688-0A    I63 @BASEBOARD_FAB2_LIB.BASEBOARD_FAB2(SCH_1):PAGE202
   CT3    1      1 SC2K2P50V3KX-GP_SMD-BCG6-SC2K2A    I76 @BASEBOARD_FAB2_LIB.BASEBOARD_FAB2(SCH_1):PAGE202

VR_PVCCIN_CPU0_PHASE2 @BASEBOARD_FAB2_LIB.BASEBOARD_FAB2(SCH_1):VR_PVCCIN_CPU0_PHASE2
  L4D3    1    INA INDUCTOR_SM-0.12UH,IND,D92183-A    I29 @BASEBOARD_FAB2_LIB.BASEBOARD_FAB2(SCH_1):PAGE202
 EU4D6   10     SW IR354XX_SM-IR35411,IC,H73688-0A    I64 @BASEBOARD_FAB2_LIB.BASEBOARD_FAB2(SCH_1):PAGE202
   CT5    1      1 SC2K2P50V3KX-GP_SMD-BCG6-SC2K2A    I82 @BASEBOARD_FAB2_LIB.BASEBOARD_FAB2(SCH_1):PAGE202

VR_PVCCIN_CPU0_PHASE3 @BASEBOARD_FAB2_LIB.BASEBOARD_FAB2(SCH_1):VR_PVCCIN_CPU0_PHASE3
  L4D2    1    INA INDUCTOR_SM-0.12UH,IND,D92183-A    I15 @BASEBOARD_FAB2_LIB.BASEBOARD_FAB2(SCH_1):PAGE203
 EU4D3   10     SW IR354XX_SM-IR35411,IC,H73688-0A    I70 @BASEBOARD_FAB2_LIB.BASEBOARD_FAB2(SCH_1):PAGE203
  CT38    1      1 SC2K2P50V3KX-GP_SMD-BCG6-SC2K2A   I101 @BASEBOARD_FAB2_LIB.BASEBOARD_FAB2(SCH_1):PAGE203

VR_PVCCIN_CPU0_PHASE4 @BASEBOARD_FAB2_LIB.BASEBOARD_FAB2(SCH_1):VR_PVCCIN_CPU0_PHASE4
  L4D1    1    INA INDUCTOR_SM-0.12UH,IND,D92183-A    I24 @BASEBOARD_FAB2_LIB.BASEBOARD_FAB2(SCH_1):PAGE203
 EU4D1   10     SW IR354XX_SM-IR35411,IC,H73688-0A    I71 @BASEBOARD_FAB2_LIB.BASEBOARD_FAB2(SCH_1):PAGE203
  CT41    1      1 SC2K2P50V3KX-GP_SMD-BCG6-SC2K2A   I106 @BASEBOARD_FAB2_LIB.BASEBOARD_FAB2(SCH_1):PAGE203

VR_PVCCIN_CPU0_PHASE5 @BASEBOARD_FAB2_LIB.BASEBOARD_FAB2(SCH_1):VR_PVCCIN_CPU0_PHASE5
  L4C3    1    INA INDUCTOR_SM-0.12UH,IND,D92183-A     I5 @BASEBOARD_FAB2_LIB.BASEBOARD_FAB2(SCH_1):PAGE204
 EU4C2   10     SW IR354XX_SM-IR35411,IC,H73688-0A    I71 @BASEBOARD_FAB2_LIB.BASEBOARD_FAB2(SCH_1):PAGE204
  CT35    1      1 SC2K2P50V3KX-GP_SMD-BCG6-SC2K2A    I90 @BASEBOARD_FAB2_LIB.BASEBOARD_FAB2(SCH_1):PAGE204

VR_PVCCIN_CPU0_PWM1 @BASEBOARD_FAB2_LIB.BASEBOARD_FAB2(SCH_1):VR_PVCCIN_CPU0_PWM1
 EU4D4    7  APWM1 PXE1610B_QFN-IC,H79206-001   I155 @BASEBOARD_FAB2_LIB.BASEBOARD_FAB2(SCH_1):PAGE201
 EU4E1   34    PWM IR354XX_SM-IR35411,IC,H73688-0A    I63 @BASEBOARD_FAB2_LIB.BASEBOARD_FAB2(SCH_1):PAGE202

VR_PVCCIN_CPU0_PWM2 @BASEBOARD_FAB2_LIB.BASEBOARD_FAB2(SCH_1):VR_PVCCIN_CPU0_PWM2
 EU4D4    6  APWM2 PXE1610B_QFN-IC,H79206-001   I155 @BASEBOARD_FAB2_LIB.BASEBOARD_FAB2(SCH_1):PAGE201
 EU4D6   34    PWM IR354XX_SM-IR35411,IC,H73688-0A    I64 @BASEBOARD_FAB2_LIB.BASEBOARD_FAB2(SCH_1):PAGE202

VR_PVCCIN_CPU0_PWM3 @BASEBOARD_FAB2_LIB.BASEBOARD_FAB2(SCH_1):VR_PVCCIN_CPU0_PWM3
 EU4D4    5  APWM3 PXE1610B_QFN-IC,H79206-001   I155 @BASEBOARD_FAB2_LIB.BASEBOARD_FAB2(SCH_1):PAGE201
 EU4D3   34    PWM IR354XX_SM-IR35411,IC,H73688-0A    I70 @BASEBOARD_FAB2_LIB.BASEBOARD_FAB2(SCH_1):PAGE203

VR_PVCCIN_CPU0_PWM4 @BASEBOARD_FAB2_LIB.BASEBOARD_FAB2(SCH_1):VR_PVCCIN_CPU0_PWM4
 EU4D4    4  APWM4 PXE1610B_QFN-IC,H79206-001   I155 @BASEBOARD_FAB2_LIB.BASEBOARD_FAB2(SCH_1):PAGE201
 EU4D1   34    PWM IR354XX_SM-IR35411,IC,H73688-0A    I71 @BASEBOARD_FAB2_LIB.BASEBOARD_FAB2(SCH_1):PAGE203

VR_PVCCIN_CPU0_PWM5 @BASEBOARD_FAB2_LIB.BASEBOARD_FAB2(SCH_1):VR_PVCCIN_CPU0_PWM5
 EU4D4    3  APWM5 PXE1610B_QFN-IC,H79206-001   I155 @BASEBOARD_FAB2_LIB.BASEBOARD_FAB2(SCH_1):PAGE201
 EU4C2   34    PWM IR354XX_SM-IR35411,IC,H73688-0A    I71 @BASEBOARD_FAB2_LIB.BASEBOARD_FAB2(SCH_1):PAGE204

VR_PVCCIN_CPU0_VD12 @BASEBOARD_FAB2_LIB.BASEBOARD_FAB2(SCH_1):VR_PVCCIN_CPU0_VD12
 C4D25    1      A CAP_A_0402V-1.0UF,6.3V,10%,X6SA    I30 @BASEBOARD_FAB2_LIB.BASEBOARD_FAB2(SCH_1):PAGE201
 C4D26    1      A CAP_A_0402V-0.1UF,16V,10%,X7R,A    I32 @BASEBOARD_FAB2_LIB.BASEBOARD_FAB2(SCH_1):PAGE201
 R6P42    1      A RES_0402-0.0,5%,1/16W,CHIP,G21A   I139 @BASEBOARD_FAB2_LIB.BASEBOARD_FAB2(SCH_1):PAGE201
 R6P38    1      A RES_0402-0.0,5%,1/16W,CHIP,G21A   I147 @BASEBOARD_FAB2_LIB.BASEBOARD_FAB2(SCH_1):PAGE201
 R6P34    1      A RES_0402-0.0,5%,1/16W,CHIP,G21A   I148 @BASEBOARD_FAB2_LIB.BASEBOARD_FAB2(SCH_1):PAGE201
 R6P30    1      A RES_0402-0.0,5%,1/16W,CHIP,G21A   I149 @BASEBOARD_FAB2_LIB.BASEBOARD_FAB2(SCH_1):PAGE201
 R6P43    1      A RES_0402-0.0,5%,1/16W,CHIP,G21A   I150 @BASEBOARD_FAB2_LIB.BASEBOARD_FAB2(SCH_1):PAGE201
 R6P29    1      A RES_0402-0.0,5%,1/16W,CHIP,G21A   I154 @BASEBOARD_FAB2_LIB.BASEBOARD_FAB2(SCH_1):PAGE201
 EU4D4   48   VD12 PXE1610B_QFN-IC,H79206-001   I155 @BASEBOARD_FAB2_LIB.BASEBOARD_FAB2(SCH_1):PAGE201

VR_PVCCIN_CPU0_VDD @BASEBOARD_FAB2_LIB.BASEBOARD_FAB2(SCH_1):VR_PVCCIN_CPU0_VDD
 C4D15    1      A CAP_A_0402V-1.0UF,6.3V,10%,X6SA    I37 @BASEBOARD_FAB2_LIB.BASEBOARD_FAB2(SCH_1):PAGE201
 C4D19    1      A CAP_A_0402V-0.1UF,16V,10%,X7R,A    I39 @BASEBOARD_FAB2_LIB.BASEBOARD_FAB2(SCH_1):PAGE201
 R4D26    2      B RES_0402-0.0,5%,1/16W,CHIP,G21A    I40 @BASEBOARD_FAB2_LIB.BASEBOARD_FAB2(SCH_1):PAGE201
 EU4D4   47    VDD PXE1610B_QFN-IC,H79206-001   I155 @BASEBOARD_FAB2_LIB.BASEBOARD_FAB2(SCH_1):PAGE201

VR_PVCCIN_CPU0_VREN @BASEBOARD_FAB2_LIB.BASEBOARD_FAB2(SCH_1):VR_PVCCIN_CPU0_VREN
 R6P18    2      B RES_0402-0.0,5%,1/16W,CHIP,G21A   I131 @BASEBOARD_FAB2_LIB.BASEBOARD_FAB2(SCH_1):PAGE201
 R6P16    2      B RES_0402-1.00K,1%,1/16W,CHIP,GA   I132 @BASEBOARD_FAB2_LIB.BASEBOARD_FAB2(SCH_1):PAGE201
 EU4D4   12  AVREN PXE1610B_QFN-IC,H79206-001   I155 @BASEBOARD_FAB2_LIB.BASEBOARD_FAB2(SCH_1):PAGE201

VR_PVCCIN_CPU0_XADDR1 @BASEBOARD_FAB2_LIB.BASEBOARD_FAB2(SCH_1):VR_PVCCIN_CPU0_XADDR1
 R6P28    1      A RES_0402-4.02K,1%,1/16W,CHIP,GA   I121 @BASEBOARD_FAB2_LIB.BASEBOARD_FAB2(SCH_1):PAGE201
 EU4D4   44 XADDR1 PXE1610B_QFN-IC,H79206-001   I155 @BASEBOARD_FAB2_LIB.BASEBOARD_FAB2(SCH_1):PAGE201

VR_PVCCIN_CPU0_XADDR2 @BASEBOARD_FAB2_LIB.BASEBOARD_FAB2(SCH_1):VR_PVCCIN_CPU0_XADDR2
 R6P27    1      A RES_0402-4.02K,1%,1/16W,CHIP,GA   I120 @BASEBOARD_FAB2_LIB.BASEBOARD_FAB2(SCH_1):PAGE201
 EU4D4   41 XADDR2 PXE1610B_QFN-IC,H79206-001   I155 @BASEBOARD_FAB2_LIB.BASEBOARD_FAB2(SCH_1):PAGE201

VR_PVCCIN_CPU1_AIREF1 @BASEBOARD_FAB2_LIB.BASEBOARD_FAB2(SCH_1):VR_PVCCIN_CPU1_AIREF1
 R9N15    2      B RES_0402-0.0,5%,1/16W,CHIP,G21A   I122 @BASEBOARD_FAB2_LIB.BASEBOARD_FAB2(SCH_1):PAGE206
 EU1C2   23 AIREF1 PXE1610B_QFN-IC,H79206-001   I130 @BASEBOARD_FAB2_LIB.BASEBOARD_FAB2(SCH_1):PAGE206
 EU1E2   39  REFIN IR354XX_SM-IR35411,IC,H73688-0A    I20 @BASEBOARD_FAB2_LIB.BASEBOARD_FAB2(SCH_1):PAGE207
  CT24    1      A CAP_A_0402V-0.1UF,16V,10%,X7R,A    I71 @BASEBOARD_FAB2_LIB.BASEBOARD_FAB2(SCH_1):PAGE207

VR_PVCCIN_CPU1_AIREF2 @BASEBOARD_FAB2_LIB.BASEBOARD_FAB2(SCH_1):VR_PVCCIN_CPU1_AIREF2
 R9N17    2      B RES_0402-0.0,5%,1/16W,CHIP,G21A   I123 @BASEBOARD_FAB2_LIB.BASEBOARD_FAB2(SCH_1):PAGE206
 EU1C2   25 AIREF2 PXE1610B_QFN-IC,H79206-001   I130 @BASEBOARD_FAB2_LIB.BASEBOARD_FAB2(SCH_1):PAGE206
 EU1D4   39  REFIN IR354XX_SM-IR35411,IC,H73688-0A    I24 @BASEBOARD_FAB2_LIB.BASEBOARD_FAB2(SCH_1):PAGE207
  CT25    1      A CAP_A_0402V-0.1UF,16V,10%,X7R,A    I81 @BASEBOARD_FAB2_LIB.BASEBOARD_FAB2(SCH_1):PAGE207

VR_PVCCIN_CPU1_AIREF3 @BASEBOARD_FAB2_LIB.BASEBOARD_FAB2(SCH_1):VR_PVCCIN_CPU1_AIREF3
 R9N12    2      B RES_0402-0.0,5%,1/16W,CHIP,G21A   I124 @BASEBOARD_FAB2_LIB.BASEBOARD_FAB2(SCH_1):PAGE206
 EU1C2   27 AIREF3 PXE1610B_QFN-IC,H79206-001   I130 @BASEBOARD_FAB2_LIB.BASEBOARD_FAB2(SCH_1):PAGE206
 EU1D3   39  REFIN IR354XX_SM-IR35411,IC,H73688-0A    I27 @BASEBOARD_FAB2_LIB.BASEBOARD_FAB2(SCH_1):PAGE208
  CT16    1      A CAP_A_0402V-0.1UF,16V,10%,X7R,A    I80 @BASEBOARD_FAB2_LIB.BASEBOARD_FAB2(SCH_1):PAGE208

VR_PVCCIN_CPU1_AIREF4 @BASEBOARD_FAB2_LIB.BASEBOARD_FAB2(SCH_1):VR_PVCCIN_CPU1_AIREF4
 R9N10    2      B RES_0402-0.0,5%,1/16W,CHIP,G21A   I125 @BASEBOARD_FAB2_LIB.BASEBOARD_FAB2(SCH_1):PAGE206
 EU1C2   29 AIREF4 PXE1610B_QFN-IC,H79206-001   I130 @BASEBOARD_FAB2_LIB.BASEBOARD_FAB2(SCH_1):PAGE206
 EU1D1   39  REFIN IR354XX_SM-IR35411,IC,H73688-0A    I71 @BASEBOARD_FAB2_LIB.BASEBOARD_FAB2(SCH_1):PAGE208
  CT21    1      A CAP_A_0402V-0.1UF,16V,10%,X7R,A    I87 @BASEBOARD_FAB2_LIB.BASEBOARD_FAB2(SCH_1):PAGE208

VR_PVCCIN_CPU1_AIREF5 @BASEBOARD_FAB2_LIB.BASEBOARD_FAB2(SCH_1):VR_PVCCIN_CPU1_AIREF5
  R9N9    2      B RES_0402-0.0,5%,1/16W,CHIP,G21A   I126 @BASEBOARD_FAB2_LIB.BASEBOARD_FAB2(SCH_1):PAGE206
 EU1C2   31 AIREF5 PXE1610B_QFN-IC,H79206-001   I130 @BASEBOARD_FAB2_LIB.BASEBOARD_FAB2(SCH_1):PAGE206
 EU1C3   39  REFIN IR354XX_SM-IR35411,IC,H73688-0A    I56 @BASEBOARD_FAB2_LIB.BASEBOARD_FAB2(SCH_1):PAGE209
  CT13    1      A CAP_A_0402V-0.1UF,16V,10%,X7R,A    I62 @BASEBOARD_FAB2_LIB.BASEBOARD_FAB2(SCH_1):PAGE209

VR_PVCCIN_CPU1_AVINSEN @BASEBOARD_FAB2_LIB.BASEBOARD_FAB2(SCH_1):VR_PVCCIN_CPU1_AVINSEN
 R1C13    2      B RES_0402-100.0K,1%,1/16W,CHIP,B    I49 @BASEBOARD_FAB2_LIB.BASEBOARD_FAB2(SCH_1):PAGE206
 R1C16    1      A RES_0402-1.5K,1%,1/16W,CHIP,G2A    I56 @BASEBOARD_FAB2_LIB.BASEBOARD_FAB2(SCH_1):PAGE206
  C1C8    1      A CAP_0402LF-1000PF,50V,10%,X7R,A    I73 @BASEBOARD_FAB2_LIB.BASEBOARD_FAB2(SCH_1):PAGE206
 EU1C2   45 VINSEN PXE1610B_QFN-IC,H79206-001   I130 @BASEBOARD_FAB2_LIB.BASEBOARD_FAB2(SCH_1):PAGE206

VR_PVCCIN_CPU1_PH1_BOOT @BASEBOARD_FAB2_LIB.BASEBOARD_FAB2(SCH_1):VR_PVCCIN_CPU1_PH1_BOOT
 C1E11    1      A CAP_0402-0.220UF,16V,10%,X7R,AA    I30 @BASEBOARD_FAB2_LIB.BASEBOARD_FAB2(SCH_1):PAGE207
  RT15    1      A RES_0402-0.0,5%,1/16W,CHIP,G21A    I87 @BASEBOARD_FAB2_LIB.BASEBOARD_FAB2(SCH_1):PAGE207

VR_PVCCIN_CPU1_PH1_BOOT_R @BASEBOARD_FAB2_LIB.BASEBOARD_FAB2(SCH_1):VR_PVCCIN_CPU1_PH1_BOOT_R
 EU1E2   33  BOOST IR354XX_SM-IR35411,IC,H73688-0A    I20 @BASEBOARD_FAB2_LIB.BASEBOARD_FAB2(SCH_1):PAGE207
  RT15    2      B RES_0402-0.0,5%,1/16W,CHIP,G21A    I87 @BASEBOARD_FAB2_LIB.BASEBOARD_FAB2(SCH_1):PAGE207

VR_PVCCIN_CPU1_PH1_OCSET @BASEBOARD_FAB2_LIB.BASEBOARD_FAB2(SCH_1):VR_PVCCIN_CPU1_PH1_OCSET
 EU1E2   37  OCSET IR354XX_SM-IR35411,IC,H73688-0A    I20 @BASEBOARD_FAB2_LIB.BASEBOARD_FAB2(SCH_1):PAGE207
 R1E14    1      A RES_0402-68.1K,1%,1/16W,EMPTY,A    I68 @BASEBOARD_FAB2_LIB.BASEBOARD_FAB2(SCH_1):PAGE207

VR_PVCCIN_CPU1_PH1_PHASE @BASEBOARD_FAB2_LIB.BASEBOARD_FAB2(SCH_1):VR_PVCCIN_CPU1_PH1_PHASE
 EU1E2   32  PHASE IR354XX_SM-IR35411,IC,H73688-0A    I20 @BASEBOARD_FAB2_LIB.BASEBOARD_FAB2(SCH_1):PAGE207
 C1E11    2      B CAP_0402-0.220UF,16V,10%,X7R,AA    I30 @BASEBOARD_FAB2_LIB.BASEBOARD_FAB2(SCH_1):PAGE207

VR_PVCCIN_CPU1_PH1_VCIN @BASEBOARD_FAB2_LIB.BASEBOARD_FAB2(SCH_1):VR_PVCCIN_CPU1_PH1_VCIN
 EU1E2    3    VCC IR354XX_SM-IR35411,IC,H73688-0A    I20 @BASEBOARD_FAB2_LIB.BASEBOARD_FAB2(SCH_1):PAGE207
  R9R2    1      A RES_0402-1.0,1%,1/16W,CHIP,G21A    I26 @BASEBOARD_FAB2_LIB.BASEBOARD_FAB2(SCH_1):PAGE207
  C1E8    1      A CAP_0402-1.0UF,16V,10%,X6S,D97A    I32 @BASEBOARD_FAB2_LIB.BASEBOARD_FAB2(SCH_1):PAGE207

VR_PVCCIN_CPU1_PH2_BOOT @BASEBOARD_FAB2_LIB.BASEBOARD_FAB2(SCH_1):VR_PVCCIN_CPU1_PH2_BOOT
 C1D36    1      A CAP_0402-0.220UF,16V,10%,X7R,AA    I38 @BASEBOARD_FAB2_LIB.BASEBOARD_FAB2(SCH_1):PAGE207
  RT17    1      A RES_0402-0.0,5%,1/16W,CHIP,G21A    I88 @BASEBOARD_FAB2_LIB.BASEBOARD_FAB2(SCH_1):PAGE207

VR_PVCCIN_CPU1_PH2_BOOT_R @BASEBOARD_FAB2_LIB.BASEBOARD_FAB2(SCH_1):VR_PVCCIN_CPU1_PH2_BOOT_R
 EU1D4   33  BOOST IR354XX_SM-IR35411,IC,H73688-0A    I24 @BASEBOARD_FAB2_LIB.BASEBOARD_FAB2(SCH_1):PAGE207
  RT17    2      B RES_0402-0.0,5%,1/16W,CHIP,G21A    I88 @BASEBOARD_FAB2_LIB.BASEBOARD_FAB2(SCH_1):PAGE207

VR_PVCCIN_CPU1_PH2_OCSET @BASEBOARD_FAB2_LIB.BASEBOARD_FAB2(SCH_1):VR_PVCCIN_CPU1_PH2_OCSET
 EU1D4   37  OCSET IR354XX_SM-IR35411,IC,H73688-0A    I24 @BASEBOARD_FAB2_LIB.BASEBOARD_FAB2(SCH_1):PAGE207
 R1E13    1      A RES_0402-68.1K,1%,1/16W,EMPTY,A    I67 @BASEBOARD_FAB2_LIB.BASEBOARD_FAB2(SCH_1):PAGE207

VR_PVCCIN_CPU1_PH2_PHASE @BASEBOARD_FAB2_LIB.BASEBOARD_FAB2(SCH_1):VR_PVCCIN_CPU1_PH2_PHASE
 EU1D4   32  PHASE IR354XX_SM-IR35411,IC,H73688-0A    I24 @BASEBOARD_FAB2_LIB.BASEBOARD_FAB2(SCH_1):PAGE207
 C1D36    2      B CAP_0402-0.220UF,16V,10%,X7R,AA    I38 @BASEBOARD_FAB2_LIB.BASEBOARD_FAB2(SCH_1):PAGE207

VR_PVCCIN_CPU1_PH2_VCIN @BASEBOARD_FAB2_LIB.BASEBOARD_FAB2(SCH_1):VR_PVCCIN_CPU1_PH2_VCIN
 EU1D4    3    VCC IR354XX_SM-IR35411,IC,H73688-0A    I24 @BASEBOARD_FAB2_LIB.BASEBOARD_FAB2(SCH_1):PAGE207
 R9R11    1      A RES_0402-1.0,1%,1/16W,CHIP,G21A    I39 @BASEBOARD_FAB2_LIB.BASEBOARD_FAB2(SCH_1):PAGE207
 C1E24    1      A CAP_0402-1.0UF,16V,10%,X6S,D97A    I40 @BASEBOARD_FAB2_LIB.BASEBOARD_FAB2(SCH_1):PAGE207

VR_PVCCIN_CPU1_PH3_BOOT @BASEBOARD_FAB2_LIB.BASEBOARD_FAB2(SCH_1):VR_PVCCIN_CPU1_PH3_BOOT
 C1D20    1      A CAP_0402-0.220UF,16V,10%,X7R,AA    I40 @BASEBOARD_FAB2_LIB.BASEBOARD_FAB2(SCH_1):PAGE208
  RT11    1      A RES_0402-0.0,5%,1/16W,CHIP,G21A    I96 @BASEBOARD_FAB2_LIB.BASEBOARD_FAB2(SCH_1):PAGE208

VR_PVCCIN_CPU1_PH3_BOOT_R @BASEBOARD_FAB2_LIB.BASEBOARD_FAB2(SCH_1):VR_PVCCIN_CPU1_PH3_BOOT_R
 EU1D3   33  BOOST IR354XX_SM-IR35411,IC,H73688-0A    I27 @BASEBOARD_FAB2_LIB.BASEBOARD_FAB2(SCH_1):PAGE208
  RT11    2      B RES_0402-0.0,5%,1/16W,CHIP,G21A    I96 @BASEBOARD_FAB2_LIB.BASEBOARD_FAB2(SCH_1):PAGE208

VR_PVCCIN_CPU1_PH3_OCSET @BASEBOARD_FAB2_LIB.BASEBOARD_FAB2(SCH_1):VR_PVCCIN_CPU1_PH3_OCSET
 EU1D3   37  OCSET IR354XX_SM-IR35411,IC,H73688-0A    I27 @BASEBOARD_FAB2_LIB.BASEBOARD_FAB2(SCH_1):PAGE208
 R1D55    1      A RES_0402-68.1K,1%,1/16W,EMPTY,A    I76 @BASEBOARD_FAB2_LIB.BASEBOARD_FAB2(SCH_1):PAGE208

VR_PVCCIN_CPU1_PH3_PHASE @BASEBOARD_FAB2_LIB.BASEBOARD_FAB2(SCH_1):VR_PVCCIN_CPU1_PH3_PHASE
 EU1D3   32  PHASE IR354XX_SM-IR35411,IC,H73688-0A    I27 @BASEBOARD_FAB2_LIB.BASEBOARD_FAB2(SCH_1):PAGE208
 C1D20    2      B CAP_0402-0.220UF,16V,10%,X7R,AA    I40 @BASEBOARD_FAB2_LIB.BASEBOARD_FAB2(SCH_1):PAGE208

VR_PVCCIN_CPU1_PH3_VCIN @BASEBOARD_FAB2_LIB.BASEBOARD_FAB2(SCH_1):VR_PVCCIN_CPU1_PH3_VCIN
 EU1D3    3    VCC IR354XX_SM-IR35411,IC,H73688-0A    I27 @BASEBOARD_FAB2_LIB.BASEBOARD_FAB2(SCH_1):PAGE208
 R9P22    1      A RES_0402-1.0,1%,1/16W,CHIP,G21A    I36 @BASEBOARD_FAB2_LIB.BASEBOARD_FAB2(SCH_1):PAGE208
 C1D17    1      A CAP_0402-1.0UF,16V,10%,X6S,D97A    I43 @BASEBOARD_FAB2_LIB.BASEBOARD_FAB2(SCH_1):PAGE208

VR_PVCCIN_CPU1_PH4_BOOT @BASEBOARD_FAB2_LIB.BASEBOARD_FAB2(SCH_1):VR_PVCCIN_CPU1_PH4_BOOT
 C1D10    1      A CAP_0402-0.220UF,16V,10%,X7R,AA    I48 @BASEBOARD_FAB2_LIB.BASEBOARD_FAB2(SCH_1):PAGE208
  RT14    1      A RES_0402-0.0,5%,1/16W,CHIP,G21A    I97 @BASEBOARD_FAB2_LIB.BASEBOARD_FAB2(SCH_1):PAGE208

VR_PVCCIN_CPU1_PH4_BOOT_R @BASEBOARD_FAB2_LIB.BASEBOARD_FAB2(SCH_1):VR_PVCCIN_CPU1_PH4_BOOT_R
 EU1D1   33  BOOST IR354XX_SM-IR35411,IC,H73688-0A    I71 @BASEBOARD_FAB2_LIB.BASEBOARD_FAB2(SCH_1):PAGE208
  RT14    2      B RES_0402-0.0,5%,1/16W,CHIP,G21A    I97 @BASEBOARD_FAB2_LIB.BASEBOARD_FAB2(SCH_1):PAGE208

VR_PVCCIN_CPU1_PH4_OCSET @BASEBOARD_FAB2_LIB.BASEBOARD_FAB2(SCH_1):VR_PVCCIN_CPU1_PH4_OCSET
 EU1D1   37  OCSET IR354XX_SM-IR35411,IC,H73688-0A    I71 @BASEBOARD_FAB2_LIB.BASEBOARD_FAB2(SCH_1):PAGE208
 R1D54    1      A RES_0402-68.1K,1%,1/16W,EMPTY,A    I75 @BASEBOARD_FAB2_LIB.BASEBOARD_FAB2(SCH_1):PAGE208

VR_PVCCIN_CPU1_PH4_PHASE @BASEBOARD_FAB2_LIB.BASEBOARD_FAB2(SCH_1):VR_PVCCIN_CPU1_PH4_PHASE
 C1D10    2      B CAP_0402-0.220UF,16V,10%,X7R,AA    I48 @BASEBOARD_FAB2_LIB.BASEBOARD_FAB2(SCH_1):PAGE208
 EU1D1   32  PHASE IR354XX_SM-IR35411,IC,H73688-0A    I71 @BASEBOARD_FAB2_LIB.BASEBOARD_FAB2(SCH_1):PAGE208

VR_PVCCIN_CPU1_PH4_VCIN @BASEBOARD_FAB2_LIB.BASEBOARD_FAB2(SCH_1):VR_PVCCIN_CPU1_PH4_VCIN
  R9P8    1      A RES_0402-1.0,1%,1/16W,CHIP,G21A    I49 @BASEBOARD_FAB2_LIB.BASEBOARD_FAB2(SCH_1):PAGE208
  C1D7    1      A CAP_0402-1.0UF,16V,10%,X6S,D97A    I50 @BASEBOARD_FAB2_LIB.BASEBOARD_FAB2(SCH_1):PAGE208
 EU1D1    3    VCC IR354XX_SM-IR35411,IC,H73688-0A    I71 @BASEBOARD_FAB2_LIB.BASEBOARD_FAB2(SCH_1):PAGE208

VR_PVCCIN_CPU1_PH5_BOOT @BASEBOARD_FAB2_LIB.BASEBOARD_FAB2(SCH_1):VR_PVCCIN_CPU1_PH5_BOOT
 C1C24    1      A CAP_0402-0.220UF,16V,10%,X7R,AA    I20 @BASEBOARD_FAB2_LIB.BASEBOARD_FAB2(SCH_1):PAGE209
   RT9    1      A RES_0402-0.0,5%,1/16W,CHIP,G21A    I69 @BASEBOARD_FAB2_LIB.BASEBOARD_FAB2(SCH_1):PAGE209

VR_PVCCIN_CPU1_PH5_BOOT_R @BASEBOARD_FAB2_LIB.BASEBOARD_FAB2(SCH_1):VR_PVCCIN_CPU1_PH5_BOOT_R
 EU1C3   33  BOOST IR354XX_SM-IR35411,IC,H73688-0A    I56 @BASEBOARD_FAB2_LIB.BASEBOARD_FAB2(SCH_1):PAGE209
   RT9    2      B RES_0402-0.0,5%,1/16W,CHIP,G21A    I69 @BASEBOARD_FAB2_LIB.BASEBOARD_FAB2(SCH_1):PAGE209

VR_PVCCIN_CPU1_PH5_OCSET @BASEBOARD_FAB2_LIB.BASEBOARD_FAB2(SCH_1):VR_PVCCIN_CPU1_PH5_OCSET
 EU1C3   37  OCSET IR354XX_SM-IR35411,IC,H73688-0A    I56 @BASEBOARD_FAB2_LIB.BASEBOARD_FAB2(SCH_1):PAGE209
 R1D52    1      A RES_0402-68.1K,1%,1/16W,EMPTY,A    I59 @BASEBOARD_FAB2_LIB.BASEBOARD_FAB2(SCH_1):PAGE209

VR_PVCCIN_CPU1_PH5_PHASE @BASEBOARD_FAB2_LIB.BASEBOARD_FAB2(SCH_1):VR_PVCCIN_CPU1_PH5_PHASE
 C1C24    2      B CAP_0402-0.220UF,16V,10%,X7R,AA    I20 @BASEBOARD_FAB2_LIB.BASEBOARD_FAB2(SCH_1):PAGE209
 EU1C3   32  PHASE IR354XX_SM-IR35411,IC,H73688-0A    I56 @BASEBOARD_FAB2_LIB.BASEBOARD_FAB2(SCH_1):PAGE209

VR_PVCCIN_CPU1_PH5_VCIN @BASEBOARD_FAB2_LIB.BASEBOARD_FAB2(SCH_1):VR_PVCCIN_CPU1_PH5_VCIN
 C1D32    1      A CAP_0402-1.0UF,16V,10%,X6S,D97A    I18 @BASEBOARD_FAB2_LIB.BASEBOARD_FAB2(SCH_1):PAGE209
 R9P32    1      A RES_0402-1.0,1%,1/16W,CHIP,G21A    I24 @BASEBOARD_FAB2_LIB.BASEBOARD_FAB2(SCH_1):PAGE209
 EU1C3    3    VCC IR354XX_SM-IR35411,IC,H73688-0A    I56 @BASEBOARD_FAB2_LIB.BASEBOARD_FAB2(SCH_1):PAGE209

VR_PVCCIN_CPU1_PHASE1 @BASEBOARD_FAB2_LIB.BASEBOARD_FAB2(SCH_1):VR_PVCCIN_CPU1_PHASE1
  L1E1    1    INA INDUCTOR_SM-0.12UH,IND,D92183-A    I10 @BASEBOARD_FAB2_LIB.BASEBOARD_FAB2(SCH_1):PAGE207
 EU1E2   10     SW IR354XX_SM-IR35411,IC,H73688-0A    I20 @BASEBOARD_FAB2_LIB.BASEBOARD_FAB2(SCH_1):PAGE207
  CT23    1      1 SC2K2P50V3KX-GP_SMD-BCG6-SC2K2A    I77 @BASEBOARD_FAB2_LIB.BASEBOARD_FAB2(SCH_1):PAGE207

VR_PVCCIN_CPU1_PHASE2 @BASEBOARD_FAB2_LIB.BASEBOARD_FAB2(SCH_1):VR_PVCCIN_CPU1_PHASE2
  L1D3    1    INA INDUCTOR_SM-0.12UH,IND,D92183-A    I16 @BASEBOARD_FAB2_LIB.BASEBOARD_FAB2(SCH_1):PAGE207
 EU1D4   10     SW IR354XX_SM-IR35411,IC,H73688-0A    I24 @BASEBOARD_FAB2_LIB.BASEBOARD_FAB2(SCH_1):PAGE207
  CT27    1      1 SC2K2P50V3KX-GP_SMD-BCG6-SC2K2A    I84 @BASEBOARD_FAB2_LIB.BASEBOARD_FAB2(SCH_1):PAGE207

VR_PVCCIN_CPU1_PHASE3 @BASEBOARD_FAB2_LIB.BASEBOARD_FAB2(SCH_1):VR_PVCCIN_CPU1_PHASE3
  L1D2    1    INA INDUCTOR_SM-0.12UH,IND,D92183-A    I11 @BASEBOARD_FAB2_LIB.BASEBOARD_FAB2(SCH_1):PAGE208
 EU1D3   10     SW IR354XX_SM-IR35411,IC,H73688-0A    I27 @BASEBOARD_FAB2_LIB.BASEBOARD_FAB2(SCH_1):PAGE208
  CT18    1      1 SC2K2P50V3KX-GP_SMD-BCG6-SC2K2A    I84 @BASEBOARD_FAB2_LIB.BASEBOARD_FAB2(SCH_1):PAGE208

VR_PVCCIN_CPU1_PHASE4 @BASEBOARD_FAB2_LIB.BASEBOARD_FAB2(SCH_1):VR_PVCCIN_CPU1_PHASE4
  L1D1    1    INA INDUCTOR_SM-0.12UH,IND,D92183-A    I20 @BASEBOARD_FAB2_LIB.BASEBOARD_FAB2(SCH_1):PAGE208
 EU1D1   10     SW IR354XX_SM-IR35411,IC,H73688-0A    I71 @BASEBOARD_FAB2_LIB.BASEBOARD_FAB2(SCH_1):PAGE208
  CT20    1      1 SC2K2P50V3KX-GP_SMD-BCG6-SC2K2A    I92 @BASEBOARD_FAB2_LIB.BASEBOARD_FAB2(SCH_1):PAGE208

VR_PVCCIN_CPU1_PHASE5 @BASEBOARD_FAB2_LIB.BASEBOARD_FAB2(SCH_1):VR_PVCCIN_CPU1_PHASE5
  L1C2    1    INA INDUCTOR_SM-0.12UH,IND,D92183-A    I40 @BASEBOARD_FAB2_LIB.BASEBOARD_FAB2(SCH_1):PAGE209
 EU1C3   10     SW IR354XX_SM-IR35411,IC,H73688-0A    I56 @BASEBOARD_FAB2_LIB.BASEBOARD_FAB2(SCH_1):PAGE209
  CT14    1      1 SC2K2P50V3KX-GP_SMD-BCG6-SC2K2A    I64 @BASEBOARD_FAB2_LIB.BASEBOARD_FAB2(SCH_1):PAGE209

VR_PVCCIN_CPU1_PWM1 @BASEBOARD_FAB2_LIB.BASEBOARD_FAB2(SCH_1):VR_PVCCIN_CPU1_PWM1
 EU1C2    7  APWM1 PXE1610B_QFN-IC,H79206-001   I130 @BASEBOARD_FAB2_LIB.BASEBOARD_FAB2(SCH_1):PAGE206
 EU1E2   34    PWM IR354XX_SM-IR35411,IC,H73688-0A    I20 @BASEBOARD_FAB2_LIB.BASEBOARD_FAB2(SCH_1):PAGE207

VR_PVCCIN_CPU1_PWM2 @BASEBOARD_FAB2_LIB.BASEBOARD_FAB2(SCH_1):VR_PVCCIN_CPU1_PWM2
 EU1C2    6  APWM2 PXE1610B_QFN-IC,H79206-001   I130 @BASEBOARD_FAB2_LIB.BASEBOARD_FAB2(SCH_1):PAGE206
 EU1D4   34    PWM IR354XX_SM-IR35411,IC,H73688-0A    I24 @BASEBOARD_FAB2_LIB.BASEBOARD_FAB2(SCH_1):PAGE207

VR_PVCCIN_CPU1_PWM3 @BASEBOARD_FAB2_LIB.BASEBOARD_FAB2(SCH_1):VR_PVCCIN_CPU1_PWM3
 EU1C2    5  APWM3 PXE1610B_QFN-IC,H79206-001   I130 @BASEBOARD_FAB2_LIB.BASEBOARD_FAB2(SCH_1):PAGE206
 EU1D3   34    PWM IR354XX_SM-IR35411,IC,H73688-0A    I27 @BASEBOARD_FAB2_LIB.BASEBOARD_FAB2(SCH_1):PAGE208

VR_PVCCIN_CPU1_PWM4 @BASEBOARD_FAB2_LIB.BASEBOARD_FAB2(SCH_1):VR_PVCCIN_CPU1_PWM4
 EU1C2    4  APWM4 PXE1610B_QFN-IC,H79206-001   I130 @BASEBOARD_FAB2_LIB.BASEBOARD_FAB2(SCH_1):PAGE206
 EU1D1   34    PWM IR354XX_SM-IR35411,IC,H73688-0A    I71 @BASEBOARD_FAB2_LIB.BASEBOARD_FAB2(SCH_1):PAGE208

VR_PVCCIN_CPU1_PWM5 @BASEBOARD_FAB2_LIB.BASEBOARD_FAB2(SCH_1):VR_PVCCIN_CPU1_PWM5
 EU1C2    3  APWM5 PXE1610B_QFN-IC,H79206-001   I130 @BASEBOARD_FAB2_LIB.BASEBOARD_FAB2(SCH_1):PAGE206
 EU1C3   34    PWM IR354XX_SM-IR35411,IC,H73688-0A    I56 @BASEBOARD_FAB2_LIB.BASEBOARD_FAB2(SCH_1):PAGE209

VR_PVCCIN_CPU1_VD12 @BASEBOARD_FAB2_LIB.BASEBOARD_FAB2(SCH_1):VR_PVCCIN_CPU1_VD12
 C1C13    1      A CAP_A_0402V-1.0UF,6.3V,10%,X6SA    I29 @BASEBOARD_FAB2_LIB.BASEBOARD_FAB2(SCH_1):PAGE206
 C1C14    1      A CAP_A_0402V-0.1UF,16V,10%,X7R,A    I31 @BASEBOARD_FAB2_LIB.BASEBOARD_FAB2(SCH_1):PAGE206
 R9N15    1      A RES_0402-0.0,5%,1/16W,CHIP,G21A   I122 @BASEBOARD_FAB2_LIB.BASEBOARD_FAB2(SCH_1):PAGE206
 R9N17    1      A RES_0402-0.0,5%,1/16W,CHIP,G21A   I123 @BASEBOARD_FAB2_LIB.BASEBOARD_FAB2(SCH_1):PAGE206
 R9N12    1      A RES_0402-0.0,5%,1/16W,CHIP,G21A   I124 @BASEBOARD_FAB2_LIB.BASEBOARD_FAB2(SCH_1):PAGE206
 R9N10    1      A RES_0402-0.0,5%,1/16W,CHIP,G21A   I125 @BASEBOARD_FAB2_LIB.BASEBOARD_FAB2(SCH_1):PAGE206
  R9N9    1      A RES_0402-0.0,5%,1/16W,CHIP,G21A   I126 @BASEBOARD_FAB2_LIB.BASEBOARD_FAB2(SCH_1):PAGE206
  R9N5    1      A RES_0402-0.0,5%,1/16W,CHIP,G21A   I128 @BASEBOARD_FAB2_LIB.BASEBOARD_FAB2(SCH_1):PAGE206
 EU1C2   48   VD12 PXE1610B_QFN-IC,H79206-001   I130 @BASEBOARD_FAB2_LIB.BASEBOARD_FAB2(SCH_1):PAGE206

VR_PVCCIN_CPU1_VDD @BASEBOARD_FAB2_LIB.BASEBOARD_FAB2(SCH_1):VR_PVCCIN_CPU1_VDD
  C1C7    1      A CAP_A_0402V-1.0UF,6.3V,10%,X6SA    I41 @BASEBOARD_FAB2_LIB.BASEBOARD_FAB2(SCH_1):PAGE206
  C1C9    1      A CAP_A_0402V-0.1UF,16V,10%,X7R,A    I42 @BASEBOARD_FAB2_LIB.BASEBOARD_FAB2(SCH_1):PAGE206
 R1C14    2      B RES_0402-0.0,5%,1/16W,CHIP,G21A    I46 @BASEBOARD_FAB2_LIB.BASEBOARD_FAB2(SCH_1):PAGE206
 EU1C2   47    VDD PXE1610B_QFN-IC,H79206-001   I130 @BASEBOARD_FAB2_LIB.BASEBOARD_FAB2(SCH_1):PAGE206

VR_PVCCIN_CPU1_VREN @BASEBOARD_FAB2_LIB.BASEBOARD_FAB2(SCH_1):VR_PVCCIN_CPU1_VREN
 R9N16    2      B RES_0402-0.0,5%,1/16W,CHIP,G21A   I119 @BASEBOARD_FAB2_LIB.BASEBOARD_FAB2(SCH_1):PAGE206
 R9N14    2      B RES_0402-1.00K,1%,1/16W,CHIP,GA   I120 @BASEBOARD_FAB2_LIB.BASEBOARD_FAB2(SCH_1):PAGE206
 EU1C2   12  AVREN PXE1610B_QFN-IC,H79206-001   I130 @BASEBOARD_FAB2_LIB.BASEBOARD_FAB2(SCH_1):PAGE206

VR_PVCCIN_CPU1_XADDR1 @BASEBOARD_FAB2_LIB.BASEBOARD_FAB2(SCH_1):VR_PVCCIN_CPU1_XADDR1
  R9N8    1      A RES_0402-4.02K,1%,1/16W,CHIP,GA   I112 @BASEBOARD_FAB2_LIB.BASEBOARD_FAB2(SCH_1):PAGE206
 EU1C2   44 XADDR1 PXE1610B_QFN-IC,H79206-001   I130 @BASEBOARD_FAB2_LIB.BASEBOARD_FAB2(SCH_1):PAGE206

VR_PVCCIN_CPU1_XADDR2 @BASEBOARD_FAB2_LIB.BASEBOARD_FAB2(SCH_1):VR_PVCCIN_CPU1_XADDR2
  R9N7    1      A RES_0402-3.16K,1%,1/16W,CHIP,GA   I111 @BASEBOARD_FAB2_LIB.BASEBOARD_FAB2(SCH_1):PAGE206
 EU1C2   41 XADDR2 PXE1610B_QFN-IC,H79206-001   I130 @BASEBOARD_FAB2_LIB.BASEBOARD_FAB2(SCH_1):PAGE206

VR_PVCCIOMCP_CPU0_XADDR1 @BASEBOARD_FAB2_LIB.BASEBOARD_FAB2(SCH_1):VR_PVCCIOMCP_CPU0_XADDR1
  J6B1  E10  IOE10 SCONN120_H61426002_SM-CONN,H61A    I56 @BASEBOARD_FAB2_LIB.BASEBOARD_FAB2(SCH_1):PAGE194
 R3N29    1      A RES_0402-16K,1.0%,1/16W,CHIP,GA   I156 @BASEBOARD_FAB2_LIB.BASEBOARD_FAB2(SCH_1):PAGE194

VR_PVCCIOMCP_CPU1_XADDR1 @BASEBOARD_FAB2_LIB.BASEBOARD_FAB2(SCH_1):VR_PVCCIOMCP_CPU1_XADDR1
  J4B2  E10  IOE10 SCONN120_H61426002_SM-CONN,H61A    I46 @BASEBOARD_FAB2_LIB.BASEBOARD_FAB2(SCH_1):PAGE193
 R4C12    1      A RES_0402-8.06K,1%,1/16W,CHIP,GA   I169 @BASEBOARD_FAB2_LIB.BASEBOARD_FAB2(SCH_1):PAGE193

VR_PVCCIO_CPU0_AIREF1 @BASEBOARD_FAB2_LIB.BASEBOARD_FAB2(SCH_1):VR_PVCCIO_CPU0_AIREF1
 R3P57    2      B RES_0402-0.0,5%,1/16W,CHIP,G21A    I91 @BASEBOARD_FAB2_LIB.BASEBOARD_FAB2(SCH_1):PAGE211
 EU3P1   21 AIREF1 PXE1110B_QFN-IC,H89187-001    I93 @BASEBOARD_FAB2_LIB.BASEBOARD_FAB2(SCH_1):PAGE211
 EU7C1   39  REFIN IR354XX_SM-IR35412,IC,H73684-0A   I101 @BASEBOARD_FAB2_LIB.BASEBOARD_FAB2(SCH_1):PAGE212
  CT70    1      A CAP_A_0402V-0.1UF,16V,10%,X7R,A   I106 @BASEBOARD_FAB2_LIB.BASEBOARD_FAB2(SCH_1):PAGE212

VR_PVCCIO_CPU0_AVSP @BASEBOARD_FAB2_LIB.BASEBOARD_FAB2(SCH_1):VR_PVCCIO_CPU0_AVSP
 R3N19    2      B RES_0402-10.0,1%,1/16W,CHIP,G2A    I81 @BASEBOARD_FAB2_LIB.BASEBOARD_FAB2(SCH_1):PAGE211
 C3N39    1      A CAP_0402LF-220PF,50V,10%,X7R,AA    I83 @BASEBOARD_FAB2_LIB.BASEBOARD_FAB2(SCH_1):PAGE211
 EU3P1   19  AVSEN PXE1110B_QFN-IC,H89187-001    I93 @BASEBOARD_FAB2_LIB.BASEBOARD_FAB2(SCH_1):PAGE211

VR_PVCCIO_CPU0_EN @BASEBOARD_FAB2_LIB.BASEBOARD_FAB2(SCH_1):VR_PVCCIO_CPU0_EN
 R3P26    2      B RES_0402-0.0,5%,1/16W,CHIP,G21A    I87 @BASEBOARD_FAB2_LIB.BASEBOARD_FAB2(SCH_1):PAGE211
 R3P21    2      B RES_0402-100.0K,1%,1/16W,EMPTYA    I88 @BASEBOARD_FAB2_LIB.BASEBOARD_FAB2(SCH_1):PAGE211
 EU3P1   10  AVREN PXE1110B_QFN-IC,H89187-001    I93 @BASEBOARD_FAB2_LIB.BASEBOARD_FAB2(SCH_1):PAGE211

VR_PVCCIO_CPU0_OCSET @BASEBOARD_FAB2_LIB.BASEBOARD_FAB2(SCH_1):VR_PVCCIO_CPU0_OCSET
 EU7C1   37  OCSET IR354XX_SM-IR35412,IC,H73684-0A   I101 @BASEBOARD_FAB2_LIB.BASEBOARD_FAB2(SCH_1):PAGE212
 R7C25    1      A RES_0402-68.1K,1%,1/16W,EMPTY,A   I103 @BASEBOARD_FAB2_LIB.BASEBOARD_FAB2(SCH_1):PAGE212

VR_PVCCIO_CPU0_PH1_BOOT @BASEBOARD_FAB2_LIB.BASEBOARD_FAB2(SCH_1):VR_PVCCIO_CPU0_PH1_BOOT
 C7C14    1      A CAP_0402-0.220UF,16V,10%,X7R,AA    I37 @BASEBOARD_FAB2_LIB.BASEBOARD_FAB2(SCH_1):PAGE212
  RT47    1      A RES_0402-0.0,5%,1/16W,CHIP,G21A   I114 @BASEBOARD_FAB2_LIB.BASEBOARD_FAB2(SCH_1):PAGE212

VR_PVCCIO_CPU0_PH1_BOOT_R @BASEBOARD_FAB2_LIB.BASEBOARD_FAB2(SCH_1):VR_PVCCIO_CPU0_PH1_BOOT_R
 EU7C1   33  BOOST IR354XX_SM-IR35412,IC,H73684-0A   I101 @BASEBOARD_FAB2_LIB.BASEBOARD_FAB2(SCH_1):PAGE212
  RT47    2      B RES_0402-0.0,5%,1/16W,CHIP,G21A   I114 @BASEBOARD_FAB2_LIB.BASEBOARD_FAB2(SCH_1):PAGE212

VR_PVCCIO_CPU0_PH1_PHASE @BASEBOARD_FAB2_LIB.BASEBOARD_FAB2(SCH_1):VR_PVCCIO_CPU0_PH1_PHASE
 C7C14    2      B CAP_0402-0.220UF,16V,10%,X7R,AA    I37 @BASEBOARD_FAB2_LIB.BASEBOARD_FAB2(SCH_1):PAGE212
 EU7C1   32  PHASE IR354XX_SM-IR35412,IC,H73684-0A   I101 @BASEBOARD_FAB2_LIB.BASEBOARD_FAB2(SCH_1):PAGE212

VR_PVCCIO_CPU0_PH1_SW @BASEBOARD_FAB2_LIB.BASEBOARD_FAB2(SCH_1):VR_PVCCIO_CPU0_PH1_SW
  L7C2    1    INA INDUCTOR_SM-150NH,IND,D92183-0A    I25 @BASEBOARD_FAB2_LIB.BASEBOARD_FAB2(SCH_1):PAGE212
 EU7C1   10     SW IR354XX_SM-IR35412,IC,H73684-0A   I101 @BASEBOARD_FAB2_LIB.BASEBOARD_FAB2(SCH_1):PAGE212
  CT72    1      1 SC2K2P50V3KX-GP_SMD-BCG6-SC2K2A   I111 @BASEBOARD_FAB2_LIB.BASEBOARD_FAB2(SCH_1):PAGE212

VR_PVCCIO_CPU0_PH1_VCIN @BASEBOARD_FAB2_LIB.BASEBOARD_FAB2(SCH_1):VR_PVCCIO_CPU0_PH1_VCIN
  R3N7    1      A RES_0402-1.0,1%,1/16W,CHIP,G21A    I32 @BASEBOARD_FAB2_LIB.BASEBOARD_FAB2(SCH_1):PAGE212
 C7C17    1      A CAP_0402-1.0UF,16V,10%,X6S,D97A    I36 @BASEBOARD_FAB2_LIB.BASEBOARD_FAB2(SCH_1):PAGE212
 EU7C1    3    VCC IR354XX_SM-IR35412,IC,H73684-0A   I101 @BASEBOARD_FAB2_LIB.BASEBOARD_FAB2(SCH_1):PAGE212

VR_PVCCIO_CPU0_PWM1 @BASEBOARD_FAB2_LIB.BASEBOARD_FAB2(SCH_1):VR_PVCCIO_CPU0_PWM1
 EU3P1    5  APWM1 PXE1110B_QFN-IC,H89187-001    I93 @BASEBOARD_FAB2_LIB.BASEBOARD_FAB2(SCH_1):PAGE211
 EU7C1   34    PWM IR354XX_SM-IR35412,IC,H73684-0A   I101 @BASEBOARD_FAB2_LIB.BASEBOARD_FAB2(SCH_1):PAGE212

VR_PVCCIO_CPU0_VD12 @BASEBOARD_FAB2_LIB.BASEBOARD_FAB2(SCH_1):VR_PVCCIO_CPU0_VD12
  C3P4    1      A CAP_A_0402V-1.0UF,6.3V,10%,X6SA    I11 @BASEBOARD_FAB2_LIB.BASEBOARD_FAB2(SCH_1):PAGE211
  C3P5    1      A CAP_A_0402V-0.1UF,16V,10%,X7R,A    I13 @BASEBOARD_FAB2_LIB.BASEBOARD_FAB2(SCH_1):PAGE211
 R3P57    1      A RES_0402-0.0,5%,1/16W,CHIP,G21A    I91 @BASEBOARD_FAB2_LIB.BASEBOARD_FAB2(SCH_1):PAGE211
 EU3P1   40   VD12 PXE1110B_QFN-IC,H89187-001    I93 @BASEBOARD_FAB2_LIB.BASEBOARD_FAB2(SCH_1):PAGE211

VR_PVCCIO_CPU0_VDD @BASEBOARD_FAB2_LIB.BASEBOARD_FAB2(SCH_1):VR_PVCCIO_CPU0_VDD
  C3P3    1      A CAP_A_0402V-1.0UF,6.3V,10%,X6SA    I20 @BASEBOARD_FAB2_LIB.BASEBOARD_FAB2(SCH_1):PAGE211
  C3P7    1      A CAP_A_0402V-0.1UF,16V,10%,X7R,A    I22 @BASEBOARD_FAB2_LIB.BASEBOARD_FAB2(SCH_1):PAGE211
 R3P22    2      B RES_0402-0.0,5%,1/16W,CHIP,G21A    I24 @BASEBOARD_FAB2_LIB.BASEBOARD_FAB2(SCH_1):PAGE211
 EU3P1   39    VDD PXE1110B_QFN-IC,H89187-001    I93 @BASEBOARD_FAB2_LIB.BASEBOARD_FAB2(SCH_1):PAGE211

VR_PVCCIO_CPU0_VINSEN @BASEBOARD_FAB2_LIB.BASEBOARD_FAB2(SCH_1):VR_PVCCIO_CPU0_VINSEN
 R3P12    2      B RES_0402-100.0K,1%,1/16W,CHIP,B    I31 @BASEBOARD_FAB2_LIB.BASEBOARD_FAB2(SCH_1):PAGE211
 R3P16    1      A RES_0402-1.5K,1%,1/16W,CHIP,G2A    I32 @BASEBOARD_FAB2_LIB.BASEBOARD_FAB2(SCH_1):PAGE211
  C3P2    1      A CAP_0402LF-1000PF,50V,10%,X7R,A    I33 @BASEBOARD_FAB2_LIB.BASEBOARD_FAB2(SCH_1):PAGE211
 EU3P1   37 VINSEN PXE1110B_QFN-IC,H89187-001    I93 @BASEBOARD_FAB2_LIB.BASEBOARD_FAB2(SCH_1):PAGE211

VR_PVCCIO_CPU0_XADDR1 @BASEBOARD_FAB2_LIB.BASEBOARD_FAB2(SCH_1):VR_PVCCIO_CPU0_XADDR1
 R3N31    1      A RES_0402-3.16K,1%,1/16W,CHIP,GA    I52 @BASEBOARD_FAB2_LIB.BASEBOARD_FAB2(SCH_1):PAGE211
 EU3P1   36 XADDR1 PXE1110B_QFN-IC,H89187-001    I93 @BASEBOARD_FAB2_LIB.BASEBOARD_FAB2(SCH_1):PAGE211

VR_PVCCIO_CPU0_XADDR2 @BASEBOARD_FAB2_LIB.BASEBOARD_FAB2(SCH_1):VR_PVCCIO_CPU0_XADDR2
 R3N22    1      A RES_0402-4.02K,1%,1/16W,CHIP,GA    I65 @BASEBOARD_FAB2_LIB.BASEBOARD_FAB2(SCH_1):PAGE211
 EU3P1   33 XADDR2 PXE1110B_QFN-IC,H89187-001    I93 @BASEBOARD_FAB2_LIB.BASEBOARD_FAB2(SCH_1):PAGE211

VR_PVCCIO_CPU1_AIREF1 @BASEBOARD_FAB2_LIB.BASEBOARD_FAB2(SCH_1):VR_PVCCIO_CPU1_AIREF1
 R4D45    2      B RES_0402-0.0,5%,1/16W,CHIP,G21A    I94 @BASEBOARD_FAB2_LIB.BASEBOARD_FAB2(SCH_1):PAGE213
 EU4D5   21 AIREF1 PXE1110B_QFN-IC,H89187-001    I96 @BASEBOARD_FAB2_LIB.BASEBOARD_FAB2(SCH_1):PAGE213
 EU4E2   39  REFIN IR354XX_SM-IR35412,IC,H73684-0A   I126 @BASEBOARD_FAB2_LIB.BASEBOARD_FAB2(SCH_1):PAGE214
  CT63    1      A CAP_A_0402V-0.1UF,16V,10%,X7R,A   I137 @BASEBOARD_FAB2_LIB.BASEBOARD_FAB2(SCH_1):PAGE214

VR_PVCCIO_CPU1_AVSP @BASEBOARD_FAB2_LIB.BASEBOARD_FAB2(SCH_1):VR_PVCCIO_CPU1_AVSP
 C4D44    1      A CAP_0402LF-220PF,50V,10%,X7R,AA    I83 @BASEBOARD_FAB2_LIB.BASEBOARD_FAB2(SCH_1):PAGE213
  R4E7    2      B RES_0402-10.0,1%,1/16W,CHIP,G2A    I84 @BASEBOARD_FAB2_LIB.BASEBOARD_FAB2(SCH_1):PAGE213
 EU4D5   19  AVSEN PXE1110B_QFN-IC,H89187-001    I96 @BASEBOARD_FAB2_LIB.BASEBOARD_FAB2(SCH_1):PAGE213

VR_PVCCIO_CPU1_EN @BASEBOARD_FAB2_LIB.BASEBOARD_FAB2(SCH_1):VR_PVCCIO_CPU1_EN
 R6P41    2      B RES_0402-0.0,5%,1/16W,CHIP,G21A    I90 @BASEBOARD_FAB2_LIB.BASEBOARD_FAB2(SCH_1):PAGE213
 R6P40    2      B RES_0402-100.0K,1%,1/16W,EMPTYA    I91 @BASEBOARD_FAB2_LIB.BASEBOARD_FAB2(SCH_1):PAGE213
 EU4D5   10  AVREN PXE1110B_QFN-IC,H89187-001    I96 @BASEBOARD_FAB2_LIB.BASEBOARD_FAB2(SCH_1):PAGE213

VR_PVCCIO_CPU1_OCSET @BASEBOARD_FAB2_LIB.BASEBOARD_FAB2(SCH_1):VR_PVCCIO_CPU1_OCSET
 EU4E2   37  OCSET IR354XX_SM-IR35412,IC,H73684-0A   I126 @BASEBOARD_FAB2_LIB.BASEBOARD_FAB2(SCH_1):PAGE214
 R4E21    1      A RES_0402-68.1K,1%,1/16W,EMPTY,A   I127 @BASEBOARD_FAB2_LIB.BASEBOARD_FAB2(SCH_1):PAGE214

VR_PVCCIO_CPU1_PH1_BOOT @BASEBOARD_FAB2_LIB.BASEBOARD_FAB2(SCH_1):VR_PVCCIO_CPU1_PH1_BOOT
 C4E18    1      A CAP_0402-0.220UF,16V,10%,X7R,AA    I78 @BASEBOARD_FAB2_LIB.BASEBOARD_FAB2(SCH_1):PAGE214
  RT41    1      A RES_0402-0.0,5%,1/16W,CHIP,G21A   I139 @BASEBOARD_FAB2_LIB.BASEBOARD_FAB2(SCH_1):PAGE214

VR_PVCCIO_CPU1_PH1_BOOT_R @BASEBOARD_FAB2_LIB.BASEBOARD_FAB2(SCH_1):VR_PVCCIO_CPU1_PH1_BOOT_R
 EU4E2   33  BOOST IR354XX_SM-IR35412,IC,H73684-0A   I126 @BASEBOARD_FAB2_LIB.BASEBOARD_FAB2(SCH_1):PAGE214
  RT41    2      B RES_0402-0.0,5%,1/16W,CHIP,G21A   I139 @BASEBOARD_FAB2_LIB.BASEBOARD_FAB2(SCH_1):PAGE214

VR_PVCCIO_CPU1_PH1_PHASE @BASEBOARD_FAB2_LIB.BASEBOARD_FAB2(SCH_1):VR_PVCCIO_CPU1_PH1_PHASE
 C4E18    2      B CAP_0402-0.220UF,16V,10%,X7R,AA    I78 @BASEBOARD_FAB2_LIB.BASEBOARD_FAB2(SCH_1):PAGE214
 EU4E2   32  PHASE IR354XX_SM-IR35412,IC,H73684-0A   I126 @BASEBOARD_FAB2_LIB.BASEBOARD_FAB2(SCH_1):PAGE214

VR_PVCCIO_CPU1_PH1_SW @BASEBOARD_FAB2_LIB.BASEBOARD_FAB2(SCH_1):VR_PVCCIO_CPU1_PH1_SW
  L4E2    1    INA INDUCTOR_SM-150NH,IND,D92183-0A    I67 @BASEBOARD_FAB2_LIB.BASEBOARD_FAB2(SCH_1):PAGE214
 EU4E2   10     SW IR354XX_SM-IR35412,IC,H73684-0A   I126 @BASEBOARD_FAB2_LIB.BASEBOARD_FAB2(SCH_1):PAGE214
  CT62    1      1 SC2K2P50V3KX-GP_SMD-BCG6-SC2K2A   I131 @BASEBOARD_FAB2_LIB.BASEBOARD_FAB2(SCH_1):PAGE214

VR_PVCCIO_CPU1_PH1_VCIN @BASEBOARD_FAB2_LIB.BASEBOARD_FAB2(SCH_1):VR_PVCCIO_CPU1_PH1_VCIN
  R6R5    1      A RES_0402-1.0,1%,1/16W,CHIP,G21A    I71 @BASEBOARD_FAB2_LIB.BASEBOARD_FAB2(SCH_1):PAGE214
 C4E22    1      A CAP_0402-1.0UF,16V,10%,X6S,D97A    I76 @BASEBOARD_FAB2_LIB.BASEBOARD_FAB2(SCH_1):PAGE214
 EU4E2    3    VCC IR354XX_SM-IR35412,IC,H73684-0A   I126 @BASEBOARD_FAB2_LIB.BASEBOARD_FAB2(SCH_1):PAGE214

VR_PVCCIO_CPU1_PWM1 @BASEBOARD_FAB2_LIB.BASEBOARD_FAB2(SCH_1):VR_PVCCIO_CPU1_PWM1
 EU4D5    5  APWM1 PXE1110B_QFN-IC,H89187-001    I96 @BASEBOARD_FAB2_LIB.BASEBOARD_FAB2(SCH_1):PAGE213
 EU4E2   34    PWM IR354XX_SM-IR35412,IC,H73684-0A   I126 @BASEBOARD_FAB2_LIB.BASEBOARD_FAB2(SCH_1):PAGE214

VR_PVCCIO_CPU1_VD12 @BASEBOARD_FAB2_LIB.BASEBOARD_FAB2(SCH_1):VR_PVCCIO_CPU1_VD12
 C4D31    1      A CAP_A_0402V-1.0UF,6.3V,10%,X6SA     I9 @BASEBOARD_FAB2_LIB.BASEBOARD_FAB2(SCH_1):PAGE213
 C4D32    1      A CAP_A_0402V-0.1UF,16V,10%,X7R,A    I11 @BASEBOARD_FAB2_LIB.BASEBOARD_FAB2(SCH_1):PAGE213
 R4D45    1      A RES_0402-0.0,5%,1/16W,CHIP,G21A    I94 @BASEBOARD_FAB2_LIB.BASEBOARD_FAB2(SCH_1):PAGE213
 EU4D5   40   VD12 PXE1110B_QFN-IC,H89187-001    I96 @BASEBOARD_FAB2_LIB.BASEBOARD_FAB2(SCH_1):PAGE213

VR_PVCCIO_CPU1_VDD @BASEBOARD_FAB2_LIB.BASEBOARD_FAB2(SCH_1):VR_PVCCIO_CPU1_VDD
 C4D36    1      A CAP_A_0402V-1.0UF,6.3V,10%,X6SA    I17 @BASEBOARD_FAB2_LIB.BASEBOARD_FAB2(SCH_1):PAGE213
 R4D47    2      B RES_0402-0.0,5%,1/16W,CHIP,G21A    I25 @BASEBOARD_FAB2_LIB.BASEBOARD_FAB2(SCH_1):PAGE213
 C4D38    1      A CAP_A_0402V-0.1UF,16V,10%,X7R,A    I35 @BASEBOARD_FAB2_LIB.BASEBOARD_FAB2(SCH_1):PAGE213
 EU4D5   39    VDD PXE1110B_QFN-IC,H89187-001    I96 @BASEBOARD_FAB2_LIB.BASEBOARD_FAB2(SCH_1):PAGE213

VR_PVCCIO_CPU1_VINSEN @BASEBOARD_FAB2_LIB.BASEBOARD_FAB2(SCH_1):VR_PVCCIO_CPU1_VINSEN
 R4D60    2      B RES_0402-100.0K,1%,1/16W,CHIP,B    I31 @BASEBOARD_FAB2_LIB.BASEBOARD_FAB2(SCH_1):PAGE213
 R4D57    1      A RES_0402-1.5K,1%,1/16W,CHIP,G2A    I32 @BASEBOARD_FAB2_LIB.BASEBOARD_FAB2(SCH_1):PAGE213
 C4D40    1      A CAP_0402LF-1000PF,50V,10%,X7R,A    I33 @BASEBOARD_FAB2_LIB.BASEBOARD_FAB2(SCH_1):PAGE213
 EU4D5   37 VINSEN PXE1110B_QFN-IC,H89187-001    I96 @BASEBOARD_FAB2_LIB.BASEBOARD_FAB2(SCH_1):PAGE213

VR_PVCCIO_CPU1_XADDR1 @BASEBOARD_FAB2_LIB.BASEBOARD_FAB2(SCH_1):VR_PVCCIO_CPU1_XADDR1
 R4D64    1      A RES_0402-3.16K,1%,1/16W,CHIP,GA    I42 @BASEBOARD_FAB2_LIB.BASEBOARD_FAB2(SCH_1):PAGE213
 EU4D5   36 XADDR1 PXE1110B_QFN-IC,H89187-001    I96 @BASEBOARD_FAB2_LIB.BASEBOARD_FAB2(SCH_1):PAGE213

VR_PVCCIO_CPU1_XADDR2 @BASEBOARD_FAB2_LIB.BASEBOARD_FAB2(SCH_1):VR_PVCCIO_CPU1_XADDR2
  R4E2    1      A RES_0402-3.16K,1%,1/16W,CHIP,GA    I65 @BASEBOARD_FAB2_LIB.BASEBOARD_FAB2(SCH_1):PAGE213
 EU4D5   33 XADDR2 PXE1110B_QFN-IC,H89187-001    I96 @BASEBOARD_FAB2_LIB.BASEBOARD_FAB2(SCH_1):PAGE213

VR_PVCCMCP_CPU0_XADDR2 @BASEBOARD_FAB2_LIB.BASEBOARD_FAB2(SCH_1):VR_PVCCMCP_CPU0_XADDR2
  J6B1  F10  IOF10 SCONN120_H61426002_SM-CONN,H61A    I56 @BASEBOARD_FAB2_LIB.BASEBOARD_FAB2(SCH_1):PAGE194
 R7C24    1      A RES_0402-4.02K,1%,1/16W,CHIP,GA   I155 @BASEBOARD_FAB2_LIB.BASEBOARD_FAB2(SCH_1):PAGE194

VR_PVCCMCP_CPU1_XADDR2 @BASEBOARD_FAB2_LIB.BASEBOARD_FAB2(SCH_1):VR_PVCCMCP_CPU1_XADDR2
  J4B2  F10  IOF10 SCONN120_H61426002_SM-CONN,H61A    I46 @BASEBOARD_FAB2_LIB.BASEBOARD_FAB2(SCH_1):PAGE193
 R4C11    1      A RES_0402-3.16K,1%,1/16W,CHIP,GA   I170 @BASEBOARD_FAB2_LIB.BASEBOARD_FAB2(SCH_1):PAGE193

VR_PVDDQ_ABC_AIINSEN @BASEBOARD_FAB2_LIB.BASEBOARD_FAB2(SCH_1):VR_PVDDQ_ABC_AIINSEN
  R4F1    2      B RES_0402-0.0,5%,1/16W,CHIP,G21A   I110 @BASEBOARD_FAB2_LIB.BASEBOARD_FAB2(SCH_1):PAGE197
 EU7G1   38 IINSEN PXM1310B_QFN-IC,H89186-001   I358 @BASEBOARD_FAB2_LIB.BASEBOARD_FAB2(SCH_1):PAGE215
 C3U10    1      A CAP_A_0402V-0.1UF,16V,10%,X7R,A   I360 @BASEBOARD_FAB2_LIB.BASEBOARD_FAB2(SCH_1):PAGE215

VR_PVDDQ_ABC_AIINSEN_R @BASEBOARD_FAB2_LIB.BASEBOARD_FAB2(SCH_1):VR_PVDDQ_ABC_AIINSEN_R
  U4F1    3    OUT MAX9634_SOT-IC,H35789-001    I97 @BASEBOARD_FAB2_LIB.BASEBOARD_FAB2(SCH_1):PAGE197
  R4F1    1      A RES_0402-0.0,5%,1/16W,CHIP,G21A   I110 @BASEBOARD_FAB2_LIB.BASEBOARD_FAB2(SCH_1):PAGE197

VR_PVDDQ_ABC_AIREF1 @BASEBOARD_FAB2_LIB.BASEBOARD_FAB2(SCH_1):VR_PVDDQ_ABC_AIREF1
 R3U10    2      B RES_0402-0.0,5%,1/16W,CHIP,G21A   I341 @BASEBOARD_FAB2_LIB.BASEBOARD_FAB2(SCH_1):PAGE215
 EU7G1   21 AIREF1 PXM1310B_QFN-IC,H89186-001   I358 @BASEBOARD_FAB2_LIB.BASEBOARD_FAB2(SCH_1):PAGE215
 EU7G2   39  REFIN IR354XX_SM-IR35411,IC,H73688-0A   I102 @BASEBOARD_FAB2_LIB.BASEBOARD_FAB2(SCH_1):PAGE216
  CT51    1      A CAP_A_0402V-0.1UF,16V,10%,X7R,A   I108 @BASEBOARD_FAB2_LIB.BASEBOARD_FAB2(SCH_1):PAGE216

VR_PVDDQ_ABC_AIREF2 @BASEBOARD_FAB2_LIB.BASEBOARD_FAB2(SCH_1):VR_PVDDQ_ABC_AIREF2
  R3U3    2      B RES_0402-0.0,5%,1/16W,CHIP,G21A   I332 @BASEBOARD_FAB2_LIB.BASEBOARD_FAB2(SCH_1):PAGE215
 EU7G1   23 AIREF2 PXM1310B_QFN-IC,H89186-001   I358 @BASEBOARD_FAB2_LIB.BASEBOARD_FAB2(SCH_1):PAGE215
 EU7G3   39  REFIN IR354XX_SM-IR35411,IC,H73688-0A   I103 @BASEBOARD_FAB2_LIB.BASEBOARD_FAB2(SCH_1):PAGE216
  CT52    1      A CAP_A_0402V-0.1UF,16V,10%,X7R,A   I111 @BASEBOARD_FAB2_LIB.BASEBOARD_FAB2(SCH_1):PAGE216

VR_PVDDQ_ABC_AVSP @BASEBOARD_FAB2_LIB.BASEBOARD_FAB2(SCH_1):VR_PVDDQ_ABC_AVSP
  C7G4    1      A CAP_0402LF-220PF,50V,10%,X7R,AA   I342 @BASEBOARD_FAB2_LIB.BASEBOARD_FAB2(SCH_1):PAGE215
  R7G9    2      B RES_0402-10.0,1%,1/16W,CHIP,G2A   I344 @BASEBOARD_FAB2_LIB.BASEBOARD_FAB2(SCH_1):PAGE215
 EU7G1   19  AVSEN PXM1310B_QFN-IC,H89186-001   I358 @BASEBOARD_FAB2_LIB.BASEBOARD_FAB2(SCH_1):PAGE215

VR_PVDDQ_ABC_PH1_BOOT @BASEBOARD_FAB2_LIB.BASEBOARD_FAB2(SCH_1):VR_PVDDQ_ABC_PH1_BOOT
 C7G31    1      A CAP_0402-0.220UF,16V,10%,X7R,AA    I44 @BASEBOARD_FAB2_LIB.BASEBOARD_FAB2(SCH_1):PAGE216
  RT33    1      A RES_0402-0.0,5%,1/16W,CHIP,G21A   I126 @BASEBOARD_FAB2_LIB.BASEBOARD_FAB2(SCH_1):PAGE216

VR_PVDDQ_ABC_PH1_BOOT_R @BASEBOARD_FAB2_LIB.BASEBOARD_FAB2(SCH_1):VR_PVDDQ_ABC_PH1_BOOT_R
 EU7G2   33  BOOST IR354XX_SM-IR35411,IC,H73688-0A   I102 @BASEBOARD_FAB2_LIB.BASEBOARD_FAB2(SCH_1):PAGE216
  RT33    2      B RES_0402-0.0,5%,1/16W,CHIP,G21A   I126 @BASEBOARD_FAB2_LIB.BASEBOARD_FAB2(SCH_1):PAGE216

VR_PVDDQ_ABC_PH1_OCSET @BASEBOARD_FAB2_LIB.BASEBOARD_FAB2(SCH_1):VR_PVDDQ_ABC_PH1_OCSET
 EU7G2   37  OCSET IR354XX_SM-IR35411,IC,H73688-0A   I102 @BASEBOARD_FAB2_LIB.BASEBOARD_FAB2(SCH_1):PAGE216
 R7G25    1      A RES_0402-68.1K,1%,1/16W,EMPTY,A   I104 @BASEBOARD_FAB2_LIB.BASEBOARD_FAB2(SCH_1):PAGE216

VR_PVDDQ_ABC_PH1_PHASE @BASEBOARD_FAB2_LIB.BASEBOARD_FAB2(SCH_1):VR_PVDDQ_ABC_PH1_PHASE
 C7G31    2      B CAP_0402-0.220UF,16V,10%,X7R,AA    I44 @BASEBOARD_FAB2_LIB.BASEBOARD_FAB2(SCH_1):PAGE216
 EU7G2   32  PHASE IR354XX_SM-IR35411,IC,H73688-0A   I102 @BASEBOARD_FAB2_LIB.BASEBOARD_FAB2(SCH_1):PAGE216

VR_PVDDQ_ABC_PH1_SW @BASEBOARD_FAB2_LIB.BASEBOARD_FAB2(SCH_1):VR_PVDDQ_ABC_PH1_SW
 EU7G2   10     SW IR354XX_SM-IR35411,IC,H73688-0A   I102 @BASEBOARD_FAB2_LIB.BASEBOARD_FAB2(SCH_1):PAGE216
  CT50    1      1 SC2K2P50V3KX-GP_SMD-BCG6-SC2K2A   I124 @BASEBOARD_FAB2_LIB.BASEBOARD_FAB2(SCH_1):PAGE216
  L7G1    1    INA INDUCTOR_SM-0.12UH,IND,D92183-A   I125 @BASEBOARD_FAB2_LIB.BASEBOARD_FAB2(SCH_1):PAGE216

VR_PVDDQ_ABC_PH1_VCIN @BASEBOARD_FAB2_LIB.BASEBOARD_FAB2(SCH_1):VR_PVDDQ_ABC_PH1_VCIN
 C7G33    1      A CAP_0402-1.0UF,16V,10%,X6S,D97A    I50 @BASEBOARD_FAB2_LIB.BASEBOARD_FAB2(SCH_1):PAGE216
  R3U6    1      A RES_0402-1.0,1%,1/16W,CHIP,G21A    I52 @BASEBOARD_FAB2_LIB.BASEBOARD_FAB2(SCH_1):PAGE216
 EU7G2    3    VCC IR354XX_SM-IR35411,IC,H73688-0A   I102 @BASEBOARD_FAB2_LIB.BASEBOARD_FAB2(SCH_1):PAGE216

VR_PVDDQ_ABC_PH2_BOOT @BASEBOARD_FAB2_LIB.BASEBOARD_FAB2(SCH_1):VR_PVDDQ_ABC_PH2_BOOT
  RT36    1      A RES_0402-0.0,5%,1/16W,CHIP,G21A   I127 @BASEBOARD_FAB2_LIB.BASEBOARD_FAB2(SCH_1):PAGE216
 C7G38    1      A CAP_0402-0.220UF,16V,10%,X7R,AA   I128 @BASEBOARD_FAB2_LIB.BASEBOARD_FAB2(SCH_1):PAGE216

VR_PVDDQ_ABC_PH2_BOOT_R @BASEBOARD_FAB2_LIB.BASEBOARD_FAB2(SCH_1):VR_PVDDQ_ABC_PH2_BOOT_R
 EU7G3   33  BOOST IR354XX_SM-IR35411,IC,H73688-0A   I103 @BASEBOARD_FAB2_LIB.BASEBOARD_FAB2(SCH_1):PAGE216
  RT36    2      B RES_0402-0.0,5%,1/16W,CHIP,G21A   I127 @BASEBOARD_FAB2_LIB.BASEBOARD_FAB2(SCH_1):PAGE216

VR_PVDDQ_ABC_PH2_OCSET @BASEBOARD_FAB2_LIB.BASEBOARD_FAB2(SCH_1):VR_PVDDQ_ABC_PH2_OCSET
 EU7G3   37  OCSET IR354XX_SM-IR35411,IC,H73688-0A   I103 @BASEBOARD_FAB2_LIB.BASEBOARD_FAB2(SCH_1):PAGE216
 R7G30    1      A RES_0402-68.1K,1%,1/16W,EMPTY,A   I106 @BASEBOARD_FAB2_LIB.BASEBOARD_FAB2(SCH_1):PAGE216

VR_PVDDQ_ABC_PH2_PHASE @BASEBOARD_FAB2_LIB.BASEBOARD_FAB2(SCH_1):VR_PVDDQ_ABC_PH2_PHASE
 EU7G3   32  PHASE IR354XX_SM-IR35411,IC,H73688-0A   I103 @BASEBOARD_FAB2_LIB.BASEBOARD_FAB2(SCH_1):PAGE216
 C7G38    2      B CAP_0402-0.220UF,16V,10%,X7R,AA   I128 @BASEBOARD_FAB2_LIB.BASEBOARD_FAB2(SCH_1):PAGE216

VR_PVDDQ_ABC_PH2_SW @BASEBOARD_FAB2_LIB.BASEBOARD_FAB2(SCH_1):VR_PVDDQ_ABC_PH2_SW
  L7G2    1    INA INDUCTOR_SM-0.12UH,IND,D92183-A    I65 @BASEBOARD_FAB2_LIB.BASEBOARD_FAB2(SCH_1):PAGE216
 EU7G3   10     SW IR354XX_SM-IR35411,IC,H73688-0A   I103 @BASEBOARD_FAB2_LIB.BASEBOARD_FAB2(SCH_1):PAGE216
  CT53    1      1 SC2K2P50V3KX-GP_SMD-BCG6-SC2K2A   I119 @BASEBOARD_FAB2_LIB.BASEBOARD_FAB2(SCH_1):PAGE216

VR_PVDDQ_ABC_PH2_VCIN @BASEBOARD_FAB2_LIB.BASEBOARD_FAB2(SCH_1):VR_PVDDQ_ABC_PH2_VCIN
  R3U9    1      A RES_0402-1.0,1%,1/16W,CHIP,G21A    I76 @BASEBOARD_FAB2_LIB.BASEBOARD_FAB2(SCH_1):PAGE216
 C7G40    1      A CAP_0402-1.0UF,16V,10%,X6S,D97A    I77 @BASEBOARD_FAB2_LIB.BASEBOARD_FAB2(SCH_1):PAGE216
 EU7G3    3    VCC IR354XX_SM-IR35411,IC,H73688-0A   I103 @BASEBOARD_FAB2_LIB.BASEBOARD_FAB2(SCH_1):PAGE216

VR_PVDDQ_ABC_PWM1 @BASEBOARD_FAB2_LIB.BASEBOARD_FAB2(SCH_1):VR_PVDDQ_ABC_PWM1
 EU7G1    5  APWM1 PXM1310B_QFN-IC,H89186-001   I358 @BASEBOARD_FAB2_LIB.BASEBOARD_FAB2(SCH_1):PAGE215
 EU7G2   34    PWM IR354XX_SM-IR35411,IC,H73688-0A   I102 @BASEBOARD_FAB2_LIB.BASEBOARD_FAB2(SCH_1):PAGE216

VR_PVDDQ_ABC_PWM2 @BASEBOARD_FAB2_LIB.BASEBOARD_FAB2(SCH_1):VR_PVDDQ_ABC_PWM2
 EU7G1    4  APWM2 PXM1310B_QFN-IC,H89186-001   I358 @BASEBOARD_FAB2_LIB.BASEBOARD_FAB2(SCH_1):PAGE215
 EU7G3   34    PWM IR354XX_SM-IR35411,IC,H73688-0A   I103 @BASEBOARD_FAB2_LIB.BASEBOARD_FAB2(SCH_1):PAGE216

VR_PVDDQ_ABC_VD12 @BASEBOARD_FAB2_LIB.BASEBOARD_FAB2(SCH_1):VR_PVDDQ_ABC_VD12
 C7F16    1      A CAP_A_0402V-1.0UF,6.3V,10%,X6SA   I325 @BASEBOARD_FAB2_LIB.BASEBOARD_FAB2(SCH_1):PAGE215
 C7F15    1      A CAP_A_0402V-0.1UF,16V,10%,X7R,A   I327 @BASEBOARD_FAB2_LIB.BASEBOARD_FAB2(SCH_1):PAGE215
  R3U3    1      A RES_0402-0.0,5%,1/16W,CHIP,G21A   I332 @BASEBOARD_FAB2_LIB.BASEBOARD_FAB2(SCH_1):PAGE215
 R3U10    1      A RES_0402-0.0,5%,1/16W,CHIP,G21A   I341 @BASEBOARD_FAB2_LIB.BASEBOARD_FAB2(SCH_1):PAGE215
 EU7G1   40   VD12 PXM1310B_QFN-IC,H89186-001   I358 @BASEBOARD_FAB2_LIB.BASEBOARD_FAB2(SCH_1):PAGE215

VR_PVDDQ_ABC_VDD @BASEBOARD_FAB2_LIB.BASEBOARD_FAB2(SCH_1):VR_PVDDQ_ABC_VDD
 C7F18    1      A CAP_A_0402V-1.0UF,6.3V,10%,X6SA   I309 @BASEBOARD_FAB2_LIB.BASEBOARD_FAB2(SCH_1):PAGE215
 C7F17    1      A CAP_A_0402V-0.1UF,16V,10%,X7R,A   I311 @BASEBOARD_FAB2_LIB.BASEBOARD_FAB2(SCH_1):PAGE215
 R3T13    2      B RES_0402-0.0,5%,1/16W,CHIP,G21A   I313 @BASEBOARD_FAB2_LIB.BASEBOARD_FAB2(SCH_1):PAGE215
 EU7G1   39    VDD PXM1310B_QFN-IC,H89186-001   I358 @BASEBOARD_FAB2_LIB.BASEBOARD_FAB2(SCH_1):PAGE215

VR_PVDDQ_ABC_VINSEN @BASEBOARD_FAB2_LIB.BASEBOARD_FAB2(SCH_1):VR_PVDDQ_ABC_VINSEN
 R7F34    2      B RES_0402-100.0K,1%,1/16W,CHIP,B   I336 @BASEBOARD_FAB2_LIB.BASEBOARD_FAB2(SCH_1):PAGE215
  R7G3    1      A RES_0402-1.5K,1%,1/16W,CHIP,G2A   I337 @BASEBOARD_FAB2_LIB.BASEBOARD_FAB2(SCH_1):PAGE215
  C7G1    1      A CAP_0402LF-1000PF,50V,10%,X7R,A   I339 @BASEBOARD_FAB2_LIB.BASEBOARD_FAB2(SCH_1):PAGE215
 EU7G1   37 VINSEN PXM1310B_QFN-IC,H89186-001   I358 @BASEBOARD_FAB2_LIB.BASEBOARD_FAB2(SCH_1):PAGE215

VR_PVDDQ_ABC_VREN @BASEBOARD_FAB2_LIB.BASEBOARD_FAB2(SCH_1):VR_PVDDQ_ABC_VREN
 R7F20    2      B RES_0402-100.0K,1%,1/16W,EMPTYA   I315 @BASEBOARD_FAB2_LIB.BASEBOARD_FAB2(SCH_1):PAGE215
 R7F21    2      B RES_0402-0.0,5%,1/16W,CHIP,G21A   I343 @BASEBOARD_FAB2_LIB.BASEBOARD_FAB2(SCH_1):PAGE215
 EU7G1   10  AVREN PXM1310B_QFN-IC,H89186-001   I358 @BASEBOARD_FAB2_LIB.BASEBOARD_FAB2(SCH_1):PAGE215

VR_PVDDQ_ABC_XADDR1 @BASEBOARD_FAB2_LIB.BASEBOARD_FAB2(SCH_1):VR_PVDDQ_ABC_XADDR1
  R7G8    1      A RES_0402-4.02K,1%,1/16W,CHIP,GA   I321 @BASEBOARD_FAB2_LIB.BASEBOARD_FAB2(SCH_1):PAGE215
 EU7G1   36 XADDR1 PXM1310B_QFN-IC,H89186-001   I358 @BASEBOARD_FAB2_LIB.BASEBOARD_FAB2(SCH_1):PAGE215

VR_PVDDQ_ABC_XADDR2 @BASEBOARD_FAB2_LIB.BASEBOARD_FAB2(SCH_1):VR_PVDDQ_ABC_XADDR2
 R7G10    1      A RES_0402-8.06K,1%,1/16W,CHIP,GA   I317 @BASEBOARD_FAB2_LIB.BASEBOARD_FAB2(SCH_1):PAGE215
 EU7G1   33 XADDR2 PXM1310B_QFN-IC,H89186-001   I358 @BASEBOARD_FAB2_LIB.BASEBOARD_FAB2(SCH_1):PAGE215

VR_PVDDQ_DEF_AIINSEN @BASEBOARD_FAB2_LIB.BASEBOARD_FAB2(SCH_1):VR_PVDDQ_DEF_AIINSEN
 R4B11    2      B RES_0402-0.0,5%,1/16W,CHIP,G21A   I113 @BASEBOARD_FAB2_LIB.BASEBOARD_FAB2(SCH_1):PAGE197
 EU7A5   38 IINSEN PXM1310B_QFN-IC,H89186-001    I75 @BASEBOARD_FAB2_LIB.BASEBOARD_FAB2(SCH_1):PAGE218
 C3L31    1      A CAP_A_0402V-0.1UF,16V,10%,X7R,A    I77 @BASEBOARD_FAB2_LIB.BASEBOARD_FAB2(SCH_1):PAGE218

VR_PVDDQ_DEF_AIINSEN_R @BASEBOARD_FAB2_LIB.BASEBOARD_FAB2(SCH_1):VR_PVDDQ_DEF_AIINSEN_R
 R4B11    1      A RES_0402-0.0,5%,1/16W,CHIP,G21A   I113 @BASEBOARD_FAB2_LIB.BASEBOARD_FAB2(SCH_1):PAGE197
  U4B1    3    OUT MAX9634_SOT-IC,H35789-001   I120 @BASEBOARD_FAB2_LIB.BASEBOARD_FAB2(SCH_1):PAGE197

VR_PVDDQ_DEF_AIREF1 @BASEBOARD_FAB2_LIB.BASEBOARD_FAB2(SCH_1):VR_PVDDQ_DEF_AIREF1
  R3L9    2      B RES_0402-0.0,5%,1/16W,CHIP,G21A    I57 @BASEBOARD_FAB2_LIB.BASEBOARD_FAB2(SCH_1):PAGE218
 EU7A5   21 AIREF1 PXM1310B_QFN-IC,H89186-001    I75 @BASEBOARD_FAB2_LIB.BASEBOARD_FAB2(SCH_1):PAGE218
 EU7A1   39  REFIN IR354XX_SM-IR35411,IC,H73688-0A   I106 @BASEBOARD_FAB2_LIB.BASEBOARD_FAB2(SCH_1):PAGE219
  CT45    1      A CAP_A_0402V-0.1UF,16V,10%,X7R,A   I116 @BASEBOARD_FAB2_LIB.BASEBOARD_FAB2(SCH_1):PAGE219

VR_PVDDQ_DEF_AIREF2 @BASEBOARD_FAB2_LIB.BASEBOARD_FAB2(SCH_1):VR_PVDDQ_DEF_AIREF2
 R3L10    2      B RES_0402-0.0,5%,1/16W,CHIP,G21A    I50 @BASEBOARD_FAB2_LIB.BASEBOARD_FAB2(SCH_1):PAGE218
 EU7A5   23 AIREF2 PXM1310B_QFN-IC,H89186-001    I75 @BASEBOARD_FAB2_LIB.BASEBOARD_FAB2(SCH_1):PAGE218
 EU7A4   39  REFIN IR354XX_SM-IR35411,IC,H73688-0A   I107 @BASEBOARD_FAB2_LIB.BASEBOARD_FAB2(SCH_1):PAGE219
  CT46    1      A CAP_A_0402V-0.1UF,16V,10%,X7R,A   I113 @BASEBOARD_FAB2_LIB.BASEBOARD_FAB2(SCH_1):PAGE219

VR_PVDDQ_DEF_AVSP @BASEBOARD_FAB2_LIB.BASEBOARD_FAB2(SCH_1):VR_PVDDQ_DEF_AVSP
  R7A7    2      B RES_0402-10.0,1%,1/16W,CHIP,G2A    I60 @BASEBOARD_FAB2_LIB.BASEBOARD_FAB2(SCH_1):PAGE218
 C7A28    1      A CAP_0402LF-220PF,50V,10%,X7R,AA    I61 @BASEBOARD_FAB2_LIB.BASEBOARD_FAB2(SCH_1):PAGE218
 EU7A5   19  AVSEN PXM1310B_QFN-IC,H89186-001    I75 @BASEBOARD_FAB2_LIB.BASEBOARD_FAB2(SCH_1):PAGE218

VR_PVDDQ_DEF_PH1_BOOT @BASEBOARD_FAB2_LIB.BASEBOARD_FAB2(SCH_1):VR_PVDDQ_DEF_PH1_BOOT
 C7A12    1      A CAP_0402-0.220UF,16V,10%,X7R,AA    I44 @BASEBOARD_FAB2_LIB.BASEBOARD_FAB2(SCH_1):PAGE219
  RT30    1      A RES_0402-0.0,5%,1/16W,CHIP,G21A   I129 @BASEBOARD_FAB2_LIB.BASEBOARD_FAB2(SCH_1):PAGE219

VR_PVDDQ_DEF_PH1_BOOT_R @BASEBOARD_FAB2_LIB.BASEBOARD_FAB2(SCH_1):VR_PVDDQ_DEF_PH1_BOOT_R
 EU7A1   33  BOOST IR354XX_SM-IR35411,IC,H73688-0A   I106 @BASEBOARD_FAB2_LIB.BASEBOARD_FAB2(SCH_1):PAGE219
  RT30    2      B RES_0402-0.0,5%,1/16W,CHIP,G21A   I129 @BASEBOARD_FAB2_LIB.BASEBOARD_FAB2(SCH_1):PAGE219

VR_PVDDQ_DEF_PH1_OCSET @BASEBOARD_FAB2_LIB.BASEBOARD_FAB2(SCH_1):VR_PVDDQ_DEF_PH1_OCSET
 EU7A1   37  OCSET IR354XX_SM-IR35411,IC,H73688-0A   I106 @BASEBOARD_FAB2_LIB.BASEBOARD_FAB2(SCH_1):PAGE219
 R7A20    1      A RES_0402-68.1K,1%,1/16W,EMPTY,A   I108 @BASEBOARD_FAB2_LIB.BASEBOARD_FAB2(SCH_1):PAGE219

VR_PVDDQ_DEF_PH1_PHASE @BASEBOARD_FAB2_LIB.BASEBOARD_FAB2(SCH_1):VR_PVDDQ_DEF_PH1_PHASE
 C7A12    2      B CAP_0402-0.220UF,16V,10%,X7R,AA    I44 @BASEBOARD_FAB2_LIB.BASEBOARD_FAB2(SCH_1):PAGE219
 EU7A1   32  PHASE IR354XX_SM-IR35411,IC,H73688-0A   I106 @BASEBOARD_FAB2_LIB.BASEBOARD_FAB2(SCH_1):PAGE219

VR_PVDDQ_DEF_PH1_SW @BASEBOARD_FAB2_LIB.BASEBOARD_FAB2(SCH_1):VR_PVDDQ_DEF_PH1_SW
  L7A1    1    INA INDUCTOR_SM-0.12UH,IND,D92183-A    I55 @BASEBOARD_FAB2_LIB.BASEBOARD_FAB2(SCH_1):PAGE219
 EU7A1   10     SW IR354XX_SM-IR35411,IC,H73688-0A   I106 @BASEBOARD_FAB2_LIB.BASEBOARD_FAB2(SCH_1):PAGE219
  CT44    1      1 SC2K2P50V3KX-GP_SMD-BCG6-SC2K2A   I127 @BASEBOARD_FAB2_LIB.BASEBOARD_FAB2(SCH_1):PAGE219

VR_PVDDQ_DEF_PH1_VCIN @BASEBOARD_FAB2_LIB.BASEBOARD_FAB2(SCH_1):VR_PVDDQ_DEF_PH1_VCIN
 C7A16    1      A CAP_0402-1.0UF,16V,10%,X6S,D97A    I50 @BASEBOARD_FAB2_LIB.BASEBOARD_FAB2(SCH_1):PAGE219
  R3L6    1      A RES_0402-1.0,1%,1/16W,CHIP,G21A    I52 @BASEBOARD_FAB2_LIB.BASEBOARD_FAB2(SCH_1):PAGE219
 EU7A1    3    VCC IR354XX_SM-IR35411,IC,H73688-0A   I106 @BASEBOARD_FAB2_LIB.BASEBOARD_FAB2(SCH_1):PAGE219

VR_PVDDQ_DEF_PH2_BOOT @BASEBOARD_FAB2_LIB.BASEBOARD_FAB2(SCH_1):VR_PVDDQ_DEF_PH2_BOOT
 C7A22    1      A CAP_0402-0.220UF,16V,10%,X7R,AA    I75 @BASEBOARD_FAB2_LIB.BASEBOARD_FAB2(SCH_1):PAGE219
  RT31    1      A RES_0402-0.0,5%,1/16W,CHIP,G21A   I130 @BASEBOARD_FAB2_LIB.BASEBOARD_FAB2(SCH_1):PAGE219

VR_PVDDQ_DEF_PH2_BOOT_R @BASEBOARD_FAB2_LIB.BASEBOARD_FAB2(SCH_1):VR_PVDDQ_DEF_PH2_BOOT_R
 EU7A4   33  BOOST IR354XX_SM-IR35411,IC,H73688-0A   I107 @BASEBOARD_FAB2_LIB.BASEBOARD_FAB2(SCH_1):PAGE219
  RT31    2      B RES_0402-0.0,5%,1/16W,CHIP,G21A   I130 @BASEBOARD_FAB2_LIB.BASEBOARD_FAB2(SCH_1):PAGE219

VR_PVDDQ_DEF_PH2_OCSET @BASEBOARD_FAB2_LIB.BASEBOARD_FAB2(SCH_1):VR_PVDDQ_DEF_PH2_OCSET
 EU7A4   37  OCSET IR354XX_SM-IR35411,IC,H73688-0A   I107 @BASEBOARD_FAB2_LIB.BASEBOARD_FAB2(SCH_1):PAGE219
 R7A21    1      A RES_0402-68.1K,1%,1/16W,EMPTY,A   I110 @BASEBOARD_FAB2_LIB.BASEBOARD_FAB2(SCH_1):PAGE219

VR_PVDDQ_DEF_PH2_PHASE @BASEBOARD_FAB2_LIB.BASEBOARD_FAB2(SCH_1):VR_PVDDQ_DEF_PH2_PHASE
 C7A22    2      B CAP_0402-0.220UF,16V,10%,X7R,AA    I75 @BASEBOARD_FAB2_LIB.BASEBOARD_FAB2(SCH_1):PAGE219
 EU7A4   32  PHASE IR354XX_SM-IR35411,IC,H73688-0A   I107 @BASEBOARD_FAB2_LIB.BASEBOARD_FAB2(SCH_1):PAGE219

VR_PVDDQ_DEF_PH2_SW @BASEBOARD_FAB2_LIB.BASEBOARD_FAB2(SCH_1):VR_PVDDQ_DEF_PH2_SW
  L7A3    1    INA INDUCTOR_SM-0.12UH,IND,D92183-A    I65 @BASEBOARD_FAB2_LIB.BASEBOARD_FAB2(SCH_1):PAGE219
 EU7A4   10     SW IR354XX_SM-IR35411,IC,H73688-0A   I107 @BASEBOARD_FAB2_LIB.BASEBOARD_FAB2(SCH_1):PAGE219
  CT47    1      1 SC2K2P50V3KX-GP_SMD-BCG6-SC2K2A   I121 @BASEBOARD_FAB2_LIB.BASEBOARD_FAB2(SCH_1):PAGE219

VR_PVDDQ_DEF_PH2_VCIN @BASEBOARD_FAB2_LIB.BASEBOARD_FAB2(SCH_1):VR_PVDDQ_DEF_PH2_VCIN
  R3L8    1      A RES_0402-1.0,1%,1/16W,CHIP,G21A    I76 @BASEBOARD_FAB2_LIB.BASEBOARD_FAB2(SCH_1):PAGE219
 C7A24    1      A CAP_0402-1.0UF,16V,10%,X6S,D97A    I77 @BASEBOARD_FAB2_LIB.BASEBOARD_FAB2(SCH_1):PAGE219
 EU7A4    3    VCC IR354XX_SM-IR35411,IC,H73688-0A   I107 @BASEBOARD_FAB2_LIB.BASEBOARD_FAB2(SCH_1):PAGE219

VR_PVDDQ_DEF_PWM1 @BASEBOARD_FAB2_LIB.BASEBOARD_FAB2(SCH_1):VR_PVDDQ_DEF_PWM1
 EU7A5    5  APWM1 PXM1310B_QFN-IC,H89186-001    I75 @BASEBOARD_FAB2_LIB.BASEBOARD_FAB2(SCH_1):PAGE218
 EU7A1   34    PWM IR354XX_SM-IR35411,IC,H73688-0A   I106 @BASEBOARD_FAB2_LIB.BASEBOARD_FAB2(SCH_1):PAGE219

VR_PVDDQ_DEF_PWM2 @BASEBOARD_FAB2_LIB.BASEBOARD_FAB2(SCH_1):VR_PVDDQ_DEF_PWM2
 EU7A5    4  APWM2 PXM1310B_QFN-IC,H89186-001    I75 @BASEBOARD_FAB2_LIB.BASEBOARD_FAB2(SCH_1):PAGE218
 EU7A4   34    PWM IR354XX_SM-IR35411,IC,H73688-0A   I107 @BASEBOARD_FAB2_LIB.BASEBOARD_FAB2(SCH_1):PAGE219

VR_PVDDQ_DEF_VD12 @BASEBOARD_FAB2_LIB.BASEBOARD_FAB2(SCH_1):VR_PVDDQ_DEF_VD12
  C7B1    1      A CAP_A_0402V-1.0UF,6.3V,10%,X6SA    I22 @BASEBOARD_FAB2_LIB.BASEBOARD_FAB2(SCH_1):PAGE218
  C7B2    1      A CAP_A_0402V-0.1UF,16V,10%,X7R,A    I23 @BASEBOARD_FAB2_LIB.BASEBOARD_FAB2(SCH_1):PAGE218
 R3L10    1      A RES_0402-0.0,5%,1/16W,CHIP,G21A    I50 @BASEBOARD_FAB2_LIB.BASEBOARD_FAB2(SCH_1):PAGE218
  R3L9    1      A RES_0402-0.0,5%,1/16W,CHIP,G21A    I57 @BASEBOARD_FAB2_LIB.BASEBOARD_FAB2(SCH_1):PAGE218
 EU7A5   40   VD12 PXM1310B_QFN-IC,H89186-001    I75 @BASEBOARD_FAB2_LIB.BASEBOARD_FAB2(SCH_1):PAGE218

VR_PVDDQ_DEF_VDD @BASEBOARD_FAB2_LIB.BASEBOARD_FAB2(SCH_1):VR_PVDDQ_DEF_VDD
 C7A37    1      A CAP_A_0402V-1.0UF,6.3V,10%,X6SA    I29 @BASEBOARD_FAB2_LIB.BASEBOARD_FAB2(SCH_1):PAGE218
 C7A38    1      A CAP_A_0402V-0.1UF,16V,10%,X7R,A    I31 @BASEBOARD_FAB2_LIB.BASEBOARD_FAB2(SCH_1):PAGE218
  R3M1    2      B RES_0402-0.0,5%,1/16W,CHIP,G21A    I34 @BASEBOARD_FAB2_LIB.BASEBOARD_FAB2(SCH_1):PAGE218
 EU7A5   39    VDD PXM1310B_QFN-IC,H89186-001    I75 @BASEBOARD_FAB2_LIB.BASEBOARD_FAB2(SCH_1):PAGE218

VR_PVDDQ_DEF_VINSEN @BASEBOARD_FAB2_LIB.BASEBOARD_FAB2(SCH_1):VR_PVDDQ_DEF_VINSEN
 R3L12    2      B RES_0402-100.0K,1%,1/16W,CHIP,B    I53 @BASEBOARD_FAB2_LIB.BASEBOARD_FAB2(SCH_1):PAGE218
 R7A16    1      A RES_0402-1.5K,1%,1/16W,CHIP,G2A    I54 @BASEBOARD_FAB2_LIB.BASEBOARD_FAB2(SCH_1):PAGE218
 C7A35    1      A CAP_0402LF-1000PF,50V,10%,X7R,A    I55 @BASEBOARD_FAB2_LIB.BASEBOARD_FAB2(SCH_1):PAGE218
 EU7A5   37 VINSEN PXM1310B_QFN-IC,H89186-001    I75 @BASEBOARD_FAB2_LIB.BASEBOARD_FAB2(SCH_1):PAGE218

VR_PVDDQ_DEF_VREN @BASEBOARD_FAB2_LIB.BASEBOARD_FAB2(SCH_1):VR_PVDDQ_DEF_VREN
  R3M5    2      B RES_0402-100.0K,1%,1/16W,EMPTYA    I35 @BASEBOARD_FAB2_LIB.BASEBOARD_FAB2(SCH_1):PAGE218
  R3M6    2      B RES_0402-0.0,5%,1/16W,CHIP,G21A    I59 @BASEBOARD_FAB2_LIB.BASEBOARD_FAB2(SCH_1):PAGE218
 EU7A5   10  AVREN PXM1310B_QFN-IC,H89186-001    I75 @BASEBOARD_FAB2_LIB.BASEBOARD_FAB2(SCH_1):PAGE218

VR_PVDDQ_DEF_XADDR1 @BASEBOARD_FAB2_LIB.BASEBOARD_FAB2(SCH_1):VR_PVDDQ_DEF_XADDR1
 R7A10    1      A RES_0402-3.16K,1%,1/16W,CHIP,GA    I40 @BASEBOARD_FAB2_LIB.BASEBOARD_FAB2(SCH_1):PAGE218
 EU7A5   36 XADDR1 PXM1310B_QFN-IC,H89186-001    I75 @BASEBOARD_FAB2_LIB.BASEBOARD_FAB2(SCH_1):PAGE218

VR_PVDDQ_DEF_XADDR2 @BASEBOARD_FAB2_LIB.BASEBOARD_FAB2(SCH_1):VR_PVDDQ_DEF_XADDR2
  R7A8    1      A RES_0402-8.06K,1%,1/16W,CHIP,GA    I37 @BASEBOARD_FAB2_LIB.BASEBOARD_FAB2(SCH_1):PAGE218
 EU7A5   33 XADDR2 PXM1310B_QFN-IC,H89186-001    I75 @BASEBOARD_FAB2_LIB.BASEBOARD_FAB2(SCH_1):PAGE218

VR_PVDDQ_GHJ_AIINSEN @BASEBOARD_FAB2_LIB.BASEBOARD_FAB2(SCH_1):VR_PVDDQ_GHJ_AIINSEN
  R9T4    2      B RES_0402-0.0,5%,1/16W,CHIP,G21A   I126 @BASEBOARD_FAB2_LIB.BASEBOARD_FAB2(SCH_1):PAGE197
 EU1G2   38 IINSEN PXM1310B_QFN-IC,H89186-001    I90 @BASEBOARD_FAB2_LIB.BASEBOARD_FAB2(SCH_1):PAGE223
 C9U12    1      A CAP_A_0402V-0.1UF,16V,10%,X7R,A    I92 @BASEBOARD_FAB2_LIB.BASEBOARD_FAB2(SCH_1):PAGE223

VR_PVDDQ_GHJ_AIINSEN_R @BASEBOARD_FAB2_LIB.BASEBOARD_FAB2(SCH_1):VR_PVDDQ_GHJ_AIINSEN_R
  R9T4    1      A RES_0402-0.0,5%,1/16W,CHIP,G21A   I126 @BASEBOARD_FAB2_LIB.BASEBOARD_FAB2(SCH_1):PAGE197
  U1F1    3    OUT MAX9634_SOT-IC,H35789-001   I133 @BASEBOARD_FAB2_LIB.BASEBOARD_FAB2(SCH_1):PAGE197

VR_PVDDQ_GHJ_AIREF1 @BASEBOARD_FAB2_LIB.BASEBOARD_FAB2(SCH_1):VR_PVDDQ_GHJ_AIREF1
 R1G28    2      B RES_0402-0.0,5%,1/16W,CHIP,G21A    I87 @BASEBOARD_FAB2_LIB.BASEBOARD_FAB2(SCH_1):PAGE223
 EU1G2   21 AIREF1 PXM1310B_QFN-IC,H89186-001    I90 @BASEBOARD_FAB2_LIB.BASEBOARD_FAB2(SCH_1):PAGE223
 EU1G1   39  REFIN IR354XX_SM-IR35411,IC,H73688-0A   I110 @BASEBOARD_FAB2_LIB.BASEBOARD_FAB2(SCH_1):PAGE224
  CT30    1      A CAP_A_0402V-0.1UF,16V,10%,X7R,A   I117 @BASEBOARD_FAB2_LIB.BASEBOARD_FAB2(SCH_1):PAGE224

VR_PVDDQ_GHJ_AIREF2 @BASEBOARD_FAB2_LIB.BASEBOARD_FAB2(SCH_1):VR_PVDDQ_GHJ_AIREF2
 R1G27    2      B RES_0402-0.0,5%,1/16W,CHIP,G21A    I88 @BASEBOARD_FAB2_LIB.BASEBOARD_FAB2(SCH_1):PAGE223
 EU1G2   23 AIREF2 PXM1310B_QFN-IC,H89186-001    I90 @BASEBOARD_FAB2_LIB.BASEBOARD_FAB2(SCH_1):PAGE223
 EU1F1   39  REFIN IR354XX_SM-IR35411,IC,H73688-0A   I111 @BASEBOARD_FAB2_LIB.BASEBOARD_FAB2(SCH_1):PAGE224
  CT31    1      A CAP_A_0402V-0.1UF,16V,10%,X7R,A   I124 @BASEBOARD_FAB2_LIB.BASEBOARD_FAB2(SCH_1):PAGE224

VR_PVDDQ_GHJ_AVSP @BASEBOARD_FAB2_LIB.BASEBOARD_FAB2(SCH_1):VR_PVDDQ_GHJ_AVSP
  R1G5    2      B RES_0402-10.0,1%,1/16W,CHIP,G2A    I32 @BASEBOARD_FAB2_LIB.BASEBOARD_FAB2(SCH_1):PAGE223
 C1G16    1      A CAP_0402LF-220PF,50V,10%,X7R,AA    I39 @BASEBOARD_FAB2_LIB.BASEBOARD_FAB2(SCH_1):PAGE223
 EU1G2   19  AVSEN PXM1310B_QFN-IC,H89186-001    I90 @BASEBOARD_FAB2_LIB.BASEBOARD_FAB2(SCH_1):PAGE223

VR_PVDDQ_GHJ_PH1_BOOT @BASEBOARD_FAB2_LIB.BASEBOARD_FAB2(SCH_1):VR_PVDDQ_GHJ_PH1_BOOT
 C1G11    1      A CAP_0402-0.220UF,16V,10%,X7R,AA    I44 @BASEBOARD_FAB2_LIB.BASEBOARD_FAB2(SCH_1):PAGE224
  RT19    1      A RES_0402-0.0,5%,1/16W,CHIP,G21A   I132 @BASEBOARD_FAB2_LIB.BASEBOARD_FAB2(SCH_1):PAGE224

VR_PVDDQ_GHJ_PH1_BOOT_R @BASEBOARD_FAB2_LIB.BASEBOARD_FAB2(SCH_1):VR_PVDDQ_GHJ_PH1_BOOT_R
 EU1G1   33  BOOST IR354XX_SM-IR35411,IC,H73688-0A   I110 @BASEBOARD_FAB2_LIB.BASEBOARD_FAB2(SCH_1):PAGE224
  RT19    2      B RES_0402-0.0,5%,1/16W,CHIP,G21A   I132 @BASEBOARD_FAB2_LIB.BASEBOARD_FAB2(SCH_1):PAGE224

VR_PVDDQ_GHJ_PH1_OCSET @BASEBOARD_FAB2_LIB.BASEBOARD_FAB2(SCH_1):VR_PVDDQ_GHJ_PH1_OCSET
 EU1G1   37  OCSET IR354XX_SM-IR35411,IC,H73688-0A   I110 @BASEBOARD_FAB2_LIB.BASEBOARD_FAB2(SCH_1):PAGE224
 R1G26    1      A RES_0402-68.1K,1%,1/16W,EMPTY,A   I112 @BASEBOARD_FAB2_LIB.BASEBOARD_FAB2(SCH_1):PAGE224

VR_PVDDQ_GHJ_PH1_PHASE @BASEBOARD_FAB2_LIB.BASEBOARD_FAB2(SCH_1):VR_PVDDQ_GHJ_PH1_PHASE
 C1G11    2      B CAP_0402-0.220UF,16V,10%,X7R,AA    I44 @BASEBOARD_FAB2_LIB.BASEBOARD_FAB2(SCH_1):PAGE224
 EU1G1   32  PHASE IR354XX_SM-IR35411,IC,H73688-0A   I110 @BASEBOARD_FAB2_LIB.BASEBOARD_FAB2(SCH_1):PAGE224

VR_PVDDQ_GHJ_PH1_SW @BASEBOARD_FAB2_LIB.BASEBOARD_FAB2(SCH_1):VR_PVDDQ_GHJ_PH1_SW
  L1G1    1    INA INDUCTOR_SM-0.12UH,IND,D92183-A    I55 @BASEBOARD_FAB2_LIB.BASEBOARD_FAB2(SCH_1):PAGE224
 EU1G1   10     SW IR354XX_SM-IR35411,IC,H73688-0A   I110 @BASEBOARD_FAB2_LIB.BASEBOARD_FAB2(SCH_1):PAGE224
  CT29    1      1 SC2K2P50V3KX-GP_SMD-BCG6-SC2K2A   I121 @BASEBOARD_FAB2_LIB.BASEBOARD_FAB2(SCH_1):PAGE224

VR_PVDDQ_GHJ_PH1_VCIN @BASEBOARD_FAB2_LIB.BASEBOARD_FAB2(SCH_1):VR_PVDDQ_GHJ_PH1_VCIN
  C1G6    1      A CAP_0402-1.0UF,16V,10%,X6S,D97A    I50 @BASEBOARD_FAB2_LIB.BASEBOARD_FAB2(SCH_1):PAGE224
  R9U1    1      A RES_0402-1.0,1%,1/16W,CHIP,G21A    I52 @BASEBOARD_FAB2_LIB.BASEBOARD_FAB2(SCH_1):PAGE224
 EU1G1    3    VCC IR354XX_SM-IR35411,IC,H73688-0A   I110 @BASEBOARD_FAB2_LIB.BASEBOARD_FAB2(SCH_1):PAGE224

VR_PVDDQ_GHJ_PH2_BOOT @BASEBOARD_FAB2_LIB.BASEBOARD_FAB2(SCH_1):VR_PVDDQ_GHJ_PH2_BOOT
 C1F26    1      A CAP_0402-0.220UF,16V,10%,X7R,AA    I75 @BASEBOARD_FAB2_LIB.BASEBOARD_FAB2(SCH_1):PAGE224
  RT21    1      A RES_0402-0.0,5%,1/16W,CHIP,G21A   I133 @BASEBOARD_FAB2_LIB.BASEBOARD_FAB2(SCH_1):PAGE224

VR_PVDDQ_GHJ_PH2_BOOT_R @BASEBOARD_FAB2_LIB.BASEBOARD_FAB2(SCH_1):VR_PVDDQ_GHJ_PH2_BOOT_R
 EU1F1   33  BOOST IR354XX_SM-IR35411,IC,H73688-0A   I111 @BASEBOARD_FAB2_LIB.BASEBOARD_FAB2(SCH_1):PAGE224
  RT21    2      B RES_0402-0.0,5%,1/16W,CHIP,G21A   I133 @BASEBOARD_FAB2_LIB.BASEBOARD_FAB2(SCH_1):PAGE224

VR_PVDDQ_GHJ_PH2_OCSET @BASEBOARD_FAB2_LIB.BASEBOARD_FAB2(SCH_1):VR_PVDDQ_GHJ_PH2_OCSET
 EU1F1   37  OCSET IR354XX_SM-IR35411,IC,H73688-0A   I111 @BASEBOARD_FAB2_LIB.BASEBOARD_FAB2(SCH_1):PAGE224
 R1G25    1      A RES_0402-68.1K,1%,1/16W,EMPTY,A   I114 @BASEBOARD_FAB2_LIB.BASEBOARD_FAB2(SCH_1):PAGE224

VR_PVDDQ_GHJ_PH2_PHASE @BASEBOARD_FAB2_LIB.BASEBOARD_FAB2(SCH_1):VR_PVDDQ_GHJ_PH2_PHASE
 C1F26    2      B CAP_0402-0.220UF,16V,10%,X7R,AA    I75 @BASEBOARD_FAB2_LIB.BASEBOARD_FAB2(SCH_1):PAGE224
 EU1F1   32  PHASE IR354XX_SM-IR35411,IC,H73688-0A   I111 @BASEBOARD_FAB2_LIB.BASEBOARD_FAB2(SCH_1):PAGE224

VR_PVDDQ_GHJ_PH2_SW @BASEBOARD_FAB2_LIB.BASEBOARD_FAB2(SCH_1):VR_PVDDQ_GHJ_PH2_SW
  L1F2    1    INA INDUCTOR_SM-0.12UH,IND,D92183-A    I65 @BASEBOARD_FAB2_LIB.BASEBOARD_FAB2(SCH_1):PAGE224
 EU1F1   10     SW IR354XX_SM-IR35411,IC,H73688-0A   I111 @BASEBOARD_FAB2_LIB.BASEBOARD_FAB2(SCH_1):PAGE224
  CT33    1      1 SC2K2P50V3KX-GP_SMD-BCG6-SC2K2A   I127 @BASEBOARD_FAB2_LIB.BASEBOARD_FAB2(SCH_1):PAGE224

VR_PVDDQ_GHJ_PH2_VCIN @BASEBOARD_FAB2_LIB.BASEBOARD_FAB2(SCH_1):VR_PVDDQ_GHJ_PH2_VCIN
 R9U12    1      A RES_0402-1.0,1%,1/16W,CHIP,G21A    I76 @BASEBOARD_FAB2_LIB.BASEBOARD_FAB2(SCH_1):PAGE224
 C1G28    1      A CAP_0402-1.0UF,16V,10%,X6S,D97A    I77 @BASEBOARD_FAB2_LIB.BASEBOARD_FAB2(SCH_1):PAGE224
 EU1F1    3    VCC IR354XX_SM-IR35411,IC,H73688-0A   I111 @BASEBOARD_FAB2_LIB.BASEBOARD_FAB2(SCH_1):PAGE224

VR_PVDDQ_GHJ_PWM1 @BASEBOARD_FAB2_LIB.BASEBOARD_FAB2(SCH_1):VR_PVDDQ_GHJ_PWM1
 EU1G2    5  APWM1 PXM1310B_QFN-IC,H89186-001    I90 @BASEBOARD_FAB2_LIB.BASEBOARD_FAB2(SCH_1):PAGE223
 EU1G1   34    PWM IR354XX_SM-IR35411,IC,H73688-0A   I110 @BASEBOARD_FAB2_LIB.BASEBOARD_FAB2(SCH_1):PAGE224

VR_PVDDQ_GHJ_PWM2 @BASEBOARD_FAB2_LIB.BASEBOARD_FAB2(SCH_1):VR_PVDDQ_GHJ_PWM2
 EU1G2    4  APWM2 PXM1310B_QFN-IC,H89186-001    I90 @BASEBOARD_FAB2_LIB.BASEBOARD_FAB2(SCH_1):PAGE223
 EU1F1   34    PWM IR354XX_SM-IR35411,IC,H73688-0A   I111 @BASEBOARD_FAB2_LIB.BASEBOARD_FAB2(SCH_1):PAGE224

VR_PVDDQ_GHJ_VD12 @BASEBOARD_FAB2_LIB.BASEBOARD_FAB2(SCH_1):VR_PVDDQ_GHJ_VD12
 C1G23    1      A CAP_A_0402V-1.0UF,6.3V,10%,X6SA    I41 @BASEBOARD_FAB2_LIB.BASEBOARD_FAB2(SCH_1):PAGE223
 C1G22    1      A CAP_A_0402V-0.1UF,16V,10%,X7R,A    I44 @BASEBOARD_FAB2_LIB.BASEBOARD_FAB2(SCH_1):PAGE223
 R1G28    1      A RES_0402-0.0,5%,1/16W,CHIP,G21A    I87 @BASEBOARD_FAB2_LIB.BASEBOARD_FAB2(SCH_1):PAGE223
 R1G27    1      A RES_0402-0.0,5%,1/16W,CHIP,G21A    I88 @BASEBOARD_FAB2_LIB.BASEBOARD_FAB2(SCH_1):PAGE223
 EU1G2   40   VD12 PXM1310B_QFN-IC,H89186-001    I90 @BASEBOARD_FAB2_LIB.BASEBOARD_FAB2(SCH_1):PAGE223

VR_PVDDQ_GHJ_VDD @BASEBOARD_FAB2_LIB.BASEBOARD_FAB2(SCH_1):VR_PVDDQ_GHJ_VDD
 C1G27    1      A CAP_A_0402V-1.0UF,6.3V,10%,X6SA    I25 @BASEBOARD_FAB2_LIB.BASEBOARD_FAB2(SCH_1):PAGE223
 C1G25    1      A CAP_A_0402V-0.1UF,16V,10%,X7R,A    I27 @BASEBOARD_FAB2_LIB.BASEBOARD_FAB2(SCH_1):PAGE223
 R9U10    2      B RES_0402-0.0,5%,1/16W,CHIP,G21A    I30 @BASEBOARD_FAB2_LIB.BASEBOARD_FAB2(SCH_1):PAGE223
 EU1G2   39    VDD PXM1310B_QFN-IC,H89186-001    I90 @BASEBOARD_FAB2_LIB.BASEBOARD_FAB2(SCH_1):PAGE223

VR_PVDDQ_GHJ_VINSEN @BASEBOARD_FAB2_LIB.BASEBOARD_FAB2(SCH_1):VR_PVDDQ_GHJ_VINSEN
 R9U11    2      B RES_0402-100.0K,1%,1/16W,CHIP,B    I57 @BASEBOARD_FAB2_LIB.BASEBOARD_FAB2(SCH_1):PAGE223
 R1G24    1      A RES_0402-1.5K,1%,1/16W,CHIP,G2A    I58 @BASEBOARD_FAB2_LIB.BASEBOARD_FAB2(SCH_1):PAGE223
 C1G26    1      A CAP_0402LF-1000PF,50V,10%,X7R,A    I59 @BASEBOARD_FAB2_LIB.BASEBOARD_FAB2(SCH_1):PAGE223
 EU1G2   37 VINSEN PXM1310B_QFN-IC,H89186-001    I90 @BASEBOARD_FAB2_LIB.BASEBOARD_FAB2(SCH_1):PAGE223

VR_PVDDQ_GHJ_VREN @BASEBOARD_FAB2_LIB.BASEBOARD_FAB2(SCH_1):VR_PVDDQ_GHJ_VREN
  R9U7    2      B RES_0402-0.0,5%,1/16W,CHIP,G21A    I84 @BASEBOARD_FAB2_LIB.BASEBOARD_FAB2(SCH_1):PAGE223
  R9U8    2      B RES_0402-100.0K,1%,1/16W,EMPTYA    I85 @BASEBOARD_FAB2_LIB.BASEBOARD_FAB2(SCH_1):PAGE223
 EU1G2   10  AVREN PXM1310B_QFN-IC,H89186-001    I90 @BASEBOARD_FAB2_LIB.BASEBOARD_FAB2(SCH_1):PAGE223

VR_PVDDQ_GHJ_XADDR1 @BASEBOARD_FAB2_LIB.BASEBOARD_FAB2(SCH_1):VR_PVDDQ_GHJ_XADDR1
 R1G23    1      A RES_0402-4.02K,1%,1/16W,CHIP,GA    I77 @BASEBOARD_FAB2_LIB.BASEBOARD_FAB2(SCH_1):PAGE223
 EU1G2   36 XADDR1 PXM1310B_QFN-IC,H89186-001    I90 @BASEBOARD_FAB2_LIB.BASEBOARD_FAB2(SCH_1):PAGE223

VR_PVDDQ_GHJ_XADDR2 @BASEBOARD_FAB2_LIB.BASEBOARD_FAB2(SCH_1):VR_PVDDQ_GHJ_XADDR2
 R1G22    1      A RES_0402-5.36K,1.0%,1/16W,CHIPA    I78 @BASEBOARD_FAB2_LIB.BASEBOARD_FAB2(SCH_1):PAGE223
 EU1G2   33 XADDR2 PXM1310B_QFN-IC,H89186-001    I90 @BASEBOARD_FAB2_LIB.BASEBOARD_FAB2(SCH_1):PAGE223

VR_PVDDQ_KLM_AIINSEN @BASEBOARD_FAB2_LIB.BASEBOARD_FAB2(SCH_1):VR_PVDDQ_KLM_AIINSEN
 R1B14    2      B RES_0402-0.0,5%,1/16W,CHIP,G21A   I137 @BASEBOARD_FAB2_LIB.BASEBOARD_FAB2(SCH_1):PAGE197
 EU1B1   38 IINSEN PXM1310B_QFN-IC,H89186-001    I90 @BASEBOARD_FAB2_LIB.BASEBOARD_FAB2(SCH_1):PAGE226
 C9M11    1      A CAP_A_0402V-0.1UF,16V,10%,X7R,A    I92 @BASEBOARD_FAB2_LIB.BASEBOARD_FAB2(SCH_1):PAGE226

VR_PVDDQ_KLM_AIINSEN_R @BASEBOARD_FAB2_LIB.BASEBOARD_FAB2(SCH_1):VR_PVDDQ_KLM_AIINSEN_R
 R1B14    1      A RES_0402-0.0,5%,1/16W,CHIP,G21A   I137 @BASEBOARD_FAB2_LIB.BASEBOARD_FAB2(SCH_1):PAGE197
  U1B1    3    OUT MAX9634_SOT-IC,H35789-001   I144 @BASEBOARD_FAB2_LIB.BASEBOARD_FAB2(SCH_1):PAGE197

VR_PVDDQ_KLM_AIREF1 @BASEBOARD_FAB2_LIB.BASEBOARD_FAB2(SCH_1):VR_PVDDQ_KLM_AIREF1
 R9M11    2      B RES_0402-0.0,5%,1/16W,CHIP,G21A    I87 @BASEBOARD_FAB2_LIB.BASEBOARD_FAB2(SCH_1):PAGE226
 EU1B1   21 AIREF1 PXM1310B_QFN-IC,H89186-001    I90 @BASEBOARD_FAB2_LIB.BASEBOARD_FAB2(SCH_1):PAGE226
 EU1A2   39  REFIN IR354XX_SM-IR35411,IC,H73688-0A   I101 @BASEBOARD_FAB2_LIB.BASEBOARD_FAB2(SCH_1):PAGE227
   CT7    1      A CAP_A_0402V-0.1UF,16V,10%,X7R,A   I109 @BASEBOARD_FAB2_LIB.BASEBOARD_FAB2(SCH_1):PAGE227

VR_PVDDQ_KLM_AIREF2 @BASEBOARD_FAB2_LIB.BASEBOARD_FAB2(SCH_1):VR_PVDDQ_KLM_AIREF2
 R9M10    2      B RES_0402-0.0,5%,1/16W,CHIP,G21A    I88 @BASEBOARD_FAB2_LIB.BASEBOARD_FAB2(SCH_1):PAGE226
 EU1B1   23 AIREF2 PXM1310B_QFN-IC,H89186-001    I90 @BASEBOARD_FAB2_LIB.BASEBOARD_FAB2(SCH_1):PAGE226
 EU1A1   39  REFIN IR354XX_SM-IR35411,IC,H73688-0A   I102 @BASEBOARD_FAB2_LIB.BASEBOARD_FAB2(SCH_1):PAGE227
  CT12    1      A CAP_A_0402V-0.1UF,16V,10%,X7R,A   I122 @BASEBOARD_FAB2_LIB.BASEBOARD_FAB2(SCH_1):PAGE227

VR_PVDDQ_KLM_AVSP @BASEBOARD_FAB2_LIB.BASEBOARD_FAB2(SCH_1):VR_PVDDQ_KLM_AVSP
 R1B16    2      B RES_0402-10.0,1%,1/16W,CHIP,G2A    I32 @BASEBOARD_FAB2_LIB.BASEBOARD_FAB2(SCH_1):PAGE226
 C1B12    1      A CAP_0402LF-220PF,50V,10%,X7R,AA    I39 @BASEBOARD_FAB2_LIB.BASEBOARD_FAB2(SCH_1):PAGE226
 EU1B1   19  AVSEN PXM1310B_QFN-IC,H89186-001    I90 @BASEBOARD_FAB2_LIB.BASEBOARD_FAB2(SCH_1):PAGE226

VR_PVDDQ_KLM_PH1_BOOT @BASEBOARD_FAB2_LIB.BASEBOARD_FAB2(SCH_1):VR_PVDDQ_KLM_PH1_BOOT
 C1A18    1      A CAP_0402-0.220UF,16V,10%,X7R,AA    I44 @BASEBOARD_FAB2_LIB.BASEBOARD_FAB2(SCH_1):PAGE227
   RT5    1      A RES_0402-0.0,5%,1/16W,CHIP,G21A   I126 @BASEBOARD_FAB2_LIB.BASEBOARD_FAB2(SCH_1):PAGE227

VR_PVDDQ_KLM_PH1_BOOT_R @BASEBOARD_FAB2_LIB.BASEBOARD_FAB2(SCH_1):VR_PVDDQ_KLM_PH1_BOOT_R
 EU1A2   33  BOOST IR354XX_SM-IR35411,IC,H73688-0A   I101 @BASEBOARD_FAB2_LIB.BASEBOARD_FAB2(SCH_1):PAGE227
   RT5    2      B RES_0402-0.0,5%,1/16W,CHIP,G21A   I126 @BASEBOARD_FAB2_LIB.BASEBOARD_FAB2(SCH_1):PAGE227

VR_PVDDQ_KLM_PH1_OCSET @BASEBOARD_FAB2_LIB.BASEBOARD_FAB2(SCH_1):VR_PVDDQ_KLM_PH1_OCSET
 EU1A2   37  OCSET IR354XX_SM-IR35411,IC,H73688-0A   I101 @BASEBOARD_FAB2_LIB.BASEBOARD_FAB2(SCH_1):PAGE227
  R1A3    1      A RES_0402-68.1K,1%,1/16W,EMPTY,A   I103 @BASEBOARD_FAB2_LIB.BASEBOARD_FAB2(SCH_1):PAGE227

VR_PVDDQ_KLM_PH1_PHASE @BASEBOARD_FAB2_LIB.BASEBOARD_FAB2(SCH_1):VR_PVDDQ_KLM_PH1_PHASE
 C1A18    2      B CAP_0402-0.220UF,16V,10%,X7R,AA    I44 @BASEBOARD_FAB2_LIB.BASEBOARD_FAB2(SCH_1):PAGE227
 EU1A2   32  PHASE IR354XX_SM-IR35411,IC,H73688-0A   I101 @BASEBOARD_FAB2_LIB.BASEBOARD_FAB2(SCH_1):PAGE227

VR_PVDDQ_KLM_PH1_SW @BASEBOARD_FAB2_LIB.BASEBOARD_FAB2(SCH_1):VR_PVDDQ_KLM_PH1_SW
  L1A2    1    INA INDUCTOR_SM-0.12UH,IND,D92183-A    I55 @BASEBOARD_FAB2_LIB.BASEBOARD_FAB2(SCH_1):PAGE227
 EU1A2   10     SW IR354XX_SM-IR35411,IC,H73688-0A   I101 @BASEBOARD_FAB2_LIB.BASEBOARD_FAB2(SCH_1):PAGE227
   CT9    1      1 SC2K2P50V3KX-GP_SMD-BCG6-SC2K2A   I111 @BASEBOARD_FAB2_LIB.BASEBOARD_FAB2(SCH_1):PAGE227

VR_PVDDQ_KLM_PH1_VCIN @BASEBOARD_FAB2_LIB.BASEBOARD_FAB2(SCH_1):VR_PVDDQ_KLM_PH1_VCIN
 C1B20    1      A CAP_0402-1.0UF,16V,10%,X6S,D97A    I50 @BASEBOARD_FAB2_LIB.BASEBOARD_FAB2(SCH_1):PAGE227
  R9L9    1      A RES_0402-1.0,1%,1/16W,CHIP,G21A    I52 @BASEBOARD_FAB2_LIB.BASEBOARD_FAB2(SCH_1):PAGE227
 EU1A2    3    VCC IR354XX_SM-IR35411,IC,H73688-0A   I101 @BASEBOARD_FAB2_LIB.BASEBOARD_FAB2(SCH_1):PAGE227

VR_PVDDQ_KLM_PH2_BOOT @BASEBOARD_FAB2_LIB.BASEBOARD_FAB2(SCH_1):VR_PVDDQ_KLM_PH2_BOOT
  C1A8    1      A CAP_0402-0.220UF,16V,10%,X7R,AA    I75 @BASEBOARD_FAB2_LIB.BASEBOARD_FAB2(SCH_1):PAGE227
   RT8    1      A RES_0402-0.0,5%,1/16W,CHIP,G21A   I127 @BASEBOARD_FAB2_LIB.BASEBOARD_FAB2(SCH_1):PAGE227

VR_PVDDQ_KLM_PH2_BOOT_R @BASEBOARD_FAB2_LIB.BASEBOARD_FAB2(SCH_1):VR_PVDDQ_KLM_PH2_BOOT_R
 EU1A1   33  BOOST IR354XX_SM-IR35411,IC,H73688-0A   I102 @BASEBOARD_FAB2_LIB.BASEBOARD_FAB2(SCH_1):PAGE227
   RT8    2      B RES_0402-0.0,5%,1/16W,CHIP,G21A   I127 @BASEBOARD_FAB2_LIB.BASEBOARD_FAB2(SCH_1):PAGE227

VR_PVDDQ_KLM_PH2_OCSET @BASEBOARD_FAB2_LIB.BASEBOARD_FAB2(SCH_1):VR_PVDDQ_KLM_PH2_OCSET
 EU1A1   37  OCSET IR354XX_SM-IR35411,IC,H73688-0A   I102 @BASEBOARD_FAB2_LIB.BASEBOARD_FAB2(SCH_1):PAGE227
  R1A2    1      A RES_0402-68.1K,1%,1/16W,EMPTY,A   I105 @BASEBOARD_FAB2_LIB.BASEBOARD_FAB2(SCH_1):PAGE227

VR_PVDDQ_KLM_PH2_PHASE @BASEBOARD_FAB2_LIB.BASEBOARD_FAB2(SCH_1):VR_PVDDQ_KLM_PH2_PHASE
  C1A8    2      B CAP_0402-0.220UF,16V,10%,X7R,AA    I75 @BASEBOARD_FAB2_LIB.BASEBOARD_FAB2(SCH_1):PAGE227
 EU1A1   32  PHASE IR354XX_SM-IR35411,IC,H73688-0A   I102 @BASEBOARD_FAB2_LIB.BASEBOARD_FAB2(SCH_1):PAGE227

VR_PVDDQ_KLM_PH2_SW @BASEBOARD_FAB2_LIB.BASEBOARD_FAB2(SCH_1):VR_PVDDQ_KLM_PH2_SW
  L1A1    1    INA INDUCTOR_SM-0.12UH,IND,D92183-A    I65 @BASEBOARD_FAB2_LIB.BASEBOARD_FAB2(SCH_1):PAGE227
 EU1A1   10     SW IR354XX_SM-IR35411,IC,H73688-0A   I102 @BASEBOARD_FAB2_LIB.BASEBOARD_FAB2(SCH_1):PAGE227
  CT11    1      1 SC2K2P50V3KX-GP_SMD-BCG6-SC2K2A   I116 @BASEBOARD_FAB2_LIB.BASEBOARD_FAB2(SCH_1):PAGE227

VR_PVDDQ_KLM_PH2_VCIN @BASEBOARD_FAB2_LIB.BASEBOARD_FAB2(SCH_1):VR_PVDDQ_KLM_PH2_VCIN
  R9L4    1      A RES_0402-1.0,1%,1/16W,CHIP,G21A    I76 @BASEBOARD_FAB2_LIB.BASEBOARD_FAB2(SCH_1):PAGE227
  C1A6    1      A CAP_0402-1.0UF,16V,10%,X6S,D97A    I77 @BASEBOARD_FAB2_LIB.BASEBOARD_FAB2(SCH_1):PAGE227
 EU1A1    3    VCC IR354XX_SM-IR35411,IC,H73688-0A   I102 @BASEBOARD_FAB2_LIB.BASEBOARD_FAB2(SCH_1):PAGE227

VR_PVDDQ_KLM_PWM1 @BASEBOARD_FAB2_LIB.BASEBOARD_FAB2(SCH_1):VR_PVDDQ_KLM_PWM1
 EU1B1    5  APWM1 PXM1310B_QFN-IC,H89186-001    I90 @BASEBOARD_FAB2_LIB.BASEBOARD_FAB2(SCH_1):PAGE226
 EU1A2   34    PWM IR354XX_SM-IR35411,IC,H73688-0A   I101 @BASEBOARD_FAB2_LIB.BASEBOARD_FAB2(SCH_1):PAGE227

VR_PVDDQ_KLM_PWM2 @BASEBOARD_FAB2_LIB.BASEBOARD_FAB2(SCH_1):VR_PVDDQ_KLM_PWM2
 EU1B1    4  APWM2 PXM1310B_QFN-IC,H89186-001    I90 @BASEBOARD_FAB2_LIB.BASEBOARD_FAB2(SCH_1):PAGE226
 EU1A1   34    PWM IR354XX_SM-IR35411,IC,H73688-0A   I102 @BASEBOARD_FAB2_LIB.BASEBOARD_FAB2(SCH_1):PAGE227

VR_PVDDQ_KLM_VD12 @BASEBOARD_FAB2_LIB.BASEBOARD_FAB2(SCH_1):VR_PVDDQ_KLM_VD12
  C1B3    1      A CAP_A_0402V-1.0UF,6.3V,10%,X6SA    I41 @BASEBOARD_FAB2_LIB.BASEBOARD_FAB2(SCH_1):PAGE226
  C1B2    1      A CAP_A_0402V-0.1UF,16V,10%,X7R,A    I44 @BASEBOARD_FAB2_LIB.BASEBOARD_FAB2(SCH_1):PAGE226
 R9M11    1      A RES_0402-0.0,5%,1/16W,CHIP,G21A    I87 @BASEBOARD_FAB2_LIB.BASEBOARD_FAB2(SCH_1):PAGE226
 R9M10    1      A RES_0402-0.0,5%,1/16W,CHIP,G21A    I88 @BASEBOARD_FAB2_LIB.BASEBOARD_FAB2(SCH_1):PAGE226
 EU1B1   40   VD12 PXM1310B_QFN-IC,H89186-001    I90 @BASEBOARD_FAB2_LIB.BASEBOARD_FAB2(SCH_1):PAGE226

VR_PVDDQ_KLM_VDD @BASEBOARD_FAB2_LIB.BASEBOARD_FAB2(SCH_1):VR_PVDDQ_KLM_VDD
  C1B6    1      A CAP_A_0402V-1.0UF,6.3V,10%,X6SA    I25 @BASEBOARD_FAB2_LIB.BASEBOARD_FAB2(SCH_1):PAGE226
  C1B5    1      A CAP_A_0402V-0.1UF,16V,10%,X7R,A    I27 @BASEBOARD_FAB2_LIB.BASEBOARD_FAB2(SCH_1):PAGE226
  R9M3    2      B RES_0402-0.0,5%,1/16W,CHIP,G21A    I30 @BASEBOARD_FAB2_LIB.BASEBOARD_FAB2(SCH_1):PAGE226
 EU1B1   39    VDD PXM1310B_QFN-IC,H89186-001    I90 @BASEBOARD_FAB2_LIB.BASEBOARD_FAB2(SCH_1):PAGE226

VR_PVDDQ_KLM_VINSEN @BASEBOARD_FAB2_LIB.BASEBOARD_FAB2(SCH_1):VR_PVDDQ_KLM_VINSEN
  R9M8    2      B RES_0402-100.0K,1%,1/16W,CHIP,B    I57 @BASEBOARD_FAB2_LIB.BASEBOARD_FAB2(SCH_1):PAGE226
  R1B9    1      A RES_0402-1.5K,1%,1/16W,CHIP,G2A    I58 @BASEBOARD_FAB2_LIB.BASEBOARD_FAB2(SCH_1):PAGE226
  C1B8    1      A CAP_0402LF-1000PF,50V,10%,X7R,A    I59 @BASEBOARD_FAB2_LIB.BASEBOARD_FAB2(SCH_1):PAGE226
 EU1B1   37 VINSEN PXM1310B_QFN-IC,H89186-001    I90 @BASEBOARD_FAB2_LIB.BASEBOARD_FAB2(SCH_1):PAGE226

VR_PVDDQ_KLM_VREN @BASEBOARD_FAB2_LIB.BASEBOARD_FAB2(SCH_1):VR_PVDDQ_KLM_VREN
  R9M9    2      B RES_0402-0.0,5%,1/16W,CHIP,G21A    I84 @BASEBOARD_FAB2_LIB.BASEBOARD_FAB2(SCH_1):PAGE226
  R9M5    2      B RES_0402-100.0K,1%,1/16W,EMPTYA    I85 @BASEBOARD_FAB2_LIB.BASEBOARD_FAB2(SCH_1):PAGE226
 EU1B1   10  AVREN PXM1310B_QFN-IC,H89186-001    I90 @BASEBOARD_FAB2_LIB.BASEBOARD_FAB2(SCH_1):PAGE226

VR_PVDDQ_KLM_XADDR1 @BASEBOARD_FAB2_LIB.BASEBOARD_FAB2(SCH_1):VR_PVDDQ_KLM_XADDR1
 R1B12    1      A RES_0402-3.16K,1%,1/16W,CHIP,GA    I78 @BASEBOARD_FAB2_LIB.BASEBOARD_FAB2(SCH_1):PAGE226
 EU1B1   36 XADDR1 PXM1310B_QFN-IC,H89186-001    I90 @BASEBOARD_FAB2_LIB.BASEBOARD_FAB2(SCH_1):PAGE226

VR_PVDDQ_KLM_XADDR2 @BASEBOARD_FAB2_LIB.BASEBOARD_FAB2(SCH_1):VR_PVDDQ_KLM_XADDR2
 R1B15    1      A RES_0402-5.36K,1.0%,1/16W,CHIPA    I77 @BASEBOARD_FAB2_LIB.BASEBOARD_FAB2(SCH_1):PAGE226
 EU1B1   33 XADDR2 PXM1310B_QFN-IC,H89186-001    I90 @BASEBOARD_FAB2_LIB.BASEBOARD_FAB2(SCH_1):PAGE226

VR_PVNN_P1V05_PCH_VD12 @BASEBOARD_FAB2_LIB.BASEBOARD_FAB2(SCH_1):VR_PVNN_P1V05_PCH_VD12
  C8A7    1      A CAP_A_0402V-1.0UF,6.3V,10%,X6SA   I143 @BASEBOARD_FAB2_LIB.BASEBOARD_FAB2(SCH_1):PAGE235
  C8A8    1      A CAP_A_0402V-0.1UF,16V,10%,X7R,A   I145 @BASEBOARD_FAB2_LIB.BASEBOARD_FAB2(SCH_1):PAGE235
  R2L1    1      A RES_0402-0.0,5%,1/16W,CHIP,G21A   I224 @BASEBOARD_FAB2_LIB.BASEBOARD_FAB2(SCH_1):PAGE235
  R2L7    1      A RES_0402-0.0,5%,1/16W,CHIP,G21A   I225 @BASEBOARD_FAB2_LIB.BASEBOARD_FAB2(SCH_1):PAGE235
 EU8A1   40   VD12 PXE1110B_QFN-IC,H89187-001   I229 @BASEBOARD_FAB2_LIB.BASEBOARD_FAB2(SCH_1):PAGE235

VR_PVNN_PCH_AIREF1 @BASEBOARD_FAB2_LIB.BASEBOARD_FAB2(SCH_1):VR_PVNN_PCH_AIREF1
  R2L1    2      B RES_0402-0.0,5%,1/16W,CHIP,G21A   I224 @BASEBOARD_FAB2_LIB.BASEBOARD_FAB2(SCH_1):PAGE235
 EU8A1   21 AIREF1 PXE1110B_QFN-IC,H89187-001   I229 @BASEBOARD_FAB2_LIB.BASEBOARD_FAB2(SCH_1):PAGE235
 EU7A3   39  REFIN IR354XX_SM-IR35412,IC,H73684-0A   I116 @BASEBOARD_FAB2_LIB.BASEBOARD_FAB2(SCH_1):PAGE236
  CT66    1      A CAP_A_0402V-0.1UF,16V,10%,X7R,A   I127 @BASEBOARD_FAB2_LIB.BASEBOARD_FAB2(SCH_1):PAGE236

VR_PVNN_PCH_AVSP @BASEBOARD_FAB2_LIB.BASEBOARD_FAB2(SCH_1):VR_PVNN_PCH_AVSP
  C8A2    1      A CAP_0402LF-220PF,50V,10%,X7R,AA   I209 @BASEBOARD_FAB2_LIB.BASEBOARD_FAB2(SCH_1):PAGE235
  R8A1    2      B RES_0402-10.0,1%,1/16W,CHIP,G2A   I210 @BASEBOARD_FAB2_LIB.BASEBOARD_FAB2(SCH_1):PAGE235
 EU8A1   19  AVSEN PXE1110B_QFN-IC,H89187-001   I229 @BASEBOARD_FAB2_LIB.BASEBOARD_FAB2(SCH_1):PAGE235

VR_PVNN_PCH_PH1_BOOT @BASEBOARD_FAB2_LIB.BASEBOARD_FAB2(SCH_1):VR_PVNN_PCH_PH1_BOOT
 C7A43    1      A CAP_0402-0.220UF,16V,10%,X7R,AA    I21 @BASEBOARD_FAB2_LIB.BASEBOARD_FAB2(SCH_1):PAGE236
  RT44    1      A RES_0402-0.0,5%,1/16W,CHIP,G21A   I141 @BASEBOARD_FAB2_LIB.BASEBOARD_FAB2(SCH_1):PAGE236

VR_PVNN_PCH_PH1_BOOT_R @BASEBOARD_FAB2_LIB.BASEBOARD_FAB2(SCH_1):VR_PVNN_PCH_PH1_BOOT_R
 EU7A3   33  BOOST IR354XX_SM-IR35412,IC,H73684-0A   I116 @BASEBOARD_FAB2_LIB.BASEBOARD_FAB2(SCH_1):PAGE236
  RT44    2      B RES_0402-0.0,5%,1/16W,CHIP,G21A   I141 @BASEBOARD_FAB2_LIB.BASEBOARD_FAB2(SCH_1):PAGE236

VR_PVNN_PCH_PH1_PHASE @BASEBOARD_FAB2_LIB.BASEBOARD_FAB2(SCH_1):VR_PVNN_PCH_PH1_PHASE
 C7A43    2      B CAP_0402-0.220UF,16V,10%,X7R,AA    I21 @BASEBOARD_FAB2_LIB.BASEBOARD_FAB2(SCH_1):PAGE236
 EU7A3   32  PHASE IR354XX_SM-IR35412,IC,H73684-0A   I116 @BASEBOARD_FAB2_LIB.BASEBOARD_FAB2(SCH_1):PAGE236

VR_PVNN_PCH_PH1_PHASE_SW @BASEBOARD_FAB2_LIB.BASEBOARD_FAB2(SCH_1):VR_PVNN_PCH_PH1_PHASE_SW
  L7A2    1    INA INDUCTOR_SM-0.3UH,IND,D92183-0A    I10 @BASEBOARD_FAB2_LIB.BASEBOARD_FAB2(SCH_1):PAGE236
 EU7A3   10     SW IR354XX_SM-IR35412,IC,H73684-0A   I116 @BASEBOARD_FAB2_LIB.BASEBOARD_FAB2(SCH_1):PAGE236
  CT65    1      1 SC2K2P50V3KX-GP_SMD-BCG6-SC2K2A   I131 @BASEBOARD_FAB2_LIB.BASEBOARD_FAB2(SCH_1):PAGE236

VR_PVNN_PCH_PH1_VCIN @BASEBOARD_FAB2_LIB.BASEBOARD_FAB2(SCH_1):VR_PVNN_PCH_PH1_VCIN
  R3L1    1      A RES_0402-1.0,1%,1/16W,CHIP,G21A    I14 @BASEBOARD_FAB2_LIB.BASEBOARD_FAB2(SCH_1):PAGE236
  C7A6    1      A CAP_0402-1.0UF,16V,10%,X6S,D97A    I19 @BASEBOARD_FAB2_LIB.BASEBOARD_FAB2(SCH_1):PAGE236
 EU7A3    3    VCC IR354XX_SM-IR35412,IC,H73684-0A   I116 @BASEBOARD_FAB2_LIB.BASEBOARD_FAB2(SCH_1):PAGE236

VR_PVNN_PCH_PWM1 @BASEBOARD_FAB2_LIB.BASEBOARD_FAB2(SCH_1):VR_PVNN_PCH_PWM1
 EU8A1    5  APWM1 PXE1110B_QFN-IC,H89187-001   I229 @BASEBOARD_FAB2_LIB.BASEBOARD_FAB2(SCH_1):PAGE235
 EU7A3   34    PWM IR354XX_SM-IR35412,IC,H73684-0A   I116 @BASEBOARD_FAB2_LIB.BASEBOARD_FAB2(SCH_1):PAGE236

VR_PVNN_PCH_STBY_OCSET @BASEBOARD_FAB2_LIB.BASEBOARD_FAB2(SCH_1):VR_PVNN_PCH_STBY_OCSET
 EU7A3   37  OCSET IR354XX_SM-IR35412,IC,H73684-0A   I116 @BASEBOARD_FAB2_LIB.BASEBOARD_FAB2(SCH_1):PAGE236
 R3L15    1      A RES_0402-68.1K,1%,1/16W,EMPTY,A   I118 @BASEBOARD_FAB2_LIB.BASEBOARD_FAB2(SCH_1):PAGE236

VR_PVNN_PCH_VDD @BASEBOARD_FAB2_LIB.BASEBOARD_FAB2(SCH_1):VR_PVNN_PCH_VDD
  C2L8    1      A CAP_A_0402V-1.0UF,6.3V,10%,X6SA   I151 @BASEBOARD_FAB2_LIB.BASEBOARD_FAB2(SCH_1):PAGE235
 R2L14    2      B RES_0402-0.0,5%,1/16W,CHIP,G21A   I159 @BASEBOARD_FAB2_LIB.BASEBOARD_FAB2(SCH_1):PAGE235
 C2L11    1      A CAP_A_0402V-0.1UF,16V,10%,X7R,A   I169 @BASEBOARD_FAB2_LIB.BASEBOARD_FAB2(SCH_1):PAGE235
 EU8A1   39    VDD PXE1110B_QFN-IC,H89187-001   I229 @BASEBOARD_FAB2_LIB.BASEBOARD_FAB2(SCH_1):PAGE235

VR_PVNN_PCH_VINSEN @BASEBOARD_FAB2_LIB.BASEBOARD_FAB2(SCH_1):VR_PVNN_PCH_VINSEN
  R8A4    2      B RES_0402-100.0K,1%,1/16W,CHIP,B   I165 @BASEBOARD_FAB2_LIB.BASEBOARD_FAB2(SCH_1):PAGE235
 R2L10    1      A RES_0402-1.5K,1%,1/16W,CHIP,G2A   I166 @BASEBOARD_FAB2_LIB.BASEBOARD_FAB2(SCH_1):PAGE235
  C8A3    1      A CAP_0402LF-1000PF,50V,10%,X7R,A   I167 @BASEBOARD_FAB2_LIB.BASEBOARD_FAB2(SCH_1):PAGE235
 EU8A1   37 VINSEN PXE1110B_QFN-IC,H89187-001   I229 @BASEBOARD_FAB2_LIB.BASEBOARD_FAB2(SCH_1):PAGE235

VR_PVNN_PCH_VREN @BASEBOARD_FAB2_LIB.BASEBOARD_FAB2(SCH_1):VR_PVNN_PCH_VREN
 R2L17    2      B RES_0402-0.0,5%,1/16W,CHIP,G21A   I221 @BASEBOARD_FAB2_LIB.BASEBOARD_FAB2(SCH_1):PAGE235
  R8A7    2      B RES_0402-100.0K,1%,1/16W,EMPTYA   I222 @BASEBOARD_FAB2_LIB.BASEBOARD_FAB2(SCH_1):PAGE235
 EU8A1   10  AVREN PXE1110B_QFN-IC,H89187-001   I229 @BASEBOARD_FAB2_LIB.BASEBOARD_FAB2(SCH_1):PAGE235

VR_PVNN_PCH_XADDR1 @BASEBOARD_FAB2_LIB.BASEBOARD_FAB2(SCH_1):VR_PVNN_PCH_XADDR1
  R2L9    1      A RES_0402-4.02K,1%,1/16W,CHIP,GA   I176 @BASEBOARD_FAB2_LIB.BASEBOARD_FAB2(SCH_1):PAGE235
 EU8A1   36 XADDR1 PXE1110B_QFN-IC,H89187-001   I229 @BASEBOARD_FAB2_LIB.BASEBOARD_FAB2(SCH_1):PAGE235

VR_PVNN_PCH_XADDR2 @BASEBOARD_FAB2_LIB.BASEBOARD_FAB2(SCH_1):VR_PVNN_PCH_XADDR2
  R8A2    1      A RES_0402-2.67K,1%,1/16W,CHIP,GA   I217 @BASEBOARD_FAB2_LIB.BASEBOARD_FAB2(SCH_1):PAGE235
 EU8A1   33 XADDR2 PXE1110B_QFN-IC,H89187-001   I229 @BASEBOARD_FAB2_LIB.BASEBOARD_FAB2(SCH_1):PAGE235

VR_PVPP_ABC_BOOT @BASEBOARD_FAB2_LIB.BASEBOARD_FAB2(SCH_1):VR_PVPP_ABC_BOOT
  R7F8    1      A RES_0402-0.0,5%,1/16W,CHIP,G21A   I154 @BASEBOARD_FAB2_LIB.BASEBOARD_FAB2(SCH_1):PAGE231
 EU7F1   36    BST NCP3232L_SM-IC,H86355-001   I193 @BASEBOARD_FAB2_LIB.BASEBOARD_FAB2(SCH_1):PAGE231

VR_PVPP_ABC_BOOT_R @BASEBOARD_FAB2_LIB.BASEBOARD_FAB2(SCH_1):VR_PVPP_ABC_BOOT_R
  R7F8    2      B RES_0402-0.0,5%,1/16W,CHIP,G21A   I154 @BASEBOARD_FAB2_LIB.BASEBOARD_FAB2(SCH_1):PAGE231
  C7F4    2      B CAP_0603LF-0.1UF,25V,10%,X7R,6A   I159 @BASEBOARD_FAB2_LIB.BASEBOARD_FAB2(SCH_1):PAGE231

VR_PVPP_ABC_ISET @BASEBOARD_FAB2_LIB.BASEBOARD_FAB2(SCH_1):VR_PVPP_ABC_ISET
 R7F15    1      A RES_0402-7.87K,1.0%,1/16W,CHIPA   I134 @BASEBOARD_FAB2_LIB.BASEBOARD_FAB2(SCH_1):PAGE231
 EU7F1    4   ISET NCP3232L_SM-IC,H86355-001   I193 @BASEBOARD_FAB2_LIB.BASEBOARD_FAB2(SCH_1):PAGE231

VR_PVPP_ABC_PHASE @BASEBOARD_FAB2_LIB.BASEBOARD_FAB2(SCH_1):VR_PVPP_ABC_PHASE
  C7F4    1      A CAP_0603LF-0.1UF,25V,10%,X7R,6A   I159 @BASEBOARD_FAB2_LIB.BASEBOARD_FAB2(SCH_1):PAGE231
  C7F3    1      A CAP_0402LF-3300PF,50V,10%,EMPTA   I175 @BASEBOARD_FAB2_LIB.BASEBOARD_FAB2(SCH_1):PAGE231
  L7F1    1    INA INDUCTOR_SM-0.47UH,IND,E13358-A   I178 @BASEBOARD_FAB2_LIB.BASEBOARD_FAB2(SCH_1):PAGE231
 EU7F1   35    VSW NCP3232L_SM-IC,H86355-001   I193 @BASEBOARD_FAB2_LIB.BASEBOARD_FAB2(SCH_1):PAGE231
 EU7F1   15 VSWH<0> NCP3232L_SM-IC,H86355-001   I193 @BASEBOARD_FAB2_LIB.BASEBOARD_FAB2(SCH_1):PAGE231
 EU7F1   29 VSWH<1> NCP3232L_SM-IC,H86355-001   I193 @BASEBOARD_FAB2_LIB.BASEBOARD_FAB2(SCH_1):PAGE231
 EU7F1   30 VSWH<2> NCP3232L_SM-IC,H86355-001   I193 @BASEBOARD_FAB2_LIB.BASEBOARD_FAB2(SCH_1):PAGE231
 EU7F1   31 VSWH<3> NCP3232L_SM-IC,H86355-001   I193 @BASEBOARD_FAB2_LIB.BASEBOARD_FAB2(SCH_1):PAGE231
 EU7F1   32 VSWH<4> NCP3232L_SM-IC,H86355-001   I193 @BASEBOARD_FAB2_LIB.BASEBOARD_FAB2(SCH_1):PAGE231
 EU7F1   33 VSWH<5> NCP3232L_SM-IC,H86355-001   I193 @BASEBOARD_FAB2_LIB.BASEBOARD_FAB2(SCH_1):PAGE231
 EU7F1   34 VSWH<6> NCP3232L_SM-IC,H86355-001   I193 @BASEBOARD_FAB2_LIB.BASEBOARD_FAB2(SCH_1):PAGE231
 EU7F1   43 VSWH<7> NCP3232L_SM-IC,H86355-001   I193 @BASEBOARD_FAB2_LIB.BASEBOARD_FAB2(SCH_1):PAGE231

VR_PVPP_ABC_SNUB @BASEBOARD_FAB2_LIB.BASEBOARD_FAB2(SCH_1):VR_PVPP_ABC_SNUB
  R7F7    1      A RES_0402-2.2,5%,1/16W,EMPTY,G2A   I174 @BASEBOARD_FAB2_LIB.BASEBOARD_FAB2(SCH_1):PAGE231
  C7F3    2      B CAP_0402LF-3300PF,50V,10%,EMPTA   I175 @BASEBOARD_FAB2_LIB.BASEBOARD_FAB2(SCH_1):PAGE231

VR_PVPP_ABC_SS @BASEBOARD_FAB2_LIB.BASEBOARD_FAB2(SCH_1):VR_PVPP_ABC_SS
 EU7F1    1     SS NCP3232L_SM-IC,H86355-001   I193 @BASEBOARD_FAB2_LIB.BASEBOARD_FAB2(SCH_1):PAGE231
 C7F10    1      A CAP_0402-0.027UF,16V,10%,X7R,AA   I194 @BASEBOARD_FAB2_LIB.BASEBOARD_FAB2(SCH_1):PAGE231

VR_PVPP_DEF_BOOT @BASEBOARD_FAB2_LIB.BASEBOARD_FAB2(SCH_1):VR_PVPP_DEF_BOOT
 EU7B1   36    BST NCP3232L_SM-IC,H86355-001   I214 @BASEBOARD_FAB2_LIB.BASEBOARD_FAB2(SCH_1):PAGE232
 R7B19    1      A RES_0402-0.0,5%,1/16W,CHIP,G21A   I240 @BASEBOARD_FAB2_LIB.BASEBOARD_FAB2(SCH_1):PAGE232

VR_PVPP_DEF_BOOT_R @BASEBOARD_FAB2_LIB.BASEBOARD_FAB2(SCH_1):VR_PVPP_DEF_BOOT_R
 R7B19    2      B RES_0402-0.0,5%,1/16W,CHIP,G21A   I240 @BASEBOARD_FAB2_LIB.BASEBOARD_FAB2(SCH_1):PAGE232
 C7B30    2      B CAP_0603LF-0.1UF,25V,10%,X7R,6A   I241 @BASEBOARD_FAB2_LIB.BASEBOARD_FAB2(SCH_1):PAGE232

VR_PVPP_DEF_ISET @BASEBOARD_FAB2_LIB.BASEBOARD_FAB2(SCH_1):VR_PVPP_DEF_ISET
 R7B14    1      A RES_0402-7.87K,1.0%,1/16W,CHIPA   I193 @BASEBOARD_FAB2_LIB.BASEBOARD_FAB2(SCH_1):PAGE232
 EU7B1    4   ISET NCP3232L_SM-IC,H86355-001   I214 @BASEBOARD_FAB2_LIB.BASEBOARD_FAB2(SCH_1):PAGE232

VR_PVPP_DEF_PHASE @BASEBOARD_FAB2_LIB.BASEBOARD_FAB2(SCH_1):VR_PVPP_DEF_PHASE
 EU7B1   35    VSW NCP3232L_SM-IC,H86355-001   I214 @BASEBOARD_FAB2_LIB.BASEBOARD_FAB2(SCH_1):PAGE232
 EU7B1   15 VSWH<0> NCP3232L_SM-IC,H86355-001   I214 @BASEBOARD_FAB2_LIB.BASEBOARD_FAB2(SCH_1):PAGE232
 EU7B1   29 VSWH<1> NCP3232L_SM-IC,H86355-001   I214 @BASEBOARD_FAB2_LIB.BASEBOARD_FAB2(SCH_1):PAGE232
 EU7B1   30 VSWH<2> NCP3232L_SM-IC,H86355-001   I214 @BASEBOARD_FAB2_LIB.BASEBOARD_FAB2(SCH_1):PAGE232
 EU7B1   31 VSWH<3> NCP3232L_SM-IC,H86355-001   I214 @BASEBOARD_FAB2_LIB.BASEBOARD_FAB2(SCH_1):PAGE232
 EU7B1   32 VSWH<4> NCP3232L_SM-IC,H86355-001   I214 @BASEBOARD_FAB2_LIB.BASEBOARD_FAB2(SCH_1):PAGE232
 EU7B1   33 VSWH<5> NCP3232L_SM-IC,H86355-001   I214 @BASEBOARD_FAB2_LIB.BASEBOARD_FAB2(SCH_1):PAGE232
 EU7B1   34 VSWH<6> NCP3232L_SM-IC,H86355-001   I214 @BASEBOARD_FAB2_LIB.BASEBOARD_FAB2(SCH_1):PAGE232
 EU7B1   43 VSWH<7> NCP3232L_SM-IC,H86355-001   I214 @BASEBOARD_FAB2_LIB.BASEBOARD_FAB2(SCH_1):PAGE232
 C7A34    1      A CAP_0402LF-3300PF,50V,10%,EMPTA   I220 @BASEBOARD_FAB2_LIB.BASEBOARD_FAB2(SCH_1):PAGE232
  L7B1    1    INA INDUCTOR_SM-0.47UH,IND,E13358-A   I239 @BASEBOARD_FAB2_LIB.BASEBOARD_FAB2(SCH_1):PAGE232
 C7B30    1      A CAP_0603LF-0.1UF,25V,10%,X7R,6A   I241 @BASEBOARD_FAB2_LIB.BASEBOARD_FAB2(SCH_1):PAGE232

VR_PVPP_DEF_SNUB @BASEBOARD_FAB2_LIB.BASEBOARD_FAB2(SCH_1):VR_PVPP_DEF_SNUB
 R7A15    1      A RES_0402-2.2,5%,1/16W,EMPTY,G2A   I218 @BASEBOARD_FAB2_LIB.BASEBOARD_FAB2(SCH_1):PAGE232
 C7A34    2      B CAP_0402LF-3300PF,50V,10%,EMPTA   I220 @BASEBOARD_FAB2_LIB.BASEBOARD_FAB2(SCH_1):PAGE232

VR_PVPP_DEF_SS @BASEBOARD_FAB2_LIB.BASEBOARD_FAB2(SCH_1):VR_PVPP_DEF_SS
 C7B11    1      A CAP_0402-0.027UF,16V,10%,X7R,AA   I197 @BASEBOARD_FAB2_LIB.BASEBOARD_FAB2(SCH_1):PAGE232
 EU7B1    1     SS NCP3232L_SM-IC,H86355-001   I214 @BASEBOARD_FAB2_LIB.BASEBOARD_FAB2(SCH_1):PAGE232

VR_PVPP_GHJ_BOOT @BASEBOARD_FAB2_LIB.BASEBOARD_FAB2(SCH_1):VR_PVPP_GHJ_BOOT
 R4G24    1      A RES_0402-0.0,5%,1/16W,CHIP,G21A   I199 @BASEBOARD_FAB2_LIB.BASEBOARD_FAB2(SCH_1):PAGE233
 EU4G1   36    BST NCP3232L_SM-IC,H86355-001   I225 @BASEBOARD_FAB2_LIB.BASEBOARD_FAB2(SCH_1):PAGE233

VR_PVPP_GHJ_BOOT_R @BASEBOARD_FAB2_LIB.BASEBOARD_FAB2(SCH_1):VR_PVPP_GHJ_BOOT_R
 R4G24    2      B RES_0402-0.0,5%,1/16W,CHIP,G21A   I199 @BASEBOARD_FAB2_LIB.BASEBOARD_FAB2(SCH_1):PAGE233
 C4G26    2      B CAP_0603LF-0.1UF,25V,10%,X7R,6A   I224 @BASEBOARD_FAB2_LIB.BASEBOARD_FAB2(SCH_1):PAGE233

VR_PVPP_GHJ_ISET @BASEBOARD_FAB2_LIB.BASEBOARD_FAB2(SCH_1):VR_PVPP_GHJ_ISET
 R4G11    1      A RES_0402-7.87K,1.0%,1/16W,CHIPA   I184 @BASEBOARD_FAB2_LIB.BASEBOARD_FAB2(SCH_1):PAGE233
 EU4G1    4   ISET NCP3232L_SM-IC,H86355-001   I225 @BASEBOARD_FAB2_LIB.BASEBOARD_FAB2(SCH_1):PAGE233

VR_PVPP_GHJ_PHASE @BASEBOARD_FAB2_LIB.BASEBOARD_FAB2(SCH_1):VR_PVPP_GHJ_PHASE
 C4F12    1      A CAP_0402LF-3300PF,50V,10%,EMPTA   I209 @BASEBOARD_FAB2_LIB.BASEBOARD_FAB2(SCH_1):PAGE233
 C4G26    1      A CAP_0603LF-0.1UF,25V,10%,X7R,6A   I224 @BASEBOARD_FAB2_LIB.BASEBOARD_FAB2(SCH_1):PAGE233
 EU4G1   35    VSW NCP3232L_SM-IC,H86355-001   I225 @BASEBOARD_FAB2_LIB.BASEBOARD_FAB2(SCH_1):PAGE233
 EU4G1   15 VSWH<0> NCP3232L_SM-IC,H86355-001   I225 @BASEBOARD_FAB2_LIB.BASEBOARD_FAB2(SCH_1):PAGE233
 EU4G1   29 VSWH<1> NCP3232L_SM-IC,H86355-001   I225 @BASEBOARD_FAB2_LIB.BASEBOARD_FAB2(SCH_1):PAGE233
 EU4G1   30 VSWH<2> NCP3232L_SM-IC,H86355-001   I225 @BASEBOARD_FAB2_LIB.BASEBOARD_FAB2(SCH_1):PAGE233
 EU4G1   31 VSWH<3> NCP3232L_SM-IC,H86355-001   I225 @BASEBOARD_FAB2_LIB.BASEBOARD_FAB2(SCH_1):PAGE233
 EU4G1   32 VSWH<4> NCP3232L_SM-IC,H86355-001   I225 @BASEBOARD_FAB2_LIB.BASEBOARD_FAB2(SCH_1):PAGE233
 EU4G1   33 VSWH<5> NCP3232L_SM-IC,H86355-001   I225 @BASEBOARD_FAB2_LIB.BASEBOARD_FAB2(SCH_1):PAGE233
 EU4G1   34 VSWH<6> NCP3232L_SM-IC,H86355-001   I225 @BASEBOARD_FAB2_LIB.BASEBOARD_FAB2(SCH_1):PAGE233
 EU4G1   43 VSWH<7> NCP3232L_SM-IC,H86355-001   I225 @BASEBOARD_FAB2_LIB.BASEBOARD_FAB2(SCH_1):PAGE233
  L4G1    1    INA INDUCTOR_SM-0.47UH,IND,E13358-A   I277 @BASEBOARD_FAB2_LIB.BASEBOARD_FAB2(SCH_1):PAGE233

VR_PVPP_GHJ_SNUB @BASEBOARD_FAB2_LIB.BASEBOARD_FAB2(SCH_1):VR_PVPP_GHJ_SNUB
  R4F6    1      A RES_0402-2.2,5%,1/16W,EMPTY,G2A   I208 @BASEBOARD_FAB2_LIB.BASEBOARD_FAB2(SCH_1):PAGE233
 C4F12    2      B CAP_0402LF-3300PF,50V,10%,EMPTA   I209 @BASEBOARD_FAB2_LIB.BASEBOARD_FAB2(SCH_1):PAGE233

VR_PVPP_GHJ_SS @BASEBOARD_FAB2_LIB.BASEBOARD_FAB2(SCH_1):VR_PVPP_GHJ_SS
  C4G8    1      A CAP_0402-0.027UF,16V,10%,X7R,AA   I194 @BASEBOARD_FAB2_LIB.BASEBOARD_FAB2(SCH_1):PAGE233
 EU4G1    1     SS NCP3232L_SM-IC,H86355-001   I225 @BASEBOARD_FAB2_LIB.BASEBOARD_FAB2(SCH_1):PAGE233

VR_PVPP_KLM_BOOT @BASEBOARD_FAB2_LIB.BASEBOARD_FAB2(SCH_1):VR_PVPP_KLM_BOOT
 R4B13    1      A RES_0402-0.0,5%,1/16W,CHIP,G21A   I155 @BASEBOARD_FAB2_LIB.BASEBOARD_FAB2(SCH_1):PAGE234
 EU4A3   36    BST NCP3232L_SM-IC,H86355-001   I184 @BASEBOARD_FAB2_LIB.BASEBOARD_FAB2(SCH_1):PAGE234

VR_PVPP_KLM_BOOT_R @BASEBOARD_FAB2_LIB.BASEBOARD_FAB2(SCH_1):VR_PVPP_KLM_BOOT_R
 R4B13    2      B RES_0402-0.0,5%,1/16W,CHIP,G21A   I155 @BASEBOARD_FAB2_LIB.BASEBOARD_FAB2(SCH_1):PAGE234
 C4B15    2      B CAP_0603LF-0.1UF,25V,10%,X7R,6A   I182 @BASEBOARD_FAB2_LIB.BASEBOARD_FAB2(SCH_1):PAGE234

VR_PVPP_KLM_ISET @BASEBOARD_FAB2_LIB.BASEBOARD_FAB2(SCH_1):VR_PVPP_KLM_ISET
  R4B6    1      A RES_0402-7.87K,1.0%,1/16W,CHIPA   I140 @BASEBOARD_FAB2_LIB.BASEBOARD_FAB2(SCH_1):PAGE234
 EU4A3    4   ISET NCP3232L_SM-IC,H86355-001   I184 @BASEBOARD_FAB2_LIB.BASEBOARD_FAB2(SCH_1):PAGE234

VR_PVPP_KLM_PHASE @BASEBOARD_FAB2_LIB.BASEBOARD_FAB2(SCH_1):VR_PVPP_KLM_PHASE
 C4A16    1      A CAP_0402LF-3300PF,50V,10%,EMPTA   I163 @BASEBOARD_FAB2_LIB.BASEBOARD_FAB2(SCH_1):PAGE234
  L4A1    1    INA INDUCTOR_SM-0.47UH,IND,E13358-A   I164 @BASEBOARD_FAB2_LIB.BASEBOARD_FAB2(SCH_1):PAGE234
 C4B15    1      A CAP_0603LF-0.1UF,25V,10%,X7R,6A   I182 @BASEBOARD_FAB2_LIB.BASEBOARD_FAB2(SCH_1):PAGE234
 EU4A3   35    VSW NCP3232L_SM-IC,H86355-001   I184 @BASEBOARD_FAB2_LIB.BASEBOARD_FAB2(SCH_1):PAGE234
 EU4A3   15 VSWH<0> NCP3232L_SM-IC,H86355-001   I184 @BASEBOARD_FAB2_LIB.BASEBOARD_FAB2(SCH_1):PAGE234
 EU4A3   29 VSWH<1> NCP3232L_SM-IC,H86355-001   I184 @BASEBOARD_FAB2_LIB.BASEBOARD_FAB2(SCH_1):PAGE234
 EU4A3   30 VSWH<2> NCP3232L_SM-IC,H86355-001   I184 @BASEBOARD_FAB2_LIB.BASEBOARD_FAB2(SCH_1):PAGE234
 EU4A3   31 VSWH<3> NCP3232L_SM-IC,H86355-001   I184 @BASEBOARD_FAB2_LIB.BASEBOARD_FAB2(SCH_1):PAGE234
 EU4A3   32 VSWH<4> NCP3232L_SM-IC,H86355-001   I184 @BASEBOARD_FAB2_LIB.BASEBOARD_FAB2(SCH_1):PAGE234
 EU4A3   33 VSWH<5> NCP3232L_SM-IC,H86355-001   I184 @BASEBOARD_FAB2_LIB.BASEBOARD_FAB2(SCH_1):PAGE234
 EU4A3   34 VSWH<6> NCP3232L_SM-IC,H86355-001   I184 @BASEBOARD_FAB2_LIB.BASEBOARD_FAB2(SCH_1):PAGE234
 EU4A3   43 VSWH<7> NCP3232L_SM-IC,H86355-001   I184 @BASEBOARD_FAB2_LIB.BASEBOARD_FAB2(SCH_1):PAGE234

VR_PVPP_KLM_SNUB @BASEBOARD_FAB2_LIB.BASEBOARD_FAB2(SCH_1):VR_PVPP_KLM_SNUB
  R4A7    1      A RES_0402-2.2,5%,1/16W,EMPTY,G2A   I162 @BASEBOARD_FAB2_LIB.BASEBOARD_FAB2(SCH_1):PAGE234
 C4A16    2      B CAP_0402LF-3300PF,50V,10%,EMPTA   I163 @BASEBOARD_FAB2_LIB.BASEBOARD_FAB2(SCH_1):PAGE234

VR_PVPP_KLM_SS @BASEBOARD_FAB2_LIB.BASEBOARD_FAB2(SCH_1):VR_PVPP_KLM_SS
  C4B6    1      A CAP_0402-0.027UF,16V,10%,X7R,AA   I146 @BASEBOARD_FAB2_LIB.BASEBOARD_FAB2(SCH_1):PAGE234
 EU4A3    1     SS NCP3232L_SM-IC,H86355-001   I184 @BASEBOARD_FAB2_LIB.BASEBOARD_FAB2(SCH_1):PAGE234

VR_PVSA_CPU0_BIREF1 @BASEBOARD_FAB2_LIB.BASEBOARD_FAB2(SCH_1):VR_PVSA_CPU0_BIREF1
 R6P29    2      B RES_0402-0.0,5%,1/16W,CHIP,G21A   I154 @BASEBOARD_FAB2_LIB.BASEBOARD_FAB2(SCH_1):PAGE201
 EU4D4   37 BIREF1 PXE1610B_QFN-IC,H79206-001   I155 @BASEBOARD_FAB2_LIB.BASEBOARD_FAB2(SCH_1):PAGE201
 EU4C1   39  REFIN IR354XX_SM-IR35412,IC,H73684-0A    I46 @BASEBOARD_FAB2_LIB.BASEBOARD_FAB2(SCH_1):PAGE205
  CT60    1      A CAP_A_0402V-0.1UF,16V,10%,X7R,A    I69 @BASEBOARD_FAB2_LIB.BASEBOARD_FAB2(SCH_1):PAGE205

VR_PVSA_CPU0_BOOT @BASEBOARD_FAB2_LIB.BASEBOARD_FAB2(SCH_1):VR_PVSA_CPU0_BOOT
  C4C8    1      A CAP_0402-0.220UF,16V,10%,X7R,AA    I25 @BASEBOARD_FAB2_LIB.BASEBOARD_FAB2(SCH_1):PAGE205
  RT40    1      A RES_0402-0.0,5%,1/16W,CHIP,G21A    I72 @BASEBOARD_FAB2_LIB.BASEBOARD_FAB2(SCH_1):PAGE205

VR_PVSA_CPU0_BOOT_R @BASEBOARD_FAB2_LIB.BASEBOARD_FAB2(SCH_1):VR_PVSA_CPU0_BOOT_R
 EU4C1   33  BOOST IR354XX_SM-IR35412,IC,H73684-0A    I46 @BASEBOARD_FAB2_LIB.BASEBOARD_FAB2(SCH_1):PAGE205
  RT40    2      B RES_0402-0.0,5%,1/16W,CHIP,G21A    I72 @BASEBOARD_FAB2_LIB.BASEBOARD_FAB2(SCH_1):PAGE205

VR_PVSA_CPU0_OCSET @BASEBOARD_FAB2_LIB.BASEBOARD_FAB2(SCH_1):VR_PVSA_CPU0_OCSET
 EU4C1   37  OCSET IR354XX_SM-IR35412,IC,H73684-0A    I46 @BASEBOARD_FAB2_LIB.BASEBOARD_FAB2(SCH_1):PAGE205
 R4C13    1      A RES_0402-68.1K,1%,1/16W,EMPTY,A    I62 @BASEBOARD_FAB2_LIB.BASEBOARD_FAB2(SCH_1):PAGE205

VR_PVSA_CPU0_PHASE @BASEBOARD_FAB2_LIB.BASEBOARD_FAB2(SCH_1):VR_PVSA_CPU0_PHASE
  C4C8    2      B CAP_0402-0.220UF,16V,10%,X7R,AA    I25 @BASEBOARD_FAB2_LIB.BASEBOARD_FAB2(SCH_1):PAGE205
 EU4C1   32  PHASE IR354XX_SM-IR35412,IC,H73684-0A    I46 @BASEBOARD_FAB2_LIB.BASEBOARD_FAB2(SCH_1):PAGE205

VR_PVSA_CPU0_PHASE_SW @BASEBOARD_FAB2_LIB.BASEBOARD_FAB2(SCH_1):VR_PVSA_CPU0_PHASE_SW
  L4C2    1    INA INDUCTOR_SM-0.3UH,IND,D92183-0A     I7 @BASEBOARD_FAB2_LIB.BASEBOARD_FAB2(SCH_1):PAGE205
 EU4C1   10     SW IR354XX_SM-IR35412,IC,H73684-0A    I46 @BASEBOARD_FAB2_LIB.BASEBOARD_FAB2(SCH_1):PAGE205
  CT59    1      1 SC2K2P50V3KX-GP_SMD-BCG6-SC2K2A    I64 @BASEBOARD_FAB2_LIB.BASEBOARD_FAB2(SCH_1):PAGE205

VR_PVSA_CPU0_PWM @BASEBOARD_FAB2_LIB.BASEBOARD_FAB2(SCH_1):VR_PVSA_CPU0_PWM
 EU4D4    1  BPWM1 PXE1610B_QFN-IC,H79206-001   I155 @BASEBOARD_FAB2_LIB.BASEBOARD_FAB2(SCH_1):PAGE201
 EU4C1   34    PWM IR354XX_SM-IR35412,IC,H73684-0A    I46 @BASEBOARD_FAB2_LIB.BASEBOARD_FAB2(SCH_1):PAGE205

VR_PVSA_CPU0_VCIN @BASEBOARD_FAB2_LIB.BASEBOARD_FAB2(SCH_1):VR_PVSA_CPU0_VCIN
  R6N3    1      A RES_0402-1.0,1%,1/16W,CHIP,G21A    I19 @BASEBOARD_FAB2_LIB.BASEBOARD_FAB2(SCH_1):PAGE205
  C4C6    1      A CAP_0402-1.0UF,16V,10%,X6S,D97A    I20 @BASEBOARD_FAB2_LIB.BASEBOARD_FAB2(SCH_1):PAGE205
 EU4C1    3    VCC IR354XX_SM-IR35412,IC,H73684-0A    I46 @BASEBOARD_FAB2_LIB.BASEBOARD_FAB2(SCH_1):PAGE205

VR_PVSA_CPU1_BIREF1 @BASEBOARD_FAB2_LIB.BASEBOARD_FAB2(SCH_1):VR_PVSA_CPU1_BIREF1
  R9N5    2      B RES_0402-0.0,5%,1/16W,CHIP,G21A   I128 @BASEBOARD_FAB2_LIB.BASEBOARD_FAB2(SCH_1):PAGE206
 EU1C2   37 BIREF1 PXE1610B_QFN-IC,H79206-001   I130 @BASEBOARD_FAB2_LIB.BASEBOARD_FAB2(SCH_1):PAGE206
 EU1C1   39  REFIN IR354XX_SM-IR35412,IC,H73684-0A    I51 @BASEBOARD_FAB2_LIB.BASEBOARD_FAB2(SCH_1):PAGE210
  CT57    1      A CAP_A_0402V-0.1UF,16V,10%,X7R,A    I55 @BASEBOARD_FAB2_LIB.BASEBOARD_FAB2(SCH_1):PAGE210

VR_PVSA_CPU1_BOOT @BASEBOARD_FAB2_LIB.BASEBOARD_FAB2(SCH_1):VR_PVSA_CPU1_BOOT
 C1C12    1      A CAP_0402-0.220UF,16V,10%,X7R,AA    I24 @BASEBOARD_FAB2_LIB.BASEBOARD_FAB2(SCH_1):PAGE210
  RT37    1      A RES_0402-0.0,5%,1/16W,CHIP,G21A    I62 @BASEBOARD_FAB2_LIB.BASEBOARD_FAB2(SCH_1):PAGE210

VR_PVSA_CPU1_BOOT_R @BASEBOARD_FAB2_LIB.BASEBOARD_FAB2(SCH_1):VR_PVSA_CPU1_BOOT_R
 EU1C1   33  BOOST IR354XX_SM-IR35412,IC,H73684-0A    I51 @BASEBOARD_FAB2_LIB.BASEBOARD_FAB2(SCH_1):PAGE210
  RT37    2      B RES_0402-0.0,5%,1/16W,CHIP,G21A    I62 @BASEBOARD_FAB2_LIB.BASEBOARD_FAB2(SCH_1):PAGE210

VR_PVSA_CPU1_OCSET @BASEBOARD_FAB2_LIB.BASEBOARD_FAB2(SCH_1):VR_PVSA_CPU1_OCSET
 EU1C1   37  OCSET IR354XX_SM-IR35412,IC,H73684-0A    I51 @BASEBOARD_FAB2_LIB.BASEBOARD_FAB2(SCH_1):PAGE210
 R1C37    1      A RES_0402-68.1K,1%,1/16W,EMPTY,A    I52 @BASEBOARD_FAB2_LIB.BASEBOARD_FAB2(SCH_1):PAGE210

VR_PVSA_CPU1_PHASE @BASEBOARD_FAB2_LIB.BASEBOARD_FAB2(SCH_1):VR_PVSA_CPU1_PHASE
 C1C12    2      B CAP_0402-0.220UF,16V,10%,X7R,AA    I24 @BASEBOARD_FAB2_LIB.BASEBOARD_FAB2(SCH_1):PAGE210
 EU1C1   32  PHASE IR354XX_SM-IR35412,IC,H73684-0A    I51 @BASEBOARD_FAB2_LIB.BASEBOARD_FAB2(SCH_1):PAGE210

VR_PVSA_CPU1_PHASE_SW @BASEBOARD_FAB2_LIB.BASEBOARD_FAB2(SCH_1):VR_PVSA_CPU1_PHASE_SW
  L1C1    1    INA INDUCTOR_SM-0.3UH,IND,D92183-0A    I10 @BASEBOARD_FAB2_LIB.BASEBOARD_FAB2(SCH_1):PAGE210
 EU1C1   10     SW IR354XX_SM-IR35412,IC,H73684-0A    I51 @BASEBOARD_FAB2_LIB.BASEBOARD_FAB2(SCH_1):PAGE210
  CT56    1      1 SC2K2P50V3KX-GP_SMD-BCG6-SC2K2A    I57 @BASEBOARD_FAB2_LIB.BASEBOARD_FAB2(SCH_1):PAGE210

VR_PVSA_CPU1_PWM @BASEBOARD_FAB2_LIB.BASEBOARD_FAB2(SCH_1):VR_PVSA_CPU1_PWM
 EU1C2    1  BPWM1 PXE1610B_QFN-IC,H79206-001   I130 @BASEBOARD_FAB2_LIB.BASEBOARD_FAB2(SCH_1):PAGE206
 EU1C1   34    PWM IR354XX_SM-IR35412,IC,H73684-0A    I51 @BASEBOARD_FAB2_LIB.BASEBOARD_FAB2(SCH_1):PAGE210

VR_PVSA_CPU1_VCIN @BASEBOARD_FAB2_LIB.BASEBOARD_FAB2(SCH_1):VR_PVSA_CPU1_VCIN
  R9N3    1      A RES_0402-1.0,1%,1/16W,CHIP,G21A    I20 @BASEBOARD_FAB2_LIB.BASEBOARD_FAB2(SCH_1):PAGE210
  C1C5    1      A CAP_0402-1.0UF,16V,10%,X6S,D97A    I26 @BASEBOARD_FAB2_LIB.BASEBOARD_FAB2(SCH_1):PAGE210
 EU1C1    3    VCC IR354XX_SM-IR35412,IC,H73684-0A    I51 @BASEBOARD_FAB2_LIB.BASEBOARD_FAB2(SCH_1):PAGE210

VR_PVTT_ABC_BIAS @BASEBOARD_FAB2_LIB.BASEBOARD_FAB2(SCH_1):VR_PVTT_ABC_BIAS
 EU4G3    2   BIAS MIC5166_DFN-IC,H55101-001     I1 @BASEBOARD_FAB2_LIB.BASEBOARD_FAB2(SCH_1):PAGE221
 C4G15    1      A CAP_0402-1.0UF,16V,10%,X6S,D97A    I24 @BASEBOARD_FAB2_LIB.BASEBOARD_FAB2(SCH_1):PAGE221
  R6U4    2      B RES_0402-0.0,5%,1/16W,CHIP,G21A    I28 @BASEBOARD_FAB2_LIB.BASEBOARD_FAB2(SCH_1):PAGE221

VR_PVTT_ABC_SNS @BASEBOARD_FAB2_LIB.BASEBOARD_FAB2(SCH_1):VR_PVTT_ABC_SNS
 EU4G3    6    SNS MIC5166_DFN-IC,H55101-001     I1 @BASEBOARD_FAB2_LIB.BASEBOARD_FAB2(SCH_1):PAGE221
 SH5U1    1      A SHUNT_SH0201-EMPTY,N_A    I56 @BASEBOARD_FAB2_LIB.BASEBOARD_FAB2(SCH_1):PAGE221

VR_PVTT_ABC_VREF @BASEBOARD_FAB2_LIB.BASEBOARD_FAB2(SCH_1):VR_PVTT_ABC_VREF
 EU4G3    1   VREF MIC5166_DFN-IC,H55101-001     I1 @BASEBOARD_FAB2_LIB.BASEBOARD_FAB2(SCH_1):PAGE221
 C4G16    1      A CAP_0402-1.0UF,16V,10%,X6S,D97A    I34 @BASEBOARD_FAB2_LIB.BASEBOARD_FAB2(SCH_1):PAGE221

VR_PVTT_DEF_BIAS @BASEBOARD_FAB2_LIB.BASEBOARD_FAB2(SCH_1):VR_PVTT_DEF_BIAS
 C4A10    1      A CAP_0402-1.0UF,16V,10%,X6S,D97A    I28 @BASEBOARD_FAB2_LIB.BASEBOARD_FAB2(SCH_1):PAGE222
 R6L11    2      B RES_0402-0.0,5%,1/16W,CHIP,G21A    I30 @BASEBOARD_FAB2_LIB.BASEBOARD_FAB2(SCH_1):PAGE222
 EU4A1    2   BIAS MIC5166_DFN-IC,H55101-001    I31 @BASEBOARD_FAB2_LIB.BASEBOARD_FAB2(SCH_1):PAGE222

VR_PVTT_DEF_SNS @BASEBOARD_FAB2_LIB.BASEBOARD_FAB2(SCH_1):VR_PVTT_DEF_SNS
 EU4A1    6    SNS MIC5166_DFN-IC,H55101-001    I31 @BASEBOARD_FAB2_LIB.BASEBOARD_FAB2(SCH_1):PAGE222
 SH5L1    1      A SHUNT_SH0201-EMPTY,N_A    I53 @BASEBOARD_FAB2_LIB.BASEBOARD_FAB2(SCH_1):PAGE222

VR_PVTT_DEF_VREF @BASEBOARD_FAB2_LIB.BASEBOARD_FAB2(SCH_1):VR_PVTT_DEF_VREF
  C4A9    1      A CAP_0402-1.0UF,16V,10%,X6S,D97A    I21 @BASEBOARD_FAB2_LIB.BASEBOARD_FAB2(SCH_1):PAGE222
 EU4A1    1   VREF MIC5166_DFN-IC,H55101-001    I31 @BASEBOARD_FAB2_LIB.BASEBOARD_FAB2(SCH_1):PAGE222

VR_PVTT_GHJ_BIAS @BASEBOARD_FAB2_LIB.BASEBOARD_FAB2(SCH_1):VR_PVTT_GHJ_BIAS
 EU4G2    2   BIAS MIC5166_DFN-IC,H55101-001    I24 @BASEBOARD_FAB2_LIB.BASEBOARD_FAB2(SCH_1):PAGE229
 C4G18    1      A CAP_0402-1.0UF,16V,10%,X6S,D97A    I27 @BASEBOARD_FAB2_LIB.BASEBOARD_FAB2(SCH_1):PAGE229
  R6U7    2      B RES_0402-0.0,5%,1/16W,CHIP,G21A    I32 @BASEBOARD_FAB2_LIB.BASEBOARD_FAB2(SCH_1):PAGE229

VR_PVTT_GHJ_SNS @BASEBOARD_FAB2_LIB.BASEBOARD_FAB2(SCH_1):VR_PVTT_GHJ_SNS
 EU4G2    6    SNS MIC5166_DFN-IC,H55101-001    I24 @BASEBOARD_FAB2_LIB.BASEBOARD_FAB2(SCH_1):PAGE229
 SH8U1    1      A SHUNT_SH0201-EMPTY,N_A    I53 @BASEBOARD_FAB2_LIB.BASEBOARD_FAB2(SCH_1):PAGE229

VR_PVTT_GHJ_VREF @BASEBOARD_FAB2_LIB.BASEBOARD_FAB2(SCH_1):VR_PVTT_GHJ_VREF
 C4G21    1      A CAP_0402-1.0UF,16V,10%,X6S,D97A    I21 @BASEBOARD_FAB2_LIB.BASEBOARD_FAB2(SCH_1):PAGE229
 EU4G2    1   VREF MIC5166_DFN-IC,H55101-001    I24 @BASEBOARD_FAB2_LIB.BASEBOARD_FAB2(SCH_1):PAGE229

VR_PVTT_KLM_BIAS @BASEBOARD_FAB2_LIB.BASEBOARD_FAB2(SCH_1):VR_PVTT_KLM_BIAS
  C4A8    1      A CAP_0402-1.0UF,16V,10%,X6S,D97A    I28 @BASEBOARD_FAB2_LIB.BASEBOARD_FAB2(SCH_1):PAGE230
  R6L8    2      B RES_0402-0.0,5%,1/16W,CHIP,G21A    I30 @BASEBOARD_FAB2_LIB.BASEBOARD_FAB2(SCH_1):PAGE230
 EU4A2    2   BIAS MIC5166_DFN-IC,H55101-001    I31 @BASEBOARD_FAB2_LIB.BASEBOARD_FAB2(SCH_1):PAGE230

VR_PVTT_KLM_SNS @BASEBOARD_FAB2_LIB.BASEBOARD_FAB2(SCH_1):VR_PVTT_KLM_SNS
 EU4A2    6    SNS MIC5166_DFN-IC,H55101-001    I31 @BASEBOARD_FAB2_LIB.BASEBOARD_FAB2(SCH_1):PAGE230
 SH8L1    1      A SHUNT_SH0201-EMPTY,N_A    I53 @BASEBOARD_FAB2_LIB.BASEBOARD_FAB2(SCH_1):PAGE230

VR_PVTT_KLM_VREF @BASEBOARD_FAB2_LIB.BASEBOARD_FAB2(SCH_1):VR_PVTT_KLM_VREF
 C4A14    1      A CAP_0402-1.0UF,16V,10%,X6S,D97A    I21 @BASEBOARD_FAB2_LIB.BASEBOARD_FAB2(SCH_1):PAGE230
 EU4A2    1   VREF MIC5166_DFN-IC,H55101-001    I31 @BASEBOARD_FAB2_LIB.BASEBOARD_FAB2(SCH_1):PAGE230

VR_VB_PVPP_ABC @BASEBOARD_FAB2_LIB.BASEBOARD_FAB2(SCH_1):VR_VB_PVPP_ABC
 EU7F1   38     VB NCP3232L_SM-IC,H86355-001   I193 @BASEBOARD_FAB2_LIB.BASEBOARD_FAB2(SCH_1):PAGE231
 C3T11    1      A CAP_0603-4.7UF,6.3V,10%,X6S,E1A   I202 @BASEBOARD_FAB2_LIB.BASEBOARD_FAB2(SCH_1):PAGE231

VR_VB_PVPP_DEF @BASEBOARD_FAB2_LIB.BASEBOARD_FAB2(SCH_1):VR_VB_PVPP_DEF
 EU7B1   38     VB NCP3232L_SM-IC,H86355-001   I214 @BASEBOARD_FAB2_LIB.BASEBOARD_FAB2(SCH_1):PAGE232
 C3M10    1      A CAP_0603-4.7UF,6.3V,10%,X6S,E1A   I253 @BASEBOARD_FAB2_LIB.BASEBOARD_FAB2(SCH_1):PAGE232

VR_VB_PVPP_GHJ @BASEBOARD_FAB2_LIB.BASEBOARD_FAB2(SCH_1):VR_VB_PVPP_GHJ
  C6U6    1      A CAP_0603-4.7UF,6.3V,10%,X6S,E1A   I187 @BASEBOARD_FAB2_LIB.BASEBOARD_FAB2(SCH_1):PAGE233
 EU4G1   38     VB NCP3232L_SM-IC,H86355-001   I225 @BASEBOARD_FAB2_LIB.BASEBOARD_FAB2(SCH_1):PAGE233

VR_VB_PVPP_KLM @BASEBOARD_FAB2_LIB.BASEBOARD_FAB2(SCH_1):VR_VB_PVPP_KLM
 C6L12    1      A CAP_0603-4.7UF,6.3V,10%,X6S,E1A   I144 @BASEBOARD_FAB2_LIB.BASEBOARD_FAB2(SCH_1):PAGE234
 EU4A3   38     VB NCP3232L_SM-IC,H86355-001   I184 @BASEBOARD_FAB2_LIB.BASEBOARD_FAB2(SCH_1):PAGE234

VR_VRRDY_PVCCIN_CPU0 @BASEBOARD_FAB2_LIB.BASEBOARD_FAB2(SCH_1):VR_VRRDY_PVCCIN_CPU0
 R4D58    2      B RES_0402-1.00K,1%,1/16W,CHIP,GA    I25 @BASEBOARD_FAB2_LIB.BASEBOARD_FAB2(SCH_1):PAGE201
 R4D63    1      A RES_0402-22.1,1.0%,1/16W,CHIP,A   I124 @BASEBOARD_FAB2_LIB.BASEBOARD_FAB2(SCH_1):PAGE201
 C4D42    1      A CAP_0402LF-1000PF,50V,10%,X7R,A   I125 @BASEBOARD_FAB2_LIB.BASEBOARD_FAB2(SCH_1):PAGE201
 EU4D4   11 AVRRDY PXE1610B_QFN-IC,H79206-001   I155 @BASEBOARD_FAB2_LIB.BASEBOARD_FAB2(SCH_1):PAGE201

VR_VRRDY_PVCCIN_CPU1 @BASEBOARD_FAB2_LIB.BASEBOARD_FAB2(SCH_1):VR_VRRDY_PVCCIN_CPU1
 R1C28    2      B RES_0402-1.00K,1%,1/16W,CHIP,GA    I35 @BASEBOARD_FAB2_LIB.BASEBOARD_FAB2(SCH_1):PAGE206
 R1C30    1      A RES_0402-22.1,1.0%,1/16W,CHIP,A   I113 @BASEBOARD_FAB2_LIB.BASEBOARD_FAB2(SCH_1):PAGE206
 C1C23    1      A CAP_0402LF-1000PF,50V,10%,X7R,A   I114 @BASEBOARD_FAB2_LIB.BASEBOARD_FAB2(SCH_1):PAGE206
 EU1C2   11 AVRRDY PXE1610B_QFN-IC,H79206-001   I130 @BASEBOARD_FAB2_LIB.BASEBOARD_FAB2(SCH_1):PAGE206

VSENSE_P12V_ADM1085 @BASEBOARD_FAB2_LIB.BASEBOARD_FAB2(SCH_1):VSENSE_P12V_ADM1085
  U7D3    3    VIN ADM1085_SMT-IC,H46130-001    I70 @BASEBOARD_FAB2_LIB.BASEBOARD_FAB2(SCH_1):PAGE196
 R3P48    2      B RES_0402-90.9K,1%,1/16W,CHIP,GA    I74 @BASEBOARD_FAB2_LIB.BASEBOARD_FAB2(SCH_1):PAGE196
 R3P51    1      A RES_0402-6.34K,1%,1/16W,CHIP,GA    I75 @BASEBOARD_FAB2_LIB.BASEBOARD_FAB2(SCH_1):PAGE196

VSENSE_P1V05_PCH_STBY_AVSN @BASEBOARD_FAB2_LIB.BASEBOARD_FAB2(SCH_1):VSENSE_P1V05_PCH_STBY_AVSN
  C2L2    2      B CAP_0402LF-220PF,50V,10%,X7R,AA   I153 @BASEBOARD_FAB2_LIB.BASEBOARD_FAB2(SCH_1):PAGE235
 EU8A1   30  BVREF PXE1110B_QFN-IC,H89187-001   I229 @BASEBOARD_FAB2_LIB.BASEBOARD_FAB2(SCH_1):PAGE235
 R8B15    2      B RES_0402-100.0,1%,1/16W,EMPTY,A    I57 @BASEBOARD_FAB2_LIB.BASEBOARD_FAB2(SCH_1):PAGE236
 R8B12    1      A RES_0402-0.0,5%,1/16W,CHIP,G21A    I59 @BASEBOARD_FAB2_LIB.BASEBOARD_FAB2(SCH_1):PAGE236

VSENSE_P1V05_PCH_STBY_AVSP @BASEBOARD_FAB2_LIB.BASEBOARD_FAB2(SCH_1):VSENSE_P1V05_PCH_STBY_AVSP
  R2L8    1      A RES_0603-10.0,1%,1/10W,CHIP,G2A   I154 @BASEBOARD_FAB2_LIB.BASEBOARD_FAB2(SCH_1):PAGE235
 R8B14    1      A RES_0402-0.0,5%,1/16W,CHIP,G21A    I56 @BASEBOARD_FAB2_LIB.BASEBOARD_FAB2(SCH_1):PAGE236
 R8B15    1      A RES_0402-100.0,1%,1/16W,EMPTY,A    I57 @BASEBOARD_FAB2_LIB.BASEBOARD_FAB2(SCH_1):PAGE236

VSENSE_P1V8MCP_CPU0_SKT_VRTN @BASEBOARD_FAB2_LIB.BASEBOARD_FAB2(SCH_1):VSENSE_P1V8MCP_CPU0_SKT_VRTN
  U5D1 AL20 RSVD<215> SKX_EXT_B_BGA1-IC,TBD   I204 @BASEBOARD_FAB2_LIB.BASEBOARD_FAB2(SCH_1):PAGE22
  J6E1   D2   IOD2 SCONN120_H61426002_SM-CONN,H61A    I55 @BASEBOARD_FAB2_LIB.BASEBOARD_FAB2(SCH_1):PAGE194

VSENSE_P1V8MCP_CPU0_SKT_VSEN @BASEBOARD_FAB2_LIB.BASEBOARD_FAB2(SCH_1):VSENSE_P1V8MCP_CPU0_SKT_VSEN
  U5D1 AK21 RSVD<221> SKX_EXT_B_BGA1-IC,TBD   I204 @BASEBOARD_FAB2_LIB.BASEBOARD_FAB2(SCH_1):PAGE22
  J6E1   D1   IOD1 SCONN120_H61426002_SM-CONN,H61A    I55 @BASEBOARD_FAB2_LIB.BASEBOARD_FAB2(SCH_1):PAGE194

VSENSE_P1V8MCP_CPU1_SKT_VRTN @BASEBOARD_FAB2_LIB.BASEBOARD_FAB2(SCH_1):VSENSE_P1V8MCP_CPU1_SKT_VRTN
  U2D1 AL20 RSVD<215> SKX_EXT_B_BGA1-IC,TBD   I169 @BASEBOARD_FAB2_LIB.BASEBOARD_FAB2(SCH_1):PAGE56
  J4E1   D2   IOD2 SCONN120_H61426002_SM-CONN,H61A    I45 @BASEBOARD_FAB2_LIB.BASEBOARD_FAB2(SCH_1):PAGE193

VSENSE_P1V8MCP_CPU1_SKT_VSEN @BASEBOARD_FAB2_LIB.BASEBOARD_FAB2(SCH_1):VSENSE_P1V8MCP_CPU1_SKT_VSEN
  U2D1 AK21 RSVD<221> SKX_EXT_B_BGA1-IC,TBD   I169 @BASEBOARD_FAB2_LIB.BASEBOARD_FAB2(SCH_1):PAGE56
  J4E1   D1   IOD1 SCONN120_H61426002_SM-CONN,H61A    I45 @BASEBOARD_FAB2_LIB.BASEBOARD_FAB2(SCH_1):PAGE193

VSENSE_P3V3_STBY @BASEBOARD_FAB2_LIB.BASEBOARD_FAB2(SCH_1):VSENSE_P3V3_STBY
 R8E31    1      A RES_0402-23.2K,1%,1/16W,CHIP,GA   I143 @BASEBOARD_FAB2_LIB.BASEBOARD_FAB2(SCH_1):PAGE240
 R8E25    2      B RES_0402-0.0,5%,1/16W,CHIP,G21A   I144 @BASEBOARD_FAB2_LIB.BASEBOARD_FAB2(SCH_1):PAGE240

VSENSE_PMAX_CPU0 @BASEBOARD_FAB2_LIB.BASEBOARD_FAB2(SCH_1):VSENSE_PMAX_CPU0
  R5D5    1      A RES_0402-249,0.1%,1/16W,CHIP,GA   I303 @BASEBOARD_FAB2_LIB.BASEBOARD_FAB2(SCH_1):PAGE37
  U5D1 AD41 VSENSEPMAX SKX_EXT_B_BGA1-IC,TBD   I311 @BASEBOARD_FAB2_LIB.BASEBOARD_FAB2(SCH_1):PAGE37
  R5D6    2      B RES_0402-10.0,1%,1/16W,EMPTY,GA   I312 @BASEBOARD_FAB2_LIB.BASEBOARD_FAB2(SCH_1):PAGE37

VSENSE_PMAX_CPU1 @BASEBOARD_FAB2_LIB.BASEBOARD_FAB2(SCH_1):VSENSE_PMAX_CPU1
 R3D27    1      A RES_0402-249,0.1%,1/16W,CHIP,GA    I43 @BASEBOARD_FAB2_LIB.BASEBOARD_FAB2(SCH_1):PAGE71
  U2D1 AD41 VSENSEPMAX SKX_EXT_B_BGA1-IC,TBD    I51 @BASEBOARD_FAB2_LIB.BASEBOARD_FAB2(SCH_1):PAGE71
 R3D32    2      B RES_0402-10.0,1%,1/16W,EMPTY,GA    I53 @BASEBOARD_FAB2_LIB.BASEBOARD_FAB2(SCH_1):PAGE71

VSENSE_PVCCIN_CPU0_AVSP @BASEBOARD_FAB2_LIB.BASEBOARD_FAB2(SCH_1):VSENSE_PVCCIN_CPU0_AVSP
 C4D45    1      A CAP_0402LF-220PF,50V,10%,X7R,AA    I70 @BASEBOARD_FAB2_LIB.BASEBOARD_FAB2(SCH_1):PAGE201
  R4E8    2      B RES_0402-10.0,1%,1/16W,CHIP,G2A   I109 @BASEBOARD_FAB2_LIB.BASEBOARD_FAB2(SCH_1):PAGE201
 EU4D4   21  AVSEN PXE1610B_QFN-IC,H79206-001   I155 @BASEBOARD_FAB2_LIB.BASEBOARD_FAB2(SCH_1):PAGE201

VSENSE_PVCCIN_CPU0_N @BASEBOARD_FAB2_LIB.BASEBOARD_FAB2(SCH_1):VSENSE_PVCCIN_CPU0_N
 C4D45    2      B CAP_0402LF-220PF,50V,10%,X7R,AA    I70 @BASEBOARD_FAB2_LIB.BASEBOARD_FAB2(SCH_1):PAGE201
 EU4D4   22  AVREF PXE1610B_QFN-IC,H79206-001   I155 @BASEBOARD_FAB2_LIB.BASEBOARD_FAB2(SCH_1):PAGE201
 R4E17    1      A RES_0402-0.0,5%,1/16W,CHIP,G21A    I62 @BASEBOARD_FAB2_LIB.BASEBOARD_FAB2(SCH_1):PAGE204
 R4E15    2      B RES_0402-1.00K,1%,1/16W,EMPTY,A    I63 @BASEBOARD_FAB2_LIB.BASEBOARD_FAB2(SCH_1):PAGE204
 R4E18    1      A RES_0402-100.0,1%,1/16W,CHIP,GA    I64 @BASEBOARD_FAB2_LIB.BASEBOARD_FAB2(SCH_1):PAGE204

VSENSE_PVCCIN_CPU0_P @BASEBOARD_FAB2_LIB.BASEBOARD_FAB2(SCH_1):VSENSE_PVCCIN_CPU0_P
  R4E8    1      A RES_0402-10.0,1%,1/16W,CHIP,G2A   I109 @BASEBOARD_FAB2_LIB.BASEBOARD_FAB2(SCH_1):PAGE201
 R4E14    1      A RES_0402-100.0,1%,1/16W,CHIP,GA    I60 @BASEBOARD_FAB2_LIB.BASEBOARD_FAB2(SCH_1):PAGE204
 R4E16    1      A RES_0402-0.0,5%,1/16W,CHIP,G21A    I61 @BASEBOARD_FAB2_LIB.BASEBOARD_FAB2(SCH_1):PAGE204
 R4E15    1      A RES_0402-1.00K,1%,1/16W,EMPTY,A    I63 @BASEBOARD_FAB2_LIB.BASEBOARD_FAB2(SCH_1):PAGE204

VSENSE_PVCCIN_CPU0_SKT_VRTN @BASEBOARD_FAB2_LIB.BASEBOARD_FAB2(SCH_1):VSENSE_PVCCIN_CPU0_SKT_VRTN
  U5D1 AY85 VSS_VCCIN_SENSE SKX_EXT_B_BGA1-IC,TBD   I311 @BASEBOARD_FAB2_LIB.BASEBOARD_FAB2(SCH_1):PAGE37
 R4E17    2      B RES_0402-0.0,5%,1/16W,CHIP,G21A    I62 @BASEBOARD_FAB2_LIB.BASEBOARD_FAB2(SCH_1):PAGE204

VSENSE_PVCCIN_CPU0_SKT_VSEN @BASEBOARD_FAB2_LIB.BASEBOARD_FAB2(SCH_1):VSENSE_PVCCIN_CPU0_SKT_VSEN
  U5D1 BA86 VCCIN_SENSE SKX_EXT_B_BGA1-IC,TBD   I311 @BASEBOARD_FAB2_LIB.BASEBOARD_FAB2(SCH_1):PAGE37
 R4E16    2      B RES_0402-0.0,5%,1/16W,CHIP,G21A    I61 @BASEBOARD_FAB2_LIB.BASEBOARD_FAB2(SCH_1):PAGE204

VSENSE_PVCCIN_CPU1_AVSP @BASEBOARD_FAB2_LIB.BASEBOARD_FAB2(SCH_1):VSENSE_PVCCIN_CPU1_AVSP
  C1D1    1      A CAP_0402LF-220PF,50V,10%,X7R,AA    I78 @BASEBOARD_FAB2_LIB.BASEBOARD_FAB2(SCH_1):PAGE206
  R1D4    2      B RES_0402-10.0,1%,1/16W,CHIP,G2A    I79 @BASEBOARD_FAB2_LIB.BASEBOARD_FAB2(SCH_1):PAGE206
 EU1C2   21  AVSEN PXE1610B_QFN-IC,H79206-001   I130 @BASEBOARD_FAB2_LIB.BASEBOARD_FAB2(SCH_1):PAGE206

VSENSE_PVCCIN_CPU1_N @BASEBOARD_FAB2_LIB.BASEBOARD_FAB2(SCH_1):VSENSE_PVCCIN_CPU1_N
  C1D1    2      B CAP_0402LF-220PF,50V,10%,X7R,AA    I78 @BASEBOARD_FAB2_LIB.BASEBOARD_FAB2(SCH_1):PAGE206
 EU1C2   22  AVREF PXE1610B_QFN-IC,H79206-001   I130 @BASEBOARD_FAB2_LIB.BASEBOARD_FAB2(SCH_1):PAGE206
  R1E5    2      B RES_0402-1.00K,1%,1/16W,EMPTY,A     I3 @BASEBOARD_FAB2_LIB.BASEBOARD_FAB2(SCH_1):PAGE209
  R1E8    1      A RES_0402-100.0,1%,1/16W,CHIP,GA     I9 @BASEBOARD_FAB2_LIB.BASEBOARD_FAB2(SCH_1):PAGE209
  R1E7    1      A RES_0402-0.0,5%,1/16W,CHIP,G21A    I10 @BASEBOARD_FAB2_LIB.BASEBOARD_FAB2(SCH_1):PAGE209

VSENSE_PVCCIN_CPU1_P @BASEBOARD_FAB2_LIB.BASEBOARD_FAB2(SCH_1):VSENSE_PVCCIN_CPU1_P
  R1D4    1      A RES_0402-10.0,1%,1/16W,CHIP,G2A    I79 @BASEBOARD_FAB2_LIB.BASEBOARD_FAB2(SCH_1):PAGE206
  R1E5    1      A RES_0402-1.00K,1%,1/16W,EMPTY,A     I3 @BASEBOARD_FAB2_LIB.BASEBOARD_FAB2(SCH_1):PAGE209
  R1E6    1      A RES_0402-0.0,5%,1/16W,CHIP,G21A    I11 @BASEBOARD_FAB2_LIB.BASEBOARD_FAB2(SCH_1):PAGE209
  R1E4    1      A RES_0402-100.0,1%,1/16W,CHIP,GA    I15 @BASEBOARD_FAB2_LIB.BASEBOARD_FAB2(SCH_1):PAGE209

VSENSE_PVCCIN_CPU1_SKT_VRTN @BASEBOARD_FAB2_LIB.BASEBOARD_FAB2(SCH_1):VSENSE_PVCCIN_CPU1_SKT_VRTN
  U2D1 AY85 VSS_VCCIN_SENSE SKX_EXT_B_BGA1-IC,TBD    I51 @BASEBOARD_FAB2_LIB.BASEBOARD_FAB2(SCH_1):PAGE71
  R1E7    2      B RES_0402-0.0,5%,1/16W,CHIP,G21A    I10 @BASEBOARD_FAB2_LIB.BASEBOARD_FAB2(SCH_1):PAGE209

VSENSE_PVCCIN_CPU1_SKT_VSEN @BASEBOARD_FAB2_LIB.BASEBOARD_FAB2(SCH_1):VSENSE_PVCCIN_CPU1_SKT_VSEN
  U2D1 BA86 VCCIN_SENSE SKX_EXT_B_BGA1-IC,TBD    I51 @BASEBOARD_FAB2_LIB.BASEBOARD_FAB2(SCH_1):PAGE71
  R1E6    2      B RES_0402-0.0,5%,1/16W,CHIP,G21A    I11 @BASEBOARD_FAB2_LIB.BASEBOARD_FAB2(SCH_1):PAGE209

VSENSE_PVCCIOMCP_CPU0_SKT_VRTN @BASEBOARD_FAB2_LIB.BASEBOARD_FAB2(SCH_1):VSENSE_PVCCIOMCP_CPU0_SKT_VRTN
  U5D1 BU16 CD_VCCP_SENSE<0> SKX_EXT_B_BGA1-IC,TBD   I127 @BASEBOARD_FAB2_LIB.BASEBOARD_FAB2(SCH_1):PAGE39
  J6B1   F8   IOF8 SCONN120_H61426002_SM-CONN,H61A    I56 @BASEBOARD_FAB2_LIB.BASEBOARD_FAB2(SCH_1):PAGE194

VSENSE_PVCCIOMCP_CPU0_SKT_VSEN @BASEBOARD_FAB2_LIB.BASEBOARD_FAB2(SCH_1):VSENSE_PVCCIOMCP_CPU0_SKT_VSEN
  U5D1 BT17 CD_VCCP_SENSE<1> SKX_EXT_B_BGA1-IC,TBD   I127 @BASEBOARD_FAB2_LIB.BASEBOARD_FAB2(SCH_1):PAGE39
  J6B1   E8   IOE8 SCONN120_H61426002_SM-CONN,H61A    I56 @BASEBOARD_FAB2_LIB.BASEBOARD_FAB2(SCH_1):PAGE194

VSENSE_PVCCIOMCP_CPU1_SKT_VRTN @BASEBOARD_FAB2_LIB.BASEBOARD_FAB2(SCH_1):VSENSE_PVCCIOMCP_CPU1_SKT_VRTN
  U2D1 BU16 CD_VCCP_SENSE<0> SKX_EXT_B_BGA1-IC,TBD   I107 @BASEBOARD_FAB2_LIB.BASEBOARD_FAB2(SCH_1):PAGE73
  J4B2   F8   IOF8 SCONN120_H61426002_SM-CONN,H61A    I46 @BASEBOARD_FAB2_LIB.BASEBOARD_FAB2(SCH_1):PAGE193

VSENSE_PVCCIOMCP_CPU1_SKT_VSEN @BASEBOARD_FAB2_LIB.BASEBOARD_FAB2(SCH_1):VSENSE_PVCCIOMCP_CPU1_SKT_VSEN
  U2D1 BT17 CD_VCCP_SENSE<1> SKX_EXT_B_BGA1-IC,TBD   I107 @BASEBOARD_FAB2_LIB.BASEBOARD_FAB2(SCH_1):PAGE73
  J4B2   E8   IOE8 SCONN120_H61426002_SM-CONN,H61A    I46 @BASEBOARD_FAB2_LIB.BASEBOARD_FAB2(SCH_1):PAGE193

VSENSE_PVCCIO_CPU0_AVSN @BASEBOARD_FAB2_LIB.BASEBOARD_FAB2(SCH_1):VSENSE_PVCCIO_CPU0_AVSN
 C3N39    2      B CAP_0402LF-220PF,50V,10%,X7R,AA    I83 @BASEBOARD_FAB2_LIB.BASEBOARD_FAB2(SCH_1):PAGE211
 EU3P1   20  AVREF PXE1110B_QFN-IC,H89187-001    I93 @BASEBOARD_FAB2_LIB.BASEBOARD_FAB2(SCH_1):PAGE211
 R3N20    1      A RES_0402-100.0,1%,1/16W,CHIP,GA    I68 @BASEBOARD_FAB2_LIB.BASEBOARD_FAB2(SCH_1):PAGE212
 SH3P2    2      B SHUNT_SH0201-EMPTY,N_A   I105 @BASEBOARD_FAB2_LIB.BASEBOARD_FAB2(SCH_1):PAGE212

VSENSE_PVCCIO_CPU0_AVSP @BASEBOARD_FAB2_LIB.BASEBOARD_FAB2(SCH_1):VSENSE_PVCCIO_CPU0_AVSP
 R3N19    1      A RES_0402-10.0,1%,1/16W,CHIP,G2A    I81 @BASEBOARD_FAB2_LIB.BASEBOARD_FAB2(SCH_1):PAGE211
 R3N21    1      A RES_0402-100.0,1%,1/16W,CHIP,GA    I74 @BASEBOARD_FAB2_LIB.BASEBOARD_FAB2(SCH_1):PAGE212
 SH3P1    2      B SHUNT_SH0201-EMPTY,N_A   I104 @BASEBOARD_FAB2_LIB.BASEBOARD_FAB2(SCH_1):PAGE212

VSENSE_PVCCIO_CPU0_SKT_VRTN @BASEBOARD_FAB2_LIB.BASEBOARD_FAB2(SCH_1):VSENSE_PVCCIO_CPU0_SKT_VRTN
  U5D1  BF5 VSS_VCCIO_SENSE SKX_EXT_B_BGA1-IC,TBD   I127 @BASEBOARD_FAB2_LIB.BASEBOARD_FAB2(SCH_1):PAGE39
  C3P1    2      B CAP_A_0402V-0.1UF,16V,10%,EMPTA    I60 @BASEBOARD_FAB2_LIB.BASEBOARD_FAB2(SCH_1):PAGE212
 SH3P2    1      A SHUNT_SH0201-EMPTY,N_A   I105 @BASEBOARD_FAB2_LIB.BASEBOARD_FAB2(SCH_1):PAGE212

VSENSE_PVCCIO_CPU0_SKT_VSEN @BASEBOARD_FAB2_LIB.BASEBOARD_FAB2(SCH_1):VSENSE_PVCCIO_CPU0_SKT_VSEN
  U5D1  BH5 VCCIO_SENSE SKX_EXT_B_BGA1-IC,TBD   I127 @BASEBOARD_FAB2_LIB.BASEBOARD_FAB2(SCH_1):PAGE39
  C3P1    1      A CAP_A_0402V-0.1UF,16V,10%,EMPTA    I60 @BASEBOARD_FAB2_LIB.BASEBOARD_FAB2(SCH_1):PAGE212
 SH3P1    1      A SHUNT_SH0201-EMPTY,N_A   I104 @BASEBOARD_FAB2_LIB.BASEBOARD_FAB2(SCH_1):PAGE212

VSENSE_PVCCIO_CPU1_AVSN @BASEBOARD_FAB2_LIB.BASEBOARD_FAB2(SCH_1):VSENSE_PVCCIO_CPU1_AVSN
 C4D44    2      B CAP_0402LF-220PF,50V,10%,X7R,AA    I83 @BASEBOARD_FAB2_LIB.BASEBOARD_FAB2(SCH_1):PAGE213
 EU4D5   20  AVREF PXE1110B_QFN-IC,H89187-001    I96 @BASEBOARD_FAB2_LIB.BASEBOARD_FAB2(SCH_1):PAGE213
 R3D28    1      A RES_0402-100.0,1%,1/16W,CHIP,GA   I101 @BASEBOARD_FAB2_LIB.BASEBOARD_FAB2(SCH_1):PAGE214
 SH3D1    2      B SHUNT_SH0201-EMPTY,N_A   I130 @BASEBOARD_FAB2_LIB.BASEBOARD_FAB2(SCH_1):PAGE214

VSENSE_PVCCIO_CPU1_AVSP @BASEBOARD_FAB2_LIB.BASEBOARD_FAB2(SCH_1):VSENSE_PVCCIO_CPU1_AVSP
  R4E7    1      A RES_0402-10.0,1%,1/16W,CHIP,G2A    I84 @BASEBOARD_FAB2_LIB.BASEBOARD_FAB2(SCH_1):PAGE213
  R3E1    1      A RES_0402-100.0,1%,1/16W,CHIP,GA   I105 @BASEBOARD_FAB2_LIB.BASEBOARD_FAB2(SCH_1):PAGE214
 SH3D2    2      B SHUNT_SH0201-EMPTY,N_A   I129 @BASEBOARD_FAB2_LIB.BASEBOARD_FAB2(SCH_1):PAGE214

VSENSE_PVCCIO_CPU1_SKT_VRTN @BASEBOARD_FAB2_LIB.BASEBOARD_FAB2(SCH_1):VSENSE_PVCCIO_CPU1_SKT_VRTN
  U2D1  BF5 VSS_VCCIO_SENSE SKX_EXT_B_BGA1-IC,TBD   I107 @BASEBOARD_FAB2_LIB.BASEBOARD_FAB2(SCH_1):PAGE73
 C3D27    2      B CAP_A_0402V-0.1UF,16V,10%,EMPTA    I96 @BASEBOARD_FAB2_LIB.BASEBOARD_FAB2(SCH_1):PAGE214
 SH3D1    1      A SHUNT_SH0201-EMPTY,N_A   I130 @BASEBOARD_FAB2_LIB.BASEBOARD_FAB2(SCH_1):PAGE214

VSENSE_PVCCIO_CPU1_SKT_VSEN @BASEBOARD_FAB2_LIB.BASEBOARD_FAB2(SCH_1):VSENSE_PVCCIO_CPU1_SKT_VSEN
  U2D1  BH5 VCCIO_SENSE SKX_EXT_B_BGA1-IC,TBD   I107 @BASEBOARD_FAB2_LIB.BASEBOARD_FAB2(SCH_1):PAGE73
 C3D27    1      A CAP_A_0402V-0.1UF,16V,10%,EMPTA    I96 @BASEBOARD_FAB2_LIB.BASEBOARD_FAB2(SCH_1):PAGE214
 SH3D2    1      A SHUNT_SH0201-EMPTY,N_A   I129 @BASEBOARD_FAB2_LIB.BASEBOARD_FAB2(SCH_1):PAGE214

VSENSE_PVCCMCP_CPU0_SKT_VRTN @BASEBOARD_FAB2_LIB.BASEBOARD_FAB2(SCH_1):VSENSE_PVCCMCP_CPU0_SKT_VRTN
  U5D1 BL16 CD_VSS_VCC_CORE_SENSE SKX_EXT_B_BGA1-IC,TBD   I127 @BASEBOARD_FAB2_LIB.BASEBOARD_FAB2(SCH_1):PAGE39
  J6E1   B4   IOB4 SCONN120_H61426002_SM-CONN,H61A    I55 @BASEBOARD_FAB2_LIB.BASEBOARD_FAB2(SCH_1):PAGE194

VSENSE_PVCCMCP_CPU0_SKT_VSEN @BASEBOARD_FAB2_LIB.BASEBOARD_FAB2(SCH_1):VSENSE_PVCCMCP_CPU0_SKT_VSEN
  U5D1 BN16 CD_VCC_CORE_SENSE SKX_EXT_B_BGA1-IC,TBD   I127 @BASEBOARD_FAB2_LIB.BASEBOARD_FAB2(SCH_1):PAGE39
  J6E1   A4   IOA4 SCONN120_H61426002_SM-CONN,H61A    I55 @BASEBOARD_FAB2_LIB.BASEBOARD_FAB2(SCH_1):PAGE194

VSENSE_PVCCMCP_CPU1_SKT_VRTN @BASEBOARD_FAB2_LIB.BASEBOARD_FAB2(SCH_1):VSENSE_PVCCMCP_CPU1_SKT_VRTN
  U2D1 BL16 CD_VSS_VCC_CORE_SENSE SKX_EXT_B_BGA1-IC,TBD   I107 @BASEBOARD_FAB2_LIB.BASEBOARD_FAB2(SCH_1):PAGE73
  J4E1   B4   IOB4 SCONN120_H61426002_SM-CONN,H61A    I45 @BASEBOARD_FAB2_LIB.BASEBOARD_FAB2(SCH_1):PAGE193

VSENSE_PVCCMCP_CPU1_SKT_VSEN @BASEBOARD_FAB2_LIB.BASEBOARD_FAB2(SCH_1):VSENSE_PVCCMCP_CPU1_SKT_VSEN
  U2D1 BN16 CD_VCC_CORE_SENSE SKX_EXT_B_BGA1-IC,TBD   I107 @BASEBOARD_FAB2_LIB.BASEBOARD_FAB2(SCH_1):PAGE73
  J4E1   A4   IOA4 SCONN120_H61426002_SM-CONN,H61A    I45 @BASEBOARD_FAB2_LIB.BASEBOARD_FAB2(SCH_1):PAGE193

VSENSE_PVDDQ_ABC_N @BASEBOARD_FAB2_LIB.BASEBOARD_FAB2(SCH_1):VSENSE_PVDDQ_ABC_N
  C7G4    2      B CAP_0402LF-220PF,50V,10%,X7R,AA   I342 @BASEBOARD_FAB2_LIB.BASEBOARD_FAB2(SCH_1):PAGE215
 EU7G1   20  AVREF PXM1310B_QFN-IC,H89186-001   I358 @BASEBOARD_FAB2_LIB.BASEBOARD_FAB2(SCH_1):PAGE215
  R4U6    2      B RES_0402-100.0,1%,1/16W,EMPTY,A    I74 @BASEBOARD_FAB2_LIB.BASEBOARD_FAB2(SCH_1):PAGE217
 SH4U1    1      A SHUNT_SH0201-EMPTY,N_A   I259 @BASEBOARD_FAB2_LIB.BASEBOARD_FAB2(SCH_1):PAGE217

VSENSE_PVDDQ_ABC_P @BASEBOARD_FAB2_LIB.BASEBOARD_FAB2(SCH_1):VSENSE_PVDDQ_ABC_P
  R7G9    1      A RES_0402-10.0,1%,1/16W,CHIP,G2A   I344 @BASEBOARD_FAB2_LIB.BASEBOARD_FAB2(SCH_1):PAGE215
  R4U6    1      A RES_0402-100.0,1%,1/16W,EMPTY,A    I74 @BASEBOARD_FAB2_LIB.BASEBOARD_FAB2(SCH_1):PAGE217
 SH4U2    1      A SHUNT_SH0201-EMPTY,N_A   I260 @BASEBOARD_FAB2_LIB.BASEBOARD_FAB2(SCH_1):PAGE217

VSENSE_PVDDQ_ABC_VTT @BASEBOARD_FAB2_LIB.BASEBOARD_FAB2(SCH_1):VSENSE_PVDDQ_ABC_VTT
 EU4G3    4   VDDQ MIC5166_DFN-IC,H55101-001     I1 @BASEBOARD_FAB2_LIB.BASEBOARD_FAB2(SCH_1):PAGE221
  R6U5    2      B RES_0402-0.0,5%,1/16W,CHIP,G21A    I32 @BASEBOARD_FAB2_LIB.BASEBOARD_FAB2(SCH_1):PAGE221
 C6U12    1      A CAP_0603-4.7UF,6.3V,10%,X6S,E1A    I49 @BASEBOARD_FAB2_LIB.BASEBOARD_FAB2(SCH_1):PAGE221

VSENSE_PVDDQ_DEF_N @BASEBOARD_FAB2_LIB.BASEBOARD_FAB2(SCH_1):VSENSE_PVDDQ_DEF_N
 C7A28    2      B CAP_0402LF-220PF,50V,10%,X7R,AA    I61 @BASEBOARD_FAB2_LIB.BASEBOARD_FAB2(SCH_1):PAGE218
 EU7A5   20  AVREF PXM1310B_QFN-IC,H89186-001    I75 @BASEBOARD_FAB2_LIB.BASEBOARD_FAB2(SCH_1):PAGE218
  R4L2    2      B RES_0402-100.0,1%,1/16W,EMPTY,A    I74 @BASEBOARD_FAB2_LIB.BASEBOARD_FAB2(SCH_1):PAGE220
 SH4L1    1      A SHUNT_SH0201-EMPTY,N_A   I240 @BASEBOARD_FAB2_LIB.BASEBOARD_FAB2(SCH_1):PAGE220

VSENSE_PVDDQ_DEF_P @BASEBOARD_FAB2_LIB.BASEBOARD_FAB2(SCH_1):VSENSE_PVDDQ_DEF_P
  R7A7    1      A RES_0402-10.0,1%,1/16W,CHIP,G2A    I60 @BASEBOARD_FAB2_LIB.BASEBOARD_FAB2(SCH_1):PAGE218
  R4L2    1      A RES_0402-100.0,1%,1/16W,EMPTY,A    I74 @BASEBOARD_FAB2_LIB.BASEBOARD_FAB2(SCH_1):PAGE220
 SH4L2    1      A SHUNT_SH0201-EMPTY,N_A   I239 @BASEBOARD_FAB2_LIB.BASEBOARD_FAB2(SCH_1):PAGE220

VSENSE_PVDDQ_DEF_VTT @BASEBOARD_FAB2_LIB.BASEBOARD_FAB2(SCH_1):VSENSE_PVDDQ_DEF_VTT
 EU4A1    4   VDDQ MIC5166_DFN-IC,H55101-001    I31 @BASEBOARD_FAB2_LIB.BASEBOARD_FAB2(SCH_1):PAGE222
 R6L10    2      B RES_0402-0.0,5%,1/16W,CHIP,G21A    I34 @BASEBOARD_FAB2_LIB.BASEBOARD_FAB2(SCH_1):PAGE222
 C4A11    1      A CAP_0603-4.7UF,6.3V,10%,X6S,E1A    I46 @BASEBOARD_FAB2_LIB.BASEBOARD_FAB2(SCH_1):PAGE222

VSENSE_PVDDQ_GHJ_N @BASEBOARD_FAB2_LIB.BASEBOARD_FAB2(SCH_1):VSENSE_PVDDQ_GHJ_N
 C1G16    2      B CAP_0402LF-220PF,50V,10%,X7R,AA    I39 @BASEBOARD_FAB2_LIB.BASEBOARD_FAB2(SCH_1):PAGE223
 EU1G2   20  AVREF PXM1310B_QFN-IC,H89186-001    I90 @BASEBOARD_FAB2_LIB.BASEBOARD_FAB2(SCH_1):PAGE223
  R7U2    2      B RES_0402-100.0,1%,1/16W,EMPTY,A    I74 @BASEBOARD_FAB2_LIB.BASEBOARD_FAB2(SCH_1):PAGE225
 SH7U2    1      A SHUNT_SH0201-EMPTY,N_A   I244 @BASEBOARD_FAB2_LIB.BASEBOARD_FAB2(SCH_1):PAGE225

VSENSE_PVDDQ_GHJ_P @BASEBOARD_FAB2_LIB.BASEBOARD_FAB2(SCH_1):VSENSE_PVDDQ_GHJ_P
  R1G5    1      A RES_0402-10.0,1%,1/16W,CHIP,G2A    I32 @BASEBOARD_FAB2_LIB.BASEBOARD_FAB2(SCH_1):PAGE223
  R7U2    1      A RES_0402-100.0,1%,1/16W,EMPTY,A    I74 @BASEBOARD_FAB2_LIB.BASEBOARD_FAB2(SCH_1):PAGE225
 SH7U1    1      A SHUNT_SH0201-EMPTY,N_A   I243 @BASEBOARD_FAB2_LIB.BASEBOARD_FAB2(SCH_1):PAGE225

VSENSE_PVDDQ_GHJ_VTT @BASEBOARD_FAB2_LIB.BASEBOARD_FAB2(SCH_1):VSENSE_PVDDQ_GHJ_VTT
 EU4G2    4   VDDQ MIC5166_DFN-IC,H55101-001    I24 @BASEBOARD_FAB2_LIB.BASEBOARD_FAB2(SCH_1):PAGE229
  R6U6    2      B RES_0402-0.0,5%,1/16W,CHIP,G21A    I39 @BASEBOARD_FAB2_LIB.BASEBOARD_FAB2(SCH_1):PAGE229
 C6U11    1      A CAP_0603-4.7UF,6.3V,10%,X6S,E1A    I46 @BASEBOARD_FAB2_LIB.BASEBOARD_FAB2(SCH_1):PAGE229

VSENSE_PVDDQ_KLM_N @BASEBOARD_FAB2_LIB.BASEBOARD_FAB2(SCH_1):VSENSE_PVDDQ_KLM_N
 C1B12    2      B CAP_0402LF-220PF,50V,10%,X7R,AA    I39 @BASEBOARD_FAB2_LIB.BASEBOARD_FAB2(SCH_1):PAGE226
 EU1B1   20  AVREF PXM1310B_QFN-IC,H89186-001    I90 @BASEBOARD_FAB2_LIB.BASEBOARD_FAB2(SCH_1):PAGE226
  R7L2    2      B RES_0402-100.0,1%,1/16W,EMPTY,A    I74 @BASEBOARD_FAB2_LIB.BASEBOARD_FAB2(SCH_1):PAGE228
 SH7L1    1      A SHUNT_SH0201-EMPTY,N_A   I246 @BASEBOARD_FAB2_LIB.BASEBOARD_FAB2(SCH_1):PAGE228

VSENSE_PVDDQ_KLM_P @BASEBOARD_FAB2_LIB.BASEBOARD_FAB2(SCH_1):VSENSE_PVDDQ_KLM_P
 R1B16    1      A RES_0402-10.0,1%,1/16W,CHIP,G2A    I32 @BASEBOARD_FAB2_LIB.BASEBOARD_FAB2(SCH_1):PAGE226
  R7L2    1      A RES_0402-100.0,1%,1/16W,EMPTY,A    I74 @BASEBOARD_FAB2_LIB.BASEBOARD_FAB2(SCH_1):PAGE228
 SH7L2    1      A SHUNT_SH0201-EMPTY,N_A   I245 @BASEBOARD_FAB2_LIB.BASEBOARD_FAB2(SCH_1):PAGE228

VSENSE_PVDDQ_KLM_VTT @BASEBOARD_FAB2_LIB.BASEBOARD_FAB2(SCH_1):VSENSE_PVDDQ_KLM_VTT
 EU4A2    4   VDDQ MIC5166_DFN-IC,H55101-001    I31 @BASEBOARD_FAB2_LIB.BASEBOARD_FAB2(SCH_1):PAGE230
  R6L6    2      B RES_0402-0.0,5%,1/16W,CHIP,G21A    I34 @BASEBOARD_FAB2_LIB.BASEBOARD_FAB2(SCH_1):PAGE230
  C4A7    1      A CAP_0603-4.7UF,6.3V,10%,X6S,E1A    I46 @BASEBOARD_FAB2_LIB.BASEBOARD_FAB2(SCH_1):PAGE230

VSENSE_PVNN_PCH_STBY_AVSN @BASEBOARD_FAB2_LIB.BASEBOARD_FAB2(SCH_1):VSENSE_PVNN_PCH_STBY_AVSN
  C8A2    2      B CAP_0402LF-220PF,50V,10%,X7R,AA   I209 @BASEBOARD_FAB2_LIB.BASEBOARD_FAB2(SCH_1):PAGE235
 EU8A1   20  AVREF PXE1110B_QFN-IC,H89187-001   I229 @BASEBOARD_FAB2_LIB.BASEBOARD_FAB2(SCH_1):PAGE235
 R7A18    2      B RES_0402-0.0,5%,1/16W,CHIP,G21A    I92 @BASEBOARD_FAB2_LIB.BASEBOARD_FAB2(SCH_1):PAGE236

VSENSE_PVNN_PCH_STBY_AVSP @BASEBOARD_FAB2_LIB.BASEBOARD_FAB2(SCH_1):VSENSE_PVNN_PCH_STBY_AVSP
  R8A1    1      A RES_0402-10.0,1%,1/16W,CHIP,G2A   I210 @BASEBOARD_FAB2_LIB.BASEBOARD_FAB2(SCH_1):PAGE235
 R7A13    1      A RES_0402-100.0,1%,1/16W,CHIP,GA    I90 @BASEBOARD_FAB2_LIB.BASEBOARD_FAB2(SCH_1):PAGE236
 R7A19    2      B RES_0402-10.0,1%,1/16W,CHIP,G2A    I93 @BASEBOARD_FAB2_LIB.BASEBOARD_FAB2(SCH_1):PAGE236
 R7A14    2      B RES_0402-10.0,1%,1/16W,CHIP,G2A    I94 @BASEBOARD_FAB2_LIB.BASEBOARD_FAB2(SCH_1):PAGE236

VSENSE_PVNN_PCH_STBY_FPK @BASEBOARD_FAB2_LIB.BASEBOARD_FAB2(SCH_1):VSENSE_PVNN_PCH_STBY_FPK
  U7C1 AK36 VCCPRIM_AVID_SENSE LBG_CORE_QAT_EXT_D_BGA1-IC,H91A    I21 @BASEBOARD_FAB2_LIB.BASEBOARD_FAB2(SCH_1):PAGE123
 R7A14    1      A RES_0402-10.0,1%,1/16W,CHIP,G2A    I94 @BASEBOARD_FAB2_LIB.BASEBOARD_FAB2(SCH_1):PAGE236

VSENSE_PVNN_PCH_STBY_QAT @BASEBOARD_FAB2_LIB.BASEBOARD_FAB2(SCH_1):VSENSE_PVNN_PCH_STBY_QAT
  U7C1  V37 VCCPRIM_AVID_QAT_SENSE LBG_CORE_QAT_EXT_D_BGA1-IC,H91A    I21 @BASEBOARD_FAB2_LIB.BASEBOARD_FAB2(SCH_1):PAGE123
 R7A19    1      A RES_0402-10.0,1%,1/16W,CHIP,G2A    I93 @BASEBOARD_FAB2_LIB.BASEBOARD_FAB2(SCH_1):PAGE236

VSENSE_PVPP_ABC @BASEBOARD_FAB2_LIB.BASEBOARD_FAB2(SCH_1):VSENSE_PVPP_ABC
 R7F13    1      A RES_0402-20.0K,1%,1/16W,CHIP,GA   I167 @BASEBOARD_FAB2_LIB.BASEBOARD_FAB2(SCH_1):PAGE231
 R7F12    2      B RES_0402-0.0,5%,1/16W,CHIP,G21A   I168 @BASEBOARD_FAB2_LIB.BASEBOARD_FAB2(SCH_1):PAGE231
 R7F17    1      A RES_0402-1.0K,0.1%,1/16W,CHIP,A   I218 @BASEBOARD_FAB2_LIB.BASEBOARD_FAB2(SCH_1):PAGE231

VSENSE_PVPP_DEF @BASEBOARD_FAB2_LIB.BASEBOARD_FAB2(SCH_1):VSENSE_PVPP_DEF
 R7B18    1      A RES_0402-1.0K,0.1%,1/16W,CHIP,A   I298 @BASEBOARD_FAB2_LIB.BASEBOARD_FAB2(SCH_1):PAGE232
 R7B11    2      B RES_0402-0.0,5%,1/16W,CHIP,G21A   I299 @BASEBOARD_FAB2_LIB.BASEBOARD_FAB2(SCH_1):PAGE232
 R7B15    1      A RES_0402-20.0K,1%,1/16W,CHIP,GA   I303 @BASEBOARD_FAB2_LIB.BASEBOARD_FAB2(SCH_1):PAGE232

VSENSE_PVPP_GHJ @BASEBOARD_FAB2_LIB.BASEBOARD_FAB2(SCH_1):VSENSE_PVPP_GHJ
 R4G10    1      A RES_0402-1.0K,0.1%,1/16W,CHIP,A   I266 @BASEBOARD_FAB2_LIB.BASEBOARD_FAB2(SCH_1):PAGE233
  R4G7    1      A RES_0402-20.0K,1%,1/16W,CHIP,GA   I270 @BASEBOARD_FAB2_LIB.BASEBOARD_FAB2(SCH_1):PAGE233
  R4G8    2      B RES_0402-0.0,5%,1/16W,CHIP,G21A   I271 @BASEBOARD_FAB2_LIB.BASEBOARD_FAB2(SCH_1):PAGE233

VSENSE_PVPP_KLM @BASEBOARD_FAB2_LIB.BASEBOARD_FAB2(SCH_1):VSENSE_PVPP_KLM
  R4B3    2      B RES_0402-0.0,5%,1/16W,CHIP,G21A   I214 @BASEBOARD_FAB2_LIB.BASEBOARD_FAB2(SCH_1):PAGE234
  R4B5    1      A RES_0402-20.0K,1%,1/16W,CHIP,GA   I215 @BASEBOARD_FAB2_LIB.BASEBOARD_FAB2(SCH_1):PAGE234
  R4B9    1      A RES_0402-1.0K,0.1%,1/16W,CHIP,A   I219 @BASEBOARD_FAB2_LIB.BASEBOARD_FAB2(SCH_1):PAGE234

VSENSE_PVSA_CPU0_BVSP @BASEBOARD_FAB2_LIB.BASEBOARD_FAB2(SCH_1):VSENSE_PVSA_CPU0_BVSP
 C4D29    1      A CAP_0402LF-220PF,50V,10%,X7R,AA    I64 @BASEBOARD_FAB2_LIB.BASEBOARD_FAB2(SCH_1):PAGE201
 R4D39    2      B RES_0402-10.0,1%,1/16W,CHIP,G2A   I110 @BASEBOARD_FAB2_LIB.BASEBOARD_FAB2(SCH_1):PAGE201
 EU4D4   35  BVSEN PXE1610B_QFN-IC,H79206-001   I155 @BASEBOARD_FAB2_LIB.BASEBOARD_FAB2(SCH_1):PAGE201

VSENSE_PVSA_CPU0_N @BASEBOARD_FAB2_LIB.BASEBOARD_FAB2(SCH_1):VSENSE_PVSA_CPU0_N
 C4D29    2      B CAP_0402LF-220PF,50V,10%,X7R,AA    I64 @BASEBOARD_FAB2_LIB.BASEBOARD_FAB2(SCH_1):PAGE201
 EU4D4   36  BVREF PXE1610B_QFN-IC,H79206-001   I155 @BASEBOARD_FAB2_LIB.BASEBOARD_FAB2(SCH_1):PAGE201
  R4C1    1      A RES_0402-100.0,1%,1/16W,CHIP,GA    I29 @BASEBOARD_FAB2_LIB.BASEBOARD_FAB2(SCH_1):PAGE205
  R4C2    1      A RES_0402-0.0,5%,1/16W,CHIP,G21A    I30 @BASEBOARD_FAB2_LIB.BASEBOARD_FAB2(SCH_1):PAGE205
  R4C3    2      B RES_0402-1.00K,1%,1/16W,EMPTY,A    I37 @BASEBOARD_FAB2_LIB.BASEBOARD_FAB2(SCH_1):PAGE205

VSENSE_PVSA_CPU0_P @BASEBOARD_FAB2_LIB.BASEBOARD_FAB2(SCH_1):VSENSE_PVSA_CPU0_P
 R4D39    1      A RES_0402-10.0,1%,1/16W,CHIP,G2A   I110 @BASEBOARD_FAB2_LIB.BASEBOARD_FAB2(SCH_1):PAGE201
  R4C5    1      A RES_0402-100.0,1%,1/16W,CHIP,GA    I24 @BASEBOARD_FAB2_LIB.BASEBOARD_FAB2(SCH_1):PAGE205
  R4C4    1      A RES_0402-0.0,5%,1/16W,CHIP,G21A    I26 @BASEBOARD_FAB2_LIB.BASEBOARD_FAB2(SCH_1):PAGE205
  R4C3    1      A RES_0402-1.00K,1%,1/16W,EMPTY,A    I37 @BASEBOARD_FAB2_LIB.BASEBOARD_FAB2(SCH_1):PAGE205

VSENSE_PVSA_CPU0_SKT_VRTN @BASEBOARD_FAB2_LIB.BASEBOARD_FAB2(SCH_1):VSENSE_PVSA_CPU0_SKT_VRTN
  U5D1 CG76 VSS_VCCSA_SENSE SKX_EXT_B_BGA1-IC,TBD   I127 @BASEBOARD_FAB2_LIB.BASEBOARD_FAB2(SCH_1):PAGE39
  R4C2    2      B RES_0402-0.0,5%,1/16W,CHIP,G21A    I30 @BASEBOARD_FAB2_LIB.BASEBOARD_FAB2(SCH_1):PAGE205

VSENSE_PVSA_CPU0_SKT_VSEN @BASEBOARD_FAB2_LIB.BASEBOARD_FAB2(SCH_1):VSENSE_PVSA_CPU0_SKT_VSEN
  U5D1 CE76 VCCSA_SENSE SKX_EXT_B_BGA1-IC,TBD   I127 @BASEBOARD_FAB2_LIB.BASEBOARD_FAB2(SCH_1):PAGE39
  R4C4    2      B RES_0402-0.0,5%,1/16W,CHIP,G21A    I26 @BASEBOARD_FAB2_LIB.BASEBOARD_FAB2(SCH_1):PAGE205

VSENSE_PVSA_CPU1_BVSP @BASEBOARD_FAB2_LIB.BASEBOARD_FAB2(SCH_1):VSENSE_PVSA_CPU1_BVSP
 C1C16    1      A CAP_0402LF-220PF,50V,10%,X7R,AA    I68 @BASEBOARD_FAB2_LIB.BASEBOARD_FAB2(SCH_1):PAGE206
 R1C21    2      B RES_0402-10.0,1%,1/16W,CHIP,G2A    I77 @BASEBOARD_FAB2_LIB.BASEBOARD_FAB2(SCH_1):PAGE206
 EU1C2   35  BVSEN PXE1610B_QFN-IC,H79206-001   I130 @BASEBOARD_FAB2_LIB.BASEBOARD_FAB2(SCH_1):PAGE206

VSENSE_PVSA_CPU1_N @BASEBOARD_FAB2_LIB.BASEBOARD_FAB2(SCH_1):VSENSE_PVSA_CPU1_N
 C1C16    2      B CAP_0402LF-220PF,50V,10%,X7R,AA    I68 @BASEBOARD_FAB2_LIB.BASEBOARD_FAB2(SCH_1):PAGE206
 EU1C2   36  BVREF PXE1610B_QFN-IC,H79206-001   I130 @BASEBOARD_FAB2_LIB.BASEBOARD_FAB2(SCH_1):PAGE206
  R1C5    1      A RES_0402-0.0,5%,1/16W,CHIP,G21A    I32 @BASEBOARD_FAB2_LIB.BASEBOARD_FAB2(SCH_1):PAGE210
  R1C4    1      A RES_0402-100.0,1%,1/16W,CHIP,GA    I33 @BASEBOARD_FAB2_LIB.BASEBOARD_FAB2(SCH_1):PAGE210
  R1C6    2      B RES_0402-1.00K,1%,1/16W,EMPTY,A    I34 @BASEBOARD_FAB2_LIB.BASEBOARD_FAB2(SCH_1):PAGE210

VSENSE_PVSA_CPU1_P @BASEBOARD_FAB2_LIB.BASEBOARD_FAB2(SCH_1):VSENSE_PVSA_CPU1_P
 R1C21    1      A RES_0402-10.0,1%,1/16W,CHIP,G2A    I77 @BASEBOARD_FAB2_LIB.BASEBOARD_FAB2(SCH_1):PAGE206
 R1C12    1      A RES_0402-100.0,1%,1/16W,CHIP,GA    I29 @BASEBOARD_FAB2_LIB.BASEBOARD_FAB2(SCH_1):PAGE210
  R1C7    1      A RES_0402-0.0,5%,1/16W,CHIP,G21A    I31 @BASEBOARD_FAB2_LIB.BASEBOARD_FAB2(SCH_1):PAGE210
  R1C6    1      A RES_0402-1.00K,1%,1/16W,EMPTY,A    I34 @BASEBOARD_FAB2_LIB.BASEBOARD_FAB2(SCH_1):PAGE210

VSENSE_PVSA_CPU1_SKT_VRTN @BASEBOARD_FAB2_LIB.BASEBOARD_FAB2(SCH_1):VSENSE_PVSA_CPU1_SKT_VRTN
  U2D1 CG76 VSS_VCCSA_SENSE SKX_EXT_B_BGA1-IC,TBD   I107 @BASEBOARD_FAB2_LIB.BASEBOARD_FAB2(SCH_1):PAGE73
  R1C5    2      B RES_0402-0.0,5%,1/16W,CHIP,G21A    I32 @BASEBOARD_FAB2_LIB.BASEBOARD_FAB2(SCH_1):PAGE210

VSENSE_PVSA_CPU1_SKT_VSEN @BASEBOARD_FAB2_LIB.BASEBOARD_FAB2(SCH_1):VSENSE_PVSA_CPU1_SKT_VSEN
  U2D1 CE76 VCCSA_SENSE SKX_EXT_B_BGA1-IC,TBD   I107 @BASEBOARD_FAB2_LIB.BASEBOARD_FAB2(SCH_1):PAGE73
  R1C7    2      B RES_0402-0.0,5%,1/16W,CHIP,G21A    I31 @BASEBOARD_FAB2_LIB.BASEBOARD_FAB2(SCH_1):PAGE210

VSENSE_RGND_P3V3_STBY @BASEBOARD_FAB2_LIB.BASEBOARD_FAB2(SCH_1):VSENSE_RGND_P3V3_STBY
 EU8F1    7   RGND RT8240_QFN-IC,H66262-001   I125 @BASEBOARD_FAB2_LIB.BASEBOARD_FAB2(SCH_1):PAGE240
 R8E38    1      A RES_0402-0.0,5%,1/16W,CHIP,G21A   I140 @BASEBOARD_FAB2_LIB.BASEBOARD_FAB2(SCH_1):PAGE240

VSENSE_VCCINR2PMAX_CPU0 @BASEBOARD_FAB2_LIB.BASEBOARD_FAB2(SCH_1):VSENSE_VCCINR2PMAX_CPU0
  R5P1    2      B RES_0603-100.0K,1%,1/10W,CHIP,A   I309 @BASEBOARD_FAB2_LIB.BASEBOARD_FAB2(SCH_1):PAGE37
  U5D1 AW86 VCCINPMAX<0> SKX_EXT_B_BGA1-IC,TBD   I311 @BASEBOARD_FAB2_LIB.BASEBOARD_FAB2(SCH_1):PAGE37
  U5D1 AV85 VCCINPMAX<1> SKX_EXT_B_BGA1-IC,TBD   I311 @BASEBOARD_FAB2_LIB.BASEBOARD_FAB2(SCH_1):PAGE37

VSENSE_VCCINR2PMAX_CPU1 @BASEBOARD_FAB2_LIB.BASEBOARD_FAB2(SCH_1):VSENSE_VCCINR2PMAX_CPU1
 RT8P1    2      B RES_0603-100.0K,1%,1/10W,CHIP,A    I49 @BASEBOARD_FAB2_LIB.BASEBOARD_FAB2(SCH_1):PAGE71
  U2D1 AW86 VCCINPMAX<0> SKX_EXT_B_BGA1-IC,TBD    I51 @BASEBOARD_FAB2_LIB.BASEBOARD_FAB2(SCH_1):PAGE71
  U2D1 AV85 VCCINPMAX<1> SKX_EXT_B_BGA1-IC,TBD    I51 @BASEBOARD_FAB2_LIB.BASEBOARD_FAB2(SCH_1):PAGE71

VSENSE_VOUT_P3V3_STBY @BASEBOARD_FAB2_LIB.BASEBOARD_FAB2(SCH_1):VSENSE_VOUT_P3V3_STBY
 EU8F1    6   VOUT RT8240_QFN-IC,H66262-001   I125 @BASEBOARD_FAB2_LIB.BASEBOARD_FAB2(SCH_1):PAGE240
 R8E34    1      A RES_0402-10.0K,1%,1/16W,CHIP,GA   I142 @BASEBOARD_FAB2_LIB.BASEBOARD_FAB2(SCH_1):PAGE240
 R8E31    2      B RES_0402-23.2K,1%,1/16W,CHIP,GA   I143 @BASEBOARD_FAB2_LIB.BASEBOARD_FAB2(SCH_1):PAGE240

XDP_CPU0_TDO @BASEBOARD_FAB2_LIB.BASEBOARD_FAB2(SCH_1):XDP_CPU0_TDO
  U5D1 AE14    TDO SKX_EXT_B_BGA1-IC,TBD   I259 @BASEBOARD_FAB2_LIB.BASEBOARD_FAB2(SCH_1):PAGE21
  U1M7    1     B1 NC7SB3157_SMLF-IC,C99406-001    I40 @BASEBOARD_FAB2_LIB.BASEBOARD_FAB2(SCH_1):PAGE112
 R4P23    2      B RES_0402-150.0,1%,1/16W,CHIP,GA    I58 @BASEBOARD_FAB2_LIB.BASEBOARD_FAB2(SCH_1):PAGE112
  U1M4    2      A 74CBTLV1G125_SMLF-IC,C88177-00A   I127 @BASEBOARD_FAB2_LIB.BASEBOARD_FAB2(SCH_1):PAGE112

XDP_CPU1_TDI @BASEBOARD_FAB2_LIB.BASEBOARD_FAB2(SCH_1):XDP_CPU1_TDI
  U2D1 AC14    TDI SKX_EXT_B_BGA1-IC,TBD   I172 @BASEBOARD_FAB2_LIB.BASEBOARD_FAB2(SCH_1):PAGE55
  R6T6    2      B RES_0402-150.0,1%,1/16W,CHIP,GA    I56 @BASEBOARD_FAB2_LIB.BASEBOARD_FAB2(SCH_1):PAGE112
  U1M4    4      B 74CBTLV1G125_SMLF-IC,C88177-00A   I127 @BASEBOARD_FAB2_LIB.BASEBOARD_FAB2(SCH_1):PAGE112

XDP_CPU1_TDO @BASEBOARD_FAB2_LIB.BASEBOARD_FAB2(SCH_1):XDP_CPU1_TDO
  U2D1 AE14    TDO SKX_EXT_B_BGA1-IC,TBD   I172 @BASEBOARD_FAB2_LIB.BASEBOARD_FAB2(SCH_1):PAGE55
  U1M7    3     B0 NC7SB3157_SMLF-IC,C99406-001    I40 @BASEBOARD_FAB2_LIB.BASEBOARD_FAB2(SCH_1):PAGE112
  R6T7    2      B RES_0402-150.0,1%,1/16W,CHIP,GA    I55 @BASEBOARD_FAB2_LIB.BASEBOARD_FAB2(SCH_1):PAGE112

XDP_CPU_GTL_TCK_R2 @BASEBOARD_FAB2_LIB.BASEBOARD_FAB2(SCH_1):XDP_CPU_GTL_TCK_R2
  R9A2    2      B RES_0402-33.2,1%,1/16W,EMPTY,GA    I83 @BASEBOARD_FAB2_LIB.BASEBOARD_FAB2(SCH_1):PAGE111
  Q9A1    1   E<0> NPN_DUAL_SSOPLF-MBT3904,EMPTY,A    I93 @BASEBOARD_FAB2_LIB.BASEBOARD_FAB2(SCH_1):PAGE111

XDP_CPU_MBP0_N @BASEBOARD_FAB2_LIB.BASEBOARD_FAB2(SCH_1):XDP_CPU_MBP0_N
  U5D1 AJ10 BPM_N<0> SKX_EXT_B_BGA1-IC,TBD   I259 @BASEBOARD_FAB2_LIB.BASEBOARD_FAB2(SCH_1):PAGE21
  U2D1 AJ10 BPM_N<0> SKX_EXT_B_BGA1-IC,TBD   I172 @BASEBOARD_FAB2_LIB.BASEBOARD_FAB2(SCH_1):PAGE55
 R7P30    2      B RES_0402-100.0,1%,1/16W,CHIP,GA    I50 @BASEBOARD_FAB2_LIB.BASEBOARD_FAB2(SCH_1):PAGE112
 R4P12    2      B RES_0402-100.0,1%,1/16W,CHIP,GA    I57 @BASEBOARD_FAB2_LIB.BASEBOARD_FAB2(SCH_1):PAGE112

XDP_CPU_MBP1_N @BASEBOARD_FAB2_LIB.BASEBOARD_FAB2(SCH_1):XDP_CPU_MBP1_N
  U5D1 AH11 BPM_N<1> SKX_EXT_B_BGA1-IC,TBD   I259 @BASEBOARD_FAB2_LIB.BASEBOARD_FAB2(SCH_1):PAGE21
  U2D1 AH11 BPM_N<1> SKX_EXT_B_BGA1-IC,TBD   I172 @BASEBOARD_FAB2_LIB.BASEBOARD_FAB2(SCH_1):PAGE55
 R6P46    2      B RES_0402-100.0,1%,1/16W,CHIP,GA    I49 @BASEBOARD_FAB2_LIB.BASEBOARD_FAB2(SCH_1):PAGE112
 R4P15    2      B RES_0402-100.0,1%,1/16W,CHIP,GA    I53 @BASEBOARD_FAB2_LIB.BASEBOARD_FAB2(SCH_1):PAGE112

XDP_CPU_OBSFN_B0_MBP6_N @BASEBOARD_FAB2_LIB.BASEBOARD_FAB2(SCH_1):XDP_CPU_OBSFN_B0_MBP6_N
  U5D1 AE12 BPM_N<6> SKX_EXT_B_BGA1-IC,TBD   I259 @BASEBOARD_FAB2_LIB.BASEBOARD_FAB2(SCH_1):PAGE21
  U2D1 AE12 BPM_N<6> SKX_EXT_B_BGA1-IC,TBD   I172 @BASEBOARD_FAB2_LIB.BASEBOARD_FAB2(SCH_1):PAGE55
  U1L5    6   B<2> TTL3126_QFNLF-74CBTLV3126,IC,DB   I109 @BASEBOARD_FAB2_LIB.BASEBOARD_FAB2(SCH_1):PAGE112
  R6T8    2      B RES_0402-100.0,1%,1/16W,CHIP,GA   I121 @BASEBOARD_FAB2_LIB.BASEBOARD_FAB2(SCH_1):PAGE112

XDP_CPU_OBSFN_B1_MBP7_N @BASEBOARD_FAB2_LIB.BASEBOARD_FAB2(SCH_1):XDP_CPU_OBSFN_B1_MBP7_N
  U5D1 AC12 BPM_N<7> SKX_EXT_B_BGA1-IC,TBD   I259 @BASEBOARD_FAB2_LIB.BASEBOARD_FAB2(SCH_1):PAGE21
  U2D1 AC12 BPM_N<7> SKX_EXT_B_BGA1-IC,TBD   I172 @BASEBOARD_FAB2_LIB.BASEBOARD_FAB2(SCH_1):PAGE55
  U1L5    3   B<3> TTL3126_QFNLF-74CBTLV3126,IC,DB   I109 @BASEBOARD_FAB2_LIB.BASEBOARD_FAB2(SCH_1):PAGE112
  R6T9    2      B RES_0402-100.0,1%,1/16W,CHIP,GA   I120 @BASEBOARD_FAB2_LIB.BASEBOARD_FAB2(SCH_1):PAGE112

XDP_CPU_PRDY_N @BASEBOARD_FAB2_LIB.BASEBOARD_FAB2(SCH_1):XDP_CPU_PRDY_N
  U5D1 AG16 PRDY_N SKX_EXT_B_BGA1-IC,TBD   I259 @BASEBOARD_FAB2_LIB.BASEBOARD_FAB2(SCH_1):PAGE21
  U2D1 AG16 PRDY_N SKX_EXT_B_BGA1-IC,TBD   I172 @BASEBOARD_FAB2_LIB.BASEBOARD_FAB2(SCH_1):PAGE55
  R1M3    2      B RES_0402-100.0,1%,1/16W,CHIP,GA    I51 @BASEBOARD_FAB2_LIB.BASEBOARD_FAB2(SCH_1):PAGE112
  U1L5    8   B<1> TTL3126_QFNLF-74CBTLV3126,IC,DB   I109 @BASEBOARD_FAB2_LIB.BASEBOARD_FAB2(SCH_1):PAGE112

XDP_CPU_PREQ_N @BASEBOARD_FAB2_LIB.BASEBOARD_FAB2(SCH_1):XDP_CPU_PREQ_N
  U5D1 AR12 PREQ_N SKX_EXT_B_BGA1-IC,TBD   I259 @BASEBOARD_FAB2_LIB.BASEBOARD_FAB2(SCH_1):PAGE21
  U2D1 AR12 PREQ_N SKX_EXT_B_BGA1-IC,TBD   I172 @BASEBOARD_FAB2_LIB.BASEBOARD_FAB2(SCH_1):PAGE55
  R1M4    2      B RES_0402-100.0,1%,1/16W,CHIP,GA    I54 @BASEBOARD_FAB2_LIB.BASEBOARD_FAB2(SCH_1):PAGE112
  U1L5   11   B<0> TTL3126_QFNLF-74CBTLV3126,IC,DB   I109 @BASEBOARD_FAB2_LIB.BASEBOARD_FAB2(SCH_1):PAGE112

XDP_CPU_PWR_DEBUG_N @BASEBOARD_FAB2_LIB.BASEBOARD_FAB2(SCH_1):XDP_CPU_PWR_DEBUG_N
  U5D1 AP17 PWR_DEBUG_N SKX_EXT_B_BGA1-IC,TBD   I204 @BASEBOARD_FAB2_LIB.BASEBOARD_FAB2(SCH_1):PAGE22
  U2D1 AP17 PWR_DEBUG_N SKX_EXT_B_BGA1-IC,TBD   I169 @BASEBOARD_FAB2_LIB.BASEBOARD_FAB2(SCH_1):PAGE56
  J9A3   45   IO45 SCONN60_C21100002_SMLF-CONN,C2A    I26 @BASEBOARD_FAB2_LIB.BASEBOARD_FAB2(SCH_1):PAGE111
 R1L17    1      A RES_0402-150.0,1%,1/16W,CHIP,GA    I56 @BASEBOARD_FAB2_LIB.BASEBOARD_FAB2(SCH_1):PAGE111
  C9A4    1      A CAP_A_0402V-0.1UF,16V,10%,X7R,A    I59 @BASEBOARD_FAB2_LIB.BASEBOARD_FAB2(SCH_1):PAGE111
  U7D1    4      B 74CBTLV1G125_SMLF-IC,C88177-00A   I142 @BASEBOARD_FAB2_LIB.BASEBOARD_FAB2(SCH_1):PAGE118

XDP_CPU_TCK0 @BASEBOARD_FAB2_LIB.BASEBOARD_FAB2(SCH_1):XDP_CPU_TCK0
  U5D1 AA14    TCK SKX_EXT_B_BGA1-IC,TBD   I259 @BASEBOARD_FAB2_LIB.BASEBOARD_FAB2(SCH_1):PAGE21
  U2D1 AA14    TCK SKX_EXT_B_BGA1-IC,TBD   I172 @BASEBOARD_FAB2_LIB.BASEBOARD_FAB2(SCH_1):PAGE55
  J9A3   57   IO57 SCONN60_C21100002_SMLF-CONN,C2A    I26 @BASEBOARD_FAB2_LIB.BASEBOARD_FAB2(SCH_1):PAGE111
  R9A3    2      B RES_0402-0.0,5%,1/16W,CHIP,G21A    I74 @BASEBOARD_FAB2_LIB.BASEBOARD_FAB2(SCH_1):PAGE111
  Q9A1    4   E<0> NPN_DUAL_SSOPLF-MBT3904,EMPTY,A    I94 @BASEBOARD_FAB2_LIB.BASEBOARD_FAB2(SCH_1):PAGE111
 R7P29    1      A RES_0402-51.1,1.0%,1/16W,CHIP,A    I61 @BASEBOARD_FAB2_LIB.BASEBOARD_FAB2(SCH_1):PAGE112

XDP_CPU_TCK_BUF @BASEBOARD_FAB2_LIB.BASEBOARD_FAB2(SCH_1):XDP_CPU_TCK_BUF
  Q9A1    2   B<0> NPN_DUAL_SSOPLF-MBT3904,EMPTY,A    I93 @BASEBOARD_FAB2_LIB.BASEBOARD_FAB2(SCH_1):PAGE111
  Q9A1    6   C<0> NPN_DUAL_SSOPLF-MBT3904,EMPTY,A    I93 @BASEBOARD_FAB2_LIB.BASEBOARD_FAB2(SCH_1):PAGE111
  Q9A1    5   B<0> NPN_DUAL_SSOPLF-MBT3904,EMPTY,A    I94 @BASEBOARD_FAB2_LIB.BASEBOARD_FAB2(SCH_1):PAGE111
  R9A1    2      B RES_0402-1.00K,1%,1/16W,EMPTY,A    I95 @BASEBOARD_FAB2_LIB.BASEBOARD_FAB2(SCH_1):PAGE111

XDP_CPU_TDI @BASEBOARD_FAB2_LIB.BASEBOARD_FAB2(SCH_1):XDP_CPU_TDI
  U5D1 AC14    TDI SKX_EXT_B_BGA1-IC,TBD   I259 @BASEBOARD_FAB2_LIB.BASEBOARD_FAB2(SCH_1):PAGE21
 R4P24    2      B RES_0402-150.0,1%,1/16W,CHIP,GA    I59 @BASEBOARD_FAB2_LIB.BASEBOARD_FAB2(SCH_1):PAGE112
  U1L1   11   B<0> TTL3126_QFNLF-74CBTLV3126,IC,DB   I108 @BASEBOARD_FAB2_LIB.BASEBOARD_FAB2(SCH_1):PAGE112

XDP_CPU_TDO @BASEBOARD_FAB2_LIB.BASEBOARD_FAB2(SCH_1):XDP_CPU_TDO
  U1M7    4      A NC7SB3157_SMLF-IC,C99406-001    I40 @BASEBOARD_FAB2_LIB.BASEBOARD_FAB2(SCH_1):PAGE112
  U1L1    8   B<1> TTL3126_QFNLF-74CBTLV3126,IC,DB   I108 @BASEBOARD_FAB2_LIB.BASEBOARD_FAB2(SCH_1):PAGE112

XDP_CPU_TMS @BASEBOARD_FAB2_LIB.BASEBOARD_FAB2(SCH_1):XDP_CPU_TMS
  U5D1  W14    TMS SKX_EXT_B_BGA1-IC,TBD   I259 @BASEBOARD_FAB2_LIB.BASEBOARD_FAB2(SCH_1):PAGE21
  U2D1  W14    TMS SKX_EXT_B_BGA1-IC,TBD   I172 @BASEBOARD_FAB2_LIB.BASEBOARD_FAB2(SCH_1):PAGE55
 R1L15    2      B RES_0402-150.0,1%,1/16W,CHIP,GA    I60 @BASEBOARD_FAB2_LIB.BASEBOARD_FAB2(SCH_1):PAGE112
  U1L1    6   B<2> TTL3126_QFNLF-74CBTLV3126,IC,DB   I108 @BASEBOARD_FAB2_LIB.BASEBOARD_FAB2(SCH_1):PAGE112

XDP_CPU_TRST_N @BASEBOARD_FAB2_LIB.BASEBOARD_FAB2(SCH_1):XDP_CPU_TRST_N
  U5D1  Y13 TRST_N SKX_EXT_B_BGA1-IC,TBD   I259 @BASEBOARD_FAB2_LIB.BASEBOARD_FAB2(SCH_1):PAGE21
  U2D1  Y13 TRST_N SKX_EXT_B_BGA1-IC,TBD   I172 @BASEBOARD_FAB2_LIB.BASEBOARD_FAB2(SCH_1):PAGE55
  R6T5    1      A RES_0402-1.00K,1%,1/16W,CHIP,GA    I62 @BASEBOARD_FAB2_LIB.BASEBOARD_FAB2(SCH_1):PAGE112
  U1L1    3   B<3> TTL3126_QFNLF-74CBTLV3126,IC,DB   I108 @BASEBOARD_FAB2_LIB.BASEBOARD_FAB2(SCH_1):PAGE112

XDP_DEBUG_CONSENT_N @BASEBOARD_FAB2_LIB.BASEBOARD_FAB2(SCH_1):XDP_DEBUG_CONSENT_N
  J9A3    1    IO1 SCONN60_C21100002_SMLF-CONN,C2A    I26 @BASEBOARD_FAB2_LIB.BASEBOARD_FAB2(SCH_1):PAGE111
  R2P2    2      B RES_0402-1.00K,1%,1/16W,CHIP,GA    I37 @BASEBOARD_FAB2_LIB.BASEBOARD_FAB2(SCH_1):PAGE111

XDP_ITP_PMODE @BASEBOARD_FAB2_LIB.BASEBOARD_FAB2(SCH_1):XDP_ITP_PMODE
  J9A3   46   IO46 SCONN60_C21100002_SMLF-CONN,C2A    I26 @BASEBOARD_FAB2_LIB.BASEBOARD_FAB2(SCH_1):PAGE111
 R9A17    1      A RES_0402-1.00K,1%,1/16W,CHIP,GA    I57 @BASEBOARD_FAB2_LIB.BASEBOARD_FAB2(SCH_1):PAGE111
  U7C1 AR54 ITP_PMODE LBG_CORE_QAT_EXT_D_BGA1-IC,H91A    I73 @BASEBOARD_FAB2_LIB.BASEBOARD_FAB2(SCH_1):PAGE118

XDP_OBSFN_B0_MBP6_N @BASEBOARD_FAB2_LIB.BASEBOARD_FAB2(SCH_1):XDP_OBSFN_B0_MBP6_N
  J9A3   22   IO22 SCONN60_C21100002_SMLF-CONN,C2A    I26 @BASEBOARD_FAB2_LIB.BASEBOARD_FAB2(SCH_1):PAGE111
  U1L5    5   A<2> TTL3126_QFNLF-74CBTLV3126,IC,DB   I109 @BASEBOARD_FAB2_LIB.BASEBOARD_FAB2(SCH_1):PAGE112

XDP_OBSFN_B1_MBP7_N @BASEBOARD_FAB2_LIB.BASEBOARD_FAB2(SCH_1):XDP_OBSFN_B1_MBP7_N
  J9A3   24   IO24 SCONN60_C21100002_SMLF-CONN,C2A    I26 @BASEBOARD_FAB2_LIB.BASEBOARD_FAB2(SCH_1):PAGE111
  U1L5    2   A<3> TTL3126_QFNLF-74CBTLV3126,IC,DB   I109 @BASEBOARD_FAB2_LIB.BASEBOARD_FAB2(SCH_1):PAGE112

XDP_PCH_CPU_TCK0 @BASEBOARD_FAB2_LIB.BASEBOARD_FAB2(SCH_1):XDP_PCH_CPU_TCK0
  R9A3    1      A RES_0402-0.0,5%,1/16W,CHIP,G21A    I74 @BASEBOARD_FAB2_LIB.BASEBOARD_FAB2(SCH_1):PAGE111
  R9A2    1      A RES_0402-33.2,1%,1/16W,EMPTY,GA    I83 @BASEBOARD_FAB2_LIB.BASEBOARD_FAB2(SCH_1):PAGE111
 R3M10    1      A RES_0402-1.00K,1%,1/16W,CHIP,GA    I85 @BASEBOARD_FAB2_LIB.BASEBOARD_FAB2(SCH_1):PAGE112
  U7C1 AF54  JTAGX LBG_CORE_QAT_EXT_D_BGA1-IC,H91A    I73 @BASEBOARD_FAB2_LIB.BASEBOARD_FAB2(SCH_1):PAGE118

XDP_PCH_PWR_DEBUG_N @BASEBOARD_FAB2_LIB.BASEBOARD_FAB2(SCH_1):XDP_PCH_PWR_DEBUG_N
  U7C1  G15   GPD0 LBG_CORE_QAT_EXT_D_BGA1-IC,H91A    I73 @BASEBOARD_FAB2_LIB.BASEBOARD_FAB2(SCH_1):PAGE118
  U7D1    2      A 74CBTLV1G125_SMLF-IC,C88177-00A   I142 @BASEBOARD_FAB2_LIB.BASEBOARD_FAB2(SCH_1):PAGE118
 R7C23    2      B RES_0402-10.0K,1%,1/16W,CHIP,GA   I144 @BASEBOARD_FAB2_LIB.BASEBOARD_FAB2(SCH_1):PAGE118

XDP_PCH_TCK1 @BASEBOARD_FAB2_LIB.BASEBOARD_FAB2(SCH_1):XDP_PCH_TCK1
  J9A3   55   IO55 SCONN60_C21100002_SMLF-CONN,C2A    I26 @BASEBOARD_FAB2_LIB.BASEBOARD_FAB2(SCH_1):PAGE111
  R8B1    1      A RES_0402-51.1,1.0%,1/16W,CHIP,A    I95 @BASEBOARD_FAB2_LIB.BASEBOARD_FAB2(SCH_1):PAGE112
  U7C1 AL56 JTAG_TCK LBG_CORE_QAT_EXT_D_BGA1-IC,H91A    I73 @BASEBOARD_FAB2_LIB.BASEBOARD_FAB2(SCH_1):PAGE118

XDP_PRDY_N @BASEBOARD_FAB2_LIB.BASEBOARD_FAB2(SCH_1):XDP_PRDY_N
  J9A3    5    IO5 SCONN60_C21100002_SMLF-CONN,C2A    I26 @BASEBOARD_FAB2_LIB.BASEBOARD_FAB2(SCH_1):PAGE111
 R1L39    2      B RES_0402-100.0,1%,1/16W,CHIP,GA    I76 @BASEBOARD_FAB2_LIB.BASEBOARD_FAB2(SCH_1):PAGE112
  U1L5    9   A<1> TTL3126_QFNLF-74CBTLV3126,IC,DB   I109 @BASEBOARD_FAB2_LIB.BASEBOARD_FAB2(SCH_1):PAGE112
  U7C1 AD54 PRDY_N LBG_CORE_QAT_EXT_D_BGA1-IC,H91A    I73 @BASEBOARD_FAB2_LIB.BASEBOARD_FAB2(SCH_1):PAGE118

XDP_PREQ_N @BASEBOARD_FAB2_LIB.BASEBOARD_FAB2(SCH_1):XDP_PREQ_N
  J9A3    3    IO3 SCONN60_C21100002_SMLF-CONN,C2A    I26 @BASEBOARD_FAB2_LIB.BASEBOARD_FAB2(SCH_1):PAGE111
 R1L41    2      B RES_0402-100.0,1%,1/16W,CHIP,GA    I77 @BASEBOARD_FAB2_LIB.BASEBOARD_FAB2(SCH_1):PAGE112
  U1L5   12   A<0> TTL3126_QFNLF-74CBTLV3126,IC,DB   I109 @BASEBOARD_FAB2_LIB.BASEBOARD_FAB2(SCH_1):PAGE112
  U7C1  U54 PREQ_N LBG_CORE_QAT_EXT_D_BGA1-IC,H91A    I73 @BASEBOARD_FAB2_LIB.BASEBOARD_FAB2(SCH_1):PAGE118

XDP_PRESENT_N @BASEBOARD_FAB2_LIB.BASEBOARD_FAB2(SCH_1):XDP_PRESENT_N
  U5D1 AV21 DEBUG_EN_N SKX_EXT_B_BGA1-IC,TBD   I204 @BASEBOARD_FAB2_LIB.BASEBOARD_FAB2(SCH_1):PAGE22
  U2D1 AV21 DEBUG_EN_N SKX_EXT_B_BGA1-IC,TBD   I169 @BASEBOARD_FAB2_LIB.BASEBOARD_FAB2(SCH_1):PAGE56
  J9A3   60   IO60 SCONN60_C21100002_SMLF-CONN,C2A    I26 @BASEBOARD_FAB2_LIB.BASEBOARD_FAB2(SCH_1):PAGE111
  R9A4    1      A RES_0402-475.0,1%,1/16W,CHIP,GA    I55 @BASEBOARD_FAB2_LIB.BASEBOARD_FAB2(SCH_1):PAGE111

XDP_PWRGD_RST_N @BASEBOARD_FAB2_LIB.BASEBOARD_FAB2(SCH_1):XDP_PWRGD_RST_N
 R1L23    1      A RES_0402-1.00K,1%,1/16W,CHIP,GA    I13 @BASEBOARD_FAB2_LIB.BASEBOARD_FAB2(SCH_1):PAGE111
  C1L8    1      A CAP_A_0402V-0.1UF,16V,10%,X7R,A    I14 @BASEBOARD_FAB2_LIB.BASEBOARD_FAB2(SCH_1):PAGE111
  J9A3   41   IO41 SCONN60_C21100002_SMLF-CONN,C2A    I26 @BASEBOARD_FAB2_LIB.BASEBOARD_FAB2(SCH_1):PAGE111
  U8D7  M11  PB19D LCMXO2_A_256BGA-IC,H63395-001   I179 @BASEBOARD_FAB2_LIB.BASEBOARD_FAB2(SCH_1):PAGE190

XDP_RSMRST_N @BASEBOARD_FAB2_LIB.BASEBOARD_FAB2(SCH_1):XDP_RSMRST_N
  J9A3   39   IO39 SCONN60_C21100002_SMLF-CONN,C2A    I26 @BASEBOARD_FAB2_LIB.BASEBOARD_FAB2(SCH_1):PAGE111
 R9A15    2      B RES_0402-1.00K,1%,1/16W,CHIP,GA    I60 @BASEBOARD_FAB2_LIB.BASEBOARD_FAB2(SCH_1):PAGE111

XDP_RST_CO_N @BASEBOARD_FAB2_LIB.BASEBOARD_FAB2(SCH_1):XDP_RST_CO_N
 R9A14    1      A RES_0402-1.00K,1%,1/16W,CHIP,GA    I11 @BASEBOARD_FAB2_LIB.BASEBOARD_FAB2(SCH_1):PAGE111
  C9A5    1      A CAP_A_0402V-0.1UF,16V,10%,X7R,A    I12 @BASEBOARD_FAB2_LIB.BASEBOARD_FAB2(SCH_1):PAGE111
  J9A3   48   IO48 SCONN60_C21100002_SMLF-CONN,C2A    I26 @BASEBOARD_FAB2_LIB.BASEBOARD_FAB2(SCH_1):PAGE111
  U1L4    2      A TTL1G07_A_SOP-74LVC1G07,IC,C88B    I85 @BASEBOARD_FAB2_LIB.BASEBOARD_FAB2(SCH_1):PAGE111

XDP_SPI_PCH_MOSI_BOOT_HALT_N @BASEBOARD_FAB2_LIB.BASEBOARD_FAB2(SCH_1):XDP_SPI_PCH_MOSI_BOOT_HALT_N
  J9A3    6    IO6 SCONN60_C21100002_SMLF-CONN,C2A    I26 @BASEBOARD_FAB2_LIB.BASEBOARD_FAB2(SCH_1):PAGE111
  R8E2    1      A RES_0402-1.00K,1%,1/16W,CHIP,GA    I89 @BASEBOARD_FAB2_LIB.BASEBOARD_FAB2(SCH_1):PAGE111

XDP_SYSPWROK @BASEBOARD_FAB2_LIB.BASEBOARD_FAB2(SCH_1):XDP_SYSPWROK
 R1L13    1      A RES_0402-1.00K,1%,1/16W,CHIP,GA     I6 @BASEBOARD_FAB2_LIB.BASEBOARD_FAB2(SCH_1):PAGE111
  C9A2    1      A CAP_A_0402V-0.1UF,16V,10%,X7R,A    I10 @BASEBOARD_FAB2_LIB.BASEBOARD_FAB2(SCH_1):PAGE111
  J9A3   47   IO47 SCONN60_C21100002_SMLF-CONN,C2A    I26 @BASEBOARD_FAB2_LIB.BASEBOARD_FAB2(SCH_1):PAGE111
  U8D7  N11  PB21D LCMXO2_A_256BGA-IC,H63395-001   I179 @BASEBOARD_FAB2_LIB.BASEBOARD_FAB2(SCH_1):PAGE190

XDP_TDI @BASEBOARD_FAB2_LIB.BASEBOARD_FAB2(SCH_1):XDP_TDI
  J9A3   56   IO56 SCONN60_C21100002_SMLF-CONN,C2A    I26 @BASEBOARD_FAB2_LIB.BASEBOARD_FAB2(SCH_1):PAGE111
 R8A13    2      B RES_0402-150.0,1%,1/16W,CHIP,GA    I79 @BASEBOARD_FAB2_LIB.BASEBOARD_FAB2(SCH_1):PAGE112
  U1L1   12   A<0> TTL3126_QFNLF-74CBTLV3126,IC,DB   I108 @BASEBOARD_FAB2_LIB.BASEBOARD_FAB2(SCH_1):PAGE112
  U7C1 AN54 JTAG_TDI LBG_CORE_QAT_EXT_D_BGA1-IC,H91A    I73 @BASEBOARD_FAB2_LIB.BASEBOARD_FAB2(SCH_1):PAGE118

XDP_TDO @BASEBOARD_FAB2_LIB.BASEBOARD_FAB2(SCH_1):XDP_TDO
  J9A3   52   IO52 SCONN60_C21100002_SMLF-CONN,C2A    I26 @BASEBOARD_FAB2_LIB.BASEBOARD_FAB2(SCH_1):PAGE111
 R9A11    2      B RES_0402-150.0,1%,1/16W,CHIP,GA    I78 @BASEBOARD_FAB2_LIB.BASEBOARD_FAB2(SCH_1):PAGE112
  U1L1    9   A<1> TTL3126_QFNLF-74CBTLV3126,IC,DB   I108 @BASEBOARD_FAB2_LIB.BASEBOARD_FAB2(SCH_1):PAGE112
  U7C1 AP56 JTAG_TDO LBG_CORE_QAT_EXT_D_BGA1-IC,H91A    I73 @BASEBOARD_FAB2_LIB.BASEBOARD_FAB2(SCH_1):PAGE118

XDP_TMS @BASEBOARD_FAB2_LIB.BASEBOARD_FAB2(SCH_1):XDP_TMS
  J9A3   58   IO58 SCONN60_C21100002_SMLF-CONN,C2A    I26 @BASEBOARD_FAB2_LIB.BASEBOARD_FAB2(SCH_1):PAGE111
 R8A14    2      B RES_0402-150.0,1%,1/16W,CHIP,GA    I80 @BASEBOARD_FAB2_LIB.BASEBOARD_FAB2(SCH_1):PAGE112
  U1L1    5   A<2> TTL3126_QFNLF-74CBTLV3126,IC,DB   I108 @BASEBOARD_FAB2_LIB.BASEBOARD_FAB2(SCH_1):PAGE112
  U7C1 AH54 JTAG_TMS LBG_CORE_QAT_EXT_D_BGA1-IC,H91A    I73 @BASEBOARD_FAB2_LIB.BASEBOARD_FAB2(SCH_1):PAGE118

XDP_TRST_N @BASEBOARD_FAB2_LIB.BASEBOARD_FAB2(SCH_1):XDP_TRST_N
  J9A3   54   IO54 SCONN60_C21100002_SMLF-CONN,C2A    I26 @BASEBOARD_FAB2_LIB.BASEBOARD_FAB2(SCH_1):PAGE111
  R8B2    1      A RES_0402-1.00K,1%,1/16W,CHIP,GA    I94 @BASEBOARD_FAB2_LIB.BASEBOARD_FAB2(SCH_1):PAGE112
  U1L1    2   A<3> TTL3126_QFNLF-74CBTLV3126,IC,DB   I108 @BASEBOARD_FAB2_LIB.BASEBOARD_FAB2(SCH_1):PAGE112
  U7C1 AT56 CPU_TRST_N LBG_CORE_QAT_EXT_D_BGA1-IC,H91A    I73 @BASEBOARD_FAB2_LIB.BASEBOARD_FAB2(SCH_1):PAGE118

XTAL_24MHZ_IN_R @BASEBOARD_FAB2_LIB.BASEBOARD_FAB2(SCH_1):XTAL_24MHZ_IN_R
 EU9F3    9  XTAL1 PI7C9X1172_QFN-IC,H66899-001     I1 @BASEBOARD_FAB2_LIB.BASEBOARD_FAB2(SCH_1):PAGE183
 R9F58    2      B RES_0402-0.0,5%,1/16W,CHIP,G21A    I24 @BASEBOARD_FAB2_LIB.BASEBOARD_FAB2(SCH_1):PAGE183

XTAL_24MHZ_OUT_R @BASEBOARD_FAB2_LIB.BASEBOARD_FAB2(SCH_1):XTAL_24MHZ_OUT_R
 EU9F3   10  XTAL2 PI7C9X1172_QFN-IC,H66899-001     I1 @BASEBOARD_FAB2_LIB.BASEBOARD_FAB2(SCH_1):PAGE183
 R9F59    2      B RES_0402-0.0,5%,1/16W,CHIP,G21A    I25 @BASEBOARD_FAB2_LIB.BASEBOARD_FAB2(SCH_1):PAGE183

XTAL_24MHZ_PI7C9X1172_IN @BASEBOARD_FAB2_LIB.BASEBOARD_FAB2(SCH_1):XTAL_24MHZ_PI7C9X1172_IN
  Y9F1    1      A CRYSTAL_SM-24.000MHZ,IC,D95126A    I19 @BASEBOARD_FAB2_LIB.BASEBOARD_FAB2(SCH_1):PAGE183
 C9F20    1      A CAP_0402LF-12.0PF,50V,5%,COG,AA    I20 @BASEBOARD_FAB2_LIB.BASEBOARD_FAB2(SCH_1):PAGE183
 R9F58    1      A RES_0402-0.0,5%,1/16W,CHIP,G21A    I24 @BASEBOARD_FAB2_LIB.BASEBOARD_FAB2(SCH_1):PAGE183

XTAL_24MHZ_PI7C9X1172_OUT @BASEBOARD_FAB2_LIB.BASEBOARD_FAB2(SCH_1):XTAL_24MHZ_PI7C9X1172_OUT
  Y9F1    2      B CRYSTAL_SM-24.000MHZ,IC,D95126A    I19 @BASEBOARD_FAB2_LIB.BASEBOARD_FAB2(SCH_1):PAGE183
 C9F21    1      A CAP_0402LF-12.0PF,50V,5%,COG,AA    I21 @BASEBOARD_FAB2_LIB.BASEBOARD_FAB2(SCH_1):PAGE183
 R9F59    1      A RES_0402-0.0,5%,1/16W,CHIP,G21A    I25 @BASEBOARD_FAB2_LIB.BASEBOARD_FAB2(SCH_1):PAGE183

XTAL_25MHZ_IN @BASEBOARD_FAB2_LIB.BASEBOARD_FAB2(SCH_1):XTAL_25MHZ_IN
  Y9E1    1      A CRYSTAL_2013-25.000MHZ,IC,D717A   I109 @BASEBOARD_FAB2_LIB.BASEBOARD_FAB2(SCH_1):PAGE139
 R9E20    1      A RES_0402-0.0,5%,1/16W,CHIP,G21A   I110 @BASEBOARD_FAB2_LIB.BASEBOARD_FAB2(SCH_1):PAGE139
  C9E9    1      A CAP_0402LF-22.0PF,50V,5%,COG,AA   I112 @BASEBOARD_FAB2_LIB.BASEBOARD_FAB2(SCH_1):PAGE139

XTAL_25MHZ_IN_R @BASEBOARD_FAB2_LIB.BASEBOARD_FAB2(SCH_1):XTAL_25MHZ_IN_R
 EU9E1   46  XTAL1 SPRINGVILLE_SM1-IC,G47144-004    I72 @BASEBOARD_FAB2_LIB.BASEBOARD_FAB2(SCH_1):PAGE139
 R9E20    2      B RES_0402-0.0,5%,1/16W,CHIP,G21A   I110 @BASEBOARD_FAB2_LIB.BASEBOARD_FAB2(SCH_1):PAGE139

XTAL_25MHZ_OUT @BASEBOARD_FAB2_LIB.BASEBOARD_FAB2(SCH_1):XTAL_25MHZ_OUT
 EU9E1   45  XTAL2 SPRINGVILLE_SM1-IC,G47144-004    I72 @BASEBOARD_FAB2_LIB.BASEBOARD_FAB2(SCH_1):PAGE139
 R9E18    2      B RES_0402-0.0,5%,1/16W,CHIP,G21A   I201 @BASEBOARD_FAB2_LIB.BASEBOARD_FAB2(SCH_1):PAGE139

XTAL_25MHZ_OUT_R @BASEBOARD_FAB2_LIB.BASEBOARD_FAB2(SCH_1):XTAL_25MHZ_OUT_R
  Y9E1    3      B CRYSTAL_2013-25.000MHZ,IC,D717A   I109 @BASEBOARD_FAB2_LIB.BASEBOARD_FAB2(SCH_1):PAGE139
  C9E8    1      A CAP_0402LF-22.0PF,50V,5%,COG,AA   I111 @BASEBOARD_FAB2_LIB.BASEBOARD_FAB2(SCH_1):PAGE139
 R9E18    1      A RES_0402-0.0,5%,1/16W,CHIP,G21A   I201 @BASEBOARD_FAB2_LIB.BASEBOARD_FAB2(SCH_1):PAGE139

XTAL_33K_RTC1 @BASEBOARD_FAB2_LIB.BASEBOARD_FAB2(SCH_1):XTAL_33K_RTC1
  U7C1  K17  RTCX1 LBG_CORE_QAT_EXT_D_BGA1-IC,H91A    I40 @BASEBOARD_FAB2_LIB.BASEBOARD_FAB2(SCH_1):PAGE114
  R7C6    1      A RES_0603-10M,1.0%,1/10W,CHIP,GA    I54 @BASEBOARD_FAB2_LIB.BASEBOARD_FAB2(SCH_1):PAGE114
  Y7C2    1      A CRYSTAL_SM-32.768KHZ,IC,C13544A    I55 @BASEBOARD_FAB2_LIB.BASEBOARD_FAB2(SCH_1):PAGE114
 C7C13    1      A CAP_0402LF-18PF,50V,5%,C0G,A36A    I56 @BASEBOARD_FAB2_LIB.BASEBOARD_FAB2(SCH_1):PAGE114

XTAL_33K_RTC2 @BASEBOARD_FAB2_LIB.BASEBOARD_FAB2(SCH_1):XTAL_33K_RTC2
  U7C1  H17  RTCX2 LBG_CORE_QAT_EXT_D_BGA1-IC,H91A    I40 @BASEBOARD_FAB2_LIB.BASEBOARD_FAB2(SCH_1):PAGE114
 C7C15    1      A CAP_0402LF-18PF,50V,5%,C0G,A36A    I46 @BASEBOARD_FAB2_LIB.BASEBOARD_FAB2(SCH_1):PAGE114
  R7C6    2      B RES_0603-10M,1.0%,1/10W,CHIP,GA    I54 @BASEBOARD_FAB2_LIB.BASEBOARD_FAB2(SCH_1):PAGE114
  Y7C2    2      B CRYSTAL_SM-32.768KHZ,IC,C13544A    I55 @BASEBOARD_FAB2_LIB.BASEBOARD_FAB2(SCH_1):PAGE114

XTAL_CK_MNG_IN @BASEBOARD_FAB2_LIB.BASEBOARD_FAB2(SCH_1):XTAL_CK_MNG_IN
 EU8F2   19  X1_25 ICS9FGP204_MLFP-IC,E95226-001    I34 @BASEBOARD_FAB2_LIB.BASEBOARD_FAB2(SCH_1):PAGE101
 C8F18    1      A CAP_0402LF-27.0PF,50V,5%,COG,AA    I49 @BASEBOARD_FAB2_LIB.BASEBOARD_FAB2(SCH_1):PAGE101
  Y8F1    1      A CRYSTAL_2013LF-25.000MHZ,IC,D7B    I52 @BASEBOARD_FAB2_LIB.BASEBOARD_FAB2(SCH_1):PAGE101

XTAL_CK_MNG_OUT @BASEBOARD_FAB2_LIB.BASEBOARD_FAB2(SCH_1):XTAL_CK_MNG_OUT
 EU8F2   20  X2_25 ICS9FGP204_MLFP-IC,E95226-001    I34 @BASEBOARD_FAB2_LIB.BASEBOARD_FAB2(SCH_1):PAGE101
  Y8F1    3      B CRYSTAL_2013LF-25.000MHZ,IC,D7B    I52 @BASEBOARD_FAB2_LIB.BASEBOARD_FAB2(SCH_1):PAGE101
 C8F19    1      A CAP_0402LF-27.0PF,50V,5%,COG,AA    I53 @BASEBOARD_FAB2_LIB.BASEBOARD_FAB2(SCH_1):PAGE101

XTAL_KR_25M_IN @BASEBOARD_FAB2_LIB.BASEBOARD_FAB2(SCH_1):XTAL_KR_25M_IN
  U7C1 BV16 LAN_XTAL_IN LBG_CORE_QAT_EXT_D_BGA1-IC,H91A    I73 @BASEBOARD_FAB2_LIB.BASEBOARD_FAB2(SCH_1):PAGE118
  Y8C1    1      A CRYSTAL_2013-25.000MHZ,IC,H196A    I76 @BASEBOARD_FAB2_LIB.BASEBOARD_FAB2(SCH_1):PAGE118
  C8C1    1      A CAP_0402LF-33.0PF,50V,5%,COG,AA    I79 @BASEBOARD_FAB2_LIB.BASEBOARD_FAB2(SCH_1):PAGE118

XTAL_KR_25M_OUT @BASEBOARD_FAB2_LIB.BASEBOARD_FAB2(SCH_1):XTAL_KR_25M_OUT
  U7C1 BY16 LAN_XTAL_OUT LBG_CORE_QAT_EXT_D_BGA1-IC,H91A    I73 @BASEBOARD_FAB2_LIB.BASEBOARD_FAB2(SCH_1):PAGE118
  Y8C1    3      B CRYSTAL_2013-25.000MHZ,IC,H196A    I76 @BASEBOARD_FAB2_LIB.BASEBOARD_FAB2(SCH_1):PAGE118
  C8C2    1      A CAP_0402LF-33.0PF,50V,5%,COG,AA    I77 @BASEBOARD_FAB2_LIB.BASEBOARD_FAB2(SCH_1):PAGE118

XTAL_PCH_48M_IN @BASEBOARD_FAB2_LIB.BASEBOARD_FAB2(SCH_1):XTAL_PCH_48M_IN
  U7C1  B35 XTAL_IN LBG_CORE_QAT_EXT_D_BGA1-IC,H91A    I40 @BASEBOARD_FAB2_LIB.BASEBOARD_FAB2(SCH_1):PAGE114
  R7C1    1      A RES_0603-200K,0.1%,1/10W,CHIP,A    I48 @BASEBOARD_FAB2_LIB.BASEBOARD_FAB2(SCH_1):PAGE114
  Y7C1    1      A CRYSTAL_2013-48.000MHZ,IC,D717A    I49 @BASEBOARD_FAB2_LIB.BASEBOARD_FAB2(SCH_1):PAGE114
  C7C4    1      A CAP_0402LF-15.0PF,50V,5%,COG,AA    I50 @BASEBOARD_FAB2_LIB.BASEBOARD_FAB2(SCH_1):PAGE114

XTAL_PCH_48M_OUT @BASEBOARD_FAB2_LIB.BASEBOARD_FAB2(SCH_1):XTAL_PCH_48M_OUT
  U7C1  D35 XTAL_OUT LBG_CORE_QAT_EXT_D_BGA1-IC,H91A    I40 @BASEBOARD_FAB2_LIB.BASEBOARD_FAB2(SCH_1):PAGE114
  C7C5    1      A CAP_0402LF-15.0PF,50V,5%,COG,AA    I47 @BASEBOARD_FAB2_LIB.BASEBOARD_FAB2(SCH_1):PAGE114
  R7C1    2      B RES_0603-200K,0.1%,1/10W,CHIP,A    I48 @BASEBOARD_FAB2_LIB.BASEBOARD_FAB2(SCH_1):PAGE114
  Y7C1    3      B CRYSTAL_2013-48.000MHZ,IC,D717A    I49 @BASEBOARD_FAB2_LIB.BASEBOARD_FAB2(SCH_1):PAGE114

END GLOBAL SIGNAL CROSS REFERENCE
GLOBAL PART CROSS REFERENCE - 30-Nov-2015 AT 15:33:22

BT8G1 BATTERY_PLCLF-202168-001

C1A1 CAP_0805LF-22UF,4V,20%,X6S,C95A
     1 PVDDQ_KLM @BASEBOARD_FAB2_LIB.BASEBOARD_FAB2(SCH_1):PVDDQ_KLM    I68 @BASEBOARD_FAB2_LIB.BASEBOARD_FAB2(SCH_1):PAGE227
     2    GND @BASEBOARD_FAB2_LIB.BASEBOARD_FAB2(SCH_1):GND    I68 @BASEBOARD_FAB2_LIB.BASEBOARD_FAB2(SCH_1):PAGE227

C1A2 CAP_A_0402V-1.0UF,6.3V,10%,X6SA
     1 P5V_STBY @BASEBOARD_FAB2_LIB.BASEBOARD_FAB2(SCH_1):P5V_STBY    I53 @BASEBOARD_FAB2_LIB.BASEBOARD_FAB2(SCH_1):PAGE227
     2    GND @BASEBOARD_FAB2_LIB.BASEBOARD_FAB2(SCH_1):GND    I53 @BASEBOARD_FAB2_LIB.BASEBOARD_FAB2(SCH_1):PAGE227

C1A4 CAP_0805-10UF,16V,10%,X7R,G106A
     1 P12V_NVDIMM_KLM @BASEBOARD_FAB2_LIB.BASEBOARD_FAB2(SCH_1):P12V_NVDIMM_KLM    I79 @BASEBOARD_FAB2_LIB.BASEBOARD_FAB2(SCH_1):PAGE197
     2    GND @BASEBOARD_FAB2_LIB.BASEBOARD_FAB2(SCH_1):GND    I79 @BASEBOARD_FAB2_LIB.BASEBOARD_FAB2(SCH_1):PAGE197

C1A5 CAP_A_0402V-0.01UF,25V,10%,X7RA
     1 M_M_VREF @BASEBOARD_FAB2_LIB.BASEBOARD_FAB2(SCH_1):M_M_VREF   I178 @BASEBOARD_FAB2_LIB.BASEBOARD_FAB2(SCH_1):PAGE87
     2    GND @BASEBOARD_FAB2_LIB.BASEBOARD_FAB2(SCH_1):GND   I178 @BASEBOARD_FAB2_LIB.BASEBOARD_FAB2(SCH_1):PAGE87

C1A6 CAP_0402-1.0UF,16V,10%,X6S,D97A
     1 VR_PVDDQ_KLM_PH2_VCIN @BASEBOARD_FAB2_LIB.BASEBOARD_FAB2(SCH_1):VR_PVDDQ_KLM_PH2_VCIN    I77 @BASEBOARD_FAB2_LIB.BASEBOARD_FAB2(SCH_1):PAGE227
     2    GND @BASEBOARD_FAB2_LIB.BASEBOARD_FAB2(SCH_1):GND    I77 @BASEBOARD_FAB2_LIB.BASEBOARD_FAB2(SCH_1):PAGE227

C1A8 CAP_0402-0.220UF,16V,10%,X7R,AA
     1 VR_PVDDQ_KLM_PH2_BOOT @BASEBOARD_FAB2_LIB.BASEBOARD_FAB2(SCH_1):VR_PVDDQ_KLM_PH2_BOOT    I75 @BASEBOARD_FAB2_LIB.BASEBOARD_FAB2(SCH_1):PAGE227
     2 VR_PVDDQ_KLM_PH2_PHASE @BASEBOARD_FAB2_LIB.BASEBOARD_FAB2(SCH_1):VR_PVDDQ_KLM_PH2_PHASE    I75 @BASEBOARD_FAB2_LIB.BASEBOARD_FAB2(SCH_1):PAGE227

C1A9 CAP_0402-1.0UF,16V,10%,X6S,D97A
     1 VR_FET_SW_P12V_STBY_PVDDQ_KLM @BASEBOARD_FAB2_LIB.BASEBOARD_FAB2(SCH_1):VR_FET_SW_P12V_STBY_PVDDQ_KLM    I79 @BASEBOARD_FAB2_LIB.BASEBOARD_FAB2(SCH_1):PAGE227
     2    GND @BASEBOARD_FAB2_LIB.BASEBOARD_FAB2(SCH_1):GND    I79 @BASEBOARD_FAB2_LIB.BASEBOARD_FAB2(SCH_1):PAGE227

C1A10 CAP_A_0402V-0.1UF,16V,10%,X7R,A
     1 VR_FET_SW_P12V_STBY_PVDDQ_KLM @BASEBOARD_FAB2_LIB.BASEBOARD_FAB2(SCH_1):VR_FET_SW_P12V_STBY_PVDDQ_KLM    I51 @BASEBOARD_FAB2_LIB.BASEBOARD_FAB2(SCH_1):PAGE227
     2    GND @BASEBOARD_FAB2_LIB.BASEBOARD_FAB2(SCH_1):GND    I51 @BASEBOARD_FAB2_LIB.BASEBOARD_FAB2(SCH_1):PAGE227

C1A11 CAP_A_0402V-1.0UF,6.3V,10%,X6SA
     1 P5V_STBY @BASEBOARD_FAB2_LIB.BASEBOARD_FAB2(SCH_1):P5V_STBY    I73 @BASEBOARD_FAB2_LIB.BASEBOARD_FAB2(SCH_1):PAGE227
     2    GND @BASEBOARD_FAB2_LIB.BASEBOARD_FAB2(SCH_1):GND    I73 @BASEBOARD_FAB2_LIB.BASEBOARD_FAB2(SCH_1):PAGE227

C1A12 CAP_0805LF-22UF,4V,20%,X6S,C95A
     1 PVDDQ_KLM @BASEBOARD_FAB2_LIB.BASEBOARD_FAB2(SCH_1):PVDDQ_KLM     I6 @BASEBOARD_FAB2_LIB.BASEBOARD_FAB2(SCH_1):PAGE227
     2    GND @BASEBOARD_FAB2_LIB.BASEBOARD_FAB2(SCH_1):GND     I6 @BASEBOARD_FAB2_LIB.BASEBOARD_FAB2(SCH_1):PAGE227

C1A13 CAP_0402-0.22UF,16V,10%,X7R,A3A
     1 P5V_STBY @BASEBOARD_FAB2_LIB.BASEBOARD_FAB2(SCH_1):P5V_STBY    I72 @BASEBOARD_FAB2_LIB.BASEBOARD_FAB2(SCH_1):PAGE227
     2    GND @BASEBOARD_FAB2_LIB.BASEBOARD_FAB2(SCH_1):GND    I72 @BASEBOARD_FAB2_LIB.BASEBOARD_FAB2(SCH_1):PAGE227

C1A16 CAP_0805-10UF,16V,10%,X7R,G106A
     1 P12V_NVDIMM_KLM @BASEBOARD_FAB2_LIB.BASEBOARD_FAB2(SCH_1):P12V_NVDIMM_KLM    I85 @BASEBOARD_FAB2_LIB.BASEBOARD_FAB2(SCH_1):PAGE197
     2    GND @BASEBOARD_FAB2_LIB.BASEBOARD_FAB2(SCH_1):GND    I85 @BASEBOARD_FAB2_LIB.BASEBOARD_FAB2(SCH_1):PAGE197

C1A17 CAP_A_0402V-0.01UF,25V,10%,X7RA
     1 M_L_VREF @BASEBOARD_FAB2_LIB.BASEBOARD_FAB2(SCH_1):M_L_VREF   I182 @BASEBOARD_FAB2_LIB.BASEBOARD_FAB2(SCH_1):PAGE86
     2    GND @BASEBOARD_FAB2_LIB.BASEBOARD_FAB2(SCH_1):GND   I182 @BASEBOARD_FAB2_LIB.BASEBOARD_FAB2(SCH_1):PAGE86

C1A18 CAP_0402-0.220UF,16V,10%,X7R,AA
     1 VR_PVDDQ_KLM_PH1_BOOT @BASEBOARD_FAB2_LIB.BASEBOARD_FAB2(SCH_1):VR_PVDDQ_KLM_PH1_BOOT    I44 @BASEBOARD_FAB2_LIB.BASEBOARD_FAB2(SCH_1):PAGE227
     2 VR_PVDDQ_KLM_PH1_PHASE @BASEBOARD_FAB2_LIB.BASEBOARD_FAB2(SCH_1):VR_PVDDQ_KLM_PH1_PHASE    I44 @BASEBOARD_FAB2_LIB.BASEBOARD_FAB2(SCH_1):PAGE227

C1A19 CAP_0402-1.0UF,16V,10%,X6S,D97A
     1 VR_FET_SW_P12V_STBY_PVDDQ_KLM @BASEBOARD_FAB2_LIB.BASEBOARD_FAB2(SCH_1):VR_FET_SW_P12V_STBY_PVDDQ_KLM    I48 @BASEBOARD_FAB2_LIB.BASEBOARD_FAB2(SCH_1):PAGE227
     2    GND @BASEBOARD_FAB2_LIB.BASEBOARD_FAB2(SCH_1):GND    I48 @BASEBOARD_FAB2_LIB.BASEBOARD_FAB2(SCH_1):PAGE227

C1A20 CAP_A_0402V-0.1UF,16V,10%,X7R,A
     1 VR_FET_SW_P12V_STBY_PVDDQ_KLM @BASEBOARD_FAB2_LIB.BASEBOARD_FAB2(SCH_1):VR_FET_SW_P12V_STBY_PVDDQ_KLM    I78 @BASEBOARD_FAB2_LIB.BASEBOARD_FAB2(SCH_1):PAGE227
     2    GND @BASEBOARD_FAB2_LIB.BASEBOARD_FAB2(SCH_1):GND    I78 @BASEBOARD_FAB2_LIB.BASEBOARD_FAB2(SCH_1):PAGE227

C1B2 CAP_A_0402V-0.1UF,16V,10%,X7R,A
     1 VR_PVDDQ_KLM_VD12 @BASEBOARD_FAB2_LIB.BASEBOARD_FAB2(SCH_1):VR_PVDDQ_KLM_VD12    I44 @BASEBOARD_FAB2_LIB.BASEBOARD_FAB2(SCH_1):PAGE226
     2    GND @BASEBOARD_FAB2_LIB.BASEBOARD_FAB2(SCH_1):GND    I44 @BASEBOARD_FAB2_LIB.BASEBOARD_FAB2(SCH_1):PAGE226

C1B3 CAP_A_0402V-1.0UF,6.3V,10%,X6SA
     1 VR_PVDDQ_KLM_VD12 @BASEBOARD_FAB2_LIB.BASEBOARD_FAB2(SCH_1):VR_PVDDQ_KLM_VD12    I41 @BASEBOARD_FAB2_LIB.BASEBOARD_FAB2(SCH_1):PAGE226
     2    GND @BASEBOARD_FAB2_LIB.BASEBOARD_FAB2(SCH_1):GND    I41 @BASEBOARD_FAB2_LIB.BASEBOARD_FAB2(SCH_1):PAGE226

C1B4 CAP_0402LF-1000PF,50V,10%,X7R,A
     1 PWRGD_PVDDQ_KLM_R @BASEBOARD_FAB2_LIB.BASEBOARD_FAB2(SCH_1):PWRGD_PVDDQ_KLM_R    I80 @BASEBOARD_FAB2_LIB.BASEBOARD_FAB2(SCH_1):PAGE226
     2    GND @BASEBOARD_FAB2_LIB.BASEBOARD_FAB2(SCH_1):GND    I80 @BASEBOARD_FAB2_LIB.BASEBOARD_FAB2(SCH_1):PAGE226

C1B5 CAP_A_0402V-0.1UF,16V,10%,X7R,A
     1 VR_PVDDQ_KLM_VDD @BASEBOARD_FAB2_LIB.BASEBOARD_FAB2(SCH_1):VR_PVDDQ_KLM_VDD    I27 @BASEBOARD_FAB2_LIB.BASEBOARD_FAB2(SCH_1):PAGE226
     2    GND @BASEBOARD_FAB2_LIB.BASEBOARD_FAB2(SCH_1):GND    I27 @BASEBOARD_FAB2_LIB.BASEBOARD_FAB2(SCH_1):PAGE226

C1B6 CAP_A_0402V-1.0UF,6.3V,10%,X6SA
     1 VR_PVDDQ_KLM_VDD @BASEBOARD_FAB2_LIB.BASEBOARD_FAB2(SCH_1):VR_PVDDQ_KLM_VDD    I25 @BASEBOARD_FAB2_LIB.BASEBOARD_FAB2(SCH_1):PAGE226
     2    GND @BASEBOARD_FAB2_LIB.BASEBOARD_FAB2(SCH_1):GND    I25 @BASEBOARD_FAB2_LIB.BASEBOARD_FAB2(SCH_1):PAGE226

C1B7 CAP_0805-10UF,16V,10%,X7R,G106A
     1 P12V_NVDIMM_KLM @BASEBOARD_FAB2_LIB.BASEBOARD_FAB2(SCH_1):P12V_NVDIMM_KLM    I82 @BASEBOARD_FAB2_LIB.BASEBOARD_FAB2(SCH_1):PAGE197
     2    GND @BASEBOARD_FAB2_LIB.BASEBOARD_FAB2(SCH_1):GND    I82 @BASEBOARD_FAB2_LIB.BASEBOARD_FAB2(SCH_1):PAGE197

C1B8 CAP_0402LF-1000PF,50V,10%,X7R,A
     1 VR_PVDDQ_KLM_VINSEN @BASEBOARD_FAB2_LIB.BASEBOARD_FAB2(SCH_1):VR_PVDDQ_KLM_VINSEN    I59 @BASEBOARD_FAB2_LIB.BASEBOARD_FAB2(SCH_1):PAGE226
     2    GND @BASEBOARD_FAB2_LIB.BASEBOARD_FAB2(SCH_1):GND    I59 @BASEBOARD_FAB2_LIB.BASEBOARD_FAB2(SCH_1):PAGE226

C1B9 CAP_A_0402V-0.01UF,25V,10%,X7RA
     1 M_K_VREF @BASEBOARD_FAB2_LIB.BASEBOARD_FAB2(SCH_1):M_K_VREF   I176 @BASEBOARD_FAB2_LIB.BASEBOARD_FAB2(SCH_1):PAGE83
     2    GND @BASEBOARD_FAB2_LIB.BASEBOARD_FAB2(SCH_1):GND   I176 @BASEBOARD_FAB2_LIB.BASEBOARD_FAB2(SCH_1):PAGE83

C1B10 CAPP_2626-270UF,16V,20%,OSCON,A
     1 VR_FET_SW_P12V_STBY_PVDDQ_KLM @BASEBOARD_FAB2_LIB.BASEBOARD_FAB2(SCH_1):VR_FET_SW_P12V_STBY_PVDDQ_KLM   I175 @BASEBOARD_FAB2_LIB.BASEBOARD_FAB2(SCH_1):PAGE228
     2    GND @BASEBOARD_FAB2_LIB.BASEBOARD_FAB2(SCH_1):GND   I175 @BASEBOARD_FAB2_LIB.BASEBOARD_FAB2(SCH_1):PAGE228

C1B11 CAP_0402LF-220PF,50V,10%,X7R,AA
     1 A_TSENSE_PVDDQ_KLM @BASEBOARD_FAB2_LIB.BASEBOARD_FAB2(SCH_1):A_TSENSE_PVDDQ_KLM    I36 @BASEBOARD_FAB2_LIB.BASEBOARD_FAB2(SCH_1):PAGE226
     2    GND @BASEBOARD_FAB2_LIB.BASEBOARD_FAB2(SCH_1):GND    I36 @BASEBOARD_FAB2_LIB.BASEBOARD_FAB2(SCH_1):PAGE226

C1B12 CAP_0402LF-220PF,50V,10%,X7R,AA
     1 VR_PVDDQ_KLM_AVSP @BASEBOARD_FAB2_LIB.BASEBOARD_FAB2(SCH_1):VR_PVDDQ_KLM_AVSP    I39 @BASEBOARD_FAB2_LIB.BASEBOARD_FAB2(SCH_1):PAGE226
     2 VSENSE_PVDDQ_KLM_N @BASEBOARD_FAB2_LIB.BASEBOARD_FAB2(SCH_1):VSENSE_PVDDQ_KLM_N    I39 @BASEBOARD_FAB2_LIB.BASEBOARD_FAB2(SCH_1):PAGE226

C1B14 CAPP_4040LF-470UF,16V,20%,ALUMA
     1 P12V_STBY @BASEBOARD_FAB2_LIB.BASEBOARD_FAB2(SCH_1):P12V_STBY    I84 @BASEBOARD_FAB2_LIB.BASEBOARD_FAB2(SCH_1):PAGE195
     2    GND @BASEBOARD_FAB2_LIB.BASEBOARD_FAB2(SCH_1):GND    I84 @BASEBOARD_FAB2_LIB.BASEBOARD_FAB2(SCH_1):PAGE195

C1B15 CAP_A_0402V-0.01UF,25V,10%,X7RA
     1 FAN_TACH2 @BASEBOARD_FAB2_LIB.BASEBOARD_FAB2(SCH_1):FAN_TACH2    I68 @BASEBOARD_FAB2_LIB.BASEBOARD_FAB2(SCH_1):PAGE161
     2    GND @BASEBOARD_FAB2_LIB.BASEBOARD_FAB2(SCH_1):GND    I68 @BASEBOARD_FAB2_LIB.BASEBOARD_FAB2(SCH_1):PAGE161

C1B16 CAP_A_0402V-0.1UF,16V,10%,EMPTA
     1 VR_FET_SW_P12V_PVCCIN_CPU1_R @BASEBOARD_FAB2_LIB.BASEBOARD_FAB2(SCH_1):VR_FET_SW_P12V_PVCCIN_CPU1_R    I30 @BASEBOARD_FAB2_LIB.BASEBOARD_FAB2(SCH_1):PAGE209
     2    GND @BASEBOARD_FAB2_LIB.BASEBOARD_FAB2(SCH_1):GND    I30 @BASEBOARD_FAB2_LIB.BASEBOARD_FAB2(SCH_1):PAGE209

C1B17 CAP_A_0402V-0.01UF,25V,10%,X7RA
     1 FAN_TACH3 @BASEBOARD_FAB2_LIB.BASEBOARD_FAB2(SCH_1):FAN_TACH3   I128 @BASEBOARD_FAB2_LIB.BASEBOARD_FAB2(SCH_1):PAGE161
     2    GND @BASEBOARD_FAB2_LIB.BASEBOARD_FAB2(SCH_1):GND   I128 @BASEBOARD_FAB2_LIB.BASEBOARD_FAB2(SCH_1):PAGE161

C1B18 CAP_0805-10UF,16V,10%,X6S,C953A
     1 P12V_FAN @BASEBOARD_FAB2_LIB.BASEBOARD_FAB2(SCH_1):P12V_FAN    I61 @BASEBOARD_FAB2_LIB.BASEBOARD_FAB2(SCH_1):PAGE198
     2    GND @BASEBOARD_FAB2_LIB.BASEBOARD_FAB2(SCH_1):GND    I61 @BASEBOARD_FAB2_LIB.BASEBOARD_FAB2(SCH_1):PAGE198

C1B19 CAP_A_0402V-0.1UF,16V,10%,X7R,A
     1 P12V_FAN @BASEBOARD_FAB2_LIB.BASEBOARD_FAB2(SCH_1):P12V_FAN    I64 @BASEBOARD_FAB2_LIB.BASEBOARD_FAB2(SCH_1):PAGE198
     2    GND @BASEBOARD_FAB2_LIB.BASEBOARD_FAB2(SCH_1):GND    I64 @BASEBOARD_FAB2_LIB.BASEBOARD_FAB2(SCH_1):PAGE198

C1B20 CAP_0402-1.0UF,16V,10%,X6S,D97A
     1 VR_PVDDQ_KLM_PH1_VCIN @BASEBOARD_FAB2_LIB.BASEBOARD_FAB2(SCH_1):VR_PVDDQ_KLM_PH1_VCIN    I50 @BASEBOARD_FAB2_LIB.BASEBOARD_FAB2(SCH_1):PAGE227
     2    GND @BASEBOARD_FAB2_LIB.BASEBOARD_FAB2(SCH_1):GND    I50 @BASEBOARD_FAB2_LIB.BASEBOARD_FAB2(SCH_1):PAGE227

C1B21 CAP_0402-0.22UF,16V,10%,X7R,A3A
     1 P5V_STBY @BASEBOARD_FAB2_LIB.BASEBOARD_FAB2(SCH_1):P5V_STBY    I54 @BASEBOARD_FAB2_LIB.BASEBOARD_FAB2(SCH_1):PAGE227
     2    GND @BASEBOARD_FAB2_LIB.BASEBOARD_FAB2(SCH_1):GND    I54 @BASEBOARD_FAB2_LIB.BASEBOARD_FAB2(SCH_1):PAGE227

C1C1 CAPP_2626-270UF,16V,20%,OSCON,A
     1 VR_FET_SW_P12V_STBY_PVCCIN_CPU1 @BASEBOARD_FAB2_LIB.BASEBOARD_FAB2(SCH_1):VR_FET_SW_P12V_STBY_PVCCIN_CPU1    I35 @BASEBOARD_FAB2_LIB.BASEBOARD_FAB2(SCH_1):PAGE209
     2    GND @BASEBOARD_FAB2_LIB.BASEBOARD_FAB2(SCH_1):GND    I35 @BASEBOARD_FAB2_LIB.BASEBOARD_FAB2(SCH_1):PAGE209

C1C2 CAPP_2626-270UF,16V,20%,OSCON,A
     1 VR_FET_SW_P12V_STBY_PVCCIN_CPU1 @BASEBOARD_FAB2_LIB.BASEBOARD_FAB2(SCH_1):VR_FET_SW_P12V_STBY_PVCCIN_CPU1    I38 @BASEBOARD_FAB2_LIB.BASEBOARD_FAB2(SCH_1):PAGE209
     2    GND @BASEBOARD_FAB2_LIB.BASEBOARD_FAB2(SCH_1):GND    I38 @BASEBOARD_FAB2_LIB.BASEBOARD_FAB2(SCH_1):PAGE209

C1C3 CAP_A_0402V-1.0UF,6.3V,10%,X6SA
     1 P5V_STBY @BASEBOARD_FAB2_LIB.BASEBOARD_FAB2(SCH_1):P5V_STBY    I23 @BASEBOARD_FAB2_LIB.BASEBOARD_FAB2(SCH_1):PAGE210
     2    GND @BASEBOARD_FAB2_LIB.BASEBOARD_FAB2(SCH_1):GND    I23 @BASEBOARD_FAB2_LIB.BASEBOARD_FAB2(SCH_1):PAGE210

C1C4 CAP_0402-0.22UF,16V,10%,X7R,A3A
     1 P5V_STBY @BASEBOARD_FAB2_LIB.BASEBOARD_FAB2(SCH_1):P5V_STBY    I22 @BASEBOARD_FAB2_LIB.BASEBOARD_FAB2(SCH_1):PAGE210
     2    GND @BASEBOARD_FAB2_LIB.BASEBOARD_FAB2(SCH_1):GND    I22 @BASEBOARD_FAB2_LIB.BASEBOARD_FAB2(SCH_1):PAGE210

C1C5 CAP_0402-1.0UF,16V,10%,X6S,D97A
     1 VR_PVSA_CPU1_VCIN @BASEBOARD_FAB2_LIB.BASEBOARD_FAB2(SCH_1):VR_PVSA_CPU1_VCIN    I26 @BASEBOARD_FAB2_LIB.BASEBOARD_FAB2(SCH_1):PAGE210
     2    GND @BASEBOARD_FAB2_LIB.BASEBOARD_FAB2(SCH_1):GND    I26 @BASEBOARD_FAB2_LIB.BASEBOARD_FAB2(SCH_1):PAGE210

C1C7 CAP_A_0402V-1.0UF,6.3V,10%,X6SA
     1 VR_PVCCIN_CPU1_VDD @BASEBOARD_FAB2_LIB.BASEBOARD_FAB2(SCH_1):VR_PVCCIN_CPU1_VDD    I41 @BASEBOARD_FAB2_LIB.BASEBOARD_FAB2(SCH_1):PAGE206
     2    GND @BASEBOARD_FAB2_LIB.BASEBOARD_FAB2(SCH_1):GND    I41 @BASEBOARD_FAB2_LIB.BASEBOARD_FAB2(SCH_1):PAGE206

C1C8 CAP_0402LF-1000PF,50V,10%,X7R,A
     1 VR_PVCCIN_CPU1_AVINSEN @BASEBOARD_FAB2_LIB.BASEBOARD_FAB2(SCH_1):VR_PVCCIN_CPU1_AVINSEN    I73 @BASEBOARD_FAB2_LIB.BASEBOARD_FAB2(SCH_1):PAGE206
     2    GND @BASEBOARD_FAB2_LIB.BASEBOARD_FAB2(SCH_1):GND    I73 @BASEBOARD_FAB2_LIB.BASEBOARD_FAB2(SCH_1):PAGE206

C1C9 CAP_A_0402V-0.1UF,16V,10%,X7R,A
     1 VR_PVCCIN_CPU1_VDD @BASEBOARD_FAB2_LIB.BASEBOARD_FAB2(SCH_1):VR_PVCCIN_CPU1_VDD    I42 @BASEBOARD_FAB2_LIB.BASEBOARD_FAB2(SCH_1):PAGE206
     2    GND @BASEBOARD_FAB2_LIB.BASEBOARD_FAB2(SCH_1):GND    I42 @BASEBOARD_FAB2_LIB.BASEBOARD_FAB2(SCH_1):PAGE206

C1C10 CAP_0402LF-220PF,50V,10%,X7R,AA
     1 A_TSENSE_PVCCIN_CPU1 @BASEBOARD_FAB2_LIB.BASEBOARD_FAB2(SCH_1):A_TSENSE_PVCCIN_CPU1    I69 @BASEBOARD_FAB2_LIB.BASEBOARD_FAB2(SCH_1):PAGE206
     2    GND @BASEBOARD_FAB2_LIB.BASEBOARD_FAB2(SCH_1):GND    I69 @BASEBOARD_FAB2_LIB.BASEBOARD_FAB2(SCH_1):PAGE206

C1C11 CAP_0402LF-220PF,50V,10%,X7R,AA
     1 A_TSENSE_PVSA_CPU1 @BASEBOARD_FAB2_LIB.BASEBOARD_FAB2(SCH_1):A_TSENSE_PVSA_CPU1    I71 @BASEBOARD_FAB2_LIB.BASEBOARD_FAB2(SCH_1):PAGE206
     2    GND @BASEBOARD_FAB2_LIB.BASEBOARD_FAB2(SCH_1):GND    I71 @BASEBOARD_FAB2_LIB.BASEBOARD_FAB2(SCH_1):PAGE206

C1C12 CAP_0402-0.220UF,16V,10%,X7R,AA
     1 VR_PVSA_CPU1_BOOT @BASEBOARD_FAB2_LIB.BASEBOARD_FAB2(SCH_1):VR_PVSA_CPU1_BOOT    I24 @BASEBOARD_FAB2_LIB.BASEBOARD_FAB2(SCH_1):PAGE210
     2 VR_PVSA_CPU1_PHASE @BASEBOARD_FAB2_LIB.BASEBOARD_FAB2(SCH_1):VR_PVSA_CPU1_PHASE    I24 @BASEBOARD_FAB2_LIB.BASEBOARD_FAB2(SCH_1):PAGE210

C1C13 CAP_A_0402V-1.0UF,6.3V,10%,X6SA
     1 VR_PVCCIN_CPU1_VD12 @BASEBOARD_FAB2_LIB.BASEBOARD_FAB2(SCH_1):VR_PVCCIN_CPU1_VD12    I29 @BASEBOARD_FAB2_LIB.BASEBOARD_FAB2(SCH_1):PAGE206
     2    GND @BASEBOARD_FAB2_LIB.BASEBOARD_FAB2(SCH_1):GND    I29 @BASEBOARD_FAB2_LIB.BASEBOARD_FAB2(SCH_1):PAGE206

C1C14 CAP_A_0402V-0.1UF,16V,10%,X7R,A
     1 VR_PVCCIN_CPU1_VD12 @BASEBOARD_FAB2_LIB.BASEBOARD_FAB2(SCH_1):VR_PVCCIN_CPU1_VD12    I31 @BASEBOARD_FAB2_LIB.BASEBOARD_FAB2(SCH_1):PAGE206
     2    GND @BASEBOARD_FAB2_LIB.BASEBOARD_FAB2(SCH_1):GND    I31 @BASEBOARD_FAB2_LIB.BASEBOARD_FAB2(SCH_1):PAGE206

C1C15 CAP_0402-1.0UF,16V,10%,X6S,D97A
     1 VR_FET_SW_P12V_STBY_PVCCIN_CPU1 @BASEBOARD_FAB2_LIB.BASEBOARD_FAB2(SCH_1):VR_FET_SW_P12V_STBY_PVCCIN_CPU1    I28 @BASEBOARD_FAB2_LIB.BASEBOARD_FAB2(SCH_1):PAGE210
     2    GND @BASEBOARD_FAB2_LIB.BASEBOARD_FAB2(SCH_1):GND    I28 @BASEBOARD_FAB2_LIB.BASEBOARD_FAB2(SCH_1):PAGE210

C1C16 CAP_0402LF-220PF,50V,10%,X7R,AA
     1 VSENSE_PVSA_CPU1_BVSP @BASEBOARD_FAB2_LIB.BASEBOARD_FAB2(SCH_1):VSENSE_PVSA_CPU1_BVSP    I68 @BASEBOARD_FAB2_LIB.BASEBOARD_FAB2(SCH_1):PAGE206
     2 VSENSE_PVSA_CPU1_N @BASEBOARD_FAB2_LIB.BASEBOARD_FAB2(SCH_1):VSENSE_PVSA_CPU1_N    I68 @BASEBOARD_FAB2_LIB.BASEBOARD_FAB2(SCH_1):PAGE206

C1C17 CAP_A_0402V-0.1UF,16V,10%,X7R,A
     1 VR_FET_SW_P12V_STBY_PVCCIN_CPU1 @BASEBOARD_FAB2_LIB.BASEBOARD_FAB2(SCH_1):VR_FET_SW_P12V_STBY_PVCCIN_CPU1    I27 @BASEBOARD_FAB2_LIB.BASEBOARD_FAB2(SCH_1):PAGE210
     2    GND @BASEBOARD_FAB2_LIB.BASEBOARD_FAB2(SCH_1):GND    I27 @BASEBOARD_FAB2_LIB.BASEBOARD_FAB2(SCH_1):PAGE210

C1C18 CAP_A_0402V-1.0UF,6.3V,10%,X6SA
     1 P5V_STBY @BASEBOARD_FAB2_LIB.BASEBOARD_FAB2(SCH_1):P5V_STBY    I21 @BASEBOARD_FAB2_LIB.BASEBOARD_FAB2(SCH_1):PAGE209
     2    GND @BASEBOARD_FAB2_LIB.BASEBOARD_FAB2(SCH_1):GND    I21 @BASEBOARD_FAB2_LIB.BASEBOARD_FAB2(SCH_1):PAGE209

C1C19 CAP_A_0603V-22.0UF,4V,20%,X6S,A
     1 PVSA_CPU1 @BASEBOARD_FAB2_LIB.BASEBOARD_FAB2(SCH_1):PVSA_CPU1     I8 @BASEBOARD_FAB2_LIB.BASEBOARD_FAB2(SCH_1):PAGE210
     2    GND @BASEBOARD_FAB2_LIB.BASEBOARD_FAB2(SCH_1):GND     I8 @BASEBOARD_FAB2_LIB.BASEBOARD_FAB2(SCH_1):PAGE210

C1C23 CAP_0402LF-1000PF,50V,10%,X7R,A
     1 VR_VRRDY_PVCCIN_CPU1 @BASEBOARD_FAB2_LIB.BASEBOARD_FAB2(SCH_1):VR_VRRDY_PVCCIN_CPU1   I114 @BASEBOARD_FAB2_LIB.BASEBOARD_FAB2(SCH_1):PAGE206
     2    GND @BASEBOARD_FAB2_LIB.BASEBOARD_FAB2(SCH_1):GND   I114 @BASEBOARD_FAB2_LIB.BASEBOARD_FAB2(SCH_1):PAGE206

C1C24 CAP_0402-0.220UF,16V,10%,X7R,AA
     1 VR_PVCCIN_CPU1_PH5_BOOT @BASEBOARD_FAB2_LIB.BASEBOARD_FAB2(SCH_1):VR_PVCCIN_CPU1_PH5_BOOT    I20 @BASEBOARD_FAB2_LIB.BASEBOARD_FAB2(SCH_1):PAGE209
     2 VR_PVCCIN_CPU1_PH5_PHASE @BASEBOARD_FAB2_LIB.BASEBOARD_FAB2(SCH_1):VR_PVCCIN_CPU1_PH5_PHASE    I20 @BASEBOARD_FAB2_LIB.BASEBOARD_FAB2(SCH_1):PAGE209

C1C25 CAP_A_0402V-0.1UF,16V,10%,X7R,A
     1 VR_FET_SW_P12V_STBY_PVCCIN_CPU1 @BASEBOARD_FAB2_LIB.BASEBOARD_FAB2(SCH_1):VR_FET_SW_P12V_STBY_PVCCIN_CPU1    I17 @BASEBOARD_FAB2_LIB.BASEBOARD_FAB2(SCH_1):PAGE209
     2    GND @BASEBOARD_FAB2_LIB.BASEBOARD_FAB2(SCH_1):GND    I17 @BASEBOARD_FAB2_LIB.BASEBOARD_FAB2(SCH_1):PAGE209

C1C26 CAP_0402-1.0UF,16V,10%,X6S,D97A
     1 VR_FET_SW_P12V_STBY_PVCCIN_CPU1 @BASEBOARD_FAB2_LIB.BASEBOARD_FAB2(SCH_1):VR_FET_SW_P12V_STBY_PVCCIN_CPU1    I16 @BASEBOARD_FAB2_LIB.BASEBOARD_FAB2(SCH_1):PAGE209
     2    GND @BASEBOARD_FAB2_LIB.BASEBOARD_FAB2(SCH_1):GND    I16 @BASEBOARD_FAB2_LIB.BASEBOARD_FAB2(SCH_1):PAGE209

C1D1 CAP_0402LF-220PF,50V,10%,X7R,AA
     1 VSENSE_PVCCIN_CPU1_AVSP @BASEBOARD_FAB2_LIB.BASEBOARD_FAB2(SCH_1):VSENSE_PVCCIN_CPU1_AVSP    I78 @BASEBOARD_FAB2_LIB.BASEBOARD_FAB2(SCH_1):PAGE206
     2 VSENSE_PVCCIN_CPU1_N @BASEBOARD_FAB2_LIB.BASEBOARD_FAB2(SCH_1):VSENSE_PVCCIN_CPU1_N    I78 @BASEBOARD_FAB2_LIB.BASEBOARD_FAB2(SCH_1):PAGE206

C1D3 CAP_A_0603V-22.0UF,4V,20%,X6S,A
     1 PVCCIN_CPU1 @BASEBOARD_FAB2_LIB.BASEBOARD_FAB2(SCH_1):PVCCIN_CPU1    I22 @BASEBOARD_FAB2_LIB.BASEBOARD_FAB2(SCH_1):PAGE208
     2    GND @BASEBOARD_FAB2_LIB.BASEBOARD_FAB2(SCH_1):GND    I22 @BASEBOARD_FAB2_LIB.BASEBOARD_FAB2(SCH_1):PAGE208

C1D5 CAP_A_0402V-1.0UF,6.3V,10%,X6SA
     1 P5V_STBY @BASEBOARD_FAB2_LIB.BASEBOARD_FAB2(SCH_1):P5V_STBY    I47 @BASEBOARD_FAB2_LIB.BASEBOARD_FAB2(SCH_1):PAGE208
     2    GND @BASEBOARD_FAB2_LIB.BASEBOARD_FAB2(SCH_1):GND    I47 @BASEBOARD_FAB2_LIB.BASEBOARD_FAB2(SCH_1):PAGE208

C1D6 CAP_0402-0.22UF,16V,10%,X7R,A3A
     1 P5V_STBY @BASEBOARD_FAB2_LIB.BASEBOARD_FAB2(SCH_1):P5V_STBY    I46 @BASEBOARD_FAB2_LIB.BASEBOARD_FAB2(SCH_1):PAGE208
     2    GND @BASEBOARD_FAB2_LIB.BASEBOARD_FAB2(SCH_1):GND    I46 @BASEBOARD_FAB2_LIB.BASEBOARD_FAB2(SCH_1):PAGE208

C1D7 CAP_0402-1.0UF,16V,10%,X6S,D97A
     1 VR_PVCCIN_CPU1_PH4_VCIN @BASEBOARD_FAB2_LIB.BASEBOARD_FAB2(SCH_1):VR_PVCCIN_CPU1_PH4_VCIN    I50 @BASEBOARD_FAB2_LIB.BASEBOARD_FAB2(SCH_1):PAGE208
     2    GND @BASEBOARD_FAB2_LIB.BASEBOARD_FAB2(SCH_1):GND    I50 @BASEBOARD_FAB2_LIB.BASEBOARD_FAB2(SCH_1):PAGE208

C1D9 CAP_A_0402V-0.1UF,16V,10%,X7R,A
     1 P12V_STBY @BASEBOARD_FAB2_LIB.BASEBOARD_FAB2(SCH_1):P12V_STBY   I187 @BASEBOARD_FAB2_LIB.BASEBOARD_FAB2(SCH_1):PAGE200
     2 AGND_HSC @BASEBOARD_FAB2_LIB.BASEBOARD_FAB2(SCH_1):AGND_HSC   I187 @BASEBOARD_FAB2_LIB.BASEBOARD_FAB2(SCH_1):PAGE200

C1D10 CAP_0402-0.220UF,16V,10%,X7R,AA
     1 VR_PVCCIN_CPU1_PH4_BOOT @BASEBOARD_FAB2_LIB.BASEBOARD_FAB2(SCH_1):VR_PVCCIN_CPU1_PH4_BOOT    I48 @BASEBOARD_FAB2_LIB.BASEBOARD_FAB2(SCH_1):PAGE208
     2 VR_PVCCIN_CPU1_PH4_PHASE @BASEBOARD_FAB2_LIB.BASEBOARD_FAB2(SCH_1):VR_PVCCIN_CPU1_PH4_PHASE    I48 @BASEBOARD_FAB2_LIB.BASEBOARD_FAB2(SCH_1):PAGE208

C1D11 CAP_A_0402V-0.1UF,16V,10%,X7R,A
     1 FM_P12V_HOTSWAP0_EN @BASEBOARD_FAB2_LIB.BASEBOARD_FAB2(SCH_1):FM_P12V_HOTSWAP0_EN    I53 @BASEBOARD_FAB2_LIB.BASEBOARD_FAB2(SCH_1):PAGE199
     2 AGND_HSC @BASEBOARD_FAB2_LIB.BASEBOARD_FAB2(SCH_1):AGND_HSC    I53 @BASEBOARD_FAB2_LIB.BASEBOARD_FAB2(SCH_1):PAGE199

C1D12 CAP_0402-1.0UF,16V,10%,X6S,D97A
     1 VR_FET_SW_P12V_STBY_PVCCIN_CPU1 @BASEBOARD_FAB2_LIB.BASEBOARD_FAB2(SCH_1):VR_FET_SW_P12V_STBY_PVCCIN_CPU1    I52 @BASEBOARD_FAB2_LIB.BASEBOARD_FAB2(SCH_1):PAGE208
     2    GND @BASEBOARD_FAB2_LIB.BASEBOARD_FAB2(SCH_1):GND    I52 @BASEBOARD_FAB2_LIB.BASEBOARD_FAB2(SCH_1):PAGE208

C1D13 CAP_A_0402V-0.1UF,16V,10%,X7R,A
     1 VR_FET_SW_P12V_STBY_PVCCIN_CPU1 @BASEBOARD_FAB2_LIB.BASEBOARD_FAB2(SCH_1):VR_FET_SW_P12V_STBY_PVCCIN_CPU1    I51 @BASEBOARD_FAB2_LIB.BASEBOARD_FAB2(SCH_1):PAGE208
     2    GND @BASEBOARD_FAB2_LIB.BASEBOARD_FAB2(SCH_1):GND    I51 @BASEBOARD_FAB2_LIB.BASEBOARD_FAB2(SCH_1):PAGE208

C1D14 CAP_A_0603V-22.0UF,4V,20%,X6S,A
     1 PVCCIN_CPU1 @BASEBOARD_FAB2_LIB.BASEBOARD_FAB2(SCH_1):PVCCIN_CPU1     I9 @BASEBOARD_FAB2_LIB.BASEBOARD_FAB2(SCH_1):PAGE208
     2    GND @BASEBOARD_FAB2_LIB.BASEBOARD_FAB2(SCH_1):GND     I9 @BASEBOARD_FAB2_LIB.BASEBOARD_FAB2(SCH_1):PAGE208

C1D15 CAP_A_0402V-1.0UF,6.3V,10%,X6SA
     1 P5V_STBY @BASEBOARD_FAB2_LIB.BASEBOARD_FAB2(SCH_1):P5V_STBY    I39 @BASEBOARD_FAB2_LIB.BASEBOARD_FAB2(SCH_1):PAGE208
     2    GND @BASEBOARD_FAB2_LIB.BASEBOARD_FAB2(SCH_1):GND    I39 @BASEBOARD_FAB2_LIB.BASEBOARD_FAB2(SCH_1):PAGE208

C1D16 CAP_0402-0.22UF,16V,10%,X7R,A3A
     1 P5V_STBY @BASEBOARD_FAB2_LIB.BASEBOARD_FAB2(SCH_1):P5V_STBY    I38 @BASEBOARD_FAB2_LIB.BASEBOARD_FAB2(SCH_1):PAGE208
     2    GND @BASEBOARD_FAB2_LIB.BASEBOARD_FAB2(SCH_1):GND    I38 @BASEBOARD_FAB2_LIB.BASEBOARD_FAB2(SCH_1):PAGE208

C1D17 CAP_0402-1.0UF,16V,10%,X6S,D97A
     1 VR_PVCCIN_CPU1_PH3_VCIN @BASEBOARD_FAB2_LIB.BASEBOARD_FAB2(SCH_1):VR_PVCCIN_CPU1_PH3_VCIN    I43 @BASEBOARD_FAB2_LIB.BASEBOARD_FAB2(SCH_1):PAGE208
     2    GND @BASEBOARD_FAB2_LIB.BASEBOARD_FAB2(SCH_1):GND    I43 @BASEBOARD_FAB2_LIB.BASEBOARD_FAB2(SCH_1):PAGE208

C1D19 CAP_0402-1.0UF,16V,10%,X6S,D97A
     1 A_HSC_VCAP @BASEBOARD_FAB2_LIB.BASEBOARD_FAB2(SCH_1):A_HSC_VCAP   I119 @BASEBOARD_FAB2_LIB.BASEBOARD_FAB2(SCH_1):PAGE199
     2 AGND_HSC @BASEBOARD_FAB2_LIB.BASEBOARD_FAB2(SCH_1):AGND_HSC   I119 @BASEBOARD_FAB2_LIB.BASEBOARD_FAB2(SCH_1):PAGE199

C1D20 CAP_0402-0.220UF,16V,10%,X7R,AA
     1 VR_PVCCIN_CPU1_PH3_BOOT @BASEBOARD_FAB2_LIB.BASEBOARD_FAB2(SCH_1):VR_PVCCIN_CPU1_PH3_BOOT    I40 @BASEBOARD_FAB2_LIB.BASEBOARD_FAB2(SCH_1):PAGE208
     2 VR_PVCCIN_CPU1_PH3_PHASE @BASEBOARD_FAB2_LIB.BASEBOARD_FAB2(SCH_1):VR_PVCCIN_CPU1_PH3_PHASE    I40 @BASEBOARD_FAB2_LIB.BASEBOARD_FAB2(SCH_1):PAGE208

C1D21 CAP_A_0402V-0.1UF,16V,10%,X7R,A
     1 A_HSC_PSET @BASEBOARD_FAB2_LIB.BASEBOARD_FAB2(SCH_1):A_HSC_PSET   I121 @BASEBOARD_FAB2_LIB.BASEBOARD_FAB2(SCH_1):PAGE199
     2 AGND_HSC @BASEBOARD_FAB2_LIB.BASEBOARD_FAB2(SCH_1):AGND_HSC   I121 @BASEBOARD_FAB2_LIB.BASEBOARD_FAB2(SCH_1):PAGE199

C1D22 CAP_A_0402V-0.1UF,16V,10%,EMPTA
     1 A_HSC_MON @BASEBOARD_FAB2_LIB.BASEBOARD_FAB2(SCH_1):A_HSC_MON    I42 @BASEBOARD_FAB2_LIB.BASEBOARD_FAB2(SCH_1):PAGE200
     2 A_HSC_MOP @BASEBOARD_FAB2_LIB.BASEBOARD_FAB2(SCH_1):A_HSC_MOP    I42 @BASEBOARD_FAB2_LIB.BASEBOARD_FAB2(SCH_1):PAGE200

C1D23 CAP_0402-1.0UF,16V,10%,X6S,D97A
     1 VR_FET_SW_P12V_STBY_PVCCIN_CPU1 @BASEBOARD_FAB2_LIB.BASEBOARD_FAB2(SCH_1):VR_FET_SW_P12V_STBY_PVCCIN_CPU1    I45 @BASEBOARD_FAB2_LIB.BASEBOARD_FAB2(SCH_1):PAGE208
     2    GND @BASEBOARD_FAB2_LIB.BASEBOARD_FAB2(SCH_1):GND    I45 @BASEBOARD_FAB2_LIB.BASEBOARD_FAB2(SCH_1):PAGE208

C1D24 CAP_A_0603V-22.0UF,4V,20%,X6S,A
     1 PVCCIN_CPU1 @BASEBOARD_FAB2_LIB.BASEBOARD_FAB2(SCH_1):PVCCIN_CPU1    I42 @BASEBOARD_FAB2_LIB.BASEBOARD_FAB2(SCH_1):PAGE209
     2    GND @BASEBOARD_FAB2_LIB.BASEBOARD_FAB2(SCH_1):GND    I42 @BASEBOARD_FAB2_LIB.BASEBOARD_FAB2(SCH_1):PAGE209

C1D25 CAP_0402-1.0UF,16V,10%,X6S,D97A
     1 P12V_HSC_VCC @BASEBOARD_FAB2_LIB.BASEBOARD_FAB2(SCH_1):P12V_HSC_VCC     I3 @BASEBOARD_FAB2_LIB.BASEBOARD_FAB2(SCH_1):PAGE199
     2 AGND_HSC @BASEBOARD_FAB2_LIB.BASEBOARD_FAB2(SCH_1):AGND_HSC     I3 @BASEBOARD_FAB2_LIB.BASEBOARD_FAB2(SCH_1):PAGE199

C1D26 CAP_A_0402V-0.1UF,16V,10%,X7R,A
     1 A_HSC_UV @BASEBOARD_FAB2_LIB.BASEBOARD_FAB2(SCH_1):A_HSC_UV   I107 @BASEBOARD_FAB2_LIB.BASEBOARD_FAB2(SCH_1):PAGE199
     2 AGND_HSC @BASEBOARD_FAB2_LIB.BASEBOARD_FAB2(SCH_1):AGND_HSC   I107 @BASEBOARD_FAB2_LIB.BASEBOARD_FAB2(SCH_1):PAGE199

C1D27 CAP_A_0402V-0.1UF,16V,10%,X7R,A
     1 A_HSC_OV @BASEBOARD_FAB2_LIB.BASEBOARD_FAB2(SCH_1):A_HSC_OV     I7 @BASEBOARD_FAB2_LIB.BASEBOARD_FAB2(SCH_1):PAGE199
     2 AGND_HSC @BASEBOARD_FAB2_LIB.BASEBOARD_FAB2(SCH_1):AGND_HSC     I7 @BASEBOARD_FAB2_LIB.BASEBOARD_FAB2(SCH_1):PAGE199

C1D28 CAP_A_0402V-0.1UF,16V,10%,X7R,A
     1 VR_FET_SW_P12V_STBY_PVCCIN_CPU1 @BASEBOARD_FAB2_LIB.BASEBOARD_FAB2(SCH_1):VR_FET_SW_P12V_STBY_PVCCIN_CPU1    I44 @BASEBOARD_FAB2_LIB.BASEBOARD_FAB2(SCH_1):PAGE208
     2    GND @BASEBOARD_FAB2_LIB.BASEBOARD_FAB2(SCH_1):GND    I44 @BASEBOARD_FAB2_LIB.BASEBOARD_FAB2(SCH_1):PAGE208

C1D32 CAP_0402-1.0UF,16V,10%,X6S,D97A
     1 VR_PVCCIN_CPU1_PH5_VCIN @BASEBOARD_FAB2_LIB.BASEBOARD_FAB2(SCH_1):VR_PVCCIN_CPU1_PH5_VCIN    I18 @BASEBOARD_FAB2_LIB.BASEBOARD_FAB2(SCH_1):PAGE209
     2    GND @BASEBOARD_FAB2_LIB.BASEBOARD_FAB2(SCH_1):GND    I18 @BASEBOARD_FAB2_LIB.BASEBOARD_FAB2(SCH_1):PAGE209

C1D33 CAP_0402-0.22UF,16V,10%,X7R,A3A
     1 P5V_STBY @BASEBOARD_FAB2_LIB.BASEBOARD_FAB2(SCH_1):P5V_STBY    I22 @BASEBOARD_FAB2_LIB.BASEBOARD_FAB2(SCH_1):PAGE209
     2    GND @BASEBOARD_FAB2_LIB.BASEBOARD_FAB2(SCH_1):GND    I22 @BASEBOARD_FAB2_LIB.BASEBOARD_FAB2(SCH_1):PAGE209

C1D34 CAP_A_0402V-0.1UF,16V,10%,X7R,A
     1 VR_FET_SW_P12V_STBY_PVCCIN_CPU1 @BASEBOARD_FAB2_LIB.BASEBOARD_FAB2(SCH_1):VR_FET_SW_P12V_STBY_PVCCIN_CPU1    I41 @BASEBOARD_FAB2_LIB.BASEBOARD_FAB2(SCH_1):PAGE207
     2    GND @BASEBOARD_FAB2_LIB.BASEBOARD_FAB2(SCH_1):GND    I41 @BASEBOARD_FAB2_LIB.BASEBOARD_FAB2(SCH_1):PAGE207

C1D35 CAP_0402-1.0UF,16V,10%,X6S,D97A
     1 VR_FET_SW_P12V_STBY_PVCCIN_CPU1 @BASEBOARD_FAB2_LIB.BASEBOARD_FAB2(SCH_1):VR_FET_SW_P12V_STBY_PVCCIN_CPU1    I42 @BASEBOARD_FAB2_LIB.BASEBOARD_FAB2(SCH_1):PAGE207
     2    GND @BASEBOARD_FAB2_LIB.BASEBOARD_FAB2(SCH_1):GND    I42 @BASEBOARD_FAB2_LIB.BASEBOARD_FAB2(SCH_1):PAGE207

C1D36 CAP_0402-0.220UF,16V,10%,X7R,AA
     1 VR_PVCCIN_CPU1_PH2_BOOT @BASEBOARD_FAB2_LIB.BASEBOARD_FAB2(SCH_1):VR_PVCCIN_CPU1_PH2_BOOT    I38 @BASEBOARD_FAB2_LIB.BASEBOARD_FAB2(SCH_1):PAGE207
     2 VR_PVCCIN_CPU1_PH2_PHASE @BASEBOARD_FAB2_LIB.BASEBOARD_FAB2(SCH_1):VR_PVCCIN_CPU1_PH2_PHASE    I38 @BASEBOARD_FAB2_LIB.BASEBOARD_FAB2(SCH_1):PAGE207

C1E2 CAP_1206-0.068UF,50V,20%,X7R,1A
     1 A_HSC_C @BASEBOARD_FAB2_LIB.BASEBOARD_FAB2(SCH_1):A_HSC_C   I155 @BASEBOARD_FAB2_LIB.BASEBOARD_FAB2(SCH_1):PAGE200
     2    GND @BASEBOARD_FAB2_LIB.BASEBOARD_FAB2(SCH_1):GND   I155 @BASEBOARD_FAB2_LIB.BASEBOARD_FAB2(SCH_1):PAGE200

C1E3 CAP_A_0603V-22.0UF,4V,20%,X6S,A
     1 PVCCIN_CPU1 @BASEBOARD_FAB2_LIB.BASEBOARD_FAB2(SCH_1):PVCCIN_CPU1    I18 @BASEBOARD_FAB2_LIB.BASEBOARD_FAB2(SCH_1):PAGE207
     2    GND @BASEBOARD_FAB2_LIB.BASEBOARD_FAB2(SCH_1):GND    I18 @BASEBOARD_FAB2_LIB.BASEBOARD_FAB2(SCH_1):PAGE207

C1E6 CAP_A_0402V-1.0UF,6.3V,10%,X6SA
     1 P5V_STBY @BASEBOARD_FAB2_LIB.BASEBOARD_FAB2(SCH_1):P5V_STBY    I29 @BASEBOARD_FAB2_LIB.BASEBOARD_FAB2(SCH_1):PAGE207
     2    GND @BASEBOARD_FAB2_LIB.BASEBOARD_FAB2(SCH_1):GND    I29 @BASEBOARD_FAB2_LIB.BASEBOARD_FAB2(SCH_1):PAGE207

C1E7 CAP_0402-0.22UF,16V,10%,X7R,A3A
     1 P5V_STBY @BASEBOARD_FAB2_LIB.BASEBOARD_FAB2(SCH_1):P5V_STBY    I28 @BASEBOARD_FAB2_LIB.BASEBOARD_FAB2(SCH_1):PAGE207
     2    GND @BASEBOARD_FAB2_LIB.BASEBOARD_FAB2(SCH_1):GND    I28 @BASEBOARD_FAB2_LIB.BASEBOARD_FAB2(SCH_1):PAGE207

C1E8 CAP_0402-1.0UF,16V,10%,X6S,D97A
     1 VR_PVCCIN_CPU1_PH1_VCIN @BASEBOARD_FAB2_LIB.BASEBOARD_FAB2(SCH_1):VR_PVCCIN_CPU1_PH1_VCIN    I32 @BASEBOARD_FAB2_LIB.BASEBOARD_FAB2(SCH_1):PAGE207
     2    GND @BASEBOARD_FAB2_LIB.BASEBOARD_FAB2(SCH_1):GND    I32 @BASEBOARD_FAB2_LIB.BASEBOARD_FAB2(SCH_1):PAGE207

C1E9 CAP_A_0603V-22.0UF,4V,20%,X6S,A
     1 PVCCIN_CPU1 @BASEBOARD_FAB2_LIB.BASEBOARD_FAB2(SCH_1):PVCCIN_CPU1    I58 @BASEBOARD_FAB2_LIB.BASEBOARD_FAB2(SCH_1):PAGE207
     2    GND @BASEBOARD_FAB2_LIB.BASEBOARD_FAB2(SCH_1):GND    I58 @BASEBOARD_FAB2_LIB.BASEBOARD_FAB2(SCH_1):PAGE207

C1E11 CAP_0402-0.220UF,16V,10%,X7R,AA
     1 VR_PVCCIN_CPU1_PH1_BOOT @BASEBOARD_FAB2_LIB.BASEBOARD_FAB2(SCH_1):VR_PVCCIN_CPU1_PH1_BOOT    I30 @BASEBOARD_FAB2_LIB.BASEBOARD_FAB2(SCH_1):PAGE207
     2 VR_PVCCIN_CPU1_PH1_PHASE @BASEBOARD_FAB2_LIB.BASEBOARD_FAB2(SCH_1):VR_PVCCIN_CPU1_PH1_PHASE    I30 @BASEBOARD_FAB2_LIB.BASEBOARD_FAB2(SCH_1):PAGE207

C1E12 CAP_0805-10UF,16V,10%,X6S,C953A
     1 P12V_PSU @BASEBOARD_FAB2_LIB.BASEBOARD_FAB2(SCH_1):P12V_PSU    I32 @BASEBOARD_FAB2_LIB.BASEBOARD_FAB2(SCH_1):PAGE195
     2    GND @BASEBOARD_FAB2_LIB.BASEBOARD_FAB2(SCH_1):GND    I32 @BASEBOARD_FAB2_LIB.BASEBOARD_FAB2(SCH_1):PAGE195

C1E13 CAP_0402-1.0UF,16V,10%,X6S,D97A
     1 VR_FET_SW_P12V_STBY_PVCCIN_CPU1 @BASEBOARD_FAB2_LIB.BASEBOARD_FAB2(SCH_1):VR_FET_SW_P12V_STBY_PVCCIN_CPU1    I34 @BASEBOARD_FAB2_LIB.BASEBOARD_FAB2(SCH_1):PAGE207
     2    GND @BASEBOARD_FAB2_LIB.BASEBOARD_FAB2(SCH_1):GND    I34 @BASEBOARD_FAB2_LIB.BASEBOARD_FAB2(SCH_1):PAGE207

C1E14 CAP_A_0402V-0.1UF,16V,10%,X7R,A
     1 VR_FET_SW_P12V_STBY_PVCCIN_CPU1 @BASEBOARD_FAB2_LIB.BASEBOARD_FAB2(SCH_1):VR_FET_SW_P12V_STBY_PVCCIN_CPU1    I33 @BASEBOARD_FAB2_LIB.BASEBOARD_FAB2(SCH_1):PAGE207
     2    GND @BASEBOARD_FAB2_LIB.BASEBOARD_FAB2(SCH_1):GND    I33 @BASEBOARD_FAB2_LIB.BASEBOARD_FAB2(SCH_1):PAGE207

C1E15 CAP_0805-10UF,16V,10%,X6S,C953A
     1 P12V_PSU @BASEBOARD_FAB2_LIB.BASEBOARD_FAB2(SCH_1):P12V_PSU    I35 @BASEBOARD_FAB2_LIB.BASEBOARD_FAB2(SCH_1):PAGE195
     2    GND @BASEBOARD_FAB2_LIB.BASEBOARD_FAB2(SCH_1):GND    I35 @BASEBOARD_FAB2_LIB.BASEBOARD_FAB2(SCH_1):PAGE195

C1E16 CAP_A_0402V-0.1UF,16V,10%,X7R,A
     1 P12V_PSU @BASEBOARD_FAB2_LIB.BASEBOARD_FAB2(SCH_1):P12V_PSU    I39 @BASEBOARD_FAB2_LIB.BASEBOARD_FAB2(SCH_1):PAGE195
     2    GND @BASEBOARD_FAB2_LIB.BASEBOARD_FAB2(SCH_1):GND    I39 @BASEBOARD_FAB2_LIB.BASEBOARD_FAB2(SCH_1):PAGE195

C1E17 CAP_A_0402V-0.1UF,16V,10%,X7R,A
     1 P12V_PSU @BASEBOARD_FAB2_LIB.BASEBOARD_FAB2(SCH_1):P12V_PSU    I38 @BASEBOARD_FAB2_LIB.BASEBOARD_FAB2(SCH_1):PAGE195
     2    GND @BASEBOARD_FAB2_LIB.BASEBOARD_FAB2(SCH_1):GND    I38 @BASEBOARD_FAB2_LIB.BASEBOARD_FAB2(SCH_1):PAGE195

C1E18 CAPP_2626-270UF,16V,20%,OSCON,A
     1 VR_FET_SW_P12V_STBY_PVCCIN_CPU1 @BASEBOARD_FAB2_LIB.BASEBOARD_FAB2(SCH_1):VR_FET_SW_P12V_STBY_PVCCIN_CPU1    I37 @BASEBOARD_FAB2_LIB.BASEBOARD_FAB2(SCH_1):PAGE209
     2    GND @BASEBOARD_FAB2_LIB.BASEBOARD_FAB2(SCH_1):GND    I37 @BASEBOARD_FAB2_LIB.BASEBOARD_FAB2(SCH_1):PAGE209

C1E19 CAP_0402LF-47.0PF,50V,5%,EMPTYA
     1 ISENSE_TMP421_2_DXP @BASEBOARD_FAB2_LIB.BASEBOARD_FAB2(SCH_1):ISENSE_TMP421_2_DXP    I24 @BASEBOARD_FAB2_LIB.BASEBOARD_FAB2(SCH_1):PAGE167
     2 ISENSE_TMP421_2_DXN @BASEBOARD_FAB2_LIB.BASEBOARD_FAB2(SCH_1):ISENSE_TMP421_2_DXN    I24 @BASEBOARD_FAB2_LIB.BASEBOARD_FAB2(SCH_1):PAGE167

C1E20 CAP_A_0402V-0.1UF,16V,10%,X7R,A
     1 P12V_FAN @BASEBOARD_FAB2_LIB.BASEBOARD_FAB2(SCH_1):P12V_FAN     I4 @BASEBOARD_FAB2_LIB.BASEBOARD_FAB2(SCH_1):PAGE161
     2    GND @BASEBOARD_FAB2_LIB.BASEBOARD_FAB2(SCH_1):GND     I4 @BASEBOARD_FAB2_LIB.BASEBOARD_FAB2(SCH_1):PAGE161

C1E21 CAP_0805-10UF,16V,10%,X6S,C953A
     1 P12V_FAN @BASEBOARD_FAB2_LIB.BASEBOARD_FAB2(SCH_1):P12V_FAN     I3 @BASEBOARD_FAB2_LIB.BASEBOARD_FAB2(SCH_1):PAGE161
     2    GND @BASEBOARD_FAB2_LIB.BASEBOARD_FAB2(SCH_1):GND     I3 @BASEBOARD_FAB2_LIB.BASEBOARD_FAB2(SCH_1):PAGE161

C1E22 CAP_A_0402V-0.1UF,16V,10%,X7R,A
     1 P3V3_STBY @BASEBOARD_FAB2_LIB.BASEBOARD_FAB2(SCH_1):P3V3_STBY   I113 @BASEBOARD_FAB2_LIB.BASEBOARD_FAB2(SCH_1):PAGE161
     2    GND @BASEBOARD_FAB2_LIB.BASEBOARD_FAB2(SCH_1):GND   I113 @BASEBOARD_FAB2_LIB.BASEBOARD_FAB2(SCH_1):PAGE161

C1E23 CAP_A_0402V-1.0UF,6.3V,10%,X6SA
     1 P5V_STBY @BASEBOARD_FAB2_LIB.BASEBOARD_FAB2(SCH_1):P5V_STBY    I37 @BASEBOARD_FAB2_LIB.BASEBOARD_FAB2(SCH_1):PAGE207
     2    GND @BASEBOARD_FAB2_LIB.BASEBOARD_FAB2(SCH_1):GND    I37 @BASEBOARD_FAB2_LIB.BASEBOARD_FAB2(SCH_1):PAGE207

C1E24 CAP_0402-1.0UF,16V,10%,X6S,D97A
     1 VR_PVCCIN_CPU1_PH2_VCIN @BASEBOARD_FAB2_LIB.BASEBOARD_FAB2(SCH_1):VR_PVCCIN_CPU1_PH2_VCIN    I40 @BASEBOARD_FAB2_LIB.BASEBOARD_FAB2(SCH_1):PAGE207
     2    GND @BASEBOARD_FAB2_LIB.BASEBOARD_FAB2(SCH_1):GND    I40 @BASEBOARD_FAB2_LIB.BASEBOARD_FAB2(SCH_1):PAGE207

C1E25 CAP_0402-0.22UF,16V,10%,X7R,A3A
     1 P5V_STBY @BASEBOARD_FAB2_LIB.BASEBOARD_FAB2(SCH_1):P5V_STBY    I36 @BASEBOARD_FAB2_LIB.BASEBOARD_FAB2(SCH_1):PAGE207
     2    GND @BASEBOARD_FAB2_LIB.BASEBOARD_FAB2(SCH_1):GND    I36 @BASEBOARD_FAB2_LIB.BASEBOARD_FAB2(SCH_1):PAGE207

C1F2 CAP_0402-0.22UF,16V,10%,X7R,A3A
     1 P3E_CPU1_PE3_MP_C_TXP<7> @BASEBOARD_FAB2_LIB.BASEBOARD_FAB2(SCH_1):P3E_CPU1_PE3_MP_C_TXP(7)   I162 @BASEBOARD_FAB2_LIB.BASEBOARD_FAB2(SCH_1):PAGE181
     2 P3E_CPU1_PE3_MP_TXP<7> @BASEBOARD_FAB2_LIB.BASEBOARD_FAB2(SCH_1):P3E_CPU1_PE3_MP_TXP(7)   I162 @BASEBOARD_FAB2_LIB.BASEBOARD_FAB2(SCH_1):PAGE181

C1F3 CAP_0402-0.22UF,16V,10%,X7R,A3A
     1 P3E_CPU1_PE3_MP_C_TXN<7> @BASEBOARD_FAB2_LIB.BASEBOARD_FAB2(SCH_1):P3E_CPU1_PE3_MP_C_TXN(7)   I167 @BASEBOARD_FAB2_LIB.BASEBOARD_FAB2(SCH_1):PAGE181
     2 P3E_CPU1_PE3_MP_TXN<7> @BASEBOARD_FAB2_LIB.BASEBOARD_FAB2(SCH_1):P3E_CPU1_PE3_MP_TXN(7)   I167 @BASEBOARD_FAB2_LIB.BASEBOARD_FAB2(SCH_1):PAGE181

C1F4 CAP_0402-0.22UF,16V,10%,X7R,A3A
     1 P3E_CPU1_PE3_MP_C_TXN<6> @BASEBOARD_FAB2_LIB.BASEBOARD_FAB2(SCH_1):P3E_CPU1_PE3_MP_C_TXN(6)   I160 @BASEBOARD_FAB2_LIB.BASEBOARD_FAB2(SCH_1):PAGE181
     2 P3E_CPU1_PE3_MP_TXN<6> @BASEBOARD_FAB2_LIB.BASEBOARD_FAB2(SCH_1):P3E_CPU1_PE3_MP_TXN(6)   I160 @BASEBOARD_FAB2_LIB.BASEBOARD_FAB2(SCH_1):PAGE181

C1F5 CAP_0402-0.22UF,16V,10%,X7R,A3A
     1 P3E_CPU1_PE3_MP_C_TXP<6> @BASEBOARD_FAB2_LIB.BASEBOARD_FAB2(SCH_1):P3E_CPU1_PE3_MP_C_TXP(6)   I161 @BASEBOARD_FAB2_LIB.BASEBOARD_FAB2(SCH_1):PAGE181
     2 P3E_CPU1_PE3_MP_TXP<6> @BASEBOARD_FAB2_LIB.BASEBOARD_FAB2(SCH_1):P3E_CPU1_PE3_MP_TXP(6)   I161 @BASEBOARD_FAB2_LIB.BASEBOARD_FAB2(SCH_1):PAGE181

C1F6 CAP_0402-0.22UF,16V,10%,X7R,A3A
     1 P3E_CPU1_PE3_MP_C_TXP<5> @BASEBOARD_FAB2_LIB.BASEBOARD_FAB2(SCH_1):P3E_CPU1_PE3_MP_C_TXP(5)   I165 @BASEBOARD_FAB2_LIB.BASEBOARD_FAB2(SCH_1):PAGE181
     2 P3E_CPU1_PE3_MP_TXP<5> @BASEBOARD_FAB2_LIB.BASEBOARD_FAB2(SCH_1):P3E_CPU1_PE3_MP_TXP(5)   I165 @BASEBOARD_FAB2_LIB.BASEBOARD_FAB2(SCH_1):PAGE181

C1F7 CAPP_4040LF-470UF,16V,20%,ALUMA
     1 P12V_STBY @BASEBOARD_FAB2_LIB.BASEBOARD_FAB2(SCH_1):P12V_STBY    I85 @BASEBOARD_FAB2_LIB.BASEBOARD_FAB2(SCH_1):PAGE195
     2    GND @BASEBOARD_FAB2_LIB.BASEBOARD_FAB2(SCH_1):GND    I85 @BASEBOARD_FAB2_LIB.BASEBOARD_FAB2(SCH_1):PAGE195

C1F8 CAP_0402-0.22UF,16V,10%,X7R,A3A
     1 P3E_CPU1_PE3_MP_C_TXN<5> @BASEBOARD_FAB2_LIB.BASEBOARD_FAB2(SCH_1):P3E_CPU1_PE3_MP_C_TXN(5)   I170 @BASEBOARD_FAB2_LIB.BASEBOARD_FAB2(SCH_1):PAGE181
     2 P3E_CPU1_PE3_MP_TXN<5> @BASEBOARD_FAB2_LIB.BASEBOARD_FAB2(SCH_1):P3E_CPU1_PE3_MP_TXN(5)   I170 @BASEBOARD_FAB2_LIB.BASEBOARD_FAB2(SCH_1):PAGE181

C1F9 CAP_A_0402V-0.01UF,25V,10%,X7RA
     1 FAN_TACH0 @BASEBOARD_FAB2_LIB.BASEBOARD_FAB2(SCH_1):FAN_TACH0    I46 @BASEBOARD_FAB2_LIB.BASEBOARD_FAB2(SCH_1):PAGE161
     2    GND @BASEBOARD_FAB2_LIB.BASEBOARD_FAB2(SCH_1):GND    I46 @BASEBOARD_FAB2_LIB.BASEBOARD_FAB2(SCH_1):PAGE161

C1F10 CAP_0402-0.22UF,16V,10%,X7R,A3A
     1 P3E_CPU1_PE3_MP_C_TXN<4> @BASEBOARD_FAB2_LIB.BASEBOARD_FAB2(SCH_1):P3E_CPU1_PE3_MP_C_TXN(4)   I164 @BASEBOARD_FAB2_LIB.BASEBOARD_FAB2(SCH_1):PAGE181
     2 P3E_CPU1_PE3_MP_TXN<4> @BASEBOARD_FAB2_LIB.BASEBOARD_FAB2(SCH_1):P3E_CPU1_PE3_MP_TXN(4)   I164 @BASEBOARD_FAB2_LIB.BASEBOARD_FAB2(SCH_1):PAGE181

C1F11 CAP_0402-0.22UF,16V,10%,X7R,A3A
     1 P3E_CPU1_PE3_MP_C_TXP<4> @BASEBOARD_FAB2_LIB.BASEBOARD_FAB2(SCH_1):P3E_CPU1_PE3_MP_C_TXP(4)   I169 @BASEBOARD_FAB2_LIB.BASEBOARD_FAB2(SCH_1):PAGE181
     2 P3E_CPU1_PE3_MP_TXP<4> @BASEBOARD_FAB2_LIB.BASEBOARD_FAB2(SCH_1):P3E_CPU1_PE3_MP_TXP(4)   I169 @BASEBOARD_FAB2_LIB.BASEBOARD_FAB2(SCH_1):PAGE181

C1F12 CAP_0402-0.22UF,16V,10%,X7R,A3A
     1 P3E_CPU1_PE3_MP_C_TXP<3> @BASEBOARD_FAB2_LIB.BASEBOARD_FAB2(SCH_1):P3E_CPU1_PE3_MP_C_TXP(3)   I168 @BASEBOARD_FAB2_LIB.BASEBOARD_FAB2(SCH_1):PAGE181
     2 P3E_CPU1_PE3_MP_TXP<3> @BASEBOARD_FAB2_LIB.BASEBOARD_FAB2(SCH_1):P3E_CPU1_PE3_MP_TXP(3)   I168 @BASEBOARD_FAB2_LIB.BASEBOARD_FAB2(SCH_1):PAGE181

C1F13 CAP_0402-0.22UF,16V,10%,X7R,A3A
     1 P3E_CPU1_PE3_MP_C_TXN<3> @BASEBOARD_FAB2_LIB.BASEBOARD_FAB2(SCH_1):P3E_CPU1_PE3_MP_C_TXN(3)   I163 @BASEBOARD_FAB2_LIB.BASEBOARD_FAB2(SCH_1):PAGE181
     2 P3E_CPU1_PE3_MP_TXN<3> @BASEBOARD_FAB2_LIB.BASEBOARD_FAB2(SCH_1):P3E_CPU1_PE3_MP_TXN(3)   I163 @BASEBOARD_FAB2_LIB.BASEBOARD_FAB2(SCH_1):PAGE181

C1F14 CAP_0402-0.22UF,16V,10%,X7R,A3A
     1 P3E_CPU1_PE3_MP_C_TXP<2> @BASEBOARD_FAB2_LIB.BASEBOARD_FAB2(SCH_1):P3E_CPU1_PE3_MP_C_TXP(2)   I175 @BASEBOARD_FAB2_LIB.BASEBOARD_FAB2(SCH_1):PAGE181
     2 P3E_CPU1_PE3_MP_TXP<2> @BASEBOARD_FAB2_LIB.BASEBOARD_FAB2(SCH_1):P3E_CPU1_PE3_MP_TXP(2)   I175 @BASEBOARD_FAB2_LIB.BASEBOARD_FAB2(SCH_1):PAGE181

C1F15 CAP_0402-0.22UF,16V,10%,X7R,A3A
     1 P3E_CPU1_PE3_MP_C_TXN<2> @BASEBOARD_FAB2_LIB.BASEBOARD_FAB2(SCH_1):P3E_CPU1_PE3_MP_C_TXN(2)   I174 @BASEBOARD_FAB2_LIB.BASEBOARD_FAB2(SCH_1):PAGE181
     2 P3E_CPU1_PE3_MP_TXN<2> @BASEBOARD_FAB2_LIB.BASEBOARD_FAB2(SCH_1):P3E_CPU1_PE3_MP_TXN(2)   I174 @BASEBOARD_FAB2_LIB.BASEBOARD_FAB2(SCH_1):PAGE181

C1F16 CAP_0402-0.22UF,16V,10%,X7R,A3A
     1 P3E_CPU1_PE3_MP_C_TXN<1> @BASEBOARD_FAB2_LIB.BASEBOARD_FAB2(SCH_1):P3E_CPU1_PE3_MP_C_TXN(1)   I172 @BASEBOARD_FAB2_LIB.BASEBOARD_FAB2(SCH_1):PAGE181
     2 P3E_CPU1_PE3_MP_TXN<1> @BASEBOARD_FAB2_LIB.BASEBOARD_FAB2(SCH_1):P3E_CPU1_PE3_MP_TXN(1)   I172 @BASEBOARD_FAB2_LIB.BASEBOARD_FAB2(SCH_1):PAGE181

C1F17 CAP_0402-0.22UF,16V,10%,X7R,A3A
     1 P3E_CPU1_PE3_MP_C_TXP<1> @BASEBOARD_FAB2_LIB.BASEBOARD_FAB2(SCH_1):P3E_CPU1_PE3_MP_C_TXP(1)   I173 @BASEBOARD_FAB2_LIB.BASEBOARD_FAB2(SCH_1):PAGE181
     2 P3E_CPU1_PE3_MP_TXP<1> @BASEBOARD_FAB2_LIB.BASEBOARD_FAB2(SCH_1):P3E_CPU1_PE3_MP_TXP(1)   I173 @BASEBOARD_FAB2_LIB.BASEBOARD_FAB2(SCH_1):PAGE181

C1F18 CAP_0402-0.22UF,16V,10%,X7R,A3A
     1 P3E_CPU1_PE3_MP_C_TXP<0> @BASEBOARD_FAB2_LIB.BASEBOARD_FAB2(SCH_1):P3E_CPU1_PE3_MP_C_TXP(0)   I171 @BASEBOARD_FAB2_LIB.BASEBOARD_FAB2(SCH_1):PAGE181
     2 P3E_CPU1_PE3_MP_TXP<0> @BASEBOARD_FAB2_LIB.BASEBOARD_FAB2(SCH_1):P3E_CPU1_PE3_MP_TXP(0)   I171 @BASEBOARD_FAB2_LIB.BASEBOARD_FAB2(SCH_1):PAGE181

C1F19 CAP_A_0402V-0.01UF,25V,10%,X7RA
     1 M_G_CPU_VREF @BASEBOARD_FAB2_LIB.BASEBOARD_FAB2(SCH_1):M_G_CPU_VREF     I8 @BASEBOARD_FAB2_LIB.BASEBOARD_FAB2(SCH_1):PAGE100
     2    GND @BASEBOARD_FAB2_LIB.BASEBOARD_FAB2(SCH_1):GND     I8 @BASEBOARD_FAB2_LIB.BASEBOARD_FAB2(SCH_1):PAGE100

C1F20 CAP_0402-0.22UF,16V,10%,X7R,A3A
     1 P3E_CPU1_PE3_MP_C_TXN<0> @BASEBOARD_FAB2_LIB.BASEBOARD_FAB2(SCH_1):P3E_CPU1_PE3_MP_C_TXN(0)   I166 @BASEBOARD_FAB2_LIB.BASEBOARD_FAB2(SCH_1):PAGE181
     2 P3E_CPU1_PE3_MP_TXN<0> @BASEBOARD_FAB2_LIB.BASEBOARD_FAB2(SCH_1):P3E_CPU1_PE3_MP_TXN(0)   I166 @BASEBOARD_FAB2_LIB.BASEBOARD_FAB2(SCH_1):PAGE181

C1F21 CAP_A_0402V-1.0UF,6.3V,10%,X6SA
     1 P5V_STBY @BASEBOARD_FAB2_LIB.BASEBOARD_FAB2(SCH_1):P5V_STBY    I73 @BASEBOARD_FAB2_LIB.BASEBOARD_FAB2(SCH_1):PAGE224
     2    GND @BASEBOARD_FAB2_LIB.BASEBOARD_FAB2(SCH_1):GND    I73 @BASEBOARD_FAB2_LIB.BASEBOARD_FAB2(SCH_1):PAGE224

C1F22 CAP_A_0402V-0.01UF,25V,10%,X7RA
     1 M_G_VREF @BASEBOARD_FAB2_LIB.BASEBOARD_FAB2(SCH_1):M_G_VREF   I181 @BASEBOARD_FAB2_LIB.BASEBOARD_FAB2(SCH_1):PAGE77
     2    GND @BASEBOARD_FAB2_LIB.BASEBOARD_FAB2(SCH_1):GND   I181 @BASEBOARD_FAB2_LIB.BASEBOARD_FAB2(SCH_1):PAGE77

C1F26 CAP_0402-0.220UF,16V,10%,X7R,AA
     1 VR_PVDDQ_GHJ_PH2_BOOT @BASEBOARD_FAB2_LIB.BASEBOARD_FAB2(SCH_1):VR_PVDDQ_GHJ_PH2_BOOT    I75 @BASEBOARD_FAB2_LIB.BASEBOARD_FAB2(SCH_1):PAGE224
     2 VR_PVDDQ_GHJ_PH2_PHASE @BASEBOARD_FAB2_LIB.BASEBOARD_FAB2(SCH_1):VR_PVDDQ_GHJ_PH2_PHASE    I75 @BASEBOARD_FAB2_LIB.BASEBOARD_FAB2(SCH_1):PAGE224

C1F27 CAP_0402-1.0UF,16V,10%,X6S,D97A
     1 VR_FET_SW_P12V_STBY_PVDDQ_GHJ @BASEBOARD_FAB2_LIB.BASEBOARD_FAB2(SCH_1):VR_FET_SW_P12V_STBY_PVDDQ_GHJ    I48 @BASEBOARD_FAB2_LIB.BASEBOARD_FAB2(SCH_1):PAGE224
     2    GND @BASEBOARD_FAB2_LIB.BASEBOARD_FAB2(SCH_1):GND    I48 @BASEBOARD_FAB2_LIB.BASEBOARD_FAB2(SCH_1):PAGE224

C1F28 CAP_A_0402V-0.1UF,16V,10%,X7R,A
     1 VR_FET_SW_P12V_STBY_PVDDQ_GHJ @BASEBOARD_FAB2_LIB.BASEBOARD_FAB2(SCH_1):VR_FET_SW_P12V_STBY_PVDDQ_GHJ    I78 @BASEBOARD_FAB2_LIB.BASEBOARD_FAB2(SCH_1):PAGE224
     2    GND @BASEBOARD_FAB2_LIB.BASEBOARD_FAB2(SCH_1):GND    I78 @BASEBOARD_FAB2_LIB.BASEBOARD_FAB2(SCH_1):PAGE224

C1G2 CAP_1210-47UF,16V,20%,X6S,D384A
     1 VR_FET_SW_P12V_STBY_PVDDQ_GHJ @BASEBOARD_FAB2_LIB.BASEBOARD_FAB2(SCH_1):VR_FET_SW_P12V_STBY_PVDDQ_GHJ   I194 @BASEBOARD_FAB2_LIB.BASEBOARD_FAB2(SCH_1):PAGE225
     2    GND @BASEBOARD_FAB2_LIB.BASEBOARD_FAB2(SCH_1):GND   I194 @BASEBOARD_FAB2_LIB.BASEBOARD_FAB2(SCH_1):PAGE225

C1G4 CAP_A_0402V-1.0UF,6.3V,10%,X6SA
     1 P5V_STBY @BASEBOARD_FAB2_LIB.BASEBOARD_FAB2(SCH_1):P5V_STBY    I53 @BASEBOARD_FAB2_LIB.BASEBOARD_FAB2(SCH_1):PAGE224
     2    GND @BASEBOARD_FAB2_LIB.BASEBOARD_FAB2(SCH_1):GND    I53 @BASEBOARD_FAB2_LIB.BASEBOARD_FAB2(SCH_1):PAGE224

C1G5 CAP_0402-0.22UF,16V,10%,X7R,A3A
     1 P5V_STBY @BASEBOARD_FAB2_LIB.BASEBOARD_FAB2(SCH_1):P5V_STBY    I54 @BASEBOARD_FAB2_LIB.BASEBOARD_FAB2(SCH_1):PAGE224
     2    GND @BASEBOARD_FAB2_LIB.BASEBOARD_FAB2(SCH_1):GND    I54 @BASEBOARD_FAB2_LIB.BASEBOARD_FAB2(SCH_1):PAGE224

C1G6 CAP_0402-1.0UF,16V,10%,X6S,D97A
     1 VR_PVDDQ_GHJ_PH1_VCIN @BASEBOARD_FAB2_LIB.BASEBOARD_FAB2(SCH_1):VR_PVDDQ_GHJ_PH1_VCIN    I50 @BASEBOARD_FAB2_LIB.BASEBOARD_FAB2(SCH_1):PAGE224
     2    GND @BASEBOARD_FAB2_LIB.BASEBOARD_FAB2(SCH_1):GND    I50 @BASEBOARD_FAB2_LIB.BASEBOARD_FAB2(SCH_1):PAGE224

C1G7 CAP_1210-47UF,16V,20%,X6S,D384A
     1 VR_FET_SW_P12V_STBY_PVDDQ_GHJ @BASEBOARD_FAB2_LIB.BASEBOARD_FAB2(SCH_1):VR_FET_SW_P12V_STBY_PVDDQ_GHJ   I195 @BASEBOARD_FAB2_LIB.BASEBOARD_FAB2(SCH_1):PAGE225
     2    GND @BASEBOARD_FAB2_LIB.BASEBOARD_FAB2(SCH_1):GND   I195 @BASEBOARD_FAB2_LIB.BASEBOARD_FAB2(SCH_1):PAGE225

C1G8 CAP_A_0402V-0.01UF,25V,10%,X7RA
     1 M_H_CPU_VREF @BASEBOARD_FAB2_LIB.BASEBOARD_FAB2(SCH_1):M_H_CPU_VREF    I26 @BASEBOARD_FAB2_LIB.BASEBOARD_FAB2(SCH_1):PAGE100
     2    GND @BASEBOARD_FAB2_LIB.BASEBOARD_FAB2(SCH_1):GND    I26 @BASEBOARD_FAB2_LIB.BASEBOARD_FAB2(SCH_1):PAGE100

C1G10 CAP_A_0402V-0.01UF,25V,10%,X7RA
     1 M_H_VREF @BASEBOARD_FAB2_LIB.BASEBOARD_FAB2(SCH_1):M_H_VREF     I3 @BASEBOARD_FAB2_LIB.BASEBOARD_FAB2(SCH_1):PAGE80
     2    GND @BASEBOARD_FAB2_LIB.BASEBOARD_FAB2(SCH_1):GND     I3 @BASEBOARD_FAB2_LIB.BASEBOARD_FAB2(SCH_1):PAGE80

C1G11 CAP_0402-0.220UF,16V,10%,X7R,AA
     1 VR_PVDDQ_GHJ_PH1_BOOT @BASEBOARD_FAB2_LIB.BASEBOARD_FAB2(SCH_1):VR_PVDDQ_GHJ_PH1_BOOT    I44 @BASEBOARD_FAB2_LIB.BASEBOARD_FAB2(SCH_1):PAGE224
     2 VR_PVDDQ_GHJ_PH1_PHASE @BASEBOARD_FAB2_LIB.BASEBOARD_FAB2(SCH_1):VR_PVDDQ_GHJ_PH1_PHASE    I44 @BASEBOARD_FAB2_LIB.BASEBOARD_FAB2(SCH_1):PAGE224

C1G12 CAP_1210-47UF,16V,20%,X6S,D384A
     1 VR_FET_SW_P12V_STBY_PVDDQ_GHJ @BASEBOARD_FAB2_LIB.BASEBOARD_FAB2(SCH_1):VR_FET_SW_P12V_STBY_PVDDQ_GHJ   I193 @BASEBOARD_FAB2_LIB.BASEBOARD_FAB2(SCH_1):PAGE225
     2    GND @BASEBOARD_FAB2_LIB.BASEBOARD_FAB2(SCH_1):GND   I193 @BASEBOARD_FAB2_LIB.BASEBOARD_FAB2(SCH_1):PAGE225

C1G13 CAP_0402-1.0UF,16V,10%,X6S,D97A
     1 VR_FET_SW_P12V_STBY_PVDDQ_GHJ @BASEBOARD_FAB2_LIB.BASEBOARD_FAB2(SCH_1):VR_FET_SW_P12V_STBY_PVDDQ_GHJ    I79 @BASEBOARD_FAB2_LIB.BASEBOARD_FAB2(SCH_1):PAGE224
     2    GND @BASEBOARD_FAB2_LIB.BASEBOARD_FAB2(SCH_1):GND    I79 @BASEBOARD_FAB2_LIB.BASEBOARD_FAB2(SCH_1):PAGE224

C1G14 CAP_A_0402V-0.1UF,16V,10%,X7R,A
     1 VR_FET_SW_P12V_STBY_PVDDQ_GHJ @BASEBOARD_FAB2_LIB.BASEBOARD_FAB2(SCH_1):VR_FET_SW_P12V_STBY_PVDDQ_GHJ    I51 @BASEBOARD_FAB2_LIB.BASEBOARD_FAB2(SCH_1):PAGE224
     2    GND @BASEBOARD_FAB2_LIB.BASEBOARD_FAB2(SCH_1):GND    I51 @BASEBOARD_FAB2_LIB.BASEBOARD_FAB2(SCH_1):PAGE224

C1G15 CAP_1210-47UF,16V,20%,X6S,D384A
     1 VR_FET_SW_P12V_STBY_PVDDQ_GHJ @BASEBOARD_FAB2_LIB.BASEBOARD_FAB2(SCH_1):VR_FET_SW_P12V_STBY_PVDDQ_GHJ   I192 @BASEBOARD_FAB2_LIB.BASEBOARD_FAB2(SCH_1):PAGE225
     2    GND @BASEBOARD_FAB2_LIB.BASEBOARD_FAB2(SCH_1):GND   I192 @BASEBOARD_FAB2_LIB.BASEBOARD_FAB2(SCH_1):PAGE225

C1G16 CAP_0402LF-220PF,50V,10%,X7R,AA
     1 VR_PVDDQ_GHJ_AVSP @BASEBOARD_FAB2_LIB.BASEBOARD_FAB2(SCH_1):VR_PVDDQ_GHJ_AVSP    I39 @BASEBOARD_FAB2_LIB.BASEBOARD_FAB2(SCH_1):PAGE223
     2 VSENSE_PVDDQ_GHJ_N @BASEBOARD_FAB2_LIB.BASEBOARD_FAB2(SCH_1):VSENSE_PVDDQ_GHJ_N    I39 @BASEBOARD_FAB2_LIB.BASEBOARD_FAB2(SCH_1):PAGE223

C1G17 CAP_0805LF-22UF,4V,20%,X6S,C95A
     1 PVDDQ_GHJ @BASEBOARD_FAB2_LIB.BASEBOARD_FAB2(SCH_1):PVDDQ_GHJ     I6 @BASEBOARD_FAB2_LIB.BASEBOARD_FAB2(SCH_1):PAGE224
     2    GND @BASEBOARD_FAB2_LIB.BASEBOARD_FAB2(SCH_1):GND     I6 @BASEBOARD_FAB2_LIB.BASEBOARD_FAB2(SCH_1):PAGE224

C1G18 CAP_A_0402V-0.01UF,25V,10%,X7RA
     1 M_J_CPU_VREF @BASEBOARD_FAB2_LIB.BASEBOARD_FAB2(SCH_1):M_J_CPU_VREF    I42 @BASEBOARD_FAB2_LIB.BASEBOARD_FAB2(SCH_1):PAGE100
     2    GND @BASEBOARD_FAB2_LIB.BASEBOARD_FAB2(SCH_1):GND    I42 @BASEBOARD_FAB2_LIB.BASEBOARD_FAB2(SCH_1):PAGE100

C1G19 CAP_A_0402V-0.01UF,25V,10%,X7RA
     1 M_J_VREF @BASEBOARD_FAB2_LIB.BASEBOARD_FAB2(SCH_1):M_J_VREF   I180 @BASEBOARD_FAB2_LIB.BASEBOARD_FAB2(SCH_1):PAGE82
     2    GND @BASEBOARD_FAB2_LIB.BASEBOARD_FAB2(SCH_1):GND   I180 @BASEBOARD_FAB2_LIB.BASEBOARD_FAB2(SCH_1):PAGE82

C1G20 CAP_0805LF-22UF,4V,20%,X6S,C95A
     1 PVDDQ_GHJ @BASEBOARD_FAB2_LIB.BASEBOARD_FAB2(SCH_1):PVDDQ_GHJ    I68 @BASEBOARD_FAB2_LIB.BASEBOARD_FAB2(SCH_1):PAGE224
     2    GND @BASEBOARD_FAB2_LIB.BASEBOARD_FAB2(SCH_1):GND    I68 @BASEBOARD_FAB2_LIB.BASEBOARD_FAB2(SCH_1):PAGE224

C1G21 CAP_0402LF-1000PF,50V,10%,X7R,A
     1 PWRGD_PVDDQ_GHJ_R @BASEBOARD_FAB2_LIB.BASEBOARD_FAB2(SCH_1):PWRGD_PVDDQ_GHJ_R    I80 @BASEBOARD_FAB2_LIB.BASEBOARD_FAB2(SCH_1):PAGE223
     2    GND @BASEBOARD_FAB2_LIB.BASEBOARD_FAB2(SCH_1):GND    I80 @BASEBOARD_FAB2_LIB.BASEBOARD_FAB2(SCH_1):PAGE223

C1G22 CAP_A_0402V-0.1UF,16V,10%,X7R,A
     1 VR_PVDDQ_GHJ_VD12 @BASEBOARD_FAB2_LIB.BASEBOARD_FAB2(SCH_1):VR_PVDDQ_GHJ_VD12    I44 @BASEBOARD_FAB2_LIB.BASEBOARD_FAB2(SCH_1):PAGE223
     2    GND @BASEBOARD_FAB2_LIB.BASEBOARD_FAB2(SCH_1):GND    I44 @BASEBOARD_FAB2_LIB.BASEBOARD_FAB2(SCH_1):PAGE223

C1G23 CAP_A_0402V-1.0UF,6.3V,10%,X6SA
     1 VR_PVDDQ_GHJ_VD12 @BASEBOARD_FAB2_LIB.BASEBOARD_FAB2(SCH_1):VR_PVDDQ_GHJ_VD12    I41 @BASEBOARD_FAB2_LIB.BASEBOARD_FAB2(SCH_1):PAGE223
     2    GND @BASEBOARD_FAB2_LIB.BASEBOARD_FAB2(SCH_1):GND    I41 @BASEBOARD_FAB2_LIB.BASEBOARD_FAB2(SCH_1):PAGE223

C1G24 CAP_0402LF-220PF,50V,10%,X7R,AA
     1 A_TSENSE_PVDDQ_GHJ @BASEBOARD_FAB2_LIB.BASEBOARD_FAB2(SCH_1):A_TSENSE_PVDDQ_GHJ    I36 @BASEBOARD_FAB2_LIB.BASEBOARD_FAB2(SCH_1):PAGE223
     2    GND @BASEBOARD_FAB2_LIB.BASEBOARD_FAB2(SCH_1):GND    I36 @BASEBOARD_FAB2_LIB.BASEBOARD_FAB2(SCH_1):PAGE223

C1G25 CAP_A_0402V-0.1UF,16V,10%,X7R,A
     1 VR_PVDDQ_GHJ_VDD @BASEBOARD_FAB2_LIB.BASEBOARD_FAB2(SCH_1):VR_PVDDQ_GHJ_VDD    I27 @BASEBOARD_FAB2_LIB.BASEBOARD_FAB2(SCH_1):PAGE223
     2    GND @BASEBOARD_FAB2_LIB.BASEBOARD_FAB2(SCH_1):GND    I27 @BASEBOARD_FAB2_LIB.BASEBOARD_FAB2(SCH_1):PAGE223

C1G26 CAP_0402LF-1000PF,50V,10%,X7R,A
     1 VR_PVDDQ_GHJ_VINSEN @BASEBOARD_FAB2_LIB.BASEBOARD_FAB2(SCH_1):VR_PVDDQ_GHJ_VINSEN    I59 @BASEBOARD_FAB2_LIB.BASEBOARD_FAB2(SCH_1):PAGE223
     2    GND @BASEBOARD_FAB2_LIB.BASEBOARD_FAB2(SCH_1):GND    I59 @BASEBOARD_FAB2_LIB.BASEBOARD_FAB2(SCH_1):PAGE223

C1G27 CAP_A_0402V-1.0UF,6.3V,10%,X6SA
     1 VR_PVDDQ_GHJ_VDD @BASEBOARD_FAB2_LIB.BASEBOARD_FAB2(SCH_1):VR_PVDDQ_GHJ_VDD    I25 @BASEBOARD_FAB2_LIB.BASEBOARD_FAB2(SCH_1):PAGE223
     2    GND @BASEBOARD_FAB2_LIB.BASEBOARD_FAB2(SCH_1):GND    I25 @BASEBOARD_FAB2_LIB.BASEBOARD_FAB2(SCH_1):PAGE223

C1G28 CAP_0402-1.0UF,16V,10%,X6S,D97A
     1 VR_PVDDQ_GHJ_PH2_VCIN @BASEBOARD_FAB2_LIB.BASEBOARD_FAB2(SCH_1):VR_PVDDQ_GHJ_PH2_VCIN    I77 @BASEBOARD_FAB2_LIB.BASEBOARD_FAB2(SCH_1):PAGE224
     2    GND @BASEBOARD_FAB2_LIB.BASEBOARD_FAB2(SCH_1):GND    I77 @BASEBOARD_FAB2_LIB.BASEBOARD_FAB2(SCH_1):PAGE224

C1G29 CAP_0402-0.22UF,16V,10%,X7R,A3A
     1 P5V_STBY @BASEBOARD_FAB2_LIB.BASEBOARD_FAB2(SCH_1):P5V_STBY    I72 @BASEBOARD_FAB2_LIB.BASEBOARD_FAB2(SCH_1):PAGE224
     2    GND @BASEBOARD_FAB2_LIB.BASEBOARD_FAB2(SCH_1):GND    I72 @BASEBOARD_FAB2_LIB.BASEBOARD_FAB2(SCH_1):PAGE224

C1L1 CAP_0402-1.0UF,16V,10%,X6S,D97A
     1 P3V3_STBY @BASEBOARD_FAB2_LIB.BASEBOARD_FAB2(SCH_1):P3V3_STBY   I136 @BASEBOARD_FAB2_LIB.BASEBOARD_FAB2(SCH_1):PAGE112
     2    GND @BASEBOARD_FAB2_LIB.BASEBOARD_FAB2(SCH_1):GND   I136 @BASEBOARD_FAB2_LIB.BASEBOARD_FAB2(SCH_1):PAGE112

C1L2 CAP_A_0402V-0.01UF,25V,10%,X7RA
     1 SATA6G_P8_TX_C_DP @BASEBOARD_FAB2_LIB.BASEBOARD_FAB2(SCH_1):SATA6G_P8_TX_C_DP     I9 @BASEBOARD_FAB2_LIB.BASEBOARD_FAB2(SCH_1):PAGE174
     2 SATA6G_TX_DP<0> @BASEBOARD_FAB2_LIB.BASEBOARD_FAB2(SCH_1):SATA6G_TX_DP(0)     I9 @BASEBOARD_FAB2_LIB.BASEBOARD_FAB2(SCH_1):PAGE174

C1L3 CAP_A_0402V-0.01UF,25V,10%,X7RA
     1 SATA6G_P8_TX_C_DN @BASEBOARD_FAB2_LIB.BASEBOARD_FAB2(SCH_1):SATA6G_P8_TX_C_DN     I8 @BASEBOARD_FAB2_LIB.BASEBOARD_FAB2(SCH_1):PAGE174
     2 SATA6G_TX_DN<0> @BASEBOARD_FAB2_LIB.BASEBOARD_FAB2(SCH_1):SATA6G_TX_DN(0)     I8 @BASEBOARD_FAB2_LIB.BASEBOARD_FAB2(SCH_1):PAGE174

C1L4 CAP_A_0402V-0.1UF,16V,10%,X7R,A
     1 P5V_STBY @BASEBOARD_FAB2_LIB.BASEBOARD_FAB2(SCH_1):P5V_STBY    I64 @BASEBOARD_FAB2_LIB.BASEBOARD_FAB2(SCH_1):PAGE175
     2    GND @BASEBOARD_FAB2_LIB.BASEBOARD_FAB2(SCH_1):GND    I64 @BASEBOARD_FAB2_LIB.BASEBOARD_FAB2(SCH_1):PAGE175

C1L5 CAP_A_0402V-1.0UF,6.3V,10%,X6SA
     1 P1V05_PCH_STBY @BASEBOARD_FAB2_LIB.BASEBOARD_FAB2(SCH_1):P1V05_PCH_STBY    I30 @BASEBOARD_FAB2_LIB.BASEBOARD_FAB2(SCH_1):PAGE111
     2    GND @BASEBOARD_FAB2_LIB.BASEBOARD_FAB2(SCH_1):GND    I30 @BASEBOARD_FAB2_LIB.BASEBOARD_FAB2(SCH_1):PAGE111

C1L6 CAP_A_0402V-0.01UF,25V,10%,X7RA
     1 SATA6G_P9_TX_C_DP @BASEBOARD_FAB2_LIB.BASEBOARD_FAB2(SCH_1):SATA6G_P9_TX_C_DP    I13 @BASEBOARD_FAB2_LIB.BASEBOARD_FAB2(SCH_1):PAGE174
     2 SATA6G_TX_DP<1> @BASEBOARD_FAB2_LIB.BASEBOARD_FAB2(SCH_1):SATA6G_TX_DP(1)    I13 @BASEBOARD_FAB2_LIB.BASEBOARD_FAB2(SCH_1):PAGE174

C1L7 CAP_A_0402V-0.01UF,25V,10%,X7RA
     1 SATA6G_P9_TX_C_DN @BASEBOARD_FAB2_LIB.BASEBOARD_FAB2(SCH_1):SATA6G_P9_TX_C_DN    I12 @BASEBOARD_FAB2_LIB.BASEBOARD_FAB2(SCH_1):PAGE174
     2 SATA6G_TX_DN<1> @BASEBOARD_FAB2_LIB.BASEBOARD_FAB2(SCH_1):SATA6G_TX_DN(1)    I12 @BASEBOARD_FAB2_LIB.BASEBOARD_FAB2(SCH_1):PAGE174

C1L8 CAP_A_0402V-0.1UF,16V,10%,X7R,A
     1 XDP_PWRGD_RST_N @BASEBOARD_FAB2_LIB.BASEBOARD_FAB2(SCH_1):XDP_PWRGD_RST_N    I14 @BASEBOARD_FAB2_LIB.BASEBOARD_FAB2(SCH_1):PAGE111
     2    GND @BASEBOARD_FAB2_LIB.BASEBOARD_FAB2(SCH_1):GND    I14 @BASEBOARD_FAB2_LIB.BASEBOARD_FAB2(SCH_1):PAGE111

C1L9 CAP_A_0402V-0.1UF,16V,10%,X7R,A
     1 P3V3_STBY @BASEBOARD_FAB2_LIB.BASEBOARD_FAB2(SCH_1):P3V3_STBY    I38 @BASEBOARD_FAB2_LIB.BASEBOARD_FAB2(SCH_1):PAGE175
     2    GND @BASEBOARD_FAB2_LIB.BASEBOARD_FAB2(SCH_1):GND    I38 @BASEBOARD_FAB2_LIB.BASEBOARD_FAB2(SCH_1):PAGE175

C1L10 CAP_A_0402V-1.0UF,6.3V,10%,X6SA
     1 FP_RST_BTN_R_N @BASEBOARD_FAB2_LIB.BASEBOARD_FAB2(SCH_1):FP_RST_BTN_R_N    I19 @BASEBOARD_FAB2_LIB.BASEBOARD_FAB2(SCH_1):PAGE175
     2    GND @BASEBOARD_FAB2_LIB.BASEBOARD_FAB2(SCH_1):GND    I19 @BASEBOARD_FAB2_LIB.BASEBOARD_FAB2(SCH_1):PAGE175

C1L11 CAP_A_0402V-0.1UF,16V,10%,X7R,A
     1 P3V3_STBY @BASEBOARD_FAB2_LIB.BASEBOARD_FAB2(SCH_1):P3V3_STBY    I87 @BASEBOARD_FAB2_LIB.BASEBOARD_FAB2(SCH_1):PAGE111
     2    GND @BASEBOARD_FAB2_LIB.BASEBOARD_FAB2(SCH_1):GND    I87 @BASEBOARD_FAB2_LIB.BASEBOARD_FAB2(SCH_1):PAGE111

C1L12 CAP_A_0402V-0.01UF,25V,10%,X7RA
     1 SATA6G_P10_TX_C_DP @BASEBOARD_FAB2_LIB.BASEBOARD_FAB2(SCH_1):SATA6G_P10_TX_C_DP    I19 @BASEBOARD_FAB2_LIB.BASEBOARD_FAB2(SCH_1):PAGE174
     2 SATA6G_TX_DP<2> @BASEBOARD_FAB2_LIB.BASEBOARD_FAB2(SCH_1):SATA6G_TX_DP(2)    I19 @BASEBOARD_FAB2_LIB.BASEBOARD_FAB2(SCH_1):PAGE174

C1L13 CAP_A_0402V-0.01UF,25V,10%,X7RA
     1 SATA6G_P10_TX_C_DN @BASEBOARD_FAB2_LIB.BASEBOARD_FAB2(SCH_1):SATA6G_P10_TX_C_DN    I14 @BASEBOARD_FAB2_LIB.BASEBOARD_FAB2(SCH_1):PAGE174
     2 SATA6G_TX_DN<2> @BASEBOARD_FAB2_LIB.BASEBOARD_FAB2(SCH_1):SATA6G_TX_DN(2)    I14 @BASEBOARD_FAB2_LIB.BASEBOARD_FAB2(SCH_1):PAGE174

C1L14 CAP_A_0402V-0.01UF,25V,10%,X7RA
     1 SATA6G_P11_TX_C_DP @BASEBOARD_FAB2_LIB.BASEBOARD_FAB2(SCH_1):SATA6G_P11_TX_C_DP    I20 @BASEBOARD_FAB2_LIB.BASEBOARD_FAB2(SCH_1):PAGE174
     2 SATA6G_TX_DP<3> @BASEBOARD_FAB2_LIB.BASEBOARD_FAB2(SCH_1):SATA6G_TX_DP(3)    I20 @BASEBOARD_FAB2_LIB.BASEBOARD_FAB2(SCH_1):PAGE174

C1L15 CAP_A_0402V-0.01UF,25V,10%,X7RA
     1 SATA6G_P11_TX_C_DN @BASEBOARD_FAB2_LIB.BASEBOARD_FAB2(SCH_1):SATA6G_P11_TX_C_DN    I18 @BASEBOARD_FAB2_LIB.BASEBOARD_FAB2(SCH_1):PAGE174
     2 SATA6G_TX_DN<3> @BASEBOARD_FAB2_LIB.BASEBOARD_FAB2(SCH_1):SATA6G_TX_DN(3)    I18 @BASEBOARD_FAB2_LIB.BASEBOARD_FAB2(SCH_1):PAGE174

C1L16 CAP_A_0402V-0.1UF,16V,10%,X7R,A
     1   P3V3 @BASEBOARD_FAB2_LIB.BASEBOARD_FAB2(SCH_1):P3V3    I81 @BASEBOARD_FAB2_LIB.BASEBOARD_FAB2(SCH_1):PAGE196
     2    GND @BASEBOARD_FAB2_LIB.BASEBOARD_FAB2(SCH_1):GND    I81 @BASEBOARD_FAB2_LIB.BASEBOARD_FAB2(SCH_1):PAGE196

C1L17 CAP_A_0402V-0.1UF,16V,10%,X7R,A
     1 P3V3_STBY @BASEBOARD_FAB2_LIB.BASEBOARD_FAB2(SCH_1):P3V3_STBY    I37 @BASEBOARD_FAB2_LIB.BASEBOARD_FAB2(SCH_1):PAGE175
     2    GND @BASEBOARD_FAB2_LIB.BASEBOARD_FAB2(SCH_1):GND    I37 @BASEBOARD_FAB2_LIB.BASEBOARD_FAB2(SCH_1):PAGE175

C1L18 CAP_A_0402V-1.0UF,6.3V,10%,X6SA
     1 FP_PWR_BTN_R1_N @BASEBOARD_FAB2_LIB.BASEBOARD_FAB2(SCH_1):FP_PWR_BTN_R1_N    I11 @BASEBOARD_FAB2_LIB.BASEBOARD_FAB2(SCH_1):PAGE175
     2    GND @BASEBOARD_FAB2_LIB.BASEBOARD_FAB2(SCH_1):GND    I11 @BASEBOARD_FAB2_LIB.BASEBOARD_FAB2(SCH_1):PAGE175

C1L19 CAP_0402-1.0UF,16V,10%,X6S,D97A
     1 P3V3_STBY @BASEBOARD_FAB2_LIB.BASEBOARD_FAB2(SCH_1):P3V3_STBY   I140 @BASEBOARD_FAB2_LIB.BASEBOARD_FAB2(SCH_1):PAGE112
     2    GND @BASEBOARD_FAB2_LIB.BASEBOARD_FAB2(SCH_1):GND   I140 @BASEBOARD_FAB2_LIB.BASEBOARD_FAB2(SCH_1):PAGE112

C1L20 CAP_A_0402V-0.01UF,25V,10%,X7RA
     1 P3V3_STBY @BASEBOARD_FAB2_LIB.BASEBOARD_FAB2(SCH_1):P3V3_STBY   I267 @BASEBOARD_FAB2_LIB.BASEBOARD_FAB2(SCH_1):PAGE113
     2    GND @BASEBOARD_FAB2_LIB.BASEBOARD_FAB2(SCH_1):GND   I267 @BASEBOARD_FAB2_LIB.BASEBOARD_FAB2(SCH_1):PAGE113

C1M3 CAP_A_0402V-1.0UF,6.3V,10%,X6SA
     1   P3V3 @BASEBOARD_FAB2_LIB.BASEBOARD_FAB2(SCH_1):P3V3    I20 @BASEBOARD_FAB2_LIB.BASEBOARD_FAB2(SCH_1):PAGE177
     2    GND @BASEBOARD_FAB2_LIB.BASEBOARD_FAB2(SCH_1):GND    I20 @BASEBOARD_FAB2_LIB.BASEBOARD_FAB2(SCH_1):PAGE177

C1M4 CAP_0402LF-47.0PF,50V,5%,EMPTYA
     1 ISENSE_TMP421_1_DXP @BASEBOARD_FAB2_LIB.BASEBOARD_FAB2(SCH_1):ISENSE_TMP421_1_DXP     I7 @BASEBOARD_FAB2_LIB.BASEBOARD_FAB2(SCH_1):PAGE167
     2 ISENSE_TMP421_1_DXN @BASEBOARD_FAB2_LIB.BASEBOARD_FAB2(SCH_1):ISENSE_TMP421_1_DXN     I7 @BASEBOARD_FAB2_LIB.BASEBOARD_FAB2(SCH_1):PAGE167

C1M5 CAPP_3018-68UF,16V,20%,TANT,72A
     1 P12V_STBY @BASEBOARD_FAB2_LIB.BASEBOARD_FAB2(SCH_1):P12V_STBY   I103 @BASEBOARD_FAB2_LIB.BASEBOARD_FAB2(SCH_1):PAGE195
     2    GND @BASEBOARD_FAB2_LIB.BASEBOARD_FAB2(SCH_1):GND   I103 @BASEBOARD_FAB2_LIB.BASEBOARD_FAB2(SCH_1):PAGE195

C1M6 CAP_0402-0.22UF,16V,10%,X7R,A3A
     1 P3E_CPU0_PE3_OCP_TXP<15> @BASEBOARD_FAB2_LIB.BASEBOARD_FAB2(SCH_1):P3E_CPU0_PE3_OCP_TXP(15)   I109 @BASEBOARD_FAB2_LIB.BASEBOARD_FAB2(SCH_1):PAGE106
     2 P3E_OCP_CPU0_PE3_C_TXP<15> @BASEBOARD_FAB2_LIB.BASEBOARD_FAB2(SCH_1):P3E_OCP_CPU0_PE3_C_TXP(15)   I109 @BASEBOARD_FAB2_LIB.BASEBOARD_FAB2(SCH_1):PAGE106

C1M7 CAP_0402-0.22UF,16V,10%,X7R,A3A
     1 P3E_CPU0_PE3_OCP_TXN<15> @BASEBOARD_FAB2_LIB.BASEBOARD_FAB2(SCH_1):P3E_CPU0_PE3_OCP_TXN(15)   I122 @BASEBOARD_FAB2_LIB.BASEBOARD_FAB2(SCH_1):PAGE106
     2 P3E_OCP_CPU0_PE3_C_TXN<15> @BASEBOARD_FAB2_LIB.BASEBOARD_FAB2(SCH_1):P3E_OCP_CPU0_PE3_C_TXN(15)   I122 @BASEBOARD_FAB2_LIB.BASEBOARD_FAB2(SCH_1):PAGE106

C1M8 CAP_0402-0.22UF,16V,10%,X7R,A3A
     1 P3E_CPU0_PE3_OCP_TXP<14> @BASEBOARD_FAB2_LIB.BASEBOARD_FAB2(SCH_1):P3E_CPU0_PE3_OCP_TXP(14)   I105 @BASEBOARD_FAB2_LIB.BASEBOARD_FAB2(SCH_1):PAGE106
     2 P3E_OCP_CPU0_PE3_C_TXP<14> @BASEBOARD_FAB2_LIB.BASEBOARD_FAB2(SCH_1):P3E_OCP_CPU0_PE3_C_TXP(14)   I105 @BASEBOARD_FAB2_LIB.BASEBOARD_FAB2(SCH_1):PAGE106

C1M9 CAP_0402-0.22UF,16V,10%,X7R,A3A
     1 P3E_CPU0_PE3_OCP_TXN<14> @BASEBOARD_FAB2_LIB.BASEBOARD_FAB2(SCH_1):P3E_CPU0_PE3_OCP_TXN(14)   I114 @BASEBOARD_FAB2_LIB.BASEBOARD_FAB2(SCH_1):PAGE106
     2 P3E_OCP_CPU0_PE3_C_TXN<14> @BASEBOARD_FAB2_LIB.BASEBOARD_FAB2(SCH_1):P3E_OCP_CPU0_PE3_C_TXN(14)   I114 @BASEBOARD_FAB2_LIB.BASEBOARD_FAB2(SCH_1):PAGE106

C1M10 CAP_0402-0.22UF,16V,10%,X7R,A3A
     1 P3E_CPU0_PE3_OCP_TXP<13> @BASEBOARD_FAB2_LIB.BASEBOARD_FAB2(SCH_1):P3E_CPU0_PE3_OCP_TXP(13)   I102 @BASEBOARD_FAB2_LIB.BASEBOARD_FAB2(SCH_1):PAGE106
     2 P3E_OCP_CPU0_PE3_C_TXP<13> @BASEBOARD_FAB2_LIB.BASEBOARD_FAB2(SCH_1):P3E_OCP_CPU0_PE3_C_TXP(13)   I102 @BASEBOARD_FAB2_LIB.BASEBOARD_FAB2(SCH_1):PAGE106

C1M11 CAP_0402-0.22UF,16V,10%,X7R,A3A
     1 P3E_CPU0_PE3_OCP_TXN<13> @BASEBOARD_FAB2_LIB.BASEBOARD_FAB2(SCH_1):P3E_CPU0_PE3_OCP_TXN(13)   I117 @BASEBOARD_FAB2_LIB.BASEBOARD_FAB2(SCH_1):PAGE106
     2 P3E_OCP_CPU0_PE3_C_TXN<13> @BASEBOARD_FAB2_LIB.BASEBOARD_FAB2(SCH_1):P3E_OCP_CPU0_PE3_C_TXN(13)   I117 @BASEBOARD_FAB2_LIB.BASEBOARD_FAB2(SCH_1):PAGE106

C1M12 CAP_0402-0.22UF,16V,10%,X7R,A3A
     1 P3E_CPU0_PE3_OCP_TXP<12> @BASEBOARD_FAB2_LIB.BASEBOARD_FAB2(SCH_1):P3E_CPU0_PE3_OCP_TXP(12)   I100 @BASEBOARD_FAB2_LIB.BASEBOARD_FAB2(SCH_1):PAGE106
     2 P3E_OCP_CPU0_PE3_C_TXP<12> @BASEBOARD_FAB2_LIB.BASEBOARD_FAB2(SCH_1):P3E_OCP_CPU0_PE3_C_TXP(12)   I100 @BASEBOARD_FAB2_LIB.BASEBOARD_FAB2(SCH_1):PAGE106

C1M13 CAP_0402-0.22UF,16V,10%,X7R,A3A
     1 P3E_CPU0_PE3_OCP_TXN<12> @BASEBOARD_FAB2_LIB.BASEBOARD_FAB2(SCH_1):P3E_CPU0_PE3_OCP_TXN(12)   I111 @BASEBOARD_FAB2_LIB.BASEBOARD_FAB2(SCH_1):PAGE106
     2 P3E_OCP_CPU0_PE3_C_TXN<12> @BASEBOARD_FAB2_LIB.BASEBOARD_FAB2(SCH_1):P3E_OCP_CPU0_PE3_C_TXN(12)   I111 @BASEBOARD_FAB2_LIB.BASEBOARD_FAB2(SCH_1):PAGE106

C1M14 CAP_0402-0.22UF,16V,10%,X7R,A3A
     1 P3E_CPU0_PE3_OCP_TXP<11> @BASEBOARD_FAB2_LIB.BASEBOARD_FAB2(SCH_1):P3E_CPU0_PE3_OCP_TXP(11)    I85 @BASEBOARD_FAB2_LIB.BASEBOARD_FAB2(SCH_1):PAGE106
     2 P3E_OCP_CPU0_PE3_C_TXP<11> @BASEBOARD_FAB2_LIB.BASEBOARD_FAB2(SCH_1):P3E_OCP_CPU0_PE3_C_TXP(11)    I85 @BASEBOARD_FAB2_LIB.BASEBOARD_FAB2(SCH_1):PAGE106

C1M15 CAP_0402-0.22UF,16V,10%,X7R,A3A
     1 P3E_CPU0_PE3_OCP_TXN<11> @BASEBOARD_FAB2_LIB.BASEBOARD_FAB2(SCH_1):P3E_CPU0_PE3_OCP_TXN(11)    I95 @BASEBOARD_FAB2_LIB.BASEBOARD_FAB2(SCH_1):PAGE106
     2 P3E_OCP_CPU0_PE3_C_TXN<11> @BASEBOARD_FAB2_LIB.BASEBOARD_FAB2(SCH_1):P3E_OCP_CPU0_PE3_C_TXN(11)    I95 @BASEBOARD_FAB2_LIB.BASEBOARD_FAB2(SCH_1):PAGE106

C1M16 CAP_0402-0.22UF,16V,10%,X7R,A3A
     1 P3E_CPU0_PE3_OCP_TXP<10> @BASEBOARD_FAB2_LIB.BASEBOARD_FAB2(SCH_1):P3E_CPU0_PE3_OCP_TXP(10)    I82 @BASEBOARD_FAB2_LIB.BASEBOARD_FAB2(SCH_1):PAGE106
     2 P3E_OCP_CPU0_PE3_C_TXP<10> @BASEBOARD_FAB2_LIB.BASEBOARD_FAB2(SCH_1):P3E_OCP_CPU0_PE3_C_TXP(10)    I82 @BASEBOARD_FAB2_LIB.BASEBOARD_FAB2(SCH_1):PAGE106

C1M17 CAP_0402-0.22UF,16V,10%,X7R,A3A
     1 P3E_CPU0_PE3_OCP_TXN<10> @BASEBOARD_FAB2_LIB.BASEBOARD_FAB2(SCH_1):P3E_CPU0_PE3_OCP_TXN(10)    I92 @BASEBOARD_FAB2_LIB.BASEBOARD_FAB2(SCH_1):PAGE106
     2 P3E_OCP_CPU0_PE3_C_TXN<10> @BASEBOARD_FAB2_LIB.BASEBOARD_FAB2(SCH_1):P3E_OCP_CPU0_PE3_C_TXN(10)    I92 @BASEBOARD_FAB2_LIB.BASEBOARD_FAB2(SCH_1):PAGE106

C1M18 CAP_0402-0.22UF,16V,10%,X7R,A3A
     1 P3E_CPU0_PE3_OCP_TXP<9> @BASEBOARD_FAB2_LIB.BASEBOARD_FAB2(SCH_1):P3E_CPU0_PE3_OCP_TXP(9)    I78 @BASEBOARD_FAB2_LIB.BASEBOARD_FAB2(SCH_1):PAGE106
     2 P3E_OCP_CPU0_PE3_C_TXP<9> @BASEBOARD_FAB2_LIB.BASEBOARD_FAB2(SCH_1):P3E_OCP_CPU0_PE3_C_TXP(9)    I78 @BASEBOARD_FAB2_LIB.BASEBOARD_FAB2(SCH_1):PAGE106

C1M19 CAP_0402-0.22UF,16V,10%,X7R,A3A
     1 P3E_CPU0_PE3_OCP_TXN<9> @BASEBOARD_FAB2_LIB.BASEBOARD_FAB2(SCH_1):P3E_CPU0_PE3_OCP_TXN(9)    I90 @BASEBOARD_FAB2_LIB.BASEBOARD_FAB2(SCH_1):PAGE106
     2 P3E_OCP_CPU0_PE3_C_TXN<9> @BASEBOARD_FAB2_LIB.BASEBOARD_FAB2(SCH_1):P3E_OCP_CPU0_PE3_C_TXN(9)    I90 @BASEBOARD_FAB2_LIB.BASEBOARD_FAB2(SCH_1):PAGE106

C1M20 CAP_A_0402V-0.1UF,16V,10%,X7R,A
     1 P3V3_STBY @BASEBOARD_FAB2_LIB.BASEBOARD_FAB2(SCH_1):P3V3_STBY   I270 @BASEBOARD_FAB2_LIB.BASEBOARD_FAB2(SCH_1):PAGE186
     2    GND @BASEBOARD_FAB2_LIB.BASEBOARD_FAB2(SCH_1):GND   I270 @BASEBOARD_FAB2_LIB.BASEBOARD_FAB2(SCH_1):PAGE186

C1M21 CAP_A_0402V-1.0UF,6.3V,10%,X6SA
     1   P3V3 @BASEBOARD_FAB2_LIB.BASEBOARD_FAB2(SCH_1):P3V3   I334 @BASEBOARD_FAB2_LIB.BASEBOARD_FAB2(SCH_1):PAGE186
     2    GND @BASEBOARD_FAB2_LIB.BASEBOARD_FAB2(SCH_1):GND   I334 @BASEBOARD_FAB2_LIB.BASEBOARD_FAB2(SCH_1):PAGE186

C1M22 CAP_A_0402V-0.1UF,16V,10%,X7R,A
     1 P12V_STBY @BASEBOARD_FAB2_LIB.BASEBOARD_FAB2(SCH_1):P12V_STBY     I8 @BASEBOARD_FAB2_LIB.BASEBOARD_FAB2(SCH_1):PAGE186
     2    GND @BASEBOARD_FAB2_LIB.BASEBOARD_FAB2(SCH_1):GND     I8 @BASEBOARD_FAB2_LIB.BASEBOARD_FAB2(SCH_1):PAGE186

C1M23 CAP_A_0402V-0.1UF,16V,10%,X7R,A
     1 P12V_STBY @BASEBOARD_FAB2_LIB.BASEBOARD_FAB2(SCH_1):P12V_STBY     I7 @BASEBOARD_FAB2_LIB.BASEBOARD_FAB2(SCH_1):PAGE186
     2    GND @BASEBOARD_FAB2_LIB.BASEBOARD_FAB2(SCH_1):GND     I7 @BASEBOARD_FAB2_LIB.BASEBOARD_FAB2(SCH_1):PAGE186

C1M24 CAP_A_0402V-0.1UF,16V,10%,X7R,A
     1   P3V3 @BASEBOARD_FAB2_LIB.BASEBOARD_FAB2(SCH_1):P3V3    I10 @BASEBOARD_FAB2_LIB.BASEBOARD_FAB2(SCH_1):PAGE186
     2    GND @BASEBOARD_FAB2_LIB.BASEBOARD_FAB2(SCH_1):GND    I10 @BASEBOARD_FAB2_LIB.BASEBOARD_FAB2(SCH_1):PAGE186

C1M25 CAP_A_0402V-1.0UF,6.3V,10%,X6SA
     1 P3V3_STBY @BASEBOARD_FAB2_LIB.BASEBOARD_FAB2(SCH_1):P3V3_STBY   I335 @BASEBOARD_FAB2_LIB.BASEBOARD_FAB2(SCH_1):PAGE186
     2    GND @BASEBOARD_FAB2_LIB.BASEBOARD_FAB2(SCH_1):GND   I335 @BASEBOARD_FAB2_LIB.BASEBOARD_FAB2(SCH_1):PAGE186

C1M26 CAP_0805-10UF,16V,10%,X6S,C953A
     1 P12V_STBY @BASEBOARD_FAB2_LIB.BASEBOARD_FAB2(SCH_1):P12V_STBY     I6 @BASEBOARD_FAB2_LIB.BASEBOARD_FAB2(SCH_1):PAGE186
     2    GND @BASEBOARD_FAB2_LIB.BASEBOARD_FAB2(SCH_1):GND     I6 @BASEBOARD_FAB2_LIB.BASEBOARD_FAB2(SCH_1):PAGE186

C1M27 CAP_0805-10UF,16V,10%,X6S,C953A
     1 P12V_STBY @BASEBOARD_FAB2_LIB.BASEBOARD_FAB2(SCH_1):P12V_STBY     I3 @BASEBOARD_FAB2_LIB.BASEBOARD_FAB2(SCH_1):PAGE186
     2    GND @BASEBOARD_FAB2_LIB.BASEBOARD_FAB2(SCH_1):GND     I3 @BASEBOARD_FAB2_LIB.BASEBOARD_FAB2(SCH_1):PAGE186

C1M28 CAP_A_0402V-0.01UF,25V,10%,X7RA
     1 P3V3_STBY @BASEBOARD_FAB2_LIB.BASEBOARD_FAB2(SCH_1):P3V3_STBY   I119 @BASEBOARD_FAB2_LIB.BASEBOARD_FAB2(SCH_1):PAGE113
     2    GND @BASEBOARD_FAB2_LIB.BASEBOARD_FAB2(SCH_1):GND   I119 @BASEBOARD_FAB2_LIB.BASEBOARD_FAB2(SCH_1):PAGE113

C1M29 CAP_A_0402V-0.1UF,16V,10%,X7R,A
     1 P1V8_MCP_CPU0 @BASEBOARD_FAB2_LIB.BASEBOARD_FAB2(SCH_1):P1V8_MCP_CPU0   I147 @BASEBOARD_FAB2_LIB.BASEBOARD_FAB2(SCH_1):PAGE113
     2    GND @BASEBOARD_FAB2_LIB.BASEBOARD_FAB2(SCH_1):GND   I147 @BASEBOARD_FAB2_LIB.BASEBOARD_FAB2(SCH_1):PAGE113

C1M30 CAP_A_0402V-0.01UF,25V,10%,X7RA
     1 P3V3_STBY @BASEBOARD_FAB2_LIB.BASEBOARD_FAB2(SCH_1):P3V3_STBY   I131 @BASEBOARD_FAB2_LIB.BASEBOARD_FAB2(SCH_1):PAGE112
     2    GND @BASEBOARD_FAB2_LIB.BASEBOARD_FAB2(SCH_1):GND   I131 @BASEBOARD_FAB2_LIB.BASEBOARD_FAB2(SCH_1):PAGE112

C1M31 CAP_A_0402V-0.01UF,25V,10%,X7RA
     1 P3V3_STBY @BASEBOARD_FAB2_LIB.BASEBOARD_FAB2(SCH_1):P3V3_STBY   I116 @BASEBOARD_FAB2_LIB.BASEBOARD_FAB2(SCH_1):PAGE113
     2    GND @BASEBOARD_FAB2_LIB.BASEBOARD_FAB2(SCH_1):GND   I116 @BASEBOARD_FAB2_LIB.BASEBOARD_FAB2(SCH_1):PAGE113

C1M32 CAP_A_0402V-1.0UF,6.3V,10%,X6SA
     1 P3V3_STBY @BASEBOARD_FAB2_LIB.BASEBOARD_FAB2(SCH_1):P3V3_STBY   I117 @BASEBOARD_FAB2_LIB.BASEBOARD_FAB2(SCH_1):PAGE113
     2    GND @BASEBOARD_FAB2_LIB.BASEBOARD_FAB2(SCH_1):GND   I117 @BASEBOARD_FAB2_LIB.BASEBOARD_FAB2(SCH_1):PAGE113

C1M33 CAP_A_0402V-0.1UF,16V,10%,X7R,A
     1 JTAG_MCP_TMS_R1 @BASEBOARD_FAB2_LIB.BASEBOARD_FAB2(SCH_1):JTAG_MCP_TMS_R1   I248 @BASEBOARD_FAB2_LIB.BASEBOARD_FAB2(SCH_1):PAGE113
     2    GND @BASEBOARD_FAB2_LIB.BASEBOARD_FAB2(SCH_1):GND   I248 @BASEBOARD_FAB2_LIB.BASEBOARD_FAB2(SCH_1):PAGE113

C1M34 CAP_A_0402V-0.01UF,25V,10%,X7RA
     1 P3V3_STBY @BASEBOARD_FAB2_LIB.BASEBOARD_FAB2(SCH_1):P3V3_STBY   I265 @BASEBOARD_FAB2_LIB.BASEBOARD_FAB2(SCH_1):PAGE113
     2    GND @BASEBOARD_FAB2_LIB.BASEBOARD_FAB2(SCH_1):GND   I265 @BASEBOARD_FAB2_LIB.BASEBOARD_FAB2(SCH_1):PAGE113

C1M35 CAP_A_0402V-0.01UF,25V,10%,X7RA
     1 P3V3_STBY @BASEBOARD_FAB2_LIB.BASEBOARD_FAB2(SCH_1):P3V3_STBY   I266 @BASEBOARD_FAB2_LIB.BASEBOARD_FAB2(SCH_1):PAGE113
     2    GND @BASEBOARD_FAB2_LIB.BASEBOARD_FAB2(SCH_1):GND   I266 @BASEBOARD_FAB2_LIB.BASEBOARD_FAB2(SCH_1):PAGE113

C1M36 CAP_A_0402V-0.01UF,25V,10%,X7RA
     1 P3V3_STBY @BASEBOARD_FAB2_LIB.BASEBOARD_FAB2(SCH_1):P3V3_STBY    I42 @BASEBOARD_FAB2_LIB.BASEBOARD_FAB2(SCH_1):PAGE112
     2    GND @BASEBOARD_FAB2_LIB.BASEBOARD_FAB2(SCH_1):GND    I42 @BASEBOARD_FAB2_LIB.BASEBOARD_FAB2(SCH_1):PAGE112

C1M37 CAP_A_0402V-1.0UF,6.3V,10%,X6SA
     1 P3V3_STBY @BASEBOARD_FAB2_LIB.BASEBOARD_FAB2(SCH_1):P3V3_STBY    I47 @BASEBOARD_FAB2_LIB.BASEBOARD_FAB2(SCH_1):PAGE112
     2    GND @BASEBOARD_FAB2_LIB.BASEBOARD_FAB2(SCH_1):GND    I47 @BASEBOARD_FAB2_LIB.BASEBOARD_FAB2(SCH_1):PAGE112

C1M38 CAP_A_0402V-0.1UF,16V,10%,X7R,A
     1    P5V @BASEBOARD_FAB2_LIB.BASEBOARD_FAB2(SCH_1):P5V   I108 @BASEBOARD_FAB2_LIB.BASEBOARD_FAB2(SCH_1):PAGE176
     2    GND @BASEBOARD_FAB2_LIB.BASEBOARD_FAB2(SCH_1):GND   I108 @BASEBOARD_FAB2_LIB.BASEBOARD_FAB2(SCH_1):PAGE176

C1R1 CAP_0402-0.22UF,16V,10%,X7R,A3A
     1 P3E_CPU0_PE3_OCP_TXN<0> @BASEBOARD_FAB2_LIB.BASEBOARD_FAB2(SCH_1):P3E_CPU0_PE3_OCP_TXN(0)    I29 @BASEBOARD_FAB2_LIB.BASEBOARD_FAB2(SCH_1):PAGE106
     2 P3E_OCP_CPU0_PE3_C_TXN<0> @BASEBOARD_FAB2_LIB.BASEBOARD_FAB2(SCH_1):P3E_OCP_CPU0_PE3_C_TXN(0)    I29 @BASEBOARD_FAB2_LIB.BASEBOARD_FAB2(SCH_1):PAGE106

C1R2 CAP_0402-0.22UF,16V,10%,X7R,A3A
     1 P3E_CPU0_PE3_OCP_TXP<0> @BASEBOARD_FAB2_LIB.BASEBOARD_FAB2(SCH_1):P3E_CPU0_PE3_OCP_TXP(0)    I10 @BASEBOARD_FAB2_LIB.BASEBOARD_FAB2(SCH_1):PAGE106
     2 P3E_OCP_CPU0_PE3_C_TXP<0> @BASEBOARD_FAB2_LIB.BASEBOARD_FAB2(SCH_1):P3E_OCP_CPU0_PE3_C_TXP(0)    I10 @BASEBOARD_FAB2_LIB.BASEBOARD_FAB2(SCH_1):PAGE106

C1R3 CAP_0402-0.22UF,16V,10%,X7R,A3A
     1 P3E_CPU0_PE3_OCP_TXN<1> @BASEBOARD_FAB2_LIB.BASEBOARD_FAB2(SCH_1):P3E_CPU0_PE3_OCP_TXN(1)    I37 @BASEBOARD_FAB2_LIB.BASEBOARD_FAB2(SCH_1):PAGE106
     2 P3E_OCP_CPU0_PE3_C_TXN<1> @BASEBOARD_FAB2_LIB.BASEBOARD_FAB2(SCH_1):P3E_OCP_CPU0_PE3_C_TXN(1)    I37 @BASEBOARD_FAB2_LIB.BASEBOARD_FAB2(SCH_1):PAGE106

C1R4 CAP_0402-0.22UF,16V,10%,X7R,A3A
     1 P3E_CPU0_PE3_OCP_TXP<1> @BASEBOARD_FAB2_LIB.BASEBOARD_FAB2(SCH_1):P3E_CPU0_PE3_OCP_TXP(1)    I26 @BASEBOARD_FAB2_LIB.BASEBOARD_FAB2(SCH_1):PAGE106
     2 P3E_OCP_CPU0_PE3_C_TXP<1> @BASEBOARD_FAB2_LIB.BASEBOARD_FAB2(SCH_1):P3E_OCP_CPU0_PE3_C_TXP(1)    I26 @BASEBOARD_FAB2_LIB.BASEBOARD_FAB2(SCH_1):PAGE106

C1R5 CAP_0402-0.22UF,16V,10%,X7R,A3A
     1 P3E_CPU0_PE3_OCP_TXN<2> @BASEBOARD_FAB2_LIB.BASEBOARD_FAB2(SCH_1):P3E_CPU0_PE3_OCP_TXN(2)    I59 @BASEBOARD_FAB2_LIB.BASEBOARD_FAB2(SCH_1):PAGE106
     2 P3E_OCP_CPU0_PE3_C_TXN<2> @BASEBOARD_FAB2_LIB.BASEBOARD_FAB2(SCH_1):P3E_OCP_CPU0_PE3_C_TXN(2)    I59 @BASEBOARD_FAB2_LIB.BASEBOARD_FAB2(SCH_1):PAGE106

C1R6 CAP_0402-0.22UF,16V,10%,X7R,A3A
     1 P3E_CPU0_PE3_OCP_TXP<2> @BASEBOARD_FAB2_LIB.BASEBOARD_FAB2(SCH_1):P3E_CPU0_PE3_OCP_TXP(2)    I40 @BASEBOARD_FAB2_LIB.BASEBOARD_FAB2(SCH_1):PAGE106
     2 P3E_OCP_CPU0_PE3_C_TXP<2> @BASEBOARD_FAB2_LIB.BASEBOARD_FAB2(SCH_1):P3E_OCP_CPU0_PE3_C_TXP(2)    I40 @BASEBOARD_FAB2_LIB.BASEBOARD_FAB2(SCH_1):PAGE106

C1R7 CAP_0402-0.22UF,16V,10%,X7R,A3A
     1 P3E_CPU0_PE3_OCP_TXN<3> @BASEBOARD_FAB2_LIB.BASEBOARD_FAB2(SCH_1):P3E_CPU0_PE3_OCP_TXN(3)    I70 @BASEBOARD_FAB2_LIB.BASEBOARD_FAB2(SCH_1):PAGE106
     2 P3E_OCP_CPU0_PE3_C_TXN<3> @BASEBOARD_FAB2_LIB.BASEBOARD_FAB2(SCH_1):P3E_OCP_CPU0_PE3_C_TXN(3)    I70 @BASEBOARD_FAB2_LIB.BASEBOARD_FAB2(SCH_1):PAGE106

C1R8 CAP_0402-0.22UF,16V,10%,X7R,A3A
     1 P3E_CPU0_PE3_OCP_TXP<3> @BASEBOARD_FAB2_LIB.BASEBOARD_FAB2(SCH_1):P3E_CPU0_PE3_OCP_TXP(3)    I55 @BASEBOARD_FAB2_LIB.BASEBOARD_FAB2(SCH_1):PAGE106
     2 P3E_OCP_CPU0_PE3_C_TXP<3> @BASEBOARD_FAB2_LIB.BASEBOARD_FAB2(SCH_1):P3E_OCP_CPU0_PE3_C_TXP(3)    I55 @BASEBOARD_FAB2_LIB.BASEBOARD_FAB2(SCH_1):PAGE106

C1R9 CAP_0402-0.22UF,16V,10%,X7R,A3A
     1 P3E_CPU0_PE3_OCP_TXN<4> @BASEBOARD_FAB2_LIB.BASEBOARD_FAB2(SCH_1):P3E_CPU0_PE3_OCP_TXN(4)   I134 @BASEBOARD_FAB2_LIB.BASEBOARD_FAB2(SCH_1):PAGE106
     2 P3E_OCP_CPU0_PE3_C_TXN<4> @BASEBOARD_FAB2_LIB.BASEBOARD_FAB2(SCH_1):P3E_OCP_CPU0_PE3_C_TXN(4)   I134 @BASEBOARD_FAB2_LIB.BASEBOARD_FAB2(SCH_1):PAGE106

C1R10 CAP_0402-0.22UF,16V,10%,X7R,A3A
     1 P3E_CPU0_PE3_OCP_TXP<4> @BASEBOARD_FAB2_LIB.BASEBOARD_FAB2(SCH_1):P3E_CPU0_PE3_OCP_TXP(4)   I128 @BASEBOARD_FAB2_LIB.BASEBOARD_FAB2(SCH_1):PAGE106
     2 P3E_OCP_CPU0_PE3_C_TXP<4> @BASEBOARD_FAB2_LIB.BASEBOARD_FAB2(SCH_1):P3E_OCP_CPU0_PE3_C_TXP(4)   I128 @BASEBOARD_FAB2_LIB.BASEBOARD_FAB2(SCH_1):PAGE106

C1R13 CAP_0603-10UF,6.3V,20%,X6S,E15A
     1 P3V3_STBY @BASEBOARD_FAB2_LIB.BASEBOARD_FAB2(SCH_1):P3V3_STBY   I142 @BASEBOARD_FAB2_LIB.BASEBOARD_FAB2(SCH_1):PAGE139
     2    GND @BASEBOARD_FAB2_LIB.BASEBOARD_FAB2(SCH_1):GND   I142 @BASEBOARD_FAB2_LIB.BASEBOARD_FAB2(SCH_1):PAGE139

C1R14 CAP_A_0402V-0.1UF,16V,10%,X7R,A
     1 P3V3_STBY @BASEBOARD_FAB2_LIB.BASEBOARD_FAB2(SCH_1):P3V3_STBY   I145 @BASEBOARD_FAB2_LIB.BASEBOARD_FAB2(SCH_1):PAGE139
     2    GND @BASEBOARD_FAB2_LIB.BASEBOARD_FAB2(SCH_1):GND   I145 @BASEBOARD_FAB2_LIB.BASEBOARD_FAB2(SCH_1):PAGE139

C1R15 CAP_A_0402V-0.1UF,16V,10%,X7R,A
     1 P0V9_LAN @BASEBOARD_FAB2_LIB.BASEBOARD_FAB2(SCH_1):P0V9_LAN   I160 @BASEBOARD_FAB2_LIB.BASEBOARD_FAB2(SCH_1):PAGE139
     2    GND @BASEBOARD_FAB2_LIB.BASEBOARD_FAB2(SCH_1):GND   I160 @BASEBOARD_FAB2_LIB.BASEBOARD_FAB2(SCH_1):PAGE139

C1R16 CAP_0603-10UF,6.3V,20%,X6S,E15A
     1 P0V9_LAN @BASEBOARD_FAB2_LIB.BASEBOARD_FAB2(SCH_1):P0V9_LAN   I161 @BASEBOARD_FAB2_LIB.BASEBOARD_FAB2(SCH_1):PAGE139
     2    GND @BASEBOARD_FAB2_LIB.BASEBOARD_FAB2(SCH_1):GND   I161 @BASEBOARD_FAB2_LIB.BASEBOARD_FAB2(SCH_1):PAGE139

C1R17 CAP_0603-10UF,6.3V,20%,X6S,E15A
     1 P1V5_LAN @BASEBOARD_FAB2_LIB.BASEBOARD_FAB2(SCH_1):P1V5_LAN   I153 @BASEBOARD_FAB2_LIB.BASEBOARD_FAB2(SCH_1):PAGE139
     2    GND @BASEBOARD_FAB2_LIB.BASEBOARD_FAB2(SCH_1):GND   I153 @BASEBOARD_FAB2_LIB.BASEBOARD_FAB2(SCH_1):PAGE139

C1R18 CAP_A_0402V-0.1UF,16V,10%,X7R,A
     1 P0V9_LAN @BASEBOARD_FAB2_LIB.BASEBOARD_FAB2(SCH_1):P0V9_LAN   I157 @BASEBOARD_FAB2_LIB.BASEBOARD_FAB2(SCH_1):PAGE139
     2    GND @BASEBOARD_FAB2_LIB.BASEBOARD_FAB2(SCH_1):GND   I157 @BASEBOARD_FAB2_LIB.BASEBOARD_FAB2(SCH_1):PAGE139

C1R19 CAP_A_0402V-0.1UF,16V,10%,X7R,A
     1 P1V5_LAN @BASEBOARD_FAB2_LIB.BASEBOARD_FAB2(SCH_1):P1V5_LAN   I151 @BASEBOARD_FAB2_LIB.BASEBOARD_FAB2(SCH_1):PAGE139
     2    GND @BASEBOARD_FAB2_LIB.BASEBOARD_FAB2(SCH_1):GND   I151 @BASEBOARD_FAB2_LIB.BASEBOARD_FAB2(SCH_1):PAGE139

C1R20 CAP_A_0402V-0.1UF,16V,10%,X7R,A
     1 P3V3_STBY @BASEBOARD_FAB2_LIB.BASEBOARD_FAB2(SCH_1):P3V3_STBY   I143 @BASEBOARD_FAB2_LIB.BASEBOARD_FAB2(SCH_1):PAGE139
     2    GND @BASEBOARD_FAB2_LIB.BASEBOARD_FAB2(SCH_1):GND   I143 @BASEBOARD_FAB2_LIB.BASEBOARD_FAB2(SCH_1):PAGE139

C1R21 CAP_A_0402V-0.1UF,16V,10%,X7R,A
     1 P3V3_STBY @BASEBOARD_FAB2_LIB.BASEBOARD_FAB2(SCH_1):P3V3_STBY   I146 @BASEBOARD_FAB2_LIB.BASEBOARD_FAB2(SCH_1):PAGE139
     2    GND @BASEBOARD_FAB2_LIB.BASEBOARD_FAB2(SCH_1):GND   I146 @BASEBOARD_FAB2_LIB.BASEBOARD_FAB2(SCH_1):PAGE139

C1R22 CAP_0603-10UF,6.3V,20%,X6S,E15A
     1 P3V3_STBY @BASEBOARD_FAB2_LIB.BASEBOARD_FAB2(SCH_1):P3V3_STBY   I136 @BASEBOARD_FAB2_LIB.BASEBOARD_FAB2(SCH_1):PAGE139
     2    GND @BASEBOARD_FAB2_LIB.BASEBOARD_FAB2(SCH_1):GND   I136 @BASEBOARD_FAB2_LIB.BASEBOARD_FAB2(SCH_1):PAGE139

C1R23 CAPP_3018-68UF,16V,20%,TANT,72A
     1 P12V_STBY @BASEBOARD_FAB2_LIB.BASEBOARD_FAB2(SCH_1):P12V_STBY   I101 @BASEBOARD_FAB2_LIB.BASEBOARD_FAB2(SCH_1):PAGE195
     2    GND @BASEBOARD_FAB2_LIB.BASEBOARD_FAB2(SCH_1):GND   I101 @BASEBOARD_FAB2_LIB.BASEBOARD_FAB2(SCH_1):PAGE195

C1R24 CAP_A_0402V-0.1UF,16V,10%,X7R,A
     1 P0V9_LAN @BASEBOARD_FAB2_LIB.BASEBOARD_FAB2(SCH_1):P0V9_LAN   I159 @BASEBOARD_FAB2_LIB.BASEBOARD_FAB2(SCH_1):PAGE139
     2    GND @BASEBOARD_FAB2_LIB.BASEBOARD_FAB2(SCH_1):GND   I159 @BASEBOARD_FAB2_LIB.BASEBOARD_FAB2(SCH_1):PAGE139

C1R25 CAP_A_0402V-0.1UF,16V,10%,X7R,A
     1 P3V3_STBY @BASEBOARD_FAB2_LIB.BASEBOARD_FAB2(SCH_1):P3V3_STBY     I3 @BASEBOARD_FAB2_LIB.BASEBOARD_FAB2(SCH_1):PAGE140
     2    GND @BASEBOARD_FAB2_LIB.BASEBOARD_FAB2(SCH_1):GND     I3 @BASEBOARD_FAB2_LIB.BASEBOARD_FAB2(SCH_1):PAGE140

C1R26 CAP_A_0402V-0.1UF,16V,10%,X7R,A
     1 P1V5_LAN @BASEBOARD_FAB2_LIB.BASEBOARD_FAB2(SCH_1):P1V5_LAN   I149 @BASEBOARD_FAB2_LIB.BASEBOARD_FAB2(SCH_1):PAGE139
     2    GND @BASEBOARD_FAB2_LIB.BASEBOARD_FAB2(SCH_1):GND   I149 @BASEBOARD_FAB2_LIB.BASEBOARD_FAB2(SCH_1):PAGE139

C1R27 CAP_A_0402V-0.1UF,16V,10%,X7R,A
     1 P3V3_STBY @BASEBOARD_FAB2_LIB.BASEBOARD_FAB2(SCH_1):P3V3_STBY    I30 @BASEBOARD_FAB2_LIB.BASEBOARD_FAB2(SCH_1):PAGE170
     2    GND @BASEBOARD_FAB2_LIB.BASEBOARD_FAB2(SCH_1):GND    I30 @BASEBOARD_FAB2_LIB.BASEBOARD_FAB2(SCH_1):PAGE170

C1R28 CAP_A_0402V-0.1UF,16V,10%,X7R,A
     1 P3V3_STBY @BASEBOARD_FAB2_LIB.BASEBOARD_FAB2(SCH_1):P3V3_STBY    I49 @BASEBOARD_FAB2_LIB.BASEBOARD_FAB2(SCH_1):PAGE170
     2    GND @BASEBOARD_FAB2_LIB.BASEBOARD_FAB2(SCH_1):GND    I49 @BASEBOARD_FAB2_LIB.BASEBOARD_FAB2(SCH_1):PAGE170

C1R29 CAP_A_0402V-0.1UF,16V,10%,X7R,A
     1 P1V5_LAN @BASEBOARD_FAB2_LIB.BASEBOARD_FAB2(SCH_1):P1V5_LAN   I150 @BASEBOARD_FAB2_LIB.BASEBOARD_FAB2(SCH_1):PAGE139
     2    GND @BASEBOARD_FAB2_LIB.BASEBOARD_FAB2(SCH_1):GND   I150 @BASEBOARD_FAB2_LIB.BASEBOARD_FAB2(SCH_1):PAGE139

C1R30 CAP_0603-10UF,6.3V,20%,X6S,E15A
     1 P1V5_LAN @BASEBOARD_FAB2_LIB.BASEBOARD_FAB2(SCH_1):P1V5_LAN   I135 @BASEBOARD_FAB2_LIB.BASEBOARD_FAB2(SCH_1):PAGE139
     2    GND @BASEBOARD_FAB2_LIB.BASEBOARD_FAB2(SCH_1):GND   I135 @BASEBOARD_FAB2_LIB.BASEBOARD_FAB2(SCH_1):PAGE139

C1R31 CAP_A_0402V-0.1UF,16V,10%,X7R,A
     1 P1V5_LAN @BASEBOARD_FAB2_LIB.BASEBOARD_FAB2(SCH_1):P1V5_LAN   I152 @BASEBOARD_FAB2_LIB.BASEBOARD_FAB2(SCH_1):PAGE139
     2    GND @BASEBOARD_FAB2_LIB.BASEBOARD_FAB2(SCH_1):GND   I152 @BASEBOARD_FAB2_LIB.BASEBOARD_FAB2(SCH_1):PAGE139

C1T3 CAP_A_0402V-0.1UF,16V,10%,X7R,A
     1 P3V3_STBY @BASEBOARD_FAB2_LIB.BASEBOARD_FAB2(SCH_1):P3V3_STBY   I144 @BASEBOARD_FAB2_LIB.BASEBOARD_FAB2(SCH_1):PAGE139
     2    GND @BASEBOARD_FAB2_LIB.BASEBOARD_FAB2(SCH_1):GND   I144 @BASEBOARD_FAB2_LIB.BASEBOARD_FAB2(SCH_1):PAGE139

C1T4 CAP_0603-10UF,6.3V,20%,X6S,E15A
     1 P0V9_LAN @BASEBOARD_FAB2_LIB.BASEBOARD_FAB2(SCH_1):P0V9_LAN   I134 @BASEBOARD_FAB2_LIB.BASEBOARD_FAB2(SCH_1):PAGE139
     2    GND @BASEBOARD_FAB2_LIB.BASEBOARD_FAB2(SCH_1):GND   I134 @BASEBOARD_FAB2_LIB.BASEBOARD_FAB2(SCH_1):PAGE139

C1T5 CAP_A_0402V-0.1UF,16V,10%,X7R,A
     1 P0V9_LAN @BASEBOARD_FAB2_LIB.BASEBOARD_FAB2(SCH_1):P0V9_LAN   I158 @BASEBOARD_FAB2_LIB.BASEBOARD_FAB2(SCH_1):PAGE139
     2    GND @BASEBOARD_FAB2_LIB.BASEBOARD_FAB2(SCH_1):GND   I158 @BASEBOARD_FAB2_LIB.BASEBOARD_FAB2(SCH_1):PAGE139

C1T7 CAP_0603-10UF,6.3V,20%,X6S,E15A
     1 P3V3_STBY @BASEBOARD_FAB2_LIB.BASEBOARD_FAB2(SCH_1):P3V3_STBY    I22 @BASEBOARD_FAB2_LIB.BASEBOARD_FAB2(SCH_1):PAGE239
     2    GND @BASEBOARD_FAB2_LIB.BASEBOARD_FAB2(SCH_1):GND    I22 @BASEBOARD_FAB2_LIB.BASEBOARD_FAB2(SCH_1):PAGE239

C1T10 CAP_A_0402V-0.1UF,16V,10%,X7R,A
     1 P3V3_STBY @BASEBOARD_FAB2_LIB.BASEBOARD_FAB2(SCH_1):P3V3_STBY    I70 @BASEBOARD_FAB2_LIB.BASEBOARD_FAB2(SCH_1):PAGE158
     2    GND @BASEBOARD_FAB2_LIB.BASEBOARD_FAB2(SCH_1):GND    I70 @BASEBOARD_FAB2_LIB.BASEBOARD_FAB2(SCH_1):PAGE158

C1T11 CAP_A_0402V-0.1UF,16V,10%,X7R,A
     1 P3V3_STBY @BASEBOARD_FAB2_LIB.BASEBOARD_FAB2(SCH_1):P3V3_STBY    I97 @BASEBOARD_FAB2_LIB.BASEBOARD_FAB2(SCH_1):PAGE158
     2    GND @BASEBOARD_FAB2_LIB.BASEBOARD_FAB2(SCH_1):GND    I97 @BASEBOARD_FAB2_LIB.BASEBOARD_FAB2(SCH_1):PAGE158

C1T15 CAP_0603-10UF,6.3V,20%,X6S,E15A
     1 P1V2_AUX_BMC @BASEBOARD_FAB2_LIB.BASEBOARD_FAB2(SCH_1):P1V2_AUX_BMC    I12 @BASEBOARD_FAB2_LIB.BASEBOARD_FAB2(SCH_1):PAGE239
     2    GND @BASEBOARD_FAB2_LIB.BASEBOARD_FAB2(SCH_1):GND    I12 @BASEBOARD_FAB2_LIB.BASEBOARD_FAB2(SCH_1):PAGE239

C1T21 CAP_A_0402V-1.0UF,6.3V,10%,X6SA
     1 PVCCIO_CPU0 @BASEBOARD_FAB2_LIB.BASEBOARD_FAB2(SCH_1):PVCCIO_CPU0    I20 @BASEBOARD_FAB2_LIB.BASEBOARD_FAB2(SCH_1):PAGE148
     2    GND @BASEBOARD_FAB2_LIB.BASEBOARD_FAB2(SCH_1):GND    I20 @BASEBOARD_FAB2_LIB.BASEBOARD_FAB2(SCH_1):PAGE148

C1T56 CAP_A_0402V-0.1UF,16V,10%,X7R,A
     1 P3V3_STBY @BASEBOARD_FAB2_LIB.BASEBOARD_FAB2(SCH_1):P3V3_STBY   I184 @BASEBOARD_FAB2_LIB.BASEBOARD_FAB2(SCH_1):PAGE155
     2    GND @BASEBOARD_FAB2_LIB.BASEBOARD_FAB2(SCH_1):GND   I184 @BASEBOARD_FAB2_LIB.BASEBOARD_FAB2(SCH_1):PAGE155

C1U19 CAP_0402-1.0UF,16V,10%,X6S,D97A
     1   P3V3 @BASEBOARD_FAB2_LIB.BASEBOARD_FAB2(SCH_1):P3V3    I18 @BASEBOARD_FAB2_LIB.BASEBOARD_FAB2(SCH_1):PAGE152
     2    GND @BASEBOARD_FAB2_LIB.BASEBOARD_FAB2(SCH_1):GND    I18 @BASEBOARD_FAB2_LIB.BASEBOARD_FAB2(SCH_1):PAGE152

C1U20 CAP_0805-10UF,16V,10%,X7R,G106A
     1 P3V3_FB_ADC128_VCC @BASEBOARD_FAB2_LIB.BASEBOARD_FAB2(SCH_1):P3V3_FB_ADC128_VCC    I67 @BASEBOARD_FAB2_LIB.BASEBOARD_FAB2(SCH_1):PAGE165
     2    GND @BASEBOARD_FAB2_LIB.BASEBOARD_FAB2(SCH_1):GND    I67 @BASEBOARD_FAB2_LIB.BASEBOARD_FAB2(SCH_1):PAGE165

C1U21 CAP_0402LF-47.0PF,50V,5%,COG,AA
     1 A_P1V05_STBY_PCH_SENSOR @BASEBOARD_FAB2_LIB.BASEBOARD_FAB2(SCH_1):A_P1V05_STBY_PCH_SENSOR    I56 @BASEBOARD_FAB2_LIB.BASEBOARD_FAB2(SCH_1):PAGE169
     2    GND @BASEBOARD_FAB2_LIB.BASEBOARD_FAB2(SCH_1):GND    I56 @BASEBOARD_FAB2_LIB.BASEBOARD_FAB2(SCH_1):PAGE169

C1U22 CAP_A_0402V-0.1UF,16V,10%,X7R,A
     1 P0V7_GTL2014_2 @BASEBOARD_FAB2_LIB.BASEBOARD_FAB2(SCH_1):P0V7_GTL2014_2    I27 @BASEBOARD_FAB2_LIB.BASEBOARD_FAB2(SCH_1):PAGE152
     2    GND @BASEBOARD_FAB2_LIB.BASEBOARD_FAB2(SCH_1):GND    I27 @BASEBOARD_FAB2_LIB.BASEBOARD_FAB2(SCH_1):PAGE152

C1W7 CAP_0603-10UF,6.3V,20%,X6S,E15A
     1 P3V3_STBY @BASEBOARD_FAB2_LIB.BASEBOARD_FAB2(SCH_1):P3V3_STBY    I92 @BASEBOARD_FAB2_LIB.BASEBOARD_FAB2(SCH_1):PAGE239
     2    GND @BASEBOARD_FAB2_LIB.BASEBOARD_FAB2(SCH_1):GND    I92 @BASEBOARD_FAB2_LIB.BASEBOARD_FAB2(SCH_1):PAGE239

C1W15 CAP_0603-10UF,6.3V,20%,X6S,E15A
     1 P2V5_AUX_BMC @BASEBOARD_FAB2_LIB.BASEBOARD_FAB2(SCH_1):P2V5_AUX_BMC    I83 @BASEBOARD_FAB2_LIB.BASEBOARD_FAB2(SCH_1):PAGE239
     2    GND @BASEBOARD_FAB2_LIB.BASEBOARD_FAB2(SCH_1):GND    I83 @BASEBOARD_FAB2_LIB.BASEBOARD_FAB2(SCH_1):PAGE239

C2A1 CAP_A_0603V-22.0UF,4V,20%,X6S,A
     1 PVDDQ_KLM @BASEBOARD_FAB2_LIB.BASEBOARD_FAB2(SCH_1):PVDDQ_KLM   I210 @BASEBOARD_FAB2_LIB.BASEBOARD_FAB2(SCH_1):PAGE228
     2    GND @BASEBOARD_FAB2_LIB.BASEBOARD_FAB2(SCH_1):GND   I210 @BASEBOARD_FAB2_LIB.BASEBOARD_FAB2(SCH_1):PAGE228

C2A2 CAP_A_0603V-22.0UF,4V,20%,X6S,A
     1 PVDDQ_KLM @BASEBOARD_FAB2_LIB.BASEBOARD_FAB2(SCH_1):PVDDQ_KLM   I209 @BASEBOARD_FAB2_LIB.BASEBOARD_FAB2(SCH_1):PAGE228
     2    GND @BASEBOARD_FAB2_LIB.BASEBOARD_FAB2(SCH_1):GND   I209 @BASEBOARD_FAB2_LIB.BASEBOARD_FAB2(SCH_1):PAGE228

C2A3 CAP_A_0603V-22.0UF,4V,20%,X6S,A
     1 PVDDQ_KLM @BASEBOARD_FAB2_LIB.BASEBOARD_FAB2(SCH_1):PVDDQ_KLM   I230 @BASEBOARD_FAB2_LIB.BASEBOARD_FAB2(SCH_1):PAGE228
     2    GND @BASEBOARD_FAB2_LIB.BASEBOARD_FAB2(SCH_1):GND   I230 @BASEBOARD_FAB2_LIB.BASEBOARD_FAB2(SCH_1):PAGE228

C2A4 CAP_A_0603V-22.0UF,4V,20%,X6S,A
     1 PVDDQ_KLM @BASEBOARD_FAB2_LIB.BASEBOARD_FAB2(SCH_1):PVDDQ_KLM   I234 @BASEBOARD_FAB2_LIB.BASEBOARD_FAB2(SCH_1):PAGE228
     2    GND @BASEBOARD_FAB2_LIB.BASEBOARD_FAB2(SCH_1):GND   I234 @BASEBOARD_FAB2_LIB.BASEBOARD_FAB2(SCH_1):PAGE228

C2A5 CAP_A_0603V-47UF,4V,20%,X5R,60A
     1 PVDDQ_KLM @BASEBOARD_FAB2_LIB.BASEBOARD_FAB2(SCH_1):PVDDQ_KLM   I199 @BASEBOARD_FAB2_LIB.BASEBOARD_FAB2(SCH_1):PAGE228
     2    GND @BASEBOARD_FAB2_LIB.BASEBOARD_FAB2(SCH_1):GND   I199 @BASEBOARD_FAB2_LIB.BASEBOARD_FAB2(SCH_1):PAGE228

C2A6 CAP_A_0603V-22.0UF,4V,20%,X6S,A
     1 PVDDQ_KLM @BASEBOARD_FAB2_LIB.BASEBOARD_FAB2(SCH_1):PVDDQ_KLM   I219 @BASEBOARD_FAB2_LIB.BASEBOARD_FAB2(SCH_1):PAGE228
     2    GND @BASEBOARD_FAB2_LIB.BASEBOARD_FAB2(SCH_1):GND   I219 @BASEBOARD_FAB2_LIB.BASEBOARD_FAB2(SCH_1):PAGE228

C2A7 CAP_A_0603V-22.0UF,4V,20%,X6S,A
     1 PVDDQ_KLM @BASEBOARD_FAB2_LIB.BASEBOARD_FAB2(SCH_1):PVDDQ_KLM   I218 @BASEBOARD_FAB2_LIB.BASEBOARD_FAB2(SCH_1):PAGE228
     2    GND @BASEBOARD_FAB2_LIB.BASEBOARD_FAB2(SCH_1):GND   I218 @BASEBOARD_FAB2_LIB.BASEBOARD_FAB2(SCH_1):PAGE228

C2A8 CAP_0805-100UF,4V,20%,X5R,6024A
     1 PVDDQ_KLM @BASEBOARD_FAB2_LIB.BASEBOARD_FAB2(SCH_1):PVDDQ_KLM    I82 @BASEBOARD_FAB2_LIB.BASEBOARD_FAB2(SCH_1):PAGE228
     2    GND @BASEBOARD_FAB2_LIB.BASEBOARD_FAB2(SCH_1):GND    I82 @BASEBOARD_FAB2_LIB.BASEBOARD_FAB2(SCH_1):PAGE228

C2A9 CAP_A_0603V-22.0UF,4V,20%,X6S,A
     1 PVDDQ_KLM @BASEBOARD_FAB2_LIB.BASEBOARD_FAB2(SCH_1):PVDDQ_KLM   I215 @BASEBOARD_FAB2_LIB.BASEBOARD_FAB2(SCH_1):PAGE228
     2    GND @BASEBOARD_FAB2_LIB.BASEBOARD_FAB2(SCH_1):GND   I215 @BASEBOARD_FAB2_LIB.BASEBOARD_FAB2(SCH_1):PAGE228

C2A10 CAP_A_0603V-22.0UF,4V,20%,X6S,A
     1 PVDDQ_KLM @BASEBOARD_FAB2_LIB.BASEBOARD_FAB2(SCH_1):PVDDQ_KLM   I214 @BASEBOARD_FAB2_LIB.BASEBOARD_FAB2(SCH_1):PAGE228
     2    GND @BASEBOARD_FAB2_LIB.BASEBOARD_FAB2(SCH_1):GND   I214 @BASEBOARD_FAB2_LIB.BASEBOARD_FAB2(SCH_1):PAGE228

C2A11 CAP_A_0603V-22.0UF,4V,20%,X6S,A
     1 PVDDQ_KLM @BASEBOARD_FAB2_LIB.BASEBOARD_FAB2(SCH_1):PVDDQ_KLM   I213 @BASEBOARD_FAB2_LIB.BASEBOARD_FAB2(SCH_1):PAGE228
     2    GND @BASEBOARD_FAB2_LIB.BASEBOARD_FAB2(SCH_1):GND   I213 @BASEBOARD_FAB2_LIB.BASEBOARD_FAB2(SCH_1):PAGE228

C2A12 CAP_A_0603V-22.0UF,4V,20%,X6S,A
     1 PVDDQ_KLM @BASEBOARD_FAB2_LIB.BASEBOARD_FAB2(SCH_1):PVDDQ_KLM   I211 @BASEBOARD_FAB2_LIB.BASEBOARD_FAB2(SCH_1):PAGE228
     2    GND @BASEBOARD_FAB2_LIB.BASEBOARD_FAB2(SCH_1):GND   I211 @BASEBOARD_FAB2_LIB.BASEBOARD_FAB2(SCH_1):PAGE228

C2A13 CAP_A_0603V-22.0UF,4V,20%,X6S,A
     1 PVDDQ_KLM @BASEBOARD_FAB2_LIB.BASEBOARD_FAB2(SCH_1):PVDDQ_KLM   I212 @BASEBOARD_FAB2_LIB.BASEBOARD_FAB2(SCH_1):PAGE228
     2    GND @BASEBOARD_FAB2_LIB.BASEBOARD_FAB2(SCH_1):GND   I212 @BASEBOARD_FAB2_LIB.BASEBOARD_FAB2(SCH_1):PAGE228

C2A14 CAP_A_0603V-22.0UF,4V,20%,X6S,A
     1 PVDDQ_KLM @BASEBOARD_FAB2_LIB.BASEBOARD_FAB2(SCH_1):PVDDQ_KLM   I220 @BASEBOARD_FAB2_LIB.BASEBOARD_FAB2(SCH_1):PAGE228
     2    GND @BASEBOARD_FAB2_LIB.BASEBOARD_FAB2(SCH_1):GND   I220 @BASEBOARD_FAB2_LIB.BASEBOARD_FAB2(SCH_1):PAGE228

C2A15 CAP_A_0603V-22.0UF,4V,20%,X6S,A
     1 PVDDQ_KLM @BASEBOARD_FAB2_LIB.BASEBOARD_FAB2(SCH_1):PVDDQ_KLM   I221 @BASEBOARD_FAB2_LIB.BASEBOARD_FAB2(SCH_1):PAGE228
     2    GND @BASEBOARD_FAB2_LIB.BASEBOARD_FAB2(SCH_1):GND   I221 @BASEBOARD_FAB2_LIB.BASEBOARD_FAB2(SCH_1):PAGE228

C2A16 CAP_0805-100UF,4V,20%,X5R,6024A
     1 PVDDQ_KLM @BASEBOARD_FAB2_LIB.BASEBOARD_FAB2(SCH_1):PVDDQ_KLM    I89 @BASEBOARD_FAB2_LIB.BASEBOARD_FAB2(SCH_1):PAGE228
     2    GND @BASEBOARD_FAB2_LIB.BASEBOARD_FAB2(SCH_1):GND    I89 @BASEBOARD_FAB2_LIB.BASEBOARD_FAB2(SCH_1):PAGE228

C2B1 CAP_A_0603V-47UF,4V,20%,X5R,60A
     1 PVDDQ_KLM @BASEBOARD_FAB2_LIB.BASEBOARD_FAB2(SCH_1):PVDDQ_KLM   I200 @BASEBOARD_FAB2_LIB.BASEBOARD_FAB2(SCH_1):PAGE228
     2    GND @BASEBOARD_FAB2_LIB.BASEBOARD_FAB2(SCH_1):GND   I200 @BASEBOARD_FAB2_LIB.BASEBOARD_FAB2(SCH_1):PAGE228

C2B2 CAP_A_0603V-47UF,4V,20%,X5R,60A
     1 PVDDQ_KLM @BASEBOARD_FAB2_LIB.BASEBOARD_FAB2(SCH_1):PVDDQ_KLM   I204 @BASEBOARD_FAB2_LIB.BASEBOARD_FAB2(SCH_1):PAGE228
     2    GND @BASEBOARD_FAB2_LIB.BASEBOARD_FAB2(SCH_1):GND   I204 @BASEBOARD_FAB2_LIB.BASEBOARD_FAB2(SCH_1):PAGE228

C2D1 CAP_A_0603V-22.0UF,4V,20%,X6S,A
     1 PVCCIN_CPU1 @BASEBOARD_FAB2_LIB.BASEBOARD_FAB2(SCH_1):PVCCIN_CPU1   I116 @BASEBOARD_FAB2_LIB.BASEBOARD_FAB2(SCH_1):PAGE76
     2    GND @BASEBOARD_FAB2_LIB.BASEBOARD_FAB2(SCH_1):GND   I116 @BASEBOARD_FAB2_LIB.BASEBOARD_FAB2(SCH_1):PAGE76

C2D2 CAP_A_0603V-22.0UF,4V,20%,X6S,A
     1 PVCCIN_CPU1 @BASEBOARD_FAB2_LIB.BASEBOARD_FAB2(SCH_1):PVCCIN_CPU1   I201 @BASEBOARD_FAB2_LIB.BASEBOARD_FAB2(SCH_1):PAGE76
     2    GND @BASEBOARD_FAB2_LIB.BASEBOARD_FAB2(SCH_1):GND   I201 @BASEBOARD_FAB2_LIB.BASEBOARD_FAB2(SCH_1):PAGE76

C2D3 CAP_A_0603V-22.0UF,4V,20%,X6S,A
     1 PVCCIN_CPU1 @BASEBOARD_FAB2_LIB.BASEBOARD_FAB2(SCH_1):PVCCIN_CPU1   I202 @BASEBOARD_FAB2_LIB.BASEBOARD_FAB2(SCH_1):PAGE76
     2    GND @BASEBOARD_FAB2_LIB.BASEBOARD_FAB2(SCH_1):GND   I202 @BASEBOARD_FAB2_LIB.BASEBOARD_FAB2(SCH_1):PAGE76

C2D4 CAP_0603LF-10UF,4V,20%,X6S,E15A
     1 PVDDQ_KLM @BASEBOARD_FAB2_LIB.BASEBOARD_FAB2(SCH_1):PVDDQ_KLM   I187 @BASEBOARD_FAB2_LIB.BASEBOARD_FAB2(SCH_1):PAGE228
     2    GND @BASEBOARD_FAB2_LIB.BASEBOARD_FAB2(SCH_1):GND   I187 @BASEBOARD_FAB2_LIB.BASEBOARD_FAB2(SCH_1):PAGE228

C2D5 CAP_0603LF-10UF,4V,20%,X6S,E15A
     1 PVDDQ_KLM @BASEBOARD_FAB2_LIB.BASEBOARD_FAB2(SCH_1):PVDDQ_KLM   I188 @BASEBOARD_FAB2_LIB.BASEBOARD_FAB2(SCH_1):PAGE228
     2    GND @BASEBOARD_FAB2_LIB.BASEBOARD_FAB2(SCH_1):GND   I188 @BASEBOARD_FAB2_LIB.BASEBOARD_FAB2(SCH_1):PAGE228

C2D6 CAP_0603LF-10UF,4V,20%,X6S,E15A
     1 PVDDQ_KLM @BASEBOARD_FAB2_LIB.BASEBOARD_FAB2(SCH_1):PVDDQ_KLM   I190 @BASEBOARD_FAB2_LIB.BASEBOARD_FAB2(SCH_1):PAGE228
     2    GND @BASEBOARD_FAB2_LIB.BASEBOARD_FAB2(SCH_1):GND   I190 @BASEBOARD_FAB2_LIB.BASEBOARD_FAB2(SCH_1):PAGE228

C2D7 CAP_0603LF-10UF,4V,20%,X6S,E15A
     1 PVDDQ_KLM @BASEBOARD_FAB2_LIB.BASEBOARD_FAB2(SCH_1):PVDDQ_KLM   I186 @BASEBOARD_FAB2_LIB.BASEBOARD_FAB2(SCH_1):PAGE228
     2    GND @BASEBOARD_FAB2_LIB.BASEBOARD_FAB2(SCH_1):GND   I186 @BASEBOARD_FAB2_LIB.BASEBOARD_FAB2(SCH_1):PAGE228

C2D8 CAP_0603LF-10UF,4V,20%,X6S,E15A
     1 PVSA_CPU1 @BASEBOARD_FAB2_LIB.BASEBOARD_FAB2(SCH_1):PVSA_CPU1    I33 @BASEBOARD_FAB2_LIB.BASEBOARD_FAB2(SCH_1):PAGE76
     2    GND @BASEBOARD_FAB2_LIB.BASEBOARD_FAB2(SCH_1):GND    I33 @BASEBOARD_FAB2_LIB.BASEBOARD_FAB2(SCH_1):PAGE76

C2D9 CAP_0603LF-10UF,4V,20%,X6S,E15A
     1 PVSA_CPU1 @BASEBOARD_FAB2_LIB.BASEBOARD_FAB2(SCH_1):PVSA_CPU1    I43 @BASEBOARD_FAB2_LIB.BASEBOARD_FAB2(SCH_1):PAGE76
     2    GND @BASEBOARD_FAB2_LIB.BASEBOARD_FAB2(SCH_1):GND    I43 @BASEBOARD_FAB2_LIB.BASEBOARD_FAB2(SCH_1):PAGE76

C2D10 CAP_0603LF-10UF,4V,20%,X6S,E15A
     1 PVSA_CPU1 @BASEBOARD_FAB2_LIB.BASEBOARD_FAB2(SCH_1):PVSA_CPU1    I37 @BASEBOARD_FAB2_LIB.BASEBOARD_FAB2(SCH_1):PAGE76
     2    GND @BASEBOARD_FAB2_LIB.BASEBOARD_FAB2(SCH_1):GND    I37 @BASEBOARD_FAB2_LIB.BASEBOARD_FAB2(SCH_1):PAGE76

C2D11 CAP_0603LF-10UF,4V,20%,X6S,E15A
     1 PVSA_CPU1 @BASEBOARD_FAB2_LIB.BASEBOARD_FAB2(SCH_1):PVSA_CPU1    I42 @BASEBOARD_FAB2_LIB.BASEBOARD_FAB2(SCH_1):PAGE76
     2    GND @BASEBOARD_FAB2_LIB.BASEBOARD_FAB2(SCH_1):GND    I42 @BASEBOARD_FAB2_LIB.BASEBOARD_FAB2(SCH_1):PAGE76

C2D12 CAP_A_0603V-22.0UF,4V,20%,X6S,A
     1 PVCCIN_CPU1 @BASEBOARD_FAB2_LIB.BASEBOARD_FAB2(SCH_1):PVCCIN_CPU1    I59 @BASEBOARD_FAB2_LIB.BASEBOARD_FAB2(SCH_1):PAGE76
     2    GND @BASEBOARD_FAB2_LIB.BASEBOARD_FAB2(SCH_1):GND    I59 @BASEBOARD_FAB2_LIB.BASEBOARD_FAB2(SCH_1):PAGE76

C2D13 CAP_A_0603V-22.0UF,4V,20%,X6S,A
     1 PVCCIN_CPU1 @BASEBOARD_FAB2_LIB.BASEBOARD_FAB2(SCH_1):PVCCIN_CPU1    I73 @BASEBOARD_FAB2_LIB.BASEBOARD_FAB2(SCH_1):PAGE76
     2    GND @BASEBOARD_FAB2_LIB.BASEBOARD_FAB2(SCH_1):GND    I73 @BASEBOARD_FAB2_LIB.BASEBOARD_FAB2(SCH_1):PAGE76

C2D14 CAP_A_0603V-22.0UF,4V,20%,X6S,A
     1 PVCCIN_CPU1 @BASEBOARD_FAB2_LIB.BASEBOARD_FAB2(SCH_1):PVCCIN_CPU1    I76 @BASEBOARD_FAB2_LIB.BASEBOARD_FAB2(SCH_1):PAGE76
     2    GND @BASEBOARD_FAB2_LIB.BASEBOARD_FAB2(SCH_1):GND    I76 @BASEBOARD_FAB2_LIB.BASEBOARD_FAB2(SCH_1):PAGE76

C2D15 CAP_A_0603V-22.0UF,4V,20%,X6S,A
     1 PVCCIN_CPU1 @BASEBOARD_FAB2_LIB.BASEBOARD_FAB2(SCH_1):PVCCIN_CPU1   I159 @BASEBOARD_FAB2_LIB.BASEBOARD_FAB2(SCH_1):PAGE76
     2    GND @BASEBOARD_FAB2_LIB.BASEBOARD_FAB2(SCH_1):GND   I159 @BASEBOARD_FAB2_LIB.BASEBOARD_FAB2(SCH_1):PAGE76

C2D16 CAP_A_0603V-22.0UF,4V,20%,X6S,A
     1 PVCCIN_CPU1 @BASEBOARD_FAB2_LIB.BASEBOARD_FAB2(SCH_1):PVCCIN_CPU1   I124 @BASEBOARD_FAB2_LIB.BASEBOARD_FAB2(SCH_1):PAGE76
     2    GND @BASEBOARD_FAB2_LIB.BASEBOARD_FAB2(SCH_1):GND   I124 @BASEBOARD_FAB2_LIB.BASEBOARD_FAB2(SCH_1):PAGE76

C2D17 CAP_A_0603V-22.0UF,4V,20%,X6S,A
     1 PVCCIN_CPU1 @BASEBOARD_FAB2_LIB.BASEBOARD_FAB2(SCH_1):PVCCIN_CPU1   I114 @BASEBOARD_FAB2_LIB.BASEBOARD_FAB2(SCH_1):PAGE76
     2    GND @BASEBOARD_FAB2_LIB.BASEBOARD_FAB2(SCH_1):GND   I114 @BASEBOARD_FAB2_LIB.BASEBOARD_FAB2(SCH_1):PAGE76

C2D18 CAP_A_0603V-22.0UF,4V,20%,X6S,A
     1 PVCCMCP_CPU1 @BASEBOARD_FAB2_LIB.BASEBOARD_FAB2(SCH_1):PVCCMCP_CPU1   I197 @BASEBOARD_FAB2_LIB.BASEBOARD_FAB2(SCH_1):PAGE76
     2    GND @BASEBOARD_FAB2_LIB.BASEBOARD_FAB2(SCH_1):GND   I197 @BASEBOARD_FAB2_LIB.BASEBOARD_FAB2(SCH_1):PAGE76

C2D19 CAP_A_0603V-22.0UF,4V,20%,X6S,A
     1 PVCCIN_CPU1 @BASEBOARD_FAB2_LIB.BASEBOARD_FAB2(SCH_1):PVCCIN_CPU1    I75 @BASEBOARD_FAB2_LIB.BASEBOARD_FAB2(SCH_1):PAGE76
     2    GND @BASEBOARD_FAB2_LIB.BASEBOARD_FAB2(SCH_1):GND    I75 @BASEBOARD_FAB2_LIB.BASEBOARD_FAB2(SCH_1):PAGE76

C2D20 CAP_A_0603V-22.0UF,4V,20%,X6S,A
     1 PVCCIN_CPU1 @BASEBOARD_FAB2_LIB.BASEBOARD_FAB2(SCH_1):PVCCIN_CPU1    I79 @BASEBOARD_FAB2_LIB.BASEBOARD_FAB2(SCH_1):PAGE76
     2    GND @BASEBOARD_FAB2_LIB.BASEBOARD_FAB2(SCH_1):GND    I79 @BASEBOARD_FAB2_LIB.BASEBOARD_FAB2(SCH_1):PAGE76

C2D21 CAP_A_0603V-22.0UF,4V,20%,X6S,A
     1 PVCCIN_CPU1 @BASEBOARD_FAB2_LIB.BASEBOARD_FAB2(SCH_1):PVCCIN_CPU1    I65 @BASEBOARD_FAB2_LIB.BASEBOARD_FAB2(SCH_1):PAGE76
     2    GND @BASEBOARD_FAB2_LIB.BASEBOARD_FAB2(SCH_1):GND    I65 @BASEBOARD_FAB2_LIB.BASEBOARD_FAB2(SCH_1):PAGE76

C2D22 CAP_A_0603V-22.0UF,4V,20%,X6S,A
     1 PVCCIN_CPU1 @BASEBOARD_FAB2_LIB.BASEBOARD_FAB2(SCH_1):PVCCIN_CPU1    I61 @BASEBOARD_FAB2_LIB.BASEBOARD_FAB2(SCH_1):PAGE76
     2    GND @BASEBOARD_FAB2_LIB.BASEBOARD_FAB2(SCH_1):GND    I61 @BASEBOARD_FAB2_LIB.BASEBOARD_FAB2(SCH_1):PAGE76

C2D23 CAP_A_0603V-22.0UF,4V,20%,X6S,A
     1 PVCCIN_CPU1 @BASEBOARD_FAB2_LIB.BASEBOARD_FAB2(SCH_1):PVCCIN_CPU1   I112 @BASEBOARD_FAB2_LIB.BASEBOARD_FAB2(SCH_1):PAGE76
     2    GND @BASEBOARD_FAB2_LIB.BASEBOARD_FAB2(SCH_1):GND   I112 @BASEBOARD_FAB2_LIB.BASEBOARD_FAB2(SCH_1):PAGE76

C2D24 CAP_A_0603V-22.0UF,4V,20%,X6S,A
     1 PVCCIN_CPU1 @BASEBOARD_FAB2_LIB.BASEBOARD_FAB2(SCH_1):PVCCIN_CPU1    I80 @BASEBOARD_FAB2_LIB.BASEBOARD_FAB2(SCH_1):PAGE76
     2    GND @BASEBOARD_FAB2_LIB.BASEBOARD_FAB2(SCH_1):GND    I80 @BASEBOARD_FAB2_LIB.BASEBOARD_FAB2(SCH_1):PAGE76

C2D25 CAP_A_0603V-22.0UF,4V,20%,X6S,A
     1 PVCCIN_CPU1 @BASEBOARD_FAB2_LIB.BASEBOARD_FAB2(SCH_1):PVCCIN_CPU1    I82 @BASEBOARD_FAB2_LIB.BASEBOARD_FAB2(SCH_1):PAGE76
     2    GND @BASEBOARD_FAB2_LIB.BASEBOARD_FAB2(SCH_1):GND    I82 @BASEBOARD_FAB2_LIB.BASEBOARD_FAB2(SCH_1):PAGE76

C2D26 CAP_A_0603V-22.0UF,4V,20%,X6S,A
     1 PVCCIN_CPU1 @BASEBOARD_FAB2_LIB.BASEBOARD_FAB2(SCH_1):PVCCIN_CPU1   I108 @BASEBOARD_FAB2_LIB.BASEBOARD_FAB2(SCH_1):PAGE76
     2    GND @BASEBOARD_FAB2_LIB.BASEBOARD_FAB2(SCH_1):GND   I108 @BASEBOARD_FAB2_LIB.BASEBOARD_FAB2(SCH_1):PAGE76

C2D27 CAP_A_0603V-22.0UF,4V,20%,X6S,A
     1 PVCCIN_CPU1 @BASEBOARD_FAB2_LIB.BASEBOARD_FAB2(SCH_1):PVCCIN_CPU1    I66 @BASEBOARD_FAB2_LIB.BASEBOARD_FAB2(SCH_1):PAGE76
     2    GND @BASEBOARD_FAB2_LIB.BASEBOARD_FAB2(SCH_1):GND    I66 @BASEBOARD_FAB2_LIB.BASEBOARD_FAB2(SCH_1):PAGE76

C2D28 CAP_A_0603V-22.0UF,4V,20%,X6S,A
     1 PVCCMCP_CPU1 @BASEBOARD_FAB2_LIB.BASEBOARD_FAB2(SCH_1):PVCCMCP_CPU1   I198 @BASEBOARD_FAB2_LIB.BASEBOARD_FAB2(SCH_1):PAGE76
     2    GND @BASEBOARD_FAB2_LIB.BASEBOARD_FAB2(SCH_1):GND   I198 @BASEBOARD_FAB2_LIB.BASEBOARD_FAB2(SCH_1):PAGE76

C2D29 CAP_A_0603V-22.0UF,4V,20%,X6S,A
     1 PVCCMCP_CPU1 @BASEBOARD_FAB2_LIB.BASEBOARD_FAB2(SCH_1):PVCCMCP_CPU1   I199 @BASEBOARD_FAB2_LIB.BASEBOARD_FAB2(SCH_1):PAGE76
     2    GND @BASEBOARD_FAB2_LIB.BASEBOARD_FAB2(SCH_1):GND   I199 @BASEBOARD_FAB2_LIB.BASEBOARD_FAB2(SCH_1):PAGE76

C2D30 CAP_A_0603V-22.0UF,4V,20%,X6S,A
     1 PVCCIN_CPU1 @BASEBOARD_FAB2_LIB.BASEBOARD_FAB2(SCH_1):PVCCIN_CPU1    I83 @BASEBOARD_FAB2_LIB.BASEBOARD_FAB2(SCH_1):PAGE76
     2    GND @BASEBOARD_FAB2_LIB.BASEBOARD_FAB2(SCH_1):GND    I83 @BASEBOARD_FAB2_LIB.BASEBOARD_FAB2(SCH_1):PAGE76

C2D31 CAP_A_0603V-22.0UF,4V,20%,X6S,A
     1 PVCCIN_CPU1 @BASEBOARD_FAB2_LIB.BASEBOARD_FAB2(SCH_1):PVCCIN_CPU1    I63 @BASEBOARD_FAB2_LIB.BASEBOARD_FAB2(SCH_1):PAGE76
     2    GND @BASEBOARD_FAB2_LIB.BASEBOARD_FAB2(SCH_1):GND    I63 @BASEBOARD_FAB2_LIB.BASEBOARD_FAB2(SCH_1):PAGE76

C2D32 CAP_A_0603V-22.0UF,4V,20%,X6S,A
     1 PVCCIN_CPU1 @BASEBOARD_FAB2_LIB.BASEBOARD_FAB2(SCH_1):PVCCIN_CPU1    I90 @BASEBOARD_FAB2_LIB.BASEBOARD_FAB2(SCH_1):PAGE76
     2    GND @BASEBOARD_FAB2_LIB.BASEBOARD_FAB2(SCH_1):GND    I90 @BASEBOARD_FAB2_LIB.BASEBOARD_FAB2(SCH_1):PAGE76

C2D33 CAP_A_0603V-22.0UF,4V,20%,X6S,A
     1 PVCCIN_CPU1 @BASEBOARD_FAB2_LIB.BASEBOARD_FAB2(SCH_1):PVCCIN_CPU1    I85 @BASEBOARD_FAB2_LIB.BASEBOARD_FAB2(SCH_1):PAGE76
     2    GND @BASEBOARD_FAB2_LIB.BASEBOARD_FAB2(SCH_1):GND    I85 @BASEBOARD_FAB2_LIB.BASEBOARD_FAB2(SCH_1):PAGE76

C2D34 CAP_A_0603V-22.0UF,4V,20%,X6S,A
     1 PVCCIN_CPU1 @BASEBOARD_FAB2_LIB.BASEBOARD_FAB2(SCH_1):PVCCIN_CPU1   I122 @BASEBOARD_FAB2_LIB.BASEBOARD_FAB2(SCH_1):PAGE76
     2    GND @BASEBOARD_FAB2_LIB.BASEBOARD_FAB2(SCH_1):GND   I122 @BASEBOARD_FAB2_LIB.BASEBOARD_FAB2(SCH_1):PAGE76

C2D35 CAP_A_0603V-22.0UF,4V,20%,X6S,A
     1 PVCCIN_CPU1 @BASEBOARD_FAB2_LIB.BASEBOARD_FAB2(SCH_1):PVCCIN_CPU1   I161 @BASEBOARD_FAB2_LIB.BASEBOARD_FAB2(SCH_1):PAGE76
     2    GND @BASEBOARD_FAB2_LIB.BASEBOARD_FAB2(SCH_1):GND   I161 @BASEBOARD_FAB2_LIB.BASEBOARD_FAB2(SCH_1):PAGE76

C2D36 CAP_A_0603V-22.0UF,4V,20%,X6S,A
     1 PVCCIN_CPU1 @BASEBOARD_FAB2_LIB.BASEBOARD_FAB2(SCH_1):PVCCIN_CPU1    I70 @BASEBOARD_FAB2_LIB.BASEBOARD_FAB2(SCH_1):PAGE76
     2    GND @BASEBOARD_FAB2_LIB.BASEBOARD_FAB2(SCH_1):GND    I70 @BASEBOARD_FAB2_LIB.BASEBOARD_FAB2(SCH_1):PAGE76

C2D37 CAP_A_0603V-22.0UF,4V,20%,X6S,A
     1 PVCCIN_CPU1 @BASEBOARD_FAB2_LIB.BASEBOARD_FAB2(SCH_1):PVCCIN_CPU1   I119 @BASEBOARD_FAB2_LIB.BASEBOARD_FAB2(SCH_1):PAGE76
     2    GND @BASEBOARD_FAB2_LIB.BASEBOARD_FAB2(SCH_1):GND   I119 @BASEBOARD_FAB2_LIB.BASEBOARD_FAB2(SCH_1):PAGE76

C2D38 CAP_A_0603V-22.0UF,4V,20%,X6S,A
     1 PVCCIN_CPU1 @BASEBOARD_FAB2_LIB.BASEBOARD_FAB2(SCH_1):PVCCIN_CPU1   I160 @BASEBOARD_FAB2_LIB.BASEBOARD_FAB2(SCH_1):PAGE76
     2    GND @BASEBOARD_FAB2_LIB.BASEBOARD_FAB2(SCH_1):GND   I160 @BASEBOARD_FAB2_LIB.BASEBOARD_FAB2(SCH_1):PAGE76

C2D39 CAP_A_0603V-22.0UF,4V,20%,X6S,A
     1 PVCCMCP_CPU1 @BASEBOARD_FAB2_LIB.BASEBOARD_FAB2(SCH_1):PVCCMCP_CPU1   I165 @BASEBOARD_FAB2_LIB.BASEBOARD_FAB2(SCH_1):PAGE76
     2    GND @BASEBOARD_FAB2_LIB.BASEBOARD_FAB2(SCH_1):GND   I165 @BASEBOARD_FAB2_LIB.BASEBOARD_FAB2(SCH_1):PAGE76

C2D40 CAP_A_0603V-22.0UF,4V,20%,X6S,A
     1 PVCCMCP_CPU1 @BASEBOARD_FAB2_LIB.BASEBOARD_FAB2(SCH_1):PVCCMCP_CPU1    I10 @BASEBOARD_FAB2_LIB.BASEBOARD_FAB2(SCH_1):PAGE76
     2    GND @BASEBOARD_FAB2_LIB.BASEBOARD_FAB2(SCH_1):GND    I10 @BASEBOARD_FAB2_LIB.BASEBOARD_FAB2(SCH_1):PAGE76

C2D41 CAP_0603LF-10UF,4V,20%,X6S,E15A
     1 PVDDQ_GHJ @BASEBOARD_FAB2_LIB.BASEBOARD_FAB2(SCH_1):PVDDQ_GHJ   I180 @BASEBOARD_FAB2_LIB.BASEBOARD_FAB2(SCH_1):PAGE225
     2    GND @BASEBOARD_FAB2_LIB.BASEBOARD_FAB2(SCH_1):GND   I180 @BASEBOARD_FAB2_LIB.BASEBOARD_FAB2(SCH_1):PAGE225

C2D42 CAP_0603LF-10UF,4V,20%,X6S,E15A
     1 PVDDQ_GHJ @BASEBOARD_FAB2_LIB.BASEBOARD_FAB2(SCH_1):PVDDQ_GHJ   I183 @BASEBOARD_FAB2_LIB.BASEBOARD_FAB2(SCH_1):PAGE225
     2    GND @BASEBOARD_FAB2_LIB.BASEBOARD_FAB2(SCH_1):GND   I183 @BASEBOARD_FAB2_LIB.BASEBOARD_FAB2(SCH_1):PAGE225

C2D43 CAP_0603LF-10UF,4V,20%,X6S,E15A
     1 PVDDQ_GHJ @BASEBOARD_FAB2_LIB.BASEBOARD_FAB2(SCH_1):PVDDQ_GHJ   I179 @BASEBOARD_FAB2_LIB.BASEBOARD_FAB2(SCH_1):PAGE225
     2    GND @BASEBOARD_FAB2_LIB.BASEBOARD_FAB2(SCH_1):GND   I179 @BASEBOARD_FAB2_LIB.BASEBOARD_FAB2(SCH_1):PAGE225

C2D44 CAP_0603LF-10UF,4V,20%,X6S,E15A
     1 PVDDQ_GHJ @BASEBOARD_FAB2_LIB.BASEBOARD_FAB2(SCH_1):PVDDQ_GHJ   I181 @BASEBOARD_FAB2_LIB.BASEBOARD_FAB2(SCH_1):PAGE225
     2    GND @BASEBOARD_FAB2_LIB.BASEBOARD_FAB2(SCH_1):GND   I181 @BASEBOARD_FAB2_LIB.BASEBOARD_FAB2(SCH_1):PAGE225

C2D45 CAP_A_0603V-22.0UF,4V,20%,X6S,A
     1 PVCCIN_CPU1 @BASEBOARD_FAB2_LIB.BASEBOARD_FAB2(SCH_1):PVCCIN_CPU1   I123 @BASEBOARD_FAB2_LIB.BASEBOARD_FAB2(SCH_1):PAGE76
     2    GND @BASEBOARD_FAB2_LIB.BASEBOARD_FAB2(SCH_1):GND   I123 @BASEBOARD_FAB2_LIB.BASEBOARD_FAB2(SCH_1):PAGE76

C2D46 CAP_A_0603V-22.0UF,4V,20%,X6S,A
     1 PVCCIN_CPU1 @BASEBOARD_FAB2_LIB.BASEBOARD_FAB2(SCH_1):PVCCIN_CPU1   I204 @BASEBOARD_FAB2_LIB.BASEBOARD_FAB2(SCH_1):PAGE76
     2    GND @BASEBOARD_FAB2_LIB.BASEBOARD_FAB2(SCH_1):GND   I204 @BASEBOARD_FAB2_LIB.BASEBOARD_FAB2(SCH_1):PAGE76

C2D47 CAP_A_0603V-22.0UF,4V,20%,X6S,A
     1 PVCCIN_CPU1 @BASEBOARD_FAB2_LIB.BASEBOARD_FAB2(SCH_1):PVCCIN_CPU1   I203 @BASEBOARD_FAB2_LIB.BASEBOARD_FAB2(SCH_1):PAGE76
     2    GND @BASEBOARD_FAB2_LIB.BASEBOARD_FAB2(SCH_1):GND   I203 @BASEBOARD_FAB2_LIB.BASEBOARD_FAB2(SCH_1):PAGE76

C2F1 CAP_A_0603V-47UF,4V,20%,X5R,60A
     1 PVDDQ_GHJ @BASEBOARD_FAB2_LIB.BASEBOARD_FAB2(SCH_1):PVDDQ_GHJ   I201 @BASEBOARD_FAB2_LIB.BASEBOARD_FAB2(SCH_1):PAGE225
     2    GND @BASEBOARD_FAB2_LIB.BASEBOARD_FAB2(SCH_1):GND   I201 @BASEBOARD_FAB2_LIB.BASEBOARD_FAB2(SCH_1):PAGE225

C2F2 CAP_A_0603V-47UF,4V,20%,X5R,60A
     1 PVTT_GHJ @BASEBOARD_FAB2_LIB.BASEBOARD_FAB2(SCH_1):PVTT_GHJ    I47 @BASEBOARD_FAB2_LIB.BASEBOARD_FAB2(SCH_1):PAGE229
     2    GND @BASEBOARD_FAB2_LIB.BASEBOARD_FAB2(SCH_1):GND    I47 @BASEBOARD_FAB2_LIB.BASEBOARD_FAB2(SCH_1):PAGE229

C2G1 CAP_A_0603V-22.0UF,4V,20%,X6S,A
     1 PVDDQ_GHJ @BASEBOARD_FAB2_LIB.BASEBOARD_FAB2(SCH_1):PVDDQ_GHJ   I219 @BASEBOARD_FAB2_LIB.BASEBOARD_FAB2(SCH_1):PAGE225
     2    GND @BASEBOARD_FAB2_LIB.BASEBOARD_FAB2(SCH_1):GND   I219 @BASEBOARD_FAB2_LIB.BASEBOARD_FAB2(SCH_1):PAGE225

C2G2 CAP_A_0603V-22.0UF,4V,20%,X6S,A
     1 PVDDQ_GHJ @BASEBOARD_FAB2_LIB.BASEBOARD_FAB2(SCH_1):PVDDQ_GHJ   I217 @BASEBOARD_FAB2_LIB.BASEBOARD_FAB2(SCH_1):PAGE225
     2    GND @BASEBOARD_FAB2_LIB.BASEBOARD_FAB2(SCH_1):GND   I217 @BASEBOARD_FAB2_LIB.BASEBOARD_FAB2(SCH_1):PAGE225

C2G3 CAP_A_0603V-22.0UF,4V,20%,X6S,A
     1 PVDDQ_GHJ @BASEBOARD_FAB2_LIB.BASEBOARD_FAB2(SCH_1):PVDDQ_GHJ   I216 @BASEBOARD_FAB2_LIB.BASEBOARD_FAB2(SCH_1):PAGE225
     2    GND @BASEBOARD_FAB2_LIB.BASEBOARD_FAB2(SCH_1):GND   I216 @BASEBOARD_FAB2_LIB.BASEBOARD_FAB2(SCH_1):PAGE225

C2G4 CAP_A_0603V-22.0UF,4V,20%,X6S,A
     1 PVDDQ_GHJ @BASEBOARD_FAB2_LIB.BASEBOARD_FAB2(SCH_1):PVDDQ_GHJ   I215 @BASEBOARD_FAB2_LIB.BASEBOARD_FAB2(SCH_1):PAGE225
     2    GND @BASEBOARD_FAB2_LIB.BASEBOARD_FAB2(SCH_1):GND   I215 @BASEBOARD_FAB2_LIB.BASEBOARD_FAB2(SCH_1):PAGE225

C2G5 CAP_A_0603V-22.0UF,4V,20%,X6S,A
     1 PVDDQ_GHJ @BASEBOARD_FAB2_LIB.BASEBOARD_FAB2(SCH_1):PVDDQ_GHJ   I214 @BASEBOARD_FAB2_LIB.BASEBOARD_FAB2(SCH_1):PAGE225
     2    GND @BASEBOARD_FAB2_LIB.BASEBOARD_FAB2(SCH_1):GND   I214 @BASEBOARD_FAB2_LIB.BASEBOARD_FAB2(SCH_1):PAGE225

C2G6 CAP_A_0603V-22.0UF,4V,20%,X6S,A
     1 PVDDQ_GHJ @BASEBOARD_FAB2_LIB.BASEBOARD_FAB2(SCH_1):PVDDQ_GHJ   I213 @BASEBOARD_FAB2_LIB.BASEBOARD_FAB2(SCH_1):PAGE225
     2    GND @BASEBOARD_FAB2_LIB.BASEBOARD_FAB2(SCH_1):GND   I213 @BASEBOARD_FAB2_LIB.BASEBOARD_FAB2(SCH_1):PAGE225

C2G7 CAP_0805-100UF,4V,20%,X5R,6024A
     1 PVDDQ_GHJ @BASEBOARD_FAB2_LIB.BASEBOARD_FAB2(SCH_1):PVDDQ_GHJ    I92 @BASEBOARD_FAB2_LIB.BASEBOARD_FAB2(SCH_1):PAGE225
     2    GND @BASEBOARD_FAB2_LIB.BASEBOARD_FAB2(SCH_1):GND    I92 @BASEBOARD_FAB2_LIB.BASEBOARD_FAB2(SCH_1):PAGE225

C2G8 CAP_A_0603V-47UF,4V,20%,X5R,60A
     1 PVDDQ_GHJ @BASEBOARD_FAB2_LIB.BASEBOARD_FAB2(SCH_1):PVDDQ_GHJ   I197 @BASEBOARD_FAB2_LIB.BASEBOARD_FAB2(SCH_1):PAGE225
     2    GND @BASEBOARD_FAB2_LIB.BASEBOARD_FAB2(SCH_1):GND   I197 @BASEBOARD_FAB2_LIB.BASEBOARD_FAB2(SCH_1):PAGE225

C2G9 CAP_A_0603V-22.0UF,4V,20%,X6S,A
     1 PVDDQ_GHJ @BASEBOARD_FAB2_LIB.BASEBOARD_FAB2(SCH_1):PVDDQ_GHJ   I218 @BASEBOARD_FAB2_LIB.BASEBOARD_FAB2(SCH_1):PAGE225
     2    GND @BASEBOARD_FAB2_LIB.BASEBOARD_FAB2(SCH_1):GND   I218 @BASEBOARD_FAB2_LIB.BASEBOARD_FAB2(SCH_1):PAGE225

C2G10 CAP_A_0603V-22.0UF,4V,20%,X6S,A
     1 PVDDQ_GHJ @BASEBOARD_FAB2_LIB.BASEBOARD_FAB2(SCH_1):PVDDQ_GHJ   I223 @BASEBOARD_FAB2_LIB.BASEBOARD_FAB2(SCH_1):PAGE225
     2    GND @BASEBOARD_FAB2_LIB.BASEBOARD_FAB2(SCH_1):GND   I223 @BASEBOARD_FAB2_LIB.BASEBOARD_FAB2(SCH_1):PAGE225

C2G11 CAP_A_0603V-22.0UF,4V,20%,X6S,A
     1 PVDDQ_GHJ @BASEBOARD_FAB2_LIB.BASEBOARD_FAB2(SCH_1):PVDDQ_GHJ   I221 @BASEBOARD_FAB2_LIB.BASEBOARD_FAB2(SCH_1):PAGE225
     2    GND @BASEBOARD_FAB2_LIB.BASEBOARD_FAB2(SCH_1):GND   I221 @BASEBOARD_FAB2_LIB.BASEBOARD_FAB2(SCH_1):PAGE225

C2G12 CAP_A_0603V-22.0UF,4V,20%,X6S,A
     1 PVDDQ_GHJ @BASEBOARD_FAB2_LIB.BASEBOARD_FAB2(SCH_1):PVDDQ_GHJ   I220 @BASEBOARD_FAB2_LIB.BASEBOARD_FAB2(SCH_1):PAGE225
     2    GND @BASEBOARD_FAB2_LIB.BASEBOARD_FAB2(SCH_1):GND   I220 @BASEBOARD_FAB2_LIB.BASEBOARD_FAB2(SCH_1):PAGE225

C2G13 CAP_A_0603V-22.0UF,4V,20%,X6S,A
     1 PVDDQ_GHJ @BASEBOARD_FAB2_LIB.BASEBOARD_FAB2(SCH_1):PVDDQ_GHJ   I210 @BASEBOARD_FAB2_LIB.BASEBOARD_FAB2(SCH_1):PAGE225
     2    GND @BASEBOARD_FAB2_LIB.BASEBOARD_FAB2(SCH_1):GND   I210 @BASEBOARD_FAB2_LIB.BASEBOARD_FAB2(SCH_1):PAGE225

C2G14 CAP_A_0603V-22.0UF,4V,20%,X6S,A
     1 PVDDQ_GHJ @BASEBOARD_FAB2_LIB.BASEBOARD_FAB2(SCH_1):PVDDQ_GHJ   I209 @BASEBOARD_FAB2_LIB.BASEBOARD_FAB2(SCH_1):PAGE225
     2    GND @BASEBOARD_FAB2_LIB.BASEBOARD_FAB2(SCH_1):GND   I209 @BASEBOARD_FAB2_LIB.BASEBOARD_FAB2(SCH_1):PAGE225

C2G15 CAP_A_0603V-47UF,4V,20%,X5R,60A
     1 PVDDQ_GHJ @BASEBOARD_FAB2_LIB.BASEBOARD_FAB2(SCH_1):PVDDQ_GHJ   I200 @BASEBOARD_FAB2_LIB.BASEBOARD_FAB2(SCH_1):PAGE225
     2    GND @BASEBOARD_FAB2_LIB.BASEBOARD_FAB2(SCH_1):GND   I200 @BASEBOARD_FAB2_LIB.BASEBOARD_FAB2(SCH_1):PAGE225

C2G16 CAP_0805-100UF,4V,20%,X5R,6024A
     1 PVDDQ_GHJ @BASEBOARD_FAB2_LIB.BASEBOARD_FAB2(SCH_1):PVDDQ_GHJ   I110 @BASEBOARD_FAB2_LIB.BASEBOARD_FAB2(SCH_1):PAGE225
     2    GND @BASEBOARD_FAB2_LIB.BASEBOARD_FAB2(SCH_1):GND   I110 @BASEBOARD_FAB2_LIB.BASEBOARD_FAB2(SCH_1):PAGE225

C2L2 CAP_0402LF-220PF,50V,10%,X7R,AA
     1 VR_P1V05_PCH_STBY_AVSP @BASEBOARD_FAB2_LIB.BASEBOARD_FAB2(SCH_1):VR_P1V05_PCH_STBY_AVSP   I153 @BASEBOARD_FAB2_LIB.BASEBOARD_FAB2(SCH_1):PAGE235
     2 VSENSE_P1V05_PCH_STBY_AVSN @BASEBOARD_FAB2_LIB.BASEBOARD_FAB2(SCH_1):VSENSE_P1V05_PCH_STBY_AVSN   I153 @BASEBOARD_FAB2_LIB.BASEBOARD_FAB2(SCH_1):PAGE235

C2L3 CAP_A_0402V-0.01UF,25V,10%,X7RA
     1 SATA6G_PCH_PCIE_UP_SATA_RXN<3> @BASEBOARD_FAB2_LIB.BASEBOARD_FAB2(SCH_1):SATA6G_PCH_PCIE_UP_SATA_RXN(3)   I194 @BASEBOARD_FAB2_LIB.BASEBOARD_FAB2(SCH_1):PAGE173
     2 SATA6G_P3_RX_C_DN @BASEBOARD_FAB2_LIB.BASEBOARD_FAB2(SCH_1):SATA6G_P3_RX_C_DN   I194 @BASEBOARD_FAB2_LIB.BASEBOARD_FAB2(SCH_1):PAGE173

C2L4 CAP_A_0402V-0.01UF,25V,10%,X7RA
     1 SATA6G_PCH_PCIE_UP_SATA_RXP<3> @BASEBOARD_FAB2_LIB.BASEBOARD_FAB2(SCH_1):SATA6G_PCH_PCIE_UP_SATA_RXP(3)   I192 @BASEBOARD_FAB2_LIB.BASEBOARD_FAB2(SCH_1):PAGE173
     2 SATA6G_P3_RX_C_DP @BASEBOARD_FAB2_LIB.BASEBOARD_FAB2(SCH_1):SATA6G_P3_RX_C_DP   I192 @BASEBOARD_FAB2_LIB.BASEBOARD_FAB2(SCH_1):PAGE173

C2L5 CAP_A_0402V-0.01UF,25V,10%,X7RA
     1 SATA6G_PCH_PCIE_UP_SATA_RXN<7> @BASEBOARD_FAB2_LIB.BASEBOARD_FAB2(SCH_1):SATA6G_PCH_PCIE_UP_SATA_RXN(7)   I209 @BASEBOARD_FAB2_LIB.BASEBOARD_FAB2(SCH_1):PAGE173
     2 SATA6G_P7_RX_C_DN @BASEBOARD_FAB2_LIB.BASEBOARD_FAB2(SCH_1):SATA6G_P7_RX_C_DN   I209 @BASEBOARD_FAB2_LIB.BASEBOARD_FAB2(SCH_1):PAGE173

C2L6 CAP_A_0402V-0.01UF,25V,10%,X7RA
     1 SATA6G_PCH_PCIE_UP_SATA_RXN<1> @BASEBOARD_FAB2_LIB.BASEBOARD_FAB2(SCH_1):SATA6G_PCH_PCIE_UP_SATA_RXN(1)   I166 @BASEBOARD_FAB2_LIB.BASEBOARD_FAB2(SCH_1):PAGE173
     2 SATA6G_P1_RX_C_DN @BASEBOARD_FAB2_LIB.BASEBOARD_FAB2(SCH_1):SATA6G_P1_RX_C_DN   I166 @BASEBOARD_FAB2_LIB.BASEBOARD_FAB2(SCH_1):PAGE173

C2L7 CAP_A_0402V-0.01UF,25V,10%,X7RA
     1 SATA6G_PCH_PCIE_UP_SATA_RXP<7> @BASEBOARD_FAB2_LIB.BASEBOARD_FAB2(SCH_1):SATA6G_PCH_PCIE_UP_SATA_RXP(7)   I206 @BASEBOARD_FAB2_LIB.BASEBOARD_FAB2(SCH_1):PAGE173
     2 SATA6G_P7_RX_C_DP @BASEBOARD_FAB2_LIB.BASEBOARD_FAB2(SCH_1):SATA6G_P7_RX_C_DP   I206 @BASEBOARD_FAB2_LIB.BASEBOARD_FAB2(SCH_1):PAGE173

C2L8 CAP_A_0402V-1.0UF,6.3V,10%,X6SA
     1 VR_PVNN_PCH_VDD @BASEBOARD_FAB2_LIB.BASEBOARD_FAB2(SCH_1):VR_PVNN_PCH_VDD   I151 @BASEBOARD_FAB2_LIB.BASEBOARD_FAB2(SCH_1):PAGE235
     2    GND @BASEBOARD_FAB2_LIB.BASEBOARD_FAB2(SCH_1):GND   I151 @BASEBOARD_FAB2_LIB.BASEBOARD_FAB2(SCH_1):PAGE235

C2L9 CAP_A_0402V-0.01UF,25V,10%,X7RA
     1 SATA6G_PCH_PCIE_UP_SATA_RXN<5> @BASEBOARD_FAB2_LIB.BASEBOARD_FAB2(SCH_1):SATA6G_PCH_PCIE_UP_SATA_RXN(5)   I207 @BASEBOARD_FAB2_LIB.BASEBOARD_FAB2(SCH_1):PAGE173
     2 SATA6G_P5_RX_C_DN @BASEBOARD_FAB2_LIB.BASEBOARD_FAB2(SCH_1):SATA6G_P5_RX_C_DN   I207 @BASEBOARD_FAB2_LIB.BASEBOARD_FAB2(SCH_1):PAGE173

C2L10 CAP_A_0402V-0.01UF,25V,10%,X7RA
     1 SATA6G_PCH_PCIE_UP_SATA_RXP<1> @BASEBOARD_FAB2_LIB.BASEBOARD_FAB2(SCH_1):SATA6G_PCH_PCIE_UP_SATA_RXP(1)   I173 @BASEBOARD_FAB2_LIB.BASEBOARD_FAB2(SCH_1):PAGE173
     2 SATA6G_P1_RX_C_DP @BASEBOARD_FAB2_LIB.BASEBOARD_FAB2(SCH_1):SATA6G_P1_RX_C_DP   I173 @BASEBOARD_FAB2_LIB.BASEBOARD_FAB2(SCH_1):PAGE173

C2L11 CAP_A_0402V-0.1UF,16V,10%,X7R,A
     1 VR_PVNN_PCH_VDD @BASEBOARD_FAB2_LIB.BASEBOARD_FAB2(SCH_1):VR_PVNN_PCH_VDD   I169 @BASEBOARD_FAB2_LIB.BASEBOARD_FAB2(SCH_1):PAGE235
     2    GND @BASEBOARD_FAB2_LIB.BASEBOARD_FAB2(SCH_1):GND   I169 @BASEBOARD_FAB2_LIB.BASEBOARD_FAB2(SCH_1):PAGE235

C2L12 CAP_A_0402V-0.01UF,25V,10%,X7RA
     1 SATA6G_PCH_PCIE_UP_SATA_RXP<5> @BASEBOARD_FAB2_LIB.BASEBOARD_FAB2(SCH_1):SATA6G_PCH_PCIE_UP_SATA_RXP(5)   I196 @BASEBOARD_FAB2_LIB.BASEBOARD_FAB2(SCH_1):PAGE173
     2 SATA6G_P5_RX_C_DP @BASEBOARD_FAB2_LIB.BASEBOARD_FAB2(SCH_1):SATA6G_P5_RX_C_DP   I196 @BASEBOARD_FAB2_LIB.BASEBOARD_FAB2(SCH_1):PAGE173

C2L13 CAP_A_0402V-0.01UF,25V,10%,X7RA
     1 SATA6G_PCH_PCIE_UP_SATA_RXN<2> @BASEBOARD_FAB2_LIB.BASEBOARD_FAB2(SCH_1):SATA6G_PCH_PCIE_UP_SATA_RXN(2)   I165 @BASEBOARD_FAB2_LIB.BASEBOARD_FAB2(SCH_1):PAGE173
     2 SATA6G_P2_RX_C_DN @BASEBOARD_FAB2_LIB.BASEBOARD_FAB2(SCH_1):SATA6G_P2_RX_C_DN   I165 @BASEBOARD_FAB2_LIB.BASEBOARD_FAB2(SCH_1):PAGE173

C2L14 CAP_A_0402V-0.01UF,25V,10%,X7RA
     1 SATA6G_PCH_PCIE_UP_SATA_RXN<6> @BASEBOARD_FAB2_LIB.BASEBOARD_FAB2(SCH_1):SATA6G_PCH_PCIE_UP_SATA_RXN(6)   I208 @BASEBOARD_FAB2_LIB.BASEBOARD_FAB2(SCH_1):PAGE173
     2 SATA6G_P6_RX_C_DN @BASEBOARD_FAB2_LIB.BASEBOARD_FAB2(SCH_1):SATA6G_P6_RX_C_DN   I208 @BASEBOARD_FAB2_LIB.BASEBOARD_FAB2(SCH_1):PAGE173

C2L15 CAP_A_0402V-0.01UF,25V,10%,X7RA
     1 SATA6G_PCH_PCIE_UP_SATA_RXP<2> @BASEBOARD_FAB2_LIB.BASEBOARD_FAB2(SCH_1):SATA6G_PCH_PCIE_UP_SATA_RXP(2)   I191 @BASEBOARD_FAB2_LIB.BASEBOARD_FAB2(SCH_1):PAGE173
     2 SATA6G_P2_RX_C_DP @BASEBOARD_FAB2_LIB.BASEBOARD_FAB2(SCH_1):SATA6G_P2_RX_C_DP   I191 @BASEBOARD_FAB2_LIB.BASEBOARD_FAB2(SCH_1):PAGE173

C2L16 CAP_A_0402V-0.01UF,25V,10%,X7RA
     1 SATA6G_PCH_PCIE_UP_SATA_RXP<6> @BASEBOARD_FAB2_LIB.BASEBOARD_FAB2(SCH_1):SATA6G_PCH_PCIE_UP_SATA_RXP(6)   I205 @BASEBOARD_FAB2_LIB.BASEBOARD_FAB2(SCH_1):PAGE173
     2 SATA6G_P6_RX_C_DP @BASEBOARD_FAB2_LIB.BASEBOARD_FAB2(SCH_1):SATA6G_P6_RX_C_DP   I205 @BASEBOARD_FAB2_LIB.BASEBOARD_FAB2(SCH_1):PAGE173

C2L17 CAP_A_0402V-0.01UF,25V,10%,X7RA
     1 SATA6G_PCH_PCIE_UP_SATA_RXN<0> @BASEBOARD_FAB2_LIB.BASEBOARD_FAB2(SCH_1):SATA6G_PCH_PCIE_UP_SATA_RXN(0)   I174 @BASEBOARD_FAB2_LIB.BASEBOARD_FAB2(SCH_1):PAGE173
     2 SATA6G_P0_RX_C_DN @BASEBOARD_FAB2_LIB.BASEBOARD_FAB2(SCH_1):SATA6G_P0_RX_C_DN   I174 @BASEBOARD_FAB2_LIB.BASEBOARD_FAB2(SCH_1):PAGE173

C2L18 CAP_A_0402V-0.01UF,25V,10%,X7RA
     1 SATA6G_PCH_PCIE_UP_SATA_RXN<4> @BASEBOARD_FAB2_LIB.BASEBOARD_FAB2(SCH_1):SATA6G_PCH_PCIE_UP_SATA_RXN(4)   I197 @BASEBOARD_FAB2_LIB.BASEBOARD_FAB2(SCH_1):PAGE173
     2 SATA6G_P4_RX_C_DN @BASEBOARD_FAB2_LIB.BASEBOARD_FAB2(SCH_1):SATA6G_P4_RX_C_DN   I197 @BASEBOARD_FAB2_LIB.BASEBOARD_FAB2(SCH_1):PAGE173

C2L19 CAP_A_0402V-0.01UF,25V,10%,X7RA
     1 SATA6G_PCH_PCIE_UP_SATA_RXP<0> @BASEBOARD_FAB2_LIB.BASEBOARD_FAB2(SCH_1):SATA6G_PCH_PCIE_UP_SATA_RXP(0)   I172 @BASEBOARD_FAB2_LIB.BASEBOARD_FAB2(SCH_1):PAGE173
     2 SATA6G_P0_RX_C_DP @BASEBOARD_FAB2_LIB.BASEBOARD_FAB2(SCH_1):SATA6G_P0_RX_C_DP   I172 @BASEBOARD_FAB2_LIB.BASEBOARD_FAB2(SCH_1):PAGE173

C2L20 CAP_A_0402V-0.01UF,25V,10%,X7RA
     1 SATA6G_PCH_PCIE_UP_SATA_RXP<4> @BASEBOARD_FAB2_LIB.BASEBOARD_FAB2(SCH_1):SATA6G_PCH_PCIE_UP_SATA_RXP(4)   I195 @BASEBOARD_FAB2_LIB.BASEBOARD_FAB2(SCH_1):PAGE173
     2 SATA6G_P4_RX_C_DP @BASEBOARD_FAB2_LIB.BASEBOARD_FAB2(SCH_1):SATA6G_P4_RX_C_DP   I195 @BASEBOARD_FAB2_LIB.BASEBOARD_FAB2(SCH_1):PAGE173

C2L21 CAP_A_0402V-0.01UF,25V,10%,X7RA
     1 SATA6G_P7_TX_C_DN @BASEBOARD_FAB2_LIB.BASEBOARD_FAB2(SCH_1):SATA6G_P7_TX_C_DN   I259 @BASEBOARD_FAB2_LIB.BASEBOARD_FAB2(SCH_1):PAGE173
     2 SATA6G_PCH_PCIE_UP_SATA_TXN<7> @BASEBOARD_FAB2_LIB.BASEBOARD_FAB2(SCH_1):SATA6G_PCH_PCIE_UP_SATA_TXN(7)   I259 @BASEBOARD_FAB2_LIB.BASEBOARD_FAB2(SCH_1):PAGE173

C2L22 CAP_A_0402V-0.01UF,25V,10%,X7RA
     1 SATA6G_P3_TX_C_DN @BASEBOARD_FAB2_LIB.BASEBOARD_FAB2(SCH_1):SATA6G_P3_TX_C_DN   I234 @BASEBOARD_FAB2_LIB.BASEBOARD_FAB2(SCH_1):PAGE173
     2 SATA6G_PCH_PCIE_UP_SATA_TXN<3> @BASEBOARD_FAB2_LIB.BASEBOARD_FAB2(SCH_1):SATA6G_PCH_PCIE_UP_SATA_TXN(3)   I234 @BASEBOARD_FAB2_LIB.BASEBOARD_FAB2(SCH_1):PAGE173

C2L23 CAP_A_0402V-0.01UF,25V,10%,X7RA
     1 SATA6G_P3_TX_C_DP @BASEBOARD_FAB2_LIB.BASEBOARD_FAB2(SCH_1):SATA6G_P3_TX_C_DP   I241 @BASEBOARD_FAB2_LIB.BASEBOARD_FAB2(SCH_1):PAGE173
     2 SATA6G_PCH_PCIE_UP_SATA_TXP<3> @BASEBOARD_FAB2_LIB.BASEBOARD_FAB2(SCH_1):SATA6G_PCH_PCIE_UP_SATA_TXP(3)   I241 @BASEBOARD_FAB2_LIB.BASEBOARD_FAB2(SCH_1):PAGE173

C2L24 CAP_A_0402V-0.01UF,25V,10%,X7RA
     1 SATA6G_P7_TX_C_DP @BASEBOARD_FAB2_LIB.BASEBOARD_FAB2(SCH_1):SATA6G_P7_TX_C_DP   I258 @BASEBOARD_FAB2_LIB.BASEBOARD_FAB2(SCH_1):PAGE173
     2 SATA6G_PCH_PCIE_UP_SATA_TXP<7> @BASEBOARD_FAB2_LIB.BASEBOARD_FAB2(SCH_1):SATA6G_PCH_PCIE_UP_SATA_TXP(7)   I258 @BASEBOARD_FAB2_LIB.BASEBOARD_FAB2(SCH_1):PAGE173

C2L25 CAPP_SM-470UF,2V,20%,ALUM,6990A
     1 P1V05_PCH_STBY @BASEBOARD_FAB2_LIB.BASEBOARD_FAB2(SCH_1):P1V05_PCH_STBY    I79 @BASEBOARD_FAB2_LIB.BASEBOARD_FAB2(SCH_1):PAGE236
     2    GND @BASEBOARD_FAB2_LIB.BASEBOARD_FAB2(SCH_1):GND    I79 @BASEBOARD_FAB2_LIB.BASEBOARD_FAB2(SCH_1):PAGE236

C2L26 CAP_A_0402V-0.01UF,25V,10%,X7RA
     1 SATA6G_P5_TX_C_DN @BASEBOARD_FAB2_LIB.BASEBOARD_FAB2(SCH_1):SATA6G_P5_TX_C_DN   I255 @BASEBOARD_FAB2_LIB.BASEBOARD_FAB2(SCH_1):PAGE173
     2 SATA6G_PCH_PCIE_UP_SATA_TXN<5> @BASEBOARD_FAB2_LIB.BASEBOARD_FAB2(SCH_1):SATA6G_PCH_PCIE_UP_SATA_TXN(5)   I255 @BASEBOARD_FAB2_LIB.BASEBOARD_FAB2(SCH_1):PAGE173

C2L27 CAP_A_0402V-0.01UF,25V,10%,X7RA
     1 SATA6G_P5_TX_C_DP @BASEBOARD_FAB2_LIB.BASEBOARD_FAB2(SCH_1):SATA6G_P5_TX_C_DP   I240 @BASEBOARD_FAB2_LIB.BASEBOARD_FAB2(SCH_1):PAGE173
     2 SATA6G_PCH_PCIE_UP_SATA_TXP<5> @BASEBOARD_FAB2_LIB.BASEBOARD_FAB2(SCH_1):SATA6G_PCH_PCIE_UP_SATA_TXP(5)   I240 @BASEBOARD_FAB2_LIB.BASEBOARD_FAB2(SCH_1):PAGE173

C2L28 CAP_A_0402V-0.01UF,25V,10%,X7RA
     1 SATA6G_RX_DP<1> @BASEBOARD_FAB2_LIB.BASEBOARD_FAB2(SCH_1):SATA6G_RX_DP(1)    I30 @BASEBOARD_FAB2_LIB.BASEBOARD_FAB2(SCH_1):PAGE174
     2 SATA6G_P9_RX_C_DP @BASEBOARD_FAB2_LIB.BASEBOARD_FAB2(SCH_1):SATA6G_P9_RX_C_DP    I30 @BASEBOARD_FAB2_LIB.BASEBOARD_FAB2(SCH_1):PAGE174

C2L29 CAP_A_0402V-0.01UF,25V,10%,X7RA
     1 SATA6G_RX_DN<1> @BASEBOARD_FAB2_LIB.BASEBOARD_FAB2(SCH_1):SATA6G_RX_DN(1)    I32 @BASEBOARD_FAB2_LIB.BASEBOARD_FAB2(SCH_1):PAGE174
     2 SATA6G_P9_RX_C_DN @BASEBOARD_FAB2_LIB.BASEBOARD_FAB2(SCH_1):SATA6G_P9_RX_C_DN    I32 @BASEBOARD_FAB2_LIB.BASEBOARD_FAB2(SCH_1):PAGE174

C2L30 CAP_A_0402V-0.01UF,25V,10%,X7RA
     1 SATA6G_RX_DP<0> @BASEBOARD_FAB2_LIB.BASEBOARD_FAB2(SCH_1):SATA6G_RX_DP(0)    I28 @BASEBOARD_FAB2_LIB.BASEBOARD_FAB2(SCH_1):PAGE174
     2 SATA6G_P8_RX_C_DP @BASEBOARD_FAB2_LIB.BASEBOARD_FAB2(SCH_1):SATA6G_P8_RX_C_DP    I28 @BASEBOARD_FAB2_LIB.BASEBOARD_FAB2(SCH_1):PAGE174

C2L31 CAP_A_0402V-0.01UF,25V,10%,X7RA
     1 SATA6G_RX_DN<0> @BASEBOARD_FAB2_LIB.BASEBOARD_FAB2(SCH_1):SATA6G_RX_DN(0)    I29 @BASEBOARD_FAB2_LIB.BASEBOARD_FAB2(SCH_1):PAGE174
     2 SATA6G_P8_RX_C_DN @BASEBOARD_FAB2_LIB.BASEBOARD_FAB2(SCH_1):SATA6G_P8_RX_C_DN    I29 @BASEBOARD_FAB2_LIB.BASEBOARD_FAB2(SCH_1):PAGE174

C2L32 CAP_0805-47UF,4V,20%,X6S,C9533A
     1 P1V8_PCH_STBY @BASEBOARD_FAB2_LIB.BASEBOARD_FAB2(SCH_1):P1V8_PCH_STBY    I79 @BASEBOARD_FAB2_LIB.BASEBOARD_FAB2(SCH_1):PAGE237
     2    GND @BASEBOARD_FAB2_LIB.BASEBOARD_FAB2(SCH_1):GND    I79 @BASEBOARD_FAB2_LIB.BASEBOARD_FAB2(SCH_1):PAGE237

C2L33 CAP_A_0402V-0.01UF,25V,10%,X7RA
     1 SATA6G_RX_DP<3> @BASEBOARD_FAB2_LIB.BASEBOARD_FAB2(SCH_1):SATA6G_RX_DP(3)    I40 @BASEBOARD_FAB2_LIB.BASEBOARD_FAB2(SCH_1):PAGE174
     2 SATA6G_P11_RX_C_DP @BASEBOARD_FAB2_LIB.BASEBOARD_FAB2(SCH_1):SATA6G_P11_RX_C_DP    I40 @BASEBOARD_FAB2_LIB.BASEBOARD_FAB2(SCH_1):PAGE174

C2L34 CAP_A_0402V-0.01UF,25V,10%,X7RA
     1 SATA6G_RX_DN<3> @BASEBOARD_FAB2_LIB.BASEBOARD_FAB2(SCH_1):SATA6G_RX_DN(3)    I41 @BASEBOARD_FAB2_LIB.BASEBOARD_FAB2(SCH_1):PAGE174
     2 SATA6G_P11_RX_C_DN @BASEBOARD_FAB2_LIB.BASEBOARD_FAB2(SCH_1):SATA6G_P11_RX_C_DN    I41 @BASEBOARD_FAB2_LIB.BASEBOARD_FAB2(SCH_1):PAGE174

C2L35 CAP_A_0402V-0.01UF,25V,10%,X7RA
     1 SATA6G_RX_DP<2> @BASEBOARD_FAB2_LIB.BASEBOARD_FAB2(SCH_1):SATA6G_RX_DP(2)    I31 @BASEBOARD_FAB2_LIB.BASEBOARD_FAB2(SCH_1):PAGE174
     2 SATA6G_P10_RX_C_DP @BASEBOARD_FAB2_LIB.BASEBOARD_FAB2(SCH_1):SATA6G_P10_RX_C_DP    I31 @BASEBOARD_FAB2_LIB.BASEBOARD_FAB2(SCH_1):PAGE174

C2L36 CAP_A_0402V-0.01UF,25V,10%,X7RA
     1 SATA6G_RX_DN<2> @BASEBOARD_FAB2_LIB.BASEBOARD_FAB2(SCH_1):SATA6G_RX_DN(2)    I39 @BASEBOARD_FAB2_LIB.BASEBOARD_FAB2(SCH_1):PAGE174
     2 SATA6G_P10_RX_C_DN @BASEBOARD_FAB2_LIB.BASEBOARD_FAB2(SCH_1):SATA6G_P10_RX_C_DN    I39 @BASEBOARD_FAB2_LIB.BASEBOARD_FAB2(SCH_1):PAGE174

C2L37 CAP_A_0402V-0.01UF,25V,10%,X7RA
     1 SATA6G_P4_TX_C_DN @BASEBOARD_FAB2_LIB.BASEBOARD_FAB2(SCH_1):SATA6G_P4_TX_C_DN   I238 @BASEBOARD_FAB2_LIB.BASEBOARD_FAB2(SCH_1):PAGE173
     2 SATA6G_PCH_PCIE_UP_SATA_TXN<4> @BASEBOARD_FAB2_LIB.BASEBOARD_FAB2(SCH_1):SATA6G_PCH_PCIE_UP_SATA_TXN(4)   I238 @BASEBOARD_FAB2_LIB.BASEBOARD_FAB2(SCH_1):PAGE173

C2L38 CAP_A_0402V-0.01UF,25V,10%,X7RA
     1 SATA6G_P6_TX_C_DN @BASEBOARD_FAB2_LIB.BASEBOARD_FAB2(SCH_1):SATA6G_P6_TX_C_DN   I256 @BASEBOARD_FAB2_LIB.BASEBOARD_FAB2(SCH_1):PAGE173
     2 SATA6G_PCH_PCIE_UP_SATA_TXN<6> @BASEBOARD_FAB2_LIB.BASEBOARD_FAB2(SCH_1):SATA6G_PCH_PCIE_UP_SATA_TXN(6)   I256 @BASEBOARD_FAB2_LIB.BASEBOARD_FAB2(SCH_1):PAGE173

C2L39 CAP_A_0402V-0.01UF,25V,10%,X7RA
     1 SATA6G_P0_TX_C_DP @BASEBOARD_FAB2_LIB.BASEBOARD_FAB2(SCH_1):SATA6G_P0_TX_C_DP   I221 @BASEBOARD_FAB2_LIB.BASEBOARD_FAB2(SCH_1):PAGE173
     2 SATA6G_PCH_PCIE_UP_SATA_TXP<0> @BASEBOARD_FAB2_LIB.BASEBOARD_FAB2(SCH_1):SATA6G_PCH_PCIE_UP_SATA_TXP(0)   I221 @BASEBOARD_FAB2_LIB.BASEBOARD_FAB2(SCH_1):PAGE173

C2L40 CAP_A_0402V-0.01UF,25V,10%,X7RA
     1 SATA6G_P0_TX_C_DN @BASEBOARD_FAB2_LIB.BASEBOARD_FAB2(SCH_1):SATA6G_P0_TX_C_DN   I220 @BASEBOARD_FAB2_LIB.BASEBOARD_FAB2(SCH_1):PAGE173
     2 SATA6G_PCH_PCIE_UP_SATA_TXN<0> @BASEBOARD_FAB2_LIB.BASEBOARD_FAB2(SCH_1):SATA6G_PCH_PCIE_UP_SATA_TXN(0)   I220 @BASEBOARD_FAB2_LIB.BASEBOARD_FAB2(SCH_1):PAGE173

C2L41 CAP_A_0402V-0.01UF,25V,10%,X7RA
     1 SATA6G_P2_TX_C_DP @BASEBOARD_FAB2_LIB.BASEBOARD_FAB2(SCH_1):SATA6G_P2_TX_C_DP   I242 @BASEBOARD_FAB2_LIB.BASEBOARD_FAB2(SCH_1):PAGE173
     2 SATA6G_PCH_PCIE_UP_SATA_TXP<2> @BASEBOARD_FAB2_LIB.BASEBOARD_FAB2(SCH_1):SATA6G_PCH_PCIE_UP_SATA_TXP(2)   I242 @BASEBOARD_FAB2_LIB.BASEBOARD_FAB2(SCH_1):PAGE173

C2L42 CAP_A_0402V-0.01UF,25V,10%,X7RA
     1 SATA6G_P2_TX_C_DN @BASEBOARD_FAB2_LIB.BASEBOARD_FAB2(SCH_1):SATA6G_P2_TX_C_DN   I233 @BASEBOARD_FAB2_LIB.BASEBOARD_FAB2(SCH_1):PAGE173
     2 SATA6G_PCH_PCIE_UP_SATA_TXN<2> @BASEBOARD_FAB2_LIB.BASEBOARD_FAB2(SCH_1):SATA6G_PCH_PCIE_UP_SATA_TXN(2)   I233 @BASEBOARD_FAB2_LIB.BASEBOARD_FAB2(SCH_1):PAGE173

C2L43 CAP_A_0402V-0.01UF,25V,10%,X7RA
     1 SATA6G_P1_TX_C_DP @BASEBOARD_FAB2_LIB.BASEBOARD_FAB2(SCH_1):SATA6G_P1_TX_C_DP   I222 @BASEBOARD_FAB2_LIB.BASEBOARD_FAB2(SCH_1):PAGE173
     2 SATA6G_PCH_PCIE_UP_SATA_TXP<1> @BASEBOARD_FAB2_LIB.BASEBOARD_FAB2(SCH_1):SATA6G_PCH_PCIE_UP_SATA_TXP(1)   I222 @BASEBOARD_FAB2_LIB.BASEBOARD_FAB2(SCH_1):PAGE173

C2L44 CAP_A_0402V-0.01UF,25V,10%,X7RA
     1 SATA6G_P1_TX_C_DN @BASEBOARD_FAB2_LIB.BASEBOARD_FAB2(SCH_1):SATA6G_P1_TX_C_DN   I228 @BASEBOARD_FAB2_LIB.BASEBOARD_FAB2(SCH_1):PAGE173
     2 SATA6G_PCH_PCIE_UP_SATA_TXN<1> @BASEBOARD_FAB2_LIB.BASEBOARD_FAB2(SCH_1):SATA6G_PCH_PCIE_UP_SATA_TXN(1)   I228 @BASEBOARD_FAB2_LIB.BASEBOARD_FAB2(SCH_1):PAGE173

C2L45 CAP_0805-22UF,6.3V,20%,X6S,C95A
     1 P1V8_PCH_STBY @BASEBOARD_FAB2_LIB.BASEBOARD_FAB2(SCH_1):P1V8_PCH_STBY    I12 @BASEBOARD_FAB2_LIB.BASEBOARD_FAB2(SCH_1):PAGE237
     2    GND @BASEBOARD_FAB2_LIB.BASEBOARD_FAB2(SCH_1):GND    I12 @BASEBOARD_FAB2_LIB.BASEBOARD_FAB2(SCH_1):PAGE237

C2L46 CAPP_SM-470UF,2V,20%,ALUM,6990A
     1 P1V05_PCH_STBY @BASEBOARD_FAB2_LIB.BASEBOARD_FAB2(SCH_1):P1V05_PCH_STBY    I77 @BASEBOARD_FAB2_LIB.BASEBOARD_FAB2(SCH_1):PAGE236
     2    GND @BASEBOARD_FAB2_LIB.BASEBOARD_FAB2(SCH_1):GND    I77 @BASEBOARD_FAB2_LIB.BASEBOARD_FAB2(SCH_1):PAGE236

C2L47 CAP_A_0402V-0.01UF,25V,10%,X7RA
     1 SATA6G_P4_TX_C_DP @BASEBOARD_FAB2_LIB.BASEBOARD_FAB2(SCH_1):SATA6G_P4_TX_C_DP   I239 @BASEBOARD_FAB2_LIB.BASEBOARD_FAB2(SCH_1):PAGE173
     2 SATA6G_PCH_PCIE_UP_SATA_TXP<4> @BASEBOARD_FAB2_LIB.BASEBOARD_FAB2(SCH_1):SATA6G_PCH_PCIE_UP_SATA_TXP(4)   I239 @BASEBOARD_FAB2_LIB.BASEBOARD_FAB2(SCH_1):PAGE173

C2L48 CAP_A_0402V-0.01UF,25V,10%,X7RA
     1 SATA6G_P6_TX_C_DP @BASEBOARD_FAB2_LIB.BASEBOARD_FAB2(SCH_1):SATA6G_P6_TX_C_DP   I257 @BASEBOARD_FAB2_LIB.BASEBOARD_FAB2(SCH_1):PAGE173
     2 SATA6G_PCH_PCIE_UP_SATA_TXP<6> @BASEBOARD_FAB2_LIB.BASEBOARD_FAB2(SCH_1):SATA6G_PCH_PCIE_UP_SATA_TXP(6)   I257 @BASEBOARD_FAB2_LIB.BASEBOARD_FAB2(SCH_1):PAGE173

C2L49 CAP_A_0402V-0.01UF,25V,10%,X7RA
     1 SATA6G_S1_RX_C_DP @BASEBOARD_FAB2_LIB.BASEBOARD_FAB2(SCH_1):SATA6G_S1_RX_C_DP     I5 @BASEBOARD_FAB2_LIB.BASEBOARD_FAB2(SCH_1):PAGE172
     2 SATA6G_S1_RX_DP @BASEBOARD_FAB2_LIB.BASEBOARD_FAB2(SCH_1):SATA6G_S1_RX_DP     I5 @BASEBOARD_FAB2_LIB.BASEBOARD_FAB2(SCH_1):PAGE172

C2L50 CAP_A_0402V-0.01UF,25V,10%,X7RA
     1 SATA6G_S1_RX_C_DN @BASEBOARD_FAB2_LIB.BASEBOARD_FAB2(SCH_1):SATA6G_S1_RX_C_DN     I7 @BASEBOARD_FAB2_LIB.BASEBOARD_FAB2(SCH_1):PAGE172
     2 SATA6G_S1_RX_DN @BASEBOARD_FAB2_LIB.BASEBOARD_FAB2(SCH_1):SATA6G_S1_RX_DN     I7 @BASEBOARD_FAB2_LIB.BASEBOARD_FAB2(SCH_1):PAGE172

C2L51 CAP_A_0402V-0.01UF,25V,10%,X7RA
     1 SATA6G_S1_TX_C_DN @BASEBOARD_FAB2_LIB.BASEBOARD_FAB2(SCH_1):SATA6G_S1_TX_C_DN     I8 @BASEBOARD_FAB2_LIB.BASEBOARD_FAB2(SCH_1):PAGE172
     2 SATA6G_S1_TX_DN @BASEBOARD_FAB2_LIB.BASEBOARD_FAB2(SCH_1):SATA6G_S1_TX_DN     I8 @BASEBOARD_FAB2_LIB.BASEBOARD_FAB2(SCH_1):PAGE172

C2L52 CAP_A_0402V-0.01UF,25V,10%,X7RA
     1 SATA6G_S1_TX_C_DP @BASEBOARD_FAB2_LIB.BASEBOARD_FAB2(SCH_1):SATA6G_S1_TX_C_DP     I6 @BASEBOARD_FAB2_LIB.BASEBOARD_FAB2(SCH_1):PAGE172
     2 SATA6G_S1_TX_DP @BASEBOARD_FAB2_LIB.BASEBOARD_FAB2(SCH_1):SATA6G_S1_TX_DP     I6 @BASEBOARD_FAB2_LIB.BASEBOARD_FAB2(SCH_1):PAGE172

C2M1 CAP_A_0603V-22.0UF,4V,20%,X6S,A
     1 P1V8_PCH_STBY @BASEBOARD_FAB2_LIB.BASEBOARD_FAB2(SCH_1):P1V8_PCH_STBY    I43 @BASEBOARD_FAB2_LIB.BASEBOARD_FAB2(SCH_1):PAGE130
     2    GND @BASEBOARD_FAB2_LIB.BASEBOARD_FAB2(SCH_1):GND    I43 @BASEBOARD_FAB2_LIB.BASEBOARD_FAB2(SCH_1):PAGE130

C2M2 CAP_A_0603V-22.0UF,4V,20%,X6S,A
     1 P1V8_PCH_STBY @BASEBOARD_FAB2_LIB.BASEBOARD_FAB2(SCH_1):P1V8_PCH_STBY    I45 @BASEBOARD_FAB2_LIB.BASEBOARD_FAB2(SCH_1):PAGE130
     2    GND @BASEBOARD_FAB2_LIB.BASEBOARD_FAB2(SCH_1):GND    I45 @BASEBOARD_FAB2_LIB.BASEBOARD_FAB2(SCH_1):PAGE130

C2M3 CAP_A_0402V-0.1UF,16V,10%,EMPTA
     1 P2E_SSB_BMC_TX_DN @BASEBOARD_FAB2_LIB.BASEBOARD_FAB2(SCH_1):P2E_SSB_BMC_TX_DN   I183 @BASEBOARD_FAB2_LIB.BASEBOARD_FAB2(SCH_1):PAGE116
     2 P2E_SSB_BMC_TX_C_DN @BASEBOARD_FAB2_LIB.BASEBOARD_FAB2(SCH_1):P2E_SSB_BMC_TX_C_DN   I183 @BASEBOARD_FAB2_LIB.BASEBOARD_FAB2(SCH_1):PAGE116

C2M4 CAP_A_0402V-0.1UF,16V,10%,EMPTA
     1 P2E_SSB_BMC_TX_DP @BASEBOARD_FAB2_LIB.BASEBOARD_FAB2(SCH_1):P2E_SSB_BMC_TX_DP   I182 @BASEBOARD_FAB2_LIB.BASEBOARD_FAB2(SCH_1):PAGE116
     2 P2E_SSB_BMC_TX_C_DP @BASEBOARD_FAB2_LIB.BASEBOARD_FAB2(SCH_1):P2E_SSB_BMC_TX_C_DP   I182 @BASEBOARD_FAB2_LIB.BASEBOARD_FAB2(SCH_1):PAGE116

C2M5 CAP_0603LF-10UF,4V,20%,X6S,E15A
     1 P1V05_PCH_STBY_WM20_PLL @BASEBOARD_FAB2_LIB.BASEBOARD_FAB2(SCH_1):P1V05_PCH_STBY_WM20_PLL    I43 @BASEBOARD_FAB2_LIB.BASEBOARD_FAB2(SCH_1):PAGE127
     2    GND @BASEBOARD_FAB2_LIB.BASEBOARD_FAB2(SCH_1):GND    I43 @BASEBOARD_FAB2_LIB.BASEBOARD_FAB2(SCH_1):PAGE127

C2M6 CAP_A_0402V-1.0UF,6.3V,10%,X6SA
     1 P1V05_PCH_STBY @BASEBOARD_FAB2_LIB.BASEBOARD_FAB2(SCH_1):P1V05_PCH_STBY    I76 @BASEBOARD_FAB2_LIB.BASEBOARD_FAB2(SCH_1):PAGE127
     2    GND @BASEBOARD_FAB2_LIB.BASEBOARD_FAB2(SCH_1):GND    I76 @BASEBOARD_FAB2_LIB.BASEBOARD_FAB2(SCH_1):PAGE127

C2M7 CAP_A_0402V-1.0UF,6.3V,10%,X6SA
     1 P1V05_PCH_STBY_WM20_PLL @BASEBOARD_FAB2_LIB.BASEBOARD_FAB2(SCH_1):P1V05_PCH_STBY_WM20_PLL    I44 @BASEBOARD_FAB2_LIB.BASEBOARD_FAB2(SCH_1):PAGE127
     2    GND @BASEBOARD_FAB2_LIB.BASEBOARD_FAB2(SCH_1):GND    I44 @BASEBOARD_FAB2_LIB.BASEBOARD_FAB2(SCH_1):PAGE127

C2M8 CAP_A_0402V-1.0UF,6.3V,10%,X6SA
     1 P1V05_PCH_STBY @BASEBOARD_FAB2_LIB.BASEBOARD_FAB2(SCH_1):P1V05_PCH_STBY    I74 @BASEBOARD_FAB2_LIB.BASEBOARD_FAB2(SCH_1):PAGE127
     2    GND @BASEBOARD_FAB2_LIB.BASEBOARD_FAB2(SCH_1):GND    I74 @BASEBOARD_FAB2_LIB.BASEBOARD_FAB2(SCH_1):PAGE127

C2M9 CAP_A_0402V-1.0UF,6.3V,10%,X6SA
     1 P1V05_PCH_STBY_WM26_PLL @BASEBOARD_FAB2_LIB.BASEBOARD_FAB2(SCH_1):P1V05_PCH_STBY_WM26_PLL    I50 @BASEBOARD_FAB2_LIB.BASEBOARD_FAB2(SCH_1):PAGE127
     2    GND @BASEBOARD_FAB2_LIB.BASEBOARD_FAB2(SCH_1):GND    I50 @BASEBOARD_FAB2_LIB.BASEBOARD_FAB2(SCH_1):PAGE127

C2M10 CAP_0603LF-10UF,4V,20%,X6S,E15A
     1 P1V05_PCH_STBY_WM26_PLL @BASEBOARD_FAB2_LIB.BASEBOARD_FAB2(SCH_1):P1V05_PCH_STBY_WM26_PLL    I49 @BASEBOARD_FAB2_LIB.BASEBOARD_FAB2(SCH_1):PAGE127
     2    GND @BASEBOARD_FAB2_LIB.BASEBOARD_FAB2(SCH_1):GND    I49 @BASEBOARD_FAB2_LIB.BASEBOARD_FAB2(SCH_1):PAGE127

C2M11 CAP_0805-47UF,4V,20%,X6S,C9533A
     1 P1V05_PCH_STBY @BASEBOARD_FAB2_LIB.BASEBOARD_FAB2(SCH_1):P1V05_PCH_STBY    I35 @BASEBOARD_FAB2_LIB.BASEBOARD_FAB2(SCH_1):PAGE131
     2    GND @BASEBOARD_FAB2_LIB.BASEBOARD_FAB2(SCH_1):GND    I35 @BASEBOARD_FAB2_LIB.BASEBOARD_FAB2(SCH_1):PAGE131

C2M12 CAP_A_0603V-22.0UF,4V,20%,X6S,A
     1 P1V05_PCH_STBY @BASEBOARD_FAB2_LIB.BASEBOARD_FAB2(SCH_1):P1V05_PCH_STBY    I52 @BASEBOARD_FAB2_LIB.BASEBOARD_FAB2(SCH_1):PAGE131
     2    GND @BASEBOARD_FAB2_LIB.BASEBOARD_FAB2(SCH_1):GND    I52 @BASEBOARD_FAB2_LIB.BASEBOARD_FAB2(SCH_1):PAGE131

C2M13 CAP_A_0603V-22.0UF,4V,20%,X6S,A
     1 P1V05_PCH_STBY @BASEBOARD_FAB2_LIB.BASEBOARD_FAB2(SCH_1):P1V05_PCH_STBY    I48 @BASEBOARD_FAB2_LIB.BASEBOARD_FAB2(SCH_1):PAGE131
     2    GND @BASEBOARD_FAB2_LIB.BASEBOARD_FAB2(SCH_1):GND    I48 @BASEBOARD_FAB2_LIB.BASEBOARD_FAB2(SCH_1):PAGE131

C2M14 CAP_0402-0.22UF,16V,10%,X7R,A3A
     1 P3E_CPU0_PE3_OCP_TXP<8> @BASEBOARD_FAB2_LIB.BASEBOARD_FAB2(SCH_1):P3E_CPU0_PE3_OCP_TXP(8)    I76 @BASEBOARD_FAB2_LIB.BASEBOARD_FAB2(SCH_1):PAGE106
     2 P3E_OCP_CPU0_PE3_C_TXP<8> @BASEBOARD_FAB2_LIB.BASEBOARD_FAB2(SCH_1):P3E_OCP_CPU0_PE3_C_TXP(8)    I76 @BASEBOARD_FAB2_LIB.BASEBOARD_FAB2(SCH_1):PAGE106

C2M15 CAP_0402-0.22UF,16V,10%,X7R,A3A
     1 P3E_CPU0_PE3_OCP_TXN<8> @BASEBOARD_FAB2_LIB.BASEBOARD_FAB2(SCH_1):P3E_CPU0_PE3_OCP_TXN(8)    I86 @BASEBOARD_FAB2_LIB.BASEBOARD_FAB2(SCH_1):PAGE106
     2 P3E_OCP_CPU0_PE3_C_TXN<8> @BASEBOARD_FAB2_LIB.BASEBOARD_FAB2(SCH_1):P3E_OCP_CPU0_PE3_C_TXN(8)    I86 @BASEBOARD_FAB2_LIB.BASEBOARD_FAB2(SCH_1):PAGE106

C2M16 CAP_A_0402V-1.0UF,6.3V,10%,X6SA
     1 P3V3_STBY @BASEBOARD_FAB2_LIB.BASEBOARD_FAB2(SCH_1):P3V3_STBY    I37 @BASEBOARD_FAB2_LIB.BASEBOARD_FAB2(SCH_1):PAGE130
     2    GND @BASEBOARD_FAB2_LIB.BASEBOARD_FAB2(SCH_1):GND    I37 @BASEBOARD_FAB2_LIB.BASEBOARD_FAB2(SCH_1):PAGE130

C2M17 CAP_0805-47UF,4V,20%,X6S,C9533A
     1 P1V05_PCH_STBY @BASEBOARD_FAB2_LIB.BASEBOARD_FAB2(SCH_1):P1V05_PCH_STBY    I34 @BASEBOARD_FAB2_LIB.BASEBOARD_FAB2(SCH_1):PAGE131
     2    GND @BASEBOARD_FAB2_LIB.BASEBOARD_FAB2(SCH_1):GND    I34 @BASEBOARD_FAB2_LIB.BASEBOARD_FAB2(SCH_1):PAGE131

C2M18 CAP_A_0402V-1.0UF,6.3V,10%,X6SA
     1 P1V05_PCH_STBY @BASEBOARD_FAB2_LIB.BASEBOARD_FAB2(SCH_1):P1V05_PCH_STBY    I29 @BASEBOARD_FAB2_LIB.BASEBOARD_FAB2(SCH_1):PAGE131
     2    GND @BASEBOARD_FAB2_LIB.BASEBOARD_FAB2(SCH_1):GND    I29 @BASEBOARD_FAB2_LIB.BASEBOARD_FAB2(SCH_1):PAGE131

C2M19 CAP_A_0402V-1.0UF,6.3V,10%,X6SA
     1 P1V05_PCH_STBY @BASEBOARD_FAB2_LIB.BASEBOARD_FAB2(SCH_1):P1V05_PCH_STBY    I31 @BASEBOARD_FAB2_LIB.BASEBOARD_FAB2(SCH_1):PAGE131
     2    GND @BASEBOARD_FAB2_LIB.BASEBOARD_FAB2(SCH_1):GND    I31 @BASEBOARD_FAB2_LIB.BASEBOARD_FAB2(SCH_1):PAGE131

C2M20 CAP_A_0402V-1.0UF,6.3V,10%,X6SA
     1 P1V05_PCH_STBY @BASEBOARD_FAB2_LIB.BASEBOARD_FAB2(SCH_1):P1V05_PCH_STBY    I39 @BASEBOARD_FAB2_LIB.BASEBOARD_FAB2(SCH_1):PAGE131
     2    GND @BASEBOARD_FAB2_LIB.BASEBOARD_FAB2(SCH_1):GND    I39 @BASEBOARD_FAB2_LIB.BASEBOARD_FAB2(SCH_1):PAGE131

C2M21 CAP_A_0402V-1.0UF,6.3V,10%,X6SA
     1 P1V05_PCH_STBY @BASEBOARD_FAB2_LIB.BASEBOARD_FAB2(SCH_1):P1V05_PCH_STBY    I28 @BASEBOARD_FAB2_LIB.BASEBOARD_FAB2(SCH_1):PAGE131
     2    GND @BASEBOARD_FAB2_LIB.BASEBOARD_FAB2(SCH_1):GND    I28 @BASEBOARD_FAB2_LIB.BASEBOARD_FAB2(SCH_1):PAGE131

C2M22 CAP_A_0402V-1.0UF,6.3V,10%,X6SA
     1 P1V05_PCH_STBY @BASEBOARD_FAB2_LIB.BASEBOARD_FAB2(SCH_1):P1V05_PCH_STBY    I27 @BASEBOARD_FAB2_LIB.BASEBOARD_FAB2(SCH_1):PAGE131
     2    GND @BASEBOARD_FAB2_LIB.BASEBOARD_FAB2(SCH_1):GND    I27 @BASEBOARD_FAB2_LIB.BASEBOARD_FAB2(SCH_1):PAGE131

C2M23 CAP_A_0402V-0.1UF,16V,10%,X7R,A
     1 PE_PCH_SPRV_TX_DP @BASEBOARD_FAB2_LIB.BASEBOARD_FAB2(SCH_1):PE_PCH_SPRV_TX_DP    I89 @BASEBOARD_FAB2_LIB.BASEBOARD_FAB2(SCH_1):PAGE139
     2 PE_PCH_SPRV_TX_C_DP @BASEBOARD_FAB2_LIB.BASEBOARD_FAB2(SCH_1):PE_PCH_SPRV_TX_C_DP    I89 @BASEBOARD_FAB2_LIB.BASEBOARD_FAB2(SCH_1):PAGE139

C2M24 CAP_A_0402V-0.1UF,16V,10%,X7R,A
     1 PE_PCH_SPRV_TX_DN @BASEBOARD_FAB2_LIB.BASEBOARD_FAB2(SCH_1):PE_PCH_SPRV_TX_DN    I90 @BASEBOARD_FAB2_LIB.BASEBOARD_FAB2(SCH_1):PAGE139
     2 PE_PCH_SPRV_TX_C_DN @BASEBOARD_FAB2_LIB.BASEBOARD_FAB2(SCH_1):PE_PCH_SPRV_TX_C_DN    I90 @BASEBOARD_FAB2_LIB.BASEBOARD_FAB2(SCH_1):PAGE139

C2M25 CAP_A_0402V-1.0UF,6.3V,10%,X6SA
     1 P1V05_PCH_STBY @BASEBOARD_FAB2_LIB.BASEBOARD_FAB2(SCH_1):P1V05_PCH_STBY    I78 @BASEBOARD_FAB2_LIB.BASEBOARD_FAB2(SCH_1):PAGE127
     2    GND @BASEBOARD_FAB2_LIB.BASEBOARD_FAB2(SCH_1):GND    I78 @BASEBOARD_FAB2_LIB.BASEBOARD_FAB2(SCH_1):PAGE127

C2N2 CAP_A_0402V-1.0UF,6.3V,10%,X6SA
     1 P1V05_PCH_STBY @BASEBOARD_FAB2_LIB.BASEBOARD_FAB2(SCH_1):P1V05_PCH_STBY    I41 @BASEBOARD_FAB2_LIB.BASEBOARD_FAB2(SCH_1):PAGE131
     2    GND @BASEBOARD_FAB2_LIB.BASEBOARD_FAB2(SCH_1):GND    I41 @BASEBOARD_FAB2_LIB.BASEBOARD_FAB2(SCH_1):PAGE131

C2N3 CAP_A_0402V-1.0UF,6.3V,10%,X6SA
     1 PVNN_PCH_STBY @BASEBOARD_FAB2_LIB.BASEBOARD_FAB2(SCH_1):PVNN_PCH_STBY    I27 @BASEBOARD_FAB2_LIB.BASEBOARD_FAB2(SCH_1):PAGE132
     2    GND @BASEBOARD_FAB2_LIB.BASEBOARD_FAB2(SCH_1):GND    I27 @BASEBOARD_FAB2_LIB.BASEBOARD_FAB2(SCH_1):PAGE132

C2N4 CAP_A_0402V-1.0UF,6.3V,10%,X6SA
     1 PVNN_PCH_STBY @BASEBOARD_FAB2_LIB.BASEBOARD_FAB2(SCH_1):PVNN_PCH_STBY    I28 @BASEBOARD_FAB2_LIB.BASEBOARD_FAB2(SCH_1):PAGE132
     2    GND @BASEBOARD_FAB2_LIB.BASEBOARD_FAB2(SCH_1):GND    I28 @BASEBOARD_FAB2_LIB.BASEBOARD_FAB2(SCH_1):PAGE132

C2N5 CAP_A_0402V-1.0UF,6.3V,10%,X6SA
     1 P1V05_PCH_STBY_KR_PLL @BASEBOARD_FAB2_LIB.BASEBOARD_FAB2(SCH_1):P1V05_PCH_STBY_KR_PLL    I65 @BASEBOARD_FAB2_LIB.BASEBOARD_FAB2(SCH_1):PAGE127
     2    GND @BASEBOARD_FAB2_LIB.BASEBOARD_FAB2(SCH_1):GND    I65 @BASEBOARD_FAB2_LIB.BASEBOARD_FAB2(SCH_1):PAGE127

C2N6 CAP_0603LF-10UF,4V,20%,X6S,E15A
     1 P1V05_PCH_STBY_KR_PLL @BASEBOARD_FAB2_LIB.BASEBOARD_FAB2(SCH_1):P1V05_PCH_STBY_KR_PLL    I64 @BASEBOARD_FAB2_LIB.BASEBOARD_FAB2(SCH_1):PAGE127
     2    GND @BASEBOARD_FAB2_LIB.BASEBOARD_FAB2(SCH_1):GND    I64 @BASEBOARD_FAB2_LIB.BASEBOARD_FAB2(SCH_1):PAGE127

C2N7 CAP_A_0402V-1.0UF,6.3V,10%,X6SA
     1 P1V05_PCH_STBY @BASEBOARD_FAB2_LIB.BASEBOARD_FAB2(SCH_1):P1V05_PCH_STBY    I43 @BASEBOARD_FAB2_LIB.BASEBOARD_FAB2(SCH_1):PAGE131
     2    GND @BASEBOARD_FAB2_LIB.BASEBOARD_FAB2(SCH_1):GND    I43 @BASEBOARD_FAB2_LIB.BASEBOARD_FAB2(SCH_1):PAGE131

C2N8 CAP_A_0402V-1.0UF,6.3V,10%,X6SA
     1 P1V05_PCH_STBY @BASEBOARD_FAB2_LIB.BASEBOARD_FAB2(SCH_1):P1V05_PCH_STBY    I47 @BASEBOARD_FAB2_LIB.BASEBOARD_FAB2(SCH_1):PAGE131
     2    GND @BASEBOARD_FAB2_LIB.BASEBOARD_FAB2(SCH_1):GND    I47 @BASEBOARD_FAB2_LIB.BASEBOARD_FAB2(SCH_1):PAGE131

C2N9 CAP_A_0402V-1.0UF,6.3V,10%,X6SA
     1 PVNN_PCH_STBY @BASEBOARD_FAB2_LIB.BASEBOARD_FAB2(SCH_1):PVNN_PCH_STBY    I26 @BASEBOARD_FAB2_LIB.BASEBOARD_FAB2(SCH_1):PAGE132
     2    GND @BASEBOARD_FAB2_LIB.BASEBOARD_FAB2(SCH_1):GND    I26 @BASEBOARD_FAB2_LIB.BASEBOARD_FAB2(SCH_1):PAGE132

C2N10 CAP_A_0603V-22.0UF,4V,20%,X6S,A
     1 P1V05_PCH_STBY @BASEBOARD_FAB2_LIB.BASEBOARD_FAB2(SCH_1):P1V05_PCH_STBY    I50 @BASEBOARD_FAB2_LIB.BASEBOARD_FAB2(SCH_1):PAGE131
     2    GND @BASEBOARD_FAB2_LIB.BASEBOARD_FAB2(SCH_1):GND    I50 @BASEBOARD_FAB2_LIB.BASEBOARD_FAB2(SCH_1):PAGE131

C2N11 CAP_A_0402V-1.0UF,6.3V,10%,X6SA
     1 PVNN_PCH_STBY @BASEBOARD_FAB2_LIB.BASEBOARD_FAB2(SCH_1):PVNN_PCH_STBY    I30 @BASEBOARD_FAB2_LIB.BASEBOARD_FAB2(SCH_1):PAGE132
     2    GND @BASEBOARD_FAB2_LIB.BASEBOARD_FAB2(SCH_1):GND    I30 @BASEBOARD_FAB2_LIB.BASEBOARD_FAB2(SCH_1):PAGE132

C2N12 CAP_A_0402V-1.0UF,6.3V,10%,X6SA
     1 PVNN_PCH_STBY @BASEBOARD_FAB2_LIB.BASEBOARD_FAB2(SCH_1):PVNN_PCH_STBY    I29 @BASEBOARD_FAB2_LIB.BASEBOARD_FAB2(SCH_1):PAGE132
     2    GND @BASEBOARD_FAB2_LIB.BASEBOARD_FAB2(SCH_1):GND    I29 @BASEBOARD_FAB2_LIB.BASEBOARD_FAB2(SCH_1):PAGE132

C2N13 CAP_A_0402V-1.0UF,6.3V,10%,X6SA
     1 P1V05_PCH_STBY @BASEBOARD_FAB2_LIB.BASEBOARD_FAB2(SCH_1):P1V05_PCH_STBY    I40 @BASEBOARD_FAB2_LIB.BASEBOARD_FAB2(SCH_1):PAGE131
     2    GND @BASEBOARD_FAB2_LIB.BASEBOARD_FAB2(SCH_1):GND    I40 @BASEBOARD_FAB2_LIB.BASEBOARD_FAB2(SCH_1):PAGE131

C2N14 CAP_0603-10UF,6.3V,20%,X6S,E15A
     1 P3V3_STBY @BASEBOARD_FAB2_LIB.BASEBOARD_FAB2(SCH_1):P3V3_STBY    I25 @BASEBOARD_FAB2_LIB.BASEBOARD_FAB2(SCH_1):PAGE130
     2    GND @BASEBOARD_FAB2_LIB.BASEBOARD_FAB2(SCH_1):GND    I25 @BASEBOARD_FAB2_LIB.BASEBOARD_FAB2(SCH_1):PAGE130

C2N15 CAP_A_0402V-1.0UF,6.3V,10%,X6SA
     1 P1V8_PCH_STBY @BASEBOARD_FAB2_LIB.BASEBOARD_FAB2(SCH_1):P1V8_PCH_STBY    I47 @BASEBOARD_FAB2_LIB.BASEBOARD_FAB2(SCH_1):PAGE130
     2    GND @BASEBOARD_FAB2_LIB.BASEBOARD_FAB2(SCH_1):GND    I47 @BASEBOARD_FAB2_LIB.BASEBOARD_FAB2(SCH_1):PAGE130

C2N16 CAP_A_0402V-1.0UF,6.3V,10%,X6SA
     1 P1V8_PCH_STBY @BASEBOARD_FAB2_LIB.BASEBOARD_FAB2(SCH_1):P1V8_PCH_STBY    I52 @BASEBOARD_FAB2_LIB.BASEBOARD_FAB2(SCH_1):PAGE130
     2    GND @BASEBOARD_FAB2_LIB.BASEBOARD_FAB2(SCH_1):GND    I52 @BASEBOARD_FAB2_LIB.BASEBOARD_FAB2(SCH_1):PAGE130

C2N17 CAP_0603-10UF,6.3V,20%,X6S,E15A
     1 P3V3_STBY @BASEBOARD_FAB2_LIB.BASEBOARD_FAB2(SCH_1):P3V3_STBY    I28 @BASEBOARD_FAB2_LIB.BASEBOARD_FAB2(SCH_1):PAGE130
     2    GND @BASEBOARD_FAB2_LIB.BASEBOARD_FAB2(SCH_1):GND    I28 @BASEBOARD_FAB2_LIB.BASEBOARD_FAB2(SCH_1):PAGE130

C2N18 CAP_A_0402V-1.0UF,6.3V,10%,X6SA
     1 P3V3_STBY @BASEBOARD_FAB2_LIB.BASEBOARD_FAB2(SCH_1):P3V3_STBY    I29 @BASEBOARD_FAB2_LIB.BASEBOARD_FAB2(SCH_1):PAGE130
     2    GND @BASEBOARD_FAB2_LIB.BASEBOARD_FAB2(SCH_1):GND    I29 @BASEBOARD_FAB2_LIB.BASEBOARD_FAB2(SCH_1):PAGE130

C2N19 CAP_A_0402V-1.0UF,6.3V,10%,X6SA
     1 P3V3_STBY @BASEBOARD_FAB2_LIB.BASEBOARD_FAB2(SCH_1):P3V3_STBY     I7 @BASEBOARD_FAB2_LIB.BASEBOARD_FAB2(SCH_1):PAGE130
     2    GND @BASEBOARD_FAB2_LIB.BASEBOARD_FAB2(SCH_1):GND     I7 @BASEBOARD_FAB2_LIB.BASEBOARD_FAB2(SCH_1):PAGE130

C2N20 CAP_A_0402V-1.0UF,6.3V,10%,X6SA
     1 P3V3_STBY @BASEBOARD_FAB2_LIB.BASEBOARD_FAB2(SCH_1):P3V3_STBY    I12 @BASEBOARD_FAB2_LIB.BASEBOARD_FAB2(SCH_1):PAGE130
     2    GND @BASEBOARD_FAB2_LIB.BASEBOARD_FAB2(SCH_1):GND    I12 @BASEBOARD_FAB2_LIB.BASEBOARD_FAB2(SCH_1):PAGE130

C2N21 CAP_0603-10UF,6.3V,20%,X6S,E15A
     1 P3V3_STBY @BASEBOARD_FAB2_LIB.BASEBOARD_FAB2(SCH_1):P3V3_STBY    I15 @BASEBOARD_FAB2_LIB.BASEBOARD_FAB2(SCH_1):PAGE130
     2    GND @BASEBOARD_FAB2_LIB.BASEBOARD_FAB2(SCH_1):GND    I15 @BASEBOARD_FAB2_LIB.BASEBOARD_FAB2(SCH_1):PAGE130

C2N22 CAP_0603-10UF,6.3V,20%,X6S,E15A
     1 P3V3_STBY @BASEBOARD_FAB2_LIB.BASEBOARD_FAB2(SCH_1):P3V3_STBY     I9 @BASEBOARD_FAB2_LIB.BASEBOARD_FAB2(SCH_1):PAGE130
     2    GND @BASEBOARD_FAB2_LIB.BASEBOARD_FAB2(SCH_1):GND     I9 @BASEBOARD_FAB2_LIB.BASEBOARD_FAB2(SCH_1):PAGE130

C2N23 CAP_0603-10UF,6.3V,20%,X6S,E15A
     1 P3V3_STBY @BASEBOARD_FAB2_LIB.BASEBOARD_FAB2(SCH_1):P3V3_STBY    I24 @BASEBOARD_FAB2_LIB.BASEBOARD_FAB2(SCH_1):PAGE130
     2    GND @BASEBOARD_FAB2_LIB.BASEBOARD_FAB2(SCH_1):GND    I24 @BASEBOARD_FAB2_LIB.BASEBOARD_FAB2(SCH_1):PAGE130

C2N24 CAP_0603-10UF,6.3V,20%,X6S,E15A
     1 P3V3_STBY @BASEBOARD_FAB2_LIB.BASEBOARD_FAB2(SCH_1):P3V3_STBY     I8 @BASEBOARD_FAB2_LIB.BASEBOARD_FAB2(SCH_1):PAGE130
     2    GND @BASEBOARD_FAB2_LIB.BASEBOARD_FAB2(SCH_1):GND     I8 @BASEBOARD_FAB2_LIB.BASEBOARD_FAB2(SCH_1):PAGE130

C2N25 CAP_A_0402V-1.0UF,6.3V,10%,X6SA
     1 P3V3_STBY @BASEBOARD_FAB2_LIB.BASEBOARD_FAB2(SCH_1):P3V3_STBY    I34 @BASEBOARD_FAB2_LIB.BASEBOARD_FAB2(SCH_1):PAGE130
     2    GND @BASEBOARD_FAB2_LIB.BASEBOARD_FAB2(SCH_1):GND    I34 @BASEBOARD_FAB2_LIB.BASEBOARD_FAB2(SCH_1):PAGE130

C2N26 CAP_A_0402V-1.0UF,6.3V,10%,X6SA
     1 P3V3_STBY @BASEBOARD_FAB2_LIB.BASEBOARD_FAB2(SCH_1):P3V3_STBY     I4 @BASEBOARD_FAB2_LIB.BASEBOARD_FAB2(SCH_1):PAGE130
     2    GND @BASEBOARD_FAB2_LIB.BASEBOARD_FAB2(SCH_1):GND     I4 @BASEBOARD_FAB2_LIB.BASEBOARD_FAB2(SCH_1):PAGE130

C2P1 CAP_A_0402V-0.1UF,16V,10%,X7R,A
     1 P3V3_STBY @BASEBOARD_FAB2_LIB.BASEBOARD_FAB2(SCH_1):P3V3_STBY     I8 @BASEBOARD_FAB2_LIB.BASEBOARD_FAB2(SCH_1):PAGE170
     2    GND @BASEBOARD_FAB2_LIB.BASEBOARD_FAB2(SCH_1):GND     I8 @BASEBOARD_FAB2_LIB.BASEBOARD_FAB2(SCH_1):PAGE170

C2P2 CAP_A_0402V-0.1UF,16V,10%,X7R,A
     1 P3V3_STBY @BASEBOARD_FAB2_LIB.BASEBOARD_FAB2(SCH_1):P3V3_STBY     I9 @BASEBOARD_FAB2_LIB.BASEBOARD_FAB2(SCH_1):PAGE192
     2    GND @BASEBOARD_FAB2_LIB.BASEBOARD_FAB2(SCH_1):GND     I9 @BASEBOARD_FAB2_LIB.BASEBOARD_FAB2(SCH_1):PAGE192

C2P3 CAP_A_0402V-0.1UF,16V,10%,X7R,A
     1 P3V3_STBY @BASEBOARD_FAB2_LIB.BASEBOARD_FAB2(SCH_1):P3V3_STBY    I22 @BASEBOARD_FAB2_LIB.BASEBOARD_FAB2(SCH_1):PAGE192
     2    GND @BASEBOARD_FAB2_LIB.BASEBOARD_FAB2(SCH_1):GND    I22 @BASEBOARD_FAB2_LIB.BASEBOARD_FAB2(SCH_1):PAGE192

C2P4 CAP_A_0402V-0.1UF,16V,10%,X7R,A
     1 P3V3_STBY @BASEBOARD_FAB2_LIB.BASEBOARD_FAB2(SCH_1):P3V3_STBY    I16 @BASEBOARD_FAB2_LIB.BASEBOARD_FAB2(SCH_1):PAGE192
     2    GND @BASEBOARD_FAB2_LIB.BASEBOARD_FAB2(SCH_1):GND    I16 @BASEBOARD_FAB2_LIB.BASEBOARD_FAB2(SCH_1):PAGE192

C2P5 CAP_A_0402V-0.1UF,16V,10%,X7R,A
     1 P3V3_STBY @BASEBOARD_FAB2_LIB.BASEBOARD_FAB2(SCH_1):P3V3_STBY     I3 @BASEBOARD_FAB2_LIB.BASEBOARD_FAB2(SCH_1):PAGE192
     2    GND @BASEBOARD_FAB2_LIB.BASEBOARD_FAB2(SCH_1):GND     I3 @BASEBOARD_FAB2_LIB.BASEBOARD_FAB2(SCH_1):PAGE192

C2P6 CAP_A_0402V-0.1UF,16V,10%,X7R,A
     1 P3V3_STBY @BASEBOARD_FAB2_LIB.BASEBOARD_FAB2(SCH_1):P3V3_STBY    I18 @BASEBOARD_FAB2_LIB.BASEBOARD_FAB2(SCH_1):PAGE192
     2    GND @BASEBOARD_FAB2_LIB.BASEBOARD_FAB2(SCH_1):GND    I18 @BASEBOARD_FAB2_LIB.BASEBOARD_FAB2(SCH_1):PAGE192

C2P7 CAP_A_0402V-0.1UF,16V,10%,X7R,A
     1 P3V3_STBY @BASEBOARD_FAB2_LIB.BASEBOARD_FAB2(SCH_1):P3V3_STBY    I20 @BASEBOARD_FAB2_LIB.BASEBOARD_FAB2(SCH_1):PAGE192
     2    GND @BASEBOARD_FAB2_LIB.BASEBOARD_FAB2(SCH_1):GND    I20 @BASEBOARD_FAB2_LIB.BASEBOARD_FAB2(SCH_1):PAGE192

C2P8 CAP_A_0402V-0.01UF,25V,10%,X7RA
     1 P3V3_STBY @BASEBOARD_FAB2_LIB.BASEBOARD_FAB2(SCH_1):P3V3_STBY     I1 @BASEBOARD_FAB2_LIB.BASEBOARD_FAB2(SCH_1):PAGE192
     2    GND @BASEBOARD_FAB2_LIB.BASEBOARD_FAB2(SCH_1):GND     I1 @BASEBOARD_FAB2_LIB.BASEBOARD_FAB2(SCH_1):PAGE192

C2P9 CAP_A_0402V-0.1UF,16V,10%,X7R,A
     1 P3V3_STBY @BASEBOARD_FAB2_LIB.BASEBOARD_FAB2(SCH_1):P3V3_STBY   I117 @BASEBOARD_FAB2_LIB.BASEBOARD_FAB2(SCH_1):PAGE185
     2    GND @BASEBOARD_FAB2_LIB.BASEBOARD_FAB2(SCH_1):GND   I117 @BASEBOARD_FAB2_LIB.BASEBOARD_FAB2(SCH_1):PAGE185

C2P10 CAP_1206LF-22UF,16V,10%,X6S,D3A
     1 P12V_STBY @BASEBOARD_FAB2_LIB.BASEBOARD_FAB2(SCH_1):P12V_STBY    I41 @BASEBOARD_FAB2_LIB.BASEBOARD_FAB2(SCH_1):PAGE188
     2    GND @BASEBOARD_FAB2_LIB.BASEBOARD_FAB2(SCH_1):GND    I41 @BASEBOARD_FAB2_LIB.BASEBOARD_FAB2(SCH_1):PAGE188

C2P11 CAP_A_0402V-0.1UF,16V,10%,X7R,A
     1 P12V_STBY @BASEBOARD_FAB2_LIB.BASEBOARD_FAB2(SCH_1):P12V_STBY    I21 @BASEBOARD_FAB2_LIB.BASEBOARD_FAB2(SCH_1):PAGE188
     2    GND @BASEBOARD_FAB2_LIB.BASEBOARD_FAB2(SCH_1):GND    I21 @BASEBOARD_FAB2_LIB.BASEBOARD_FAB2(SCH_1):PAGE188

C2P12 CAP_A_0402V-0.1UF,16V,10%,X7R,A
     1 P12V_STBY @BASEBOARD_FAB2_LIB.BASEBOARD_FAB2(SCH_1):P12V_STBY    I23 @BASEBOARD_FAB2_LIB.BASEBOARD_FAB2(SCH_1):PAGE188
     2    GND @BASEBOARD_FAB2_LIB.BASEBOARD_FAB2(SCH_1):GND    I23 @BASEBOARD_FAB2_LIB.BASEBOARD_FAB2(SCH_1):PAGE188

C2P13 CAP_A_0402V-0.1UF,16V,10%,X7R,A
     1 P12V_STBY @BASEBOARD_FAB2_LIB.BASEBOARD_FAB2(SCH_1):P12V_STBY    I57 @BASEBOARD_FAB2_LIB.BASEBOARD_FAB2(SCH_1):PAGE188
     2    GND @BASEBOARD_FAB2_LIB.BASEBOARD_FAB2(SCH_1):GND    I57 @BASEBOARD_FAB2_LIB.BASEBOARD_FAB2(SCH_1):PAGE188

C2P14 CAP_A_0402V-0.1UF,16V,10%,X7R,A
     1 P12V_STBY @BASEBOARD_FAB2_LIB.BASEBOARD_FAB2(SCH_1):P12V_STBY    I56 @BASEBOARD_FAB2_LIB.BASEBOARD_FAB2(SCH_1):PAGE188
     2    GND @BASEBOARD_FAB2_LIB.BASEBOARD_FAB2(SCH_1):GND    I56 @BASEBOARD_FAB2_LIB.BASEBOARD_FAB2(SCH_1):PAGE188

C2P15 CAP_A_0402V-0.1UF,16V,10%,X7R,A
     1 P12V_STBY @BASEBOARD_FAB2_LIB.BASEBOARD_FAB2(SCH_1):P12V_STBY    I55 @BASEBOARD_FAB2_LIB.BASEBOARD_FAB2(SCH_1):PAGE188
     2    GND @BASEBOARD_FAB2_LIB.BASEBOARD_FAB2(SCH_1):GND    I55 @BASEBOARD_FAB2_LIB.BASEBOARD_FAB2(SCH_1):PAGE188

C2P16 CAP_A_0402V-0.1UF,16V,10%,X7R,A
     1 P12V_STBY @BASEBOARD_FAB2_LIB.BASEBOARD_FAB2(SCH_1):P12V_STBY    I53 @BASEBOARD_FAB2_LIB.BASEBOARD_FAB2(SCH_1):PAGE188
     2    GND @BASEBOARD_FAB2_LIB.BASEBOARD_FAB2(SCH_1):GND    I53 @BASEBOARD_FAB2_LIB.BASEBOARD_FAB2(SCH_1):PAGE188

C2R1 CAP_A_0402V-0.1UF,16V,10%,X7R,A
     1 P3V3_STBY @BASEBOARD_FAB2_LIB.BASEBOARD_FAB2(SCH_1):P3V3_STBY     I8 @BASEBOARD_FAB2_LIB.BASEBOARD_FAB2(SCH_1):PAGE192
     2    GND @BASEBOARD_FAB2_LIB.BASEBOARD_FAB2(SCH_1):GND     I8 @BASEBOARD_FAB2_LIB.BASEBOARD_FAB2(SCH_1):PAGE192

C2R2 CAP_A_0402V-0.1UF,16V,10%,X7R,A
     1 P3V3_STBY @BASEBOARD_FAB2_LIB.BASEBOARD_FAB2(SCH_1):P3V3_STBY    I28 @BASEBOARD_FAB2_LIB.BASEBOARD_FAB2(SCH_1):PAGE192
     2    GND @BASEBOARD_FAB2_LIB.BASEBOARD_FAB2(SCH_1):GND    I28 @BASEBOARD_FAB2_LIB.BASEBOARD_FAB2(SCH_1):PAGE192

C2R3 CAP_A_0402V-0.1UF,16V,10%,X7R,A
     1 P3V3_STBY @BASEBOARD_FAB2_LIB.BASEBOARD_FAB2(SCH_1):P3V3_STBY    I19 @BASEBOARD_FAB2_LIB.BASEBOARD_FAB2(SCH_1):PAGE192
     2    GND @BASEBOARD_FAB2_LIB.BASEBOARD_FAB2(SCH_1):GND    I19 @BASEBOARD_FAB2_LIB.BASEBOARD_FAB2(SCH_1):PAGE192

C2R4 CAP_A_0402V-0.1UF,16V,10%,X7R,A
     1 P3V3_STBY @BASEBOARD_FAB2_LIB.BASEBOARD_FAB2(SCH_1):P3V3_STBY    I21 @BASEBOARD_FAB2_LIB.BASEBOARD_FAB2(SCH_1):PAGE192
     2    GND @BASEBOARD_FAB2_LIB.BASEBOARD_FAB2(SCH_1):GND    I21 @BASEBOARD_FAB2_LIB.BASEBOARD_FAB2(SCH_1):PAGE192

C2R5 CAP_A_0402V-0.1UF,16V,10%,X7R,A
     1 P3V3_STBY @BASEBOARD_FAB2_LIB.BASEBOARD_FAB2(SCH_1):P3V3_STBY    I15 @BASEBOARD_FAB2_LIB.BASEBOARD_FAB2(SCH_1):PAGE192
     2    GND @BASEBOARD_FAB2_LIB.BASEBOARD_FAB2(SCH_1):GND    I15 @BASEBOARD_FAB2_LIB.BASEBOARD_FAB2(SCH_1):PAGE192

C2R6 CAP_0402LF-470PF,50V,10%,EMPTYA
     1 FM_PS_EN @BASEBOARD_FAB2_LIB.BASEBOARD_FAB2(SCH_1):FM_PS_EN   I224 @BASEBOARD_FAB2_LIB.BASEBOARD_FAB2(SCH_1):PAGE181
     2    GND @BASEBOARD_FAB2_LIB.BASEBOARD_FAB2(SCH_1):GND   I224 @BASEBOARD_FAB2_LIB.BASEBOARD_FAB2(SCH_1):PAGE181

C2R7 CAP_0402-0.22UF,16V,10%,X7R,A3A
     1 P3E_CPU0_PE3_OCP_TXN<6> @BASEBOARD_FAB2_LIB.BASEBOARD_FAB2(SCH_1):P3E_CPU0_PE3_OCP_TXN(6)   I123 @BASEBOARD_FAB2_LIB.BASEBOARD_FAB2(SCH_1):PAGE106
     2 P3E_OCP_CPU0_PE3_C_TXN<6> @BASEBOARD_FAB2_LIB.BASEBOARD_FAB2(SCH_1):P3E_OCP_CPU0_PE3_C_TXN(6)   I123 @BASEBOARD_FAB2_LIB.BASEBOARD_FAB2(SCH_1):PAGE106

C2R8 CAP_0402-0.22UF,16V,10%,X7R,A3A
     1 P3E_CPU0_PE3_OCP_TXP<6> @BASEBOARD_FAB2_LIB.BASEBOARD_FAB2(SCH_1):P3E_CPU0_PE3_OCP_TXP(6)   I141 @BASEBOARD_FAB2_LIB.BASEBOARD_FAB2(SCH_1):PAGE106
     2 P3E_OCP_CPU0_PE3_C_TXP<6> @BASEBOARD_FAB2_LIB.BASEBOARD_FAB2(SCH_1):P3E_OCP_CPU0_PE3_C_TXP(6)   I141 @BASEBOARD_FAB2_LIB.BASEBOARD_FAB2(SCH_1):PAGE106

C2R9 CAP_0402-0.22UF,16V,10%,X7R,A3A
     1 P3E_CPU0_PE3_OCP_TXN<7> @BASEBOARD_FAB2_LIB.BASEBOARD_FAB2(SCH_1):P3E_CPU0_PE3_OCP_TXN(7)   I147 @BASEBOARD_FAB2_LIB.BASEBOARD_FAB2(SCH_1):PAGE106
     2 P3E_OCP_CPU0_PE3_C_TXN<7> @BASEBOARD_FAB2_LIB.BASEBOARD_FAB2(SCH_1):P3E_OCP_CPU0_PE3_C_TXN(7)   I147 @BASEBOARD_FAB2_LIB.BASEBOARD_FAB2(SCH_1):PAGE106

C2R10 CAP_0402-0.22UF,16V,10%,X7R,A3A
     1 P3E_CPU0_PE3_OCP_TXP<7> @BASEBOARD_FAB2_LIB.BASEBOARD_FAB2(SCH_1):P3E_CPU0_PE3_OCP_TXP(7)   I142 @BASEBOARD_FAB2_LIB.BASEBOARD_FAB2(SCH_1):PAGE106
     2 P3E_OCP_CPU0_PE3_C_TXP<7> @BASEBOARD_FAB2_LIB.BASEBOARD_FAB2(SCH_1):P3E_OCP_CPU0_PE3_C_TXP(7)   I142 @BASEBOARD_FAB2_LIB.BASEBOARD_FAB2(SCH_1):PAGE106

C2R11 CAP_0603-4.7UF,6.3V,10%,X6S,E1A
     1 P5V_STBY @BASEBOARD_FAB2_LIB.BASEBOARD_FAB2(SCH_1):P5V_STBY   I109 @BASEBOARD_FAB2_LIB.BASEBOARD_FAB2(SCH_1):PAGE240
     2 AGND_P3V3_STBY @BASEBOARD_FAB2_LIB.BASEBOARD_FAB2(SCH_1):AGND_P3V3_STBY   I109 @BASEBOARD_FAB2_LIB.BASEBOARD_FAB2(SCH_1):PAGE240

C2R12 CAP_A_0402V-1.0UF,6.3V,10%,X6SA
     1 FP_NMI_BTN_OUT_N @BASEBOARD_FAB2_LIB.BASEBOARD_FAB2(SCH_1):FP_NMI_BTN_OUT_N   I353 @BASEBOARD_FAB2_LIB.BASEBOARD_FAB2(SCH_1):PAGE157
     2    GND @BASEBOARD_FAB2_LIB.BASEBOARD_FAB2(SCH_1):GND   I353 @BASEBOARD_FAB2_LIB.BASEBOARD_FAB2(SCH_1):PAGE157

C2R13 CAP_0402-0.22UF,16V,10%,X7R,A3A
     1 P3E_CPU0_PE3_OCP_TXN<5> @BASEBOARD_FAB2_LIB.BASEBOARD_FAB2(SCH_1):P3E_CPU0_PE3_OCP_TXN(5)   I137 @BASEBOARD_FAB2_LIB.BASEBOARD_FAB2(SCH_1):PAGE106
     2 P3E_OCP_CPU0_PE3_C_TXN<5> @BASEBOARD_FAB2_LIB.BASEBOARD_FAB2(SCH_1):P3E_OCP_CPU0_PE3_C_TXN(5)   I137 @BASEBOARD_FAB2_LIB.BASEBOARD_FAB2(SCH_1):PAGE106

C2R14 CAP_0402-0.22UF,16V,10%,X7R,A3A
     1 P3E_CPU0_PE3_OCP_TXP<5> @BASEBOARD_FAB2_LIB.BASEBOARD_FAB2(SCH_1):P3E_CPU0_PE3_OCP_TXP(5)   I130 @BASEBOARD_FAB2_LIB.BASEBOARD_FAB2(SCH_1):PAGE106
     2 P3E_OCP_CPU0_PE3_C_TXP<5> @BASEBOARD_FAB2_LIB.BASEBOARD_FAB2(SCH_1):P3E_OCP_CPU0_PE3_C_TXP(5)   I130 @BASEBOARD_FAB2_LIB.BASEBOARD_FAB2(SCH_1):PAGE106

C2R15 CAP_A_0402V-0.1UF,16V,10%,X7R,A
     1 P12V_STBY @BASEBOARD_FAB2_LIB.BASEBOARD_FAB2(SCH_1):P12V_STBY     I2 @BASEBOARD_FAB2_LIB.BASEBOARD_FAB2(SCH_1):PAGE188
     2    GND @BASEBOARD_FAB2_LIB.BASEBOARD_FAB2(SCH_1):GND     I2 @BASEBOARD_FAB2_LIB.BASEBOARD_FAB2(SCH_1):PAGE188

C2R16 CAP_A_0402V-0.1UF,16V,10%,X7R,A
     1 P12V_STBY @BASEBOARD_FAB2_LIB.BASEBOARD_FAB2(SCH_1):P12V_STBY    I40 @BASEBOARD_FAB2_LIB.BASEBOARD_FAB2(SCH_1):PAGE188
     2    GND @BASEBOARD_FAB2_LIB.BASEBOARD_FAB2(SCH_1):GND    I40 @BASEBOARD_FAB2_LIB.BASEBOARD_FAB2(SCH_1):PAGE188

C2R17 CAP_A_0402V-0.1UF,16V,10%,X7R,A
     1 P12V_STBY @BASEBOARD_FAB2_LIB.BASEBOARD_FAB2(SCH_1):P12V_STBY    I25 @BASEBOARD_FAB2_LIB.BASEBOARD_FAB2(SCH_1):PAGE188
     2    GND @BASEBOARD_FAB2_LIB.BASEBOARD_FAB2(SCH_1):GND    I25 @BASEBOARD_FAB2_LIB.BASEBOARD_FAB2(SCH_1):PAGE188

C2R18 CAP_A_0402V-0.1UF,16V,10%,X7R,A
     1 P12V_STBY @BASEBOARD_FAB2_LIB.BASEBOARD_FAB2(SCH_1):P12V_STBY     I3 @BASEBOARD_FAB2_LIB.BASEBOARD_FAB2(SCH_1):PAGE188
     2    GND @BASEBOARD_FAB2_LIB.BASEBOARD_FAB2(SCH_1):GND     I3 @BASEBOARD_FAB2_LIB.BASEBOARD_FAB2(SCH_1):PAGE188

C2T1 CAP_A_0402V-0.1UF,16V,10%,X7R,A
     1 P3V3_STBY @BASEBOARD_FAB2_LIB.BASEBOARD_FAB2(SCH_1):P3V3_STBY    I94 @BASEBOARD_FAB2_LIB.BASEBOARD_FAB2(SCH_1):PAGE154
     2    GND @BASEBOARD_FAB2_LIB.BASEBOARD_FAB2(SCH_1):GND    I94 @BASEBOARD_FAB2_LIB.BASEBOARD_FAB2(SCH_1):PAGE154

C2T2 CAP_A_0402V-0.1UF,16V,10%,X7R,A
     1   P3V3 @BASEBOARD_FAB2_LIB.BASEBOARD_FAB2(SCH_1):P3V3   I131 @BASEBOARD_FAB2_LIB.BASEBOARD_FAB2(SCH_1):PAGE185
     2    GND @BASEBOARD_FAB2_LIB.BASEBOARD_FAB2(SCH_1):GND   I131 @BASEBOARD_FAB2_LIB.BASEBOARD_FAB2(SCH_1):PAGE185

C2T3 CAP_A_0402V-0.1UF,16V,10%,X7R,A
     1 P3V3_STBY @BASEBOARD_FAB2_LIB.BASEBOARD_FAB2(SCH_1):P3V3_STBY   I370 @BASEBOARD_FAB2_LIB.BASEBOARD_FAB2(SCH_1):PAGE157
     2    GND @BASEBOARD_FAB2_LIB.BASEBOARD_FAB2(SCH_1):GND   I370 @BASEBOARD_FAB2_LIB.BASEBOARD_FAB2(SCH_1):PAGE157

C2T4 CAP_A_0402V-0.1UF,16V,10%,X7R,A
     1   P3V3 @BASEBOARD_FAB2_LIB.BASEBOARD_FAB2(SCH_1):P3V3   I132 @BASEBOARD_FAB2_LIB.BASEBOARD_FAB2(SCH_1):PAGE185
     2    GND @BASEBOARD_FAB2_LIB.BASEBOARD_FAB2(SCH_1):GND   I132 @BASEBOARD_FAB2_LIB.BASEBOARD_FAB2(SCH_1):PAGE185

C2T5 CAP_A_0402V-0.1UF,16V,10%,X7R,A
     1   P3V3 @BASEBOARD_FAB2_LIB.BASEBOARD_FAB2(SCH_1):P3V3   I135 @BASEBOARD_FAB2_LIB.BASEBOARD_FAB2(SCH_1):PAGE185
     2    GND @BASEBOARD_FAB2_LIB.BASEBOARD_FAB2(SCH_1):GND   I135 @BASEBOARD_FAB2_LIB.BASEBOARD_FAB2(SCH_1):PAGE185

C2T6 CAP_0805-22UF,6.3V,20%,X6S,C95A
     1 P3V3_STBY @BASEBOARD_FAB2_LIB.BASEBOARD_FAB2(SCH_1):P3V3_STBY   I160 @BASEBOARD_FAB2_LIB.BASEBOARD_FAB2(SCH_1):PAGE240
     2    GND @BASEBOARD_FAB2_LIB.BASEBOARD_FAB2(SCH_1):GND   I160 @BASEBOARD_FAB2_LIB.BASEBOARD_FAB2(SCH_1):PAGE240

C2T7 CAP_0805-22UF,6.3V,20%,X6S,C95A
     1 P3V3_STBY @BASEBOARD_FAB2_LIB.BASEBOARD_FAB2(SCH_1):P3V3_STBY   I158 @BASEBOARD_FAB2_LIB.BASEBOARD_FAB2(SCH_1):PAGE240
     2    GND @BASEBOARD_FAB2_LIB.BASEBOARD_FAB2(SCH_1):GND   I158 @BASEBOARD_FAB2_LIB.BASEBOARD_FAB2(SCH_1):PAGE240

C2T8 CAP_A_0402V-0.1UF,16V,10%,X7R,A
     1 P3V3_STBY @BASEBOARD_FAB2_LIB.BASEBOARD_FAB2(SCH_1):P3V3_STBY   I135 @BASEBOARD_FAB2_LIB.BASEBOARD_FAB2(SCH_1):PAGE154
     2    GND @BASEBOARD_FAB2_LIB.BASEBOARD_FAB2(SCH_1):GND   I135 @BASEBOARD_FAB2_LIB.BASEBOARD_FAB2(SCH_1):PAGE154

C2T9 CAP_0805-22UF,6.3V,20%,X6S,C95A
     1 P3V3_STBY @BASEBOARD_FAB2_LIB.BASEBOARD_FAB2(SCH_1):P3V3_STBY   I174 @BASEBOARD_FAB2_LIB.BASEBOARD_FAB2(SCH_1):PAGE240
     2    GND @BASEBOARD_FAB2_LIB.BASEBOARD_FAB2(SCH_1):GND   I174 @BASEBOARD_FAB2_LIB.BASEBOARD_FAB2(SCH_1):PAGE240

C2T10 CAP_0402-0.22UF,16V,10%,X7R,A3A
     1 P3E_PCH_M2_TX_C_DP<1> @BASEBOARD_FAB2_LIB.BASEBOARD_FAB2(SCH_1):P3E_PCH_M2_TX_C_DP(1)    I63 @BASEBOARD_FAB2_LIB.BASEBOARD_FAB2(SCH_1):PAGE185
     2 P3E_PCH_M2_TX_DP<1> @BASEBOARD_FAB2_LIB.BASEBOARD_FAB2(SCH_1):P3E_PCH_M2_TX_DP(1)    I63 @BASEBOARD_FAB2_LIB.BASEBOARD_FAB2(SCH_1):PAGE185

C2T11 CAP_0402-0.22UF,16V,10%,X7R,A3A
     1 P3E_PCH_M2_TX_C_DN<1> @BASEBOARD_FAB2_LIB.BASEBOARD_FAB2(SCH_1):P3E_PCH_M2_TX_C_DN(1)    I62 @BASEBOARD_FAB2_LIB.BASEBOARD_FAB2(SCH_1):PAGE185
     2 P3E_PCH_M2_TX_DN<1> @BASEBOARD_FAB2_LIB.BASEBOARD_FAB2(SCH_1):P3E_PCH_M2_TX_DN(1)    I62 @BASEBOARD_FAB2_LIB.BASEBOARD_FAB2(SCH_1):PAGE185

C2T12 CAP_A_0402V-0.1UF,16V,10%,X7R,A
     1 P3V3_STBY @BASEBOARD_FAB2_LIB.BASEBOARD_FAB2(SCH_1):P3V3_STBY   I132 @BASEBOARD_FAB2_LIB.BASEBOARD_FAB2(SCH_1):PAGE154
     2    GND @BASEBOARD_FAB2_LIB.BASEBOARD_FAB2(SCH_1):GND   I132 @BASEBOARD_FAB2_LIB.BASEBOARD_FAB2(SCH_1):PAGE154

C2T13 CAP_0402-0.22UF,16V,10%,X7R,A3A
     1 P3E_PCH_M2_TX_C_DP<2> @BASEBOARD_FAB2_LIB.BASEBOARD_FAB2(SCH_1):P3E_PCH_M2_TX_C_DP(2)    I64 @BASEBOARD_FAB2_LIB.BASEBOARD_FAB2(SCH_1):PAGE185
     2 P3E_PCH_M2_TX_DP<2> @BASEBOARD_FAB2_LIB.BASEBOARD_FAB2(SCH_1):P3E_PCH_M2_TX_DP(2)    I64 @BASEBOARD_FAB2_LIB.BASEBOARD_FAB2(SCH_1):PAGE185

C2T14 CAP_0402-0.22UF,16V,10%,X7R,A3A
     1 P3E_PCH_M2_TX_C_DN<2> @BASEBOARD_FAB2_LIB.BASEBOARD_FAB2(SCH_1):P3E_PCH_M2_TX_C_DN(2)    I65 @BASEBOARD_FAB2_LIB.BASEBOARD_FAB2(SCH_1):PAGE185
     2 P3E_PCH_M2_TX_DN<2> @BASEBOARD_FAB2_LIB.BASEBOARD_FAB2(SCH_1):P3E_PCH_M2_TX_DN(2)    I65 @BASEBOARD_FAB2_LIB.BASEBOARD_FAB2(SCH_1):PAGE185

C2T15 CAP_A_0402V-0.1UF,16V,10%,X7R,A
     1   P3V3 @BASEBOARD_FAB2_LIB.BASEBOARD_FAB2(SCH_1):P3V3   I127 @BASEBOARD_FAB2_LIB.BASEBOARD_FAB2(SCH_1):PAGE185
     2    GND @BASEBOARD_FAB2_LIB.BASEBOARD_FAB2(SCH_1):GND   I127 @BASEBOARD_FAB2_LIB.BASEBOARD_FAB2(SCH_1):PAGE185

C2T16 CAP_A_0402V-0.1UF,16V,10%,X7R,A
     1   P3V3 @BASEBOARD_FAB2_LIB.BASEBOARD_FAB2(SCH_1):P3V3   I126 @BASEBOARD_FAB2_LIB.BASEBOARD_FAB2(SCH_1):PAGE185
     2    GND @BASEBOARD_FAB2_LIB.BASEBOARD_FAB2(SCH_1):GND   I126 @BASEBOARD_FAB2_LIB.BASEBOARD_FAB2(SCH_1):PAGE185

C2T17 CAP_A_0402V-0.1UF,16V,10%,X7R,A
     1 P3V3_STBY_MNG @BASEBOARD_FAB2_LIB.BASEBOARD_FAB2(SCH_1):P3V3_STBY_MNG   I112 @BASEBOARD_FAB2_LIB.BASEBOARD_FAB2(SCH_1):PAGE101
     2    GND @BASEBOARD_FAB2_LIB.BASEBOARD_FAB2(SCH_1):GND   I112 @BASEBOARD_FAB2_LIB.BASEBOARD_FAB2(SCH_1):PAGE101

C2T18 CAP_A_0402V-0.01UF,25V,10%,X7RA
     1 P3V3_STBY_MNG_CPU @BASEBOARD_FAB2_LIB.BASEBOARD_FAB2(SCH_1):P3V3_STBY_MNG_CPU   I104 @BASEBOARD_FAB2_LIB.BASEBOARD_FAB2(SCH_1):PAGE101
     2    GND @BASEBOARD_FAB2_LIB.BASEBOARD_FAB2(SCH_1):GND   I104 @BASEBOARD_FAB2_LIB.BASEBOARD_FAB2(SCH_1):PAGE101

C2T19 CAP_A_0402V-1.0UF,6.3V,10%,X6SA
     1 P3V3_STBY_MNG_CPU @BASEBOARD_FAB2_LIB.BASEBOARD_FAB2(SCH_1):P3V3_STBY_MNG_CPU   I106 @BASEBOARD_FAB2_LIB.BASEBOARD_FAB2(SCH_1):PAGE101
     2    GND @BASEBOARD_FAB2_LIB.BASEBOARD_FAB2(SCH_1):GND   I106 @BASEBOARD_FAB2_LIB.BASEBOARD_FAB2(SCH_1):PAGE101

C2T20 CAP_0402-0.22UF,16V,10%,X7R,A3A
     1 P3E_PCH_M2_TX_C_DP<3> @BASEBOARD_FAB2_LIB.BASEBOARD_FAB2(SCH_1):P3E_PCH_M2_TX_C_DP(3)    I66 @BASEBOARD_FAB2_LIB.BASEBOARD_FAB2(SCH_1):PAGE185
     2 P3E_PCH_M2_TX_DP<3> @BASEBOARD_FAB2_LIB.BASEBOARD_FAB2(SCH_1):P3E_PCH_M2_TX_DP(3)    I66 @BASEBOARD_FAB2_LIB.BASEBOARD_FAB2(SCH_1):PAGE185

C2T21 CAP_A_0402V-0.1UF,16V,10%,X7R,A
     1   P3V3 @BASEBOARD_FAB2_LIB.BASEBOARD_FAB2(SCH_1):P3V3   I124 @BASEBOARD_FAB2_LIB.BASEBOARD_FAB2(SCH_1):PAGE185
     2    GND @BASEBOARD_FAB2_LIB.BASEBOARD_FAB2(SCH_1):GND   I124 @BASEBOARD_FAB2_LIB.BASEBOARD_FAB2(SCH_1):PAGE185

C2T22 CAP_0805-10UF,16V,10%,X6S,C953A
     1 P3V3_STBY_MNG @BASEBOARD_FAB2_LIB.BASEBOARD_FAB2(SCH_1):P3V3_STBY_MNG   I113 @BASEBOARD_FAB2_LIB.BASEBOARD_FAB2(SCH_1):PAGE101
     2    GND @BASEBOARD_FAB2_LIB.BASEBOARD_FAB2(SCH_1):GND   I113 @BASEBOARD_FAB2_LIB.BASEBOARD_FAB2(SCH_1):PAGE101

C2T23 CAP_0402-0.22UF,16V,10%,X7R,A3A
     1 P3E_PCH_M2_TX_C_DN<3> @BASEBOARD_FAB2_LIB.BASEBOARD_FAB2(SCH_1):P3E_PCH_M2_TX_C_DN(3)    I67 @BASEBOARD_FAB2_LIB.BASEBOARD_FAB2(SCH_1):PAGE185
     2 P3E_PCH_M2_TX_DN<3> @BASEBOARD_FAB2_LIB.BASEBOARD_FAB2(SCH_1):P3E_PCH_M2_TX_DN(3)    I67 @BASEBOARD_FAB2_LIB.BASEBOARD_FAB2(SCH_1):PAGE185

C2T24 CAP_A_0402V-0.1UF,16V,10%,X7R,A
     1   P3V3 @BASEBOARD_FAB2_LIB.BASEBOARD_FAB2(SCH_1):P3V3   I129 @BASEBOARD_FAB2_LIB.BASEBOARD_FAB2(SCH_1):PAGE185
     2    GND @BASEBOARD_FAB2_LIB.BASEBOARD_FAB2(SCH_1):GND   I129 @BASEBOARD_FAB2_LIB.BASEBOARD_FAB2(SCH_1):PAGE185

C2T25 CAP_A_0402V-0.1UF,16V,10%,X7R,A
     1 P3V3_STBY_MNG @BASEBOARD_FAB2_LIB.BASEBOARD_FAB2(SCH_1):P3V3_STBY_MNG   I111 @BASEBOARD_FAB2_LIB.BASEBOARD_FAB2(SCH_1):PAGE101
     2    GND @BASEBOARD_FAB2_LIB.BASEBOARD_FAB2(SCH_1):GND   I111 @BASEBOARD_FAB2_LIB.BASEBOARD_FAB2(SCH_1):PAGE101

C2T26 CAP_A_0402V-0.1UF,16V,10%,X7R,A
     1   P3V3 @BASEBOARD_FAB2_LIB.BASEBOARD_FAB2(SCH_1):P3V3   I123 @BASEBOARD_FAB2_LIB.BASEBOARD_FAB2(SCH_1):PAGE185
     2    GND @BASEBOARD_FAB2_LIB.BASEBOARD_FAB2(SCH_1):GND   I123 @BASEBOARD_FAB2_LIB.BASEBOARD_FAB2(SCH_1):PAGE185

C2T27 CAP_A_0402V-0.01UF,25V,10%,X7RA
     1 P3V3_STBY_MNG_RGMII @BASEBOARD_FAB2_LIB.BASEBOARD_FAB2(SCH_1):P3V3_STBY_MNG_RGMII    I90 @BASEBOARD_FAB2_LIB.BASEBOARD_FAB2(SCH_1):PAGE101
     2    GND @BASEBOARD_FAB2_LIB.BASEBOARD_FAB2(SCH_1):GND    I90 @BASEBOARD_FAB2_LIB.BASEBOARD_FAB2(SCH_1):PAGE101

C2T28 CAP_A_0402V-1.0UF,6.3V,10%,X6SA
     1 P3V3_STBY @BASEBOARD_FAB2_LIB.BASEBOARD_FAB2(SCH_1):P3V3_STBY   I116 @BASEBOARD_FAB2_LIB.BASEBOARD_FAB2(SCH_1):PAGE101
     2    GND @BASEBOARD_FAB2_LIB.BASEBOARD_FAB2(SCH_1):GND   I116 @BASEBOARD_FAB2_LIB.BASEBOARD_FAB2(SCH_1):PAGE101

C2T29 CAP_A_0402V-0.1UF,16V,10%,X7R,A
     1   P3V3 @BASEBOARD_FAB2_LIB.BASEBOARD_FAB2(SCH_1):P3V3   I120 @BASEBOARD_FAB2_LIB.BASEBOARD_FAB2(SCH_1):PAGE185
     2    GND @BASEBOARD_FAB2_LIB.BASEBOARD_FAB2(SCH_1):GND   I120 @BASEBOARD_FAB2_LIB.BASEBOARD_FAB2(SCH_1):PAGE185

C2T30 CAP_A_0402V-0.1UF,16V,10%,X7R,A
     1 P3V3_STBY_MNG @BASEBOARD_FAB2_LIB.BASEBOARD_FAB2(SCH_1):P3V3_STBY_MNG   I110 @BASEBOARD_FAB2_LIB.BASEBOARD_FAB2(SCH_1):PAGE101
     2    GND @BASEBOARD_FAB2_LIB.BASEBOARD_FAB2(SCH_1):GND   I110 @BASEBOARD_FAB2_LIB.BASEBOARD_FAB2(SCH_1):PAGE101

C2T31 CAP_A_0402V-1.0UF,6.3V,10%,X6SA
     1 P3V3_STBY_MNG_RGMII @BASEBOARD_FAB2_LIB.BASEBOARD_FAB2(SCH_1):P3V3_STBY_MNG_RGMII    I89 @BASEBOARD_FAB2_LIB.BASEBOARD_FAB2(SCH_1):PAGE101
     2    GND @BASEBOARD_FAB2_LIB.BASEBOARD_FAB2(SCH_1):GND    I89 @BASEBOARD_FAB2_LIB.BASEBOARD_FAB2(SCH_1):PAGE101

C2T32 CAP_A_0402V-0.1UF,16V,10%,X7R,A
     1 P0V7_GTL2104_5_VREF @BASEBOARD_FAB2_LIB.BASEBOARD_FAB2(SCH_1):P0V7_GTL2104_5_VREF    I95 @BASEBOARD_FAB2_LIB.BASEBOARD_FAB2(SCH_1):PAGE93
     2    GND @BASEBOARD_FAB2_LIB.BASEBOARD_FAB2(SCH_1):GND    I95 @BASEBOARD_FAB2_LIB.BASEBOARD_FAB2(SCH_1):PAGE93

C2T33 CAP_A_0402V-1.0UF,6.3V,10%,X6SA
     1   P3V3 @BASEBOARD_FAB2_LIB.BASEBOARD_FAB2(SCH_1):P3V3    I72 @BASEBOARD_FAB2_LIB.BASEBOARD_FAB2(SCH_1):PAGE93
     2    GND @BASEBOARD_FAB2_LIB.BASEBOARD_FAB2(SCH_1):GND    I72 @BASEBOARD_FAB2_LIB.BASEBOARD_FAB2(SCH_1):PAGE93

C2T34 CAP_A_0402V-0.1UF,16V,10%,X7R,A
     1 P3V3_STBY_MNG @BASEBOARD_FAB2_LIB.BASEBOARD_FAB2(SCH_1):P3V3_STBY_MNG   I109 @BASEBOARD_FAB2_LIB.BASEBOARD_FAB2(SCH_1):PAGE101
     2    GND @BASEBOARD_FAB2_LIB.BASEBOARD_FAB2(SCH_1):GND   I109 @BASEBOARD_FAB2_LIB.BASEBOARD_FAB2(SCH_1):PAGE101

C2T35 CAP_A_0402V-0.1UF,16V,10%,X7R,A
     1 P3V3_STBY @BASEBOARD_FAB2_LIB.BASEBOARD_FAB2(SCH_1):P3V3_STBY   I273 @BASEBOARD_FAB2_LIB.BASEBOARD_FAB2(SCH_1):PAGE156
     2    GND @BASEBOARD_FAB2_LIB.BASEBOARD_FAB2(SCH_1):GND   I273 @BASEBOARD_FAB2_LIB.BASEBOARD_FAB2(SCH_1):PAGE156

C2T36 CAP_A_0402V-0.1UF,16V,10%,X7R,A
     1 P3V3_STBY @BASEBOARD_FAB2_LIB.BASEBOARD_FAB2(SCH_1):P3V3_STBY    I43 @BASEBOARD_FAB2_LIB.BASEBOARD_FAB2(SCH_1):PAGE198
     2    GND @BASEBOARD_FAB2_LIB.BASEBOARD_FAB2(SCH_1):GND    I43 @BASEBOARD_FAB2_LIB.BASEBOARD_FAB2(SCH_1):PAGE198

C2T37 CAP_A_0402V-0.01UF,25V,10%,X7RA
     1 P3V3_STBY_MNG_RMII @BASEBOARD_FAB2_LIB.BASEBOARD_FAB2(SCH_1):P3V3_STBY_MNG_RMII    I99 @BASEBOARD_FAB2_LIB.BASEBOARD_FAB2(SCH_1):PAGE101
     2    GND @BASEBOARD_FAB2_LIB.BASEBOARD_FAB2(SCH_1):GND    I99 @BASEBOARD_FAB2_LIB.BASEBOARD_FAB2(SCH_1):PAGE101

C2T38 CAP_A_0402V-1.0UF,6.3V,10%,X6SA
     1 P3V3_STBY_MNG_RMII @BASEBOARD_FAB2_LIB.BASEBOARD_FAB2(SCH_1):P3V3_STBY_MNG_RMII    I97 @BASEBOARD_FAB2_LIB.BASEBOARD_FAB2(SCH_1):PAGE101
     2    GND @BASEBOARD_FAB2_LIB.BASEBOARD_FAB2(SCH_1):GND    I97 @BASEBOARD_FAB2_LIB.BASEBOARD_FAB2(SCH_1):PAGE101

C2U1 CAP_0805-10UF,16V,10%,X6S,C953A
     1 P3V3_STBY @BASEBOARD_FAB2_LIB.BASEBOARD_FAB2(SCH_1):P3V3_STBY    I44 @BASEBOARD_FAB2_LIB.BASEBOARD_FAB2(SCH_1):PAGE198
     2    GND @BASEBOARD_FAB2_LIB.BASEBOARD_FAB2(SCH_1):GND    I44 @BASEBOARD_FAB2_LIB.BASEBOARD_FAB2(SCH_1):PAGE198

C2U2 CAP_0805-10UF,16V,10%,X6S,C953A
     1   P3V3 @BASEBOARD_FAB2_LIB.BASEBOARD_FAB2(SCH_1):P3V3    I47 @BASEBOARD_FAB2_LIB.BASEBOARD_FAB2(SCH_1):PAGE198
     2    GND @BASEBOARD_FAB2_LIB.BASEBOARD_FAB2(SCH_1):GND    I47 @BASEBOARD_FAB2_LIB.BASEBOARD_FAB2(SCH_1):PAGE198

C2U3 CAP_0402-0.22UF,16V,10%,X7R,A3A
     1 P3E_CPU0_PE1_PCH_RXP<0> @BASEBOARD_FAB2_LIB.BASEBOARD_FAB2(SCH_1):P3E_CPU0_PE1_PCH_RXP(0)   I272 @BASEBOARD_FAB2_LIB.BASEBOARD_FAB2(SCH_1):PAGE107
     2 P3E_CPU0_PE1_SS_RXP<0> @BASEBOARD_FAB2_LIB.BASEBOARD_FAB2(SCH_1):P3E_CPU0_PE1_SS_RXP(0)   I272 @BASEBOARD_FAB2_LIB.BASEBOARD_FAB2(SCH_1):PAGE107

C2U4 CAP_0402-0.22UF,16V,10%,X7R,A3A
     1 P3E_CPU0_PE1_PCH_RXN<0> @BASEBOARD_FAB2_LIB.BASEBOARD_FAB2(SCH_1):P3E_CPU0_PE1_PCH_RXN(0)   I257 @BASEBOARD_FAB2_LIB.BASEBOARD_FAB2(SCH_1):PAGE107
     2 P3E_CPU0_PE1_SS_RXN<0> @BASEBOARD_FAB2_LIB.BASEBOARD_FAB2(SCH_1):P3E_CPU0_PE1_SS_RXN(0)   I257 @BASEBOARD_FAB2_LIB.BASEBOARD_FAB2(SCH_1):PAGE107

C2U5 CAP_0402-0.22UF,16V,10%,X7R,A3A
     1 P3E_CPU0_PE1_PCH_RXP<1> @BASEBOARD_FAB2_LIB.BASEBOARD_FAB2(SCH_1):P3E_CPU0_PE1_PCH_RXP(1)   I274 @BASEBOARD_FAB2_LIB.BASEBOARD_FAB2(SCH_1):PAGE107
     2 P3E_CPU0_PE1_SS_RXP<1> @BASEBOARD_FAB2_LIB.BASEBOARD_FAB2(SCH_1):P3E_CPU0_PE1_SS_RXP(1)   I274 @BASEBOARD_FAB2_LIB.BASEBOARD_FAB2(SCH_1):PAGE107

C2U6 CAP_0402-0.22UF,16V,10%,X7R,A3A
     1 P3E_CPU0_PE1_PCH_RXN<1> @BASEBOARD_FAB2_LIB.BASEBOARD_FAB2(SCH_1):P3E_CPU0_PE1_PCH_RXN(1)   I260 @BASEBOARD_FAB2_LIB.BASEBOARD_FAB2(SCH_1):PAGE107
     2 P3E_CPU0_PE1_SS_RXN<1> @BASEBOARD_FAB2_LIB.BASEBOARD_FAB2(SCH_1):P3E_CPU0_PE1_SS_RXN(1)   I260 @BASEBOARD_FAB2_LIB.BASEBOARD_FAB2(SCH_1):PAGE107

C2U7 CAP_0402-0.22UF,16V,10%,X7R,A3A
     1 P3E_CPU0_PE1_PCH_RXP<2> @BASEBOARD_FAB2_LIB.BASEBOARD_FAB2(SCH_1):P3E_CPU0_PE1_PCH_RXP(2)   I277 @BASEBOARD_FAB2_LIB.BASEBOARD_FAB2(SCH_1):PAGE107
     2 P3E_CPU0_PE1_SS_RXP<2> @BASEBOARD_FAB2_LIB.BASEBOARD_FAB2(SCH_1):P3E_CPU0_PE1_SS_RXP(2)   I277 @BASEBOARD_FAB2_LIB.BASEBOARD_FAB2(SCH_1):PAGE107

C2U8 CAP_0402-0.22UF,16V,10%,X7R,A3A
     1 P3E_CPU0_PE1_PCH_RXN<2> @BASEBOARD_FAB2_LIB.BASEBOARD_FAB2(SCH_1):P3E_CPU0_PE1_PCH_RXN(2)   I264 @BASEBOARD_FAB2_LIB.BASEBOARD_FAB2(SCH_1):PAGE107
     2 P3E_CPU0_PE1_SS_RXN<2> @BASEBOARD_FAB2_LIB.BASEBOARD_FAB2(SCH_1):P3E_CPU0_PE1_SS_RXN(2)   I264 @BASEBOARD_FAB2_LIB.BASEBOARD_FAB2(SCH_1):PAGE107

C2U9 CAP_0402-0.22UF,16V,10%,X7R,A3A
     1 P3E_CPU0_PE1_PCH_RXP<3> @BASEBOARD_FAB2_LIB.BASEBOARD_FAB2(SCH_1):P3E_CPU0_PE1_PCH_RXP(3)   I279 @BASEBOARD_FAB2_LIB.BASEBOARD_FAB2(SCH_1):PAGE107
     2 P3E_CPU0_PE1_SS_RXP<3> @BASEBOARD_FAB2_LIB.BASEBOARD_FAB2(SCH_1):P3E_CPU0_PE1_SS_RXP(3)   I279 @BASEBOARD_FAB2_LIB.BASEBOARD_FAB2(SCH_1):PAGE107

C2U10 CAP_0402-0.22UF,16V,10%,X7R,A3A
     1 P3E_CPU0_PE1_PCH_RXN<3> @BASEBOARD_FAB2_LIB.BASEBOARD_FAB2(SCH_1):P3E_CPU0_PE1_PCH_RXN(3)   I267 @BASEBOARD_FAB2_LIB.BASEBOARD_FAB2(SCH_1):PAGE107
     2 P3E_CPU0_PE1_SS_RXN<3> @BASEBOARD_FAB2_LIB.BASEBOARD_FAB2(SCH_1):P3E_CPU0_PE1_SS_RXN(3)   I267 @BASEBOARD_FAB2_LIB.BASEBOARD_FAB2(SCH_1):PAGE107

C2U11 CAP_0402-0.22UF,16V,10%,X7R,A3A
     1 P3E_CPU0_PE1_PCH_RXP<4> @BASEBOARD_FAB2_LIB.BASEBOARD_FAB2(SCH_1):P3E_CPU0_PE1_PCH_RXP(4)   I278 @BASEBOARD_FAB2_LIB.BASEBOARD_FAB2(SCH_1):PAGE107
     2 P3E_CPU0_PE1_SS_RXP<4> @BASEBOARD_FAB2_LIB.BASEBOARD_FAB2(SCH_1):P3E_CPU0_PE1_SS_RXP(4)   I278 @BASEBOARD_FAB2_LIB.BASEBOARD_FAB2(SCH_1):PAGE107

C2U12 CAP_0402-0.22UF,16V,10%,X7R,A3A
     1 P3E_CPU0_PE1_PCH_RXN<4> @BASEBOARD_FAB2_LIB.BASEBOARD_FAB2(SCH_1):P3E_CPU0_PE1_PCH_RXN(4)   I265 @BASEBOARD_FAB2_LIB.BASEBOARD_FAB2(SCH_1):PAGE107
     2 P3E_CPU0_PE1_SS_RXN<4> @BASEBOARD_FAB2_LIB.BASEBOARD_FAB2(SCH_1):P3E_CPU0_PE1_SS_RXN(4)   I265 @BASEBOARD_FAB2_LIB.BASEBOARD_FAB2(SCH_1):PAGE107

C2U13 CAP_0402-0.22UF,16V,10%,X7R,A3A
     1 P3E_CPU0_PE1_PCH_RXP<5> @BASEBOARD_FAB2_LIB.BASEBOARD_FAB2(SCH_1):P3E_CPU0_PE1_PCH_RXP(5)   I297 @BASEBOARD_FAB2_LIB.BASEBOARD_FAB2(SCH_1):PAGE107
     2 P3E_CPU0_PE1_SS_RXP<5> @BASEBOARD_FAB2_LIB.BASEBOARD_FAB2(SCH_1):P3E_CPU0_PE1_SS_RXP(5)   I297 @BASEBOARD_FAB2_LIB.BASEBOARD_FAB2(SCH_1):PAGE107

C2U14 CAP_0402-0.22UF,16V,10%,X7R,A3A
     1 P3E_CPU0_PE1_PCH_RXN<5> @BASEBOARD_FAB2_LIB.BASEBOARD_FAB2(SCH_1):P3E_CPU0_PE1_PCH_RXN(5)   I287 @BASEBOARD_FAB2_LIB.BASEBOARD_FAB2(SCH_1):PAGE107
     2 P3E_CPU0_PE1_SS_RXN<5> @BASEBOARD_FAB2_LIB.BASEBOARD_FAB2(SCH_1):P3E_CPU0_PE1_SS_RXN(5)   I287 @BASEBOARD_FAB2_LIB.BASEBOARD_FAB2(SCH_1):PAGE107

C2U15 CAP_0402-0.22UF,16V,10%,X7R,A3A
     1 P3E_CPU0_PE1_PCH_RXP<6> @BASEBOARD_FAB2_LIB.BASEBOARD_FAB2(SCH_1):P3E_CPU0_PE1_PCH_RXP(6)   I296 @BASEBOARD_FAB2_LIB.BASEBOARD_FAB2(SCH_1):PAGE107
     2 P3E_CPU0_PE1_SS_RXP<6> @BASEBOARD_FAB2_LIB.BASEBOARD_FAB2(SCH_1):P3E_CPU0_PE1_SS_RXP(6)   I296 @BASEBOARD_FAB2_LIB.BASEBOARD_FAB2(SCH_1):PAGE107

C2U16 CAP_0402-0.22UF,16V,10%,X7R,A3A
     1 P3E_CPU0_PE1_PCH_RXN<6> @BASEBOARD_FAB2_LIB.BASEBOARD_FAB2(SCH_1):P3E_CPU0_PE1_PCH_RXN(6)   I286 @BASEBOARD_FAB2_LIB.BASEBOARD_FAB2(SCH_1):PAGE107
     2 P3E_CPU0_PE1_SS_RXN<6> @BASEBOARD_FAB2_LIB.BASEBOARD_FAB2(SCH_1):P3E_CPU0_PE1_SS_RXN(6)   I286 @BASEBOARD_FAB2_LIB.BASEBOARD_FAB2(SCH_1):PAGE107

C2U17 CAP_0402-0.22UF,16V,10%,X7R,A3A
     1 P3E_CPU0_PE1_PCH_RXP<7> @BASEBOARD_FAB2_LIB.BASEBOARD_FAB2(SCH_1):P3E_CPU0_PE1_PCH_RXP(7)   I300 @BASEBOARD_FAB2_LIB.BASEBOARD_FAB2(SCH_1):PAGE107
     2 P3E_CPU0_PE1_SS_RXP<7> @BASEBOARD_FAB2_LIB.BASEBOARD_FAB2(SCH_1):P3E_CPU0_PE1_SS_RXP(7)   I300 @BASEBOARD_FAB2_LIB.BASEBOARD_FAB2(SCH_1):PAGE107

C2U18 CAP_0402-0.22UF,16V,10%,X7R,A3A
     1 P3E_CPU0_PE1_PCH_RXN<7> @BASEBOARD_FAB2_LIB.BASEBOARD_FAB2(SCH_1):P3E_CPU0_PE1_PCH_RXN(7)   I294 @BASEBOARD_FAB2_LIB.BASEBOARD_FAB2(SCH_1):PAGE107
     2 P3E_CPU0_PE1_SS_RXN<7> @BASEBOARD_FAB2_LIB.BASEBOARD_FAB2(SCH_1):P3E_CPU0_PE1_SS_RXN(7)   I294 @BASEBOARD_FAB2_LIB.BASEBOARD_FAB2(SCH_1):PAGE107

C2U19 CAP_A_0402V-0.1UF,16V,10%,X7R,A
     1   P3V3 @BASEBOARD_FAB2_LIB.BASEBOARD_FAB2(SCH_1):P3V3    I46 @BASEBOARD_FAB2_LIB.BASEBOARD_FAB2(SCH_1):PAGE198
     2    GND @BASEBOARD_FAB2_LIB.BASEBOARD_FAB2(SCH_1):GND    I46 @BASEBOARD_FAB2_LIB.BASEBOARD_FAB2(SCH_1):PAGE198

C2U20 CAP_A_0402V-0.1UF,16V,10%,X7R,A
     1   P12V @BASEBOARD_FAB2_LIB.BASEBOARD_FAB2(SCH_1):P12V     I1 @BASEBOARD_FAB2_LIB.BASEBOARD_FAB2(SCH_1):PAGE108
     2    GND @BASEBOARD_FAB2_LIB.BASEBOARD_FAB2(SCH_1):GND     I1 @BASEBOARD_FAB2_LIB.BASEBOARD_FAB2(SCH_1):PAGE108

C2U21 CAP_A_0402V-0.1UF,16V,10%,X7R,A
     1   P3V3 @BASEBOARD_FAB2_LIB.BASEBOARD_FAB2(SCH_1):P3V3     I5 @BASEBOARD_FAB2_LIB.BASEBOARD_FAB2(SCH_1):PAGE108
     2    GND @BASEBOARD_FAB2_LIB.BASEBOARD_FAB2(SCH_1):GND     I5 @BASEBOARD_FAB2_LIB.BASEBOARD_FAB2(SCH_1):PAGE108

C2U22 CAP_A_0402V-0.1UF,16V,10%,X7R,A
     1 P3V3_STBY @BASEBOARD_FAB2_LIB.BASEBOARD_FAB2(SCH_1):P3V3_STBY   I318 @BASEBOARD_FAB2_LIB.BASEBOARD_FAB2(SCH_1):PAGE108
     2    GND @BASEBOARD_FAB2_LIB.BASEBOARD_FAB2(SCH_1):GND   I318 @BASEBOARD_FAB2_LIB.BASEBOARD_FAB2(SCH_1):PAGE108

C2U23 CAP_A_0402V-0.1UF,16V,10%,X7R,A
     1 P3V3_STBY @BASEBOARD_FAB2_LIB.BASEBOARD_FAB2(SCH_1):P3V3_STBY   I315 @BASEBOARD_FAB2_LIB.BASEBOARD_FAB2(SCH_1):PAGE108
     2    GND @BASEBOARD_FAB2_LIB.BASEBOARD_FAB2(SCH_1):GND   I315 @BASEBOARD_FAB2_LIB.BASEBOARD_FAB2(SCH_1):PAGE108

C2U24 CAP_A_0402V-0.1UF,16V,10%,X7R,A
     1   P12V @BASEBOARD_FAB2_LIB.BASEBOARD_FAB2(SCH_1):P12V     I2 @BASEBOARD_FAB2_LIB.BASEBOARD_FAB2(SCH_1):PAGE108
     2    GND @BASEBOARD_FAB2_LIB.BASEBOARD_FAB2(SCH_1):GND     I2 @BASEBOARD_FAB2_LIB.BASEBOARD_FAB2(SCH_1):PAGE108

C2U25 CAP_A_0402V-0.1UF,16V,10%,X7R,A
     1   P3V3 @BASEBOARD_FAB2_LIB.BASEBOARD_FAB2(SCH_1):P3V3     I7 @BASEBOARD_FAB2_LIB.BASEBOARD_FAB2(SCH_1):PAGE108
     2    GND @BASEBOARD_FAB2_LIB.BASEBOARD_FAB2(SCH_1):GND     I7 @BASEBOARD_FAB2_LIB.BASEBOARD_FAB2(SCH_1):PAGE108

C2U26 CAP_A_0402V-1.0UF,6.3V,10%,X6SA
     1 P3V3_RTC_STBY @BASEBOARD_FAB2_LIB.BASEBOARD_FAB2(SCH_1):P3V3_RTC_STBY   I102 @BASEBOARD_FAB2_LIB.BASEBOARD_FAB2(SCH_1):PAGE196
     2    GND @BASEBOARD_FAB2_LIB.BASEBOARD_FAB2(SCH_1):GND   I102 @BASEBOARD_FAB2_LIB.BASEBOARD_FAB2(SCH_1):PAGE196

C2U27 CAP_A_0402V-0.1UF,16V,10%,X7R,A
     1 P3V3_STBY @BASEBOARD_FAB2_LIB.BASEBOARD_FAB2(SCH_1):P3V3_STBY    I90 @BASEBOARD_FAB2_LIB.BASEBOARD_FAB2(SCH_1):PAGE161
     2    GND @BASEBOARD_FAB2_LIB.BASEBOARD_FAB2(SCH_1):GND    I90 @BASEBOARD_FAB2_LIB.BASEBOARD_FAB2(SCH_1):PAGE161

C2U28 CAP_A_0402V-0.1UF,16V,10%,X7R,A
     1 P3V3_STBY @BASEBOARD_FAB2_LIB.BASEBOARD_FAB2(SCH_1):P3V3_STBY    I93 @BASEBOARD_FAB2_LIB.BASEBOARD_FAB2(SCH_1):PAGE161
     2    GND @BASEBOARD_FAB2_LIB.BASEBOARD_FAB2(SCH_1):GND    I93 @BASEBOARD_FAB2_LIB.BASEBOARD_FAB2(SCH_1):PAGE161

C3A1 CAP_A_0603V-22.0UF,4V,20%,X6S,A
     1 PVDDQ_KLM @BASEBOARD_FAB2_LIB.BASEBOARD_FAB2(SCH_1):PVDDQ_KLM   I217 @BASEBOARD_FAB2_LIB.BASEBOARD_FAB2(SCH_1):PAGE228
     2    GND @BASEBOARD_FAB2_LIB.BASEBOARD_FAB2(SCH_1):GND   I217 @BASEBOARD_FAB2_LIB.BASEBOARD_FAB2(SCH_1):PAGE228

C3A2 CAP_A_0603V-22.0UF,4V,20%,X6S,A
     1 PVDDQ_KLM @BASEBOARD_FAB2_LIB.BASEBOARD_FAB2(SCH_1):PVDDQ_KLM   I216 @BASEBOARD_FAB2_LIB.BASEBOARD_FAB2(SCH_1):PAGE228
     2    GND @BASEBOARD_FAB2_LIB.BASEBOARD_FAB2(SCH_1):GND   I216 @BASEBOARD_FAB2_LIB.BASEBOARD_FAB2(SCH_1):PAGE228

C3A3 CAP_0603LF-10UF,4V,20%,X6S,E15A
     1 PVPP_KLM @BASEBOARD_FAB2_LIB.BASEBOARD_FAB2(SCH_1):PVPP_KLM    I97 @BASEBOARD_FAB2_LIB.BASEBOARD_FAB2(SCH_1):PAGE234
     2    GND @BASEBOARD_FAB2_LIB.BASEBOARD_FAB2(SCH_1):GND    I97 @BASEBOARD_FAB2_LIB.BASEBOARD_FAB2(SCH_1):PAGE234

C3A4 CAP_0603LF-10UF,4V,20%,X6S,E15A
     1 PVPP_KLM @BASEBOARD_FAB2_LIB.BASEBOARD_FAB2(SCH_1):PVPP_KLM    I93 @BASEBOARD_FAB2_LIB.BASEBOARD_FAB2(SCH_1):PAGE234
     2    GND @BASEBOARD_FAB2_LIB.BASEBOARD_FAB2(SCH_1):GND    I93 @BASEBOARD_FAB2_LIB.BASEBOARD_FAB2(SCH_1):PAGE234

C3A5 CAP_A_0603V-22.0UF,4V,20%,X6S,A
     1 PVDDQ_KLM @BASEBOARD_FAB2_LIB.BASEBOARD_FAB2(SCH_1):PVDDQ_KLM   I222 @BASEBOARD_FAB2_LIB.BASEBOARD_FAB2(SCH_1):PAGE228
     2    GND @BASEBOARD_FAB2_LIB.BASEBOARD_FAB2(SCH_1):GND   I222 @BASEBOARD_FAB2_LIB.BASEBOARD_FAB2(SCH_1):PAGE228

C3A6 CAP_A_0603V-22.0UF,4V,20%,X6S,A
     1 PVDDQ_KLM @BASEBOARD_FAB2_LIB.BASEBOARD_FAB2(SCH_1):PVDDQ_KLM   I223 @BASEBOARD_FAB2_LIB.BASEBOARD_FAB2(SCH_1):PAGE228
     2    GND @BASEBOARD_FAB2_LIB.BASEBOARD_FAB2(SCH_1):GND   I223 @BASEBOARD_FAB2_LIB.BASEBOARD_FAB2(SCH_1):PAGE228

C3A7 CAP_0603LF-10UF,4V,20%,X6S,E15A
     1 PVPP_KLM @BASEBOARD_FAB2_LIB.BASEBOARD_FAB2(SCH_1):PVPP_KLM    I95 @BASEBOARD_FAB2_LIB.BASEBOARD_FAB2(SCH_1):PAGE234
     2    GND @BASEBOARD_FAB2_LIB.BASEBOARD_FAB2(SCH_1):GND    I95 @BASEBOARD_FAB2_LIB.BASEBOARD_FAB2(SCH_1):PAGE234

C3A8 CAP_0603LF-10UF,4V,20%,X6S,E15A
     1 PVPP_KLM @BASEBOARD_FAB2_LIB.BASEBOARD_FAB2(SCH_1):PVPP_KLM    I86 @BASEBOARD_FAB2_LIB.BASEBOARD_FAB2(SCH_1):PAGE234
     2    GND @BASEBOARD_FAB2_LIB.BASEBOARD_FAB2(SCH_1):GND    I86 @BASEBOARD_FAB2_LIB.BASEBOARD_FAB2(SCH_1):PAGE234

C3B1 CAP_0603LF-10UF,4V,20%,X6S,E15A
     1 PVPP_KLM @BASEBOARD_FAB2_LIB.BASEBOARD_FAB2(SCH_1):PVPP_KLM    I94 @BASEBOARD_FAB2_LIB.BASEBOARD_FAB2(SCH_1):PAGE234
     2    GND @BASEBOARD_FAB2_LIB.BASEBOARD_FAB2(SCH_1):GND    I94 @BASEBOARD_FAB2_LIB.BASEBOARD_FAB2(SCH_1):PAGE234

C3B2 CAP_0603LF-10UF,4V,20%,X6S,E15A
     1 PVPP_KLM @BASEBOARD_FAB2_LIB.BASEBOARD_FAB2(SCH_1):PVPP_KLM    I84 @BASEBOARD_FAB2_LIB.BASEBOARD_FAB2(SCH_1):PAGE234
     2    GND @BASEBOARD_FAB2_LIB.BASEBOARD_FAB2(SCH_1):GND    I84 @BASEBOARD_FAB2_LIB.BASEBOARD_FAB2(SCH_1):PAGE234

C3B3 CAPP_7343LF-330UF,6.3V,20%,POSA
     1 PVPP_KLM @BASEBOARD_FAB2_LIB.BASEBOARD_FAB2(SCH_1):PVPP_KLM   I167 @BASEBOARD_FAB2_LIB.BASEBOARD_FAB2(SCH_1):PAGE234
     2    GND @BASEBOARD_FAB2_LIB.BASEBOARD_FAB2(SCH_1):GND   I167 @BASEBOARD_FAB2_LIB.BASEBOARD_FAB2(SCH_1):PAGE234

C3B4 CAP_A_0402V-0.1UF,16V,10%,X7R,A
     1 PVCCIO_CPU1 @BASEBOARD_FAB2_LIB.BASEBOARD_FAB2(SCH_1):PVCCIO_CPU1    I47 @BASEBOARD_FAB2_LIB.BASEBOARD_FAB2(SCH_1):PAGE99
     2    GND @BASEBOARD_FAB2_LIB.BASEBOARD_FAB2(SCH_1):GND    I47 @BASEBOARD_FAB2_LIB.BASEBOARD_FAB2(SCH_1):PAGE99

C3B5 CAP_A_0402V-0.1UF,16V,10%,X7R,A
     1 PVPP_KLM @BASEBOARD_FAB2_LIB.BASEBOARD_FAB2(SCH_1):PVPP_KLM    I53 @BASEBOARD_FAB2_LIB.BASEBOARD_FAB2(SCH_1):PAGE99
     2    GND @BASEBOARD_FAB2_LIB.BASEBOARD_FAB2(SCH_1):GND    I53 @BASEBOARD_FAB2_LIB.BASEBOARD_FAB2(SCH_1):PAGE99

C3B6 CAPP_3018-68UF,16V,20%,TANT,72A
     1 P12V_STBY @BASEBOARD_FAB2_LIB.BASEBOARD_FAB2(SCH_1):P12V_STBY   I100 @BASEBOARD_FAB2_LIB.BASEBOARD_FAB2(SCH_1):PAGE195
     2    GND @BASEBOARD_FAB2_LIB.BASEBOARD_FAB2(SCH_1):GND   I100 @BASEBOARD_FAB2_LIB.BASEBOARD_FAB2(SCH_1):PAGE195

C3C1 CAP_A_0402V-1.0UF,6.3V,10%,X6SA
     1 PVCCIOMCP_CPU1 @BASEBOARD_FAB2_LIB.BASEBOARD_FAB2(SCH_1):PVCCIOMCP_CPU1    I38 @BASEBOARD_FAB2_LIB.BASEBOARD_FAB2(SCH_1):PAGE193
     2    GND @BASEBOARD_FAB2_LIB.BASEBOARD_FAB2(SCH_1):GND    I38 @BASEBOARD_FAB2_LIB.BASEBOARD_FAB2(SCH_1):PAGE193

C3C2 CAP_A_0402V-1.0UF,6.3V,10%,X6SA
     1 PVCCIOMCP_CPU1 @BASEBOARD_FAB2_LIB.BASEBOARD_FAB2(SCH_1):PVCCIOMCP_CPU1    I31 @BASEBOARD_FAB2_LIB.BASEBOARD_FAB2(SCH_1):PAGE193
     2    GND @BASEBOARD_FAB2_LIB.BASEBOARD_FAB2(SCH_1):GND    I31 @BASEBOARD_FAB2_LIB.BASEBOARD_FAB2(SCH_1):PAGE193

C3D1 CAP_A_0603V-22.0UF,4V,20%,X6S,A
     1 PVCCIN_CPU1 @BASEBOARD_FAB2_LIB.BASEBOARD_FAB2(SCH_1):PVCCIN_CPU1   I111 @BASEBOARD_FAB2_LIB.BASEBOARD_FAB2(SCH_1):PAGE76
     2    GND @BASEBOARD_FAB2_LIB.BASEBOARD_FAB2(SCH_1):GND   I111 @BASEBOARD_FAB2_LIB.BASEBOARD_FAB2(SCH_1):PAGE76

C3D2 CAP_A_0603V-22.0UF,4V,20%,X6S,A
     1 PVCCIN_CPU1 @BASEBOARD_FAB2_LIB.BASEBOARD_FAB2(SCH_1):PVCCIN_CPU1    I69 @BASEBOARD_FAB2_LIB.BASEBOARD_FAB2(SCH_1):PAGE76
     2    GND @BASEBOARD_FAB2_LIB.BASEBOARD_FAB2(SCH_1):GND    I69 @BASEBOARD_FAB2_LIB.BASEBOARD_FAB2(SCH_1):PAGE76

C3D3 CAP_0603LF-10UF,4V,20%,X6S,E15A
     1 P1V8_MCP_CPU1 @BASEBOARD_FAB2_LIB.BASEBOARD_FAB2(SCH_1):P1V8_MCP_CPU1    I25 @BASEBOARD_FAB2_LIB.BASEBOARD_FAB2(SCH_1):PAGE72
     2    GND @BASEBOARD_FAB2_LIB.BASEBOARD_FAB2(SCH_1):GND    I25 @BASEBOARD_FAB2_LIB.BASEBOARD_FAB2(SCH_1):PAGE72

C3D4 CAP_A_0603V-22.0UF,4V,20%,X6S,A
     1 PVCCMCP_CPU1 @BASEBOARD_FAB2_LIB.BASEBOARD_FAB2(SCH_1):PVCCMCP_CPU1     I5 @BASEBOARD_FAB2_LIB.BASEBOARD_FAB2(SCH_1):PAGE76
     2    GND @BASEBOARD_FAB2_LIB.BASEBOARD_FAB2(SCH_1):GND     I5 @BASEBOARD_FAB2_LIB.BASEBOARD_FAB2(SCH_1):PAGE76

C3D5 CAP_A_0603V-22.0UF,4V,20%,X6S,A
     1 PVCCMCP_CPU1 @BASEBOARD_FAB2_LIB.BASEBOARD_FAB2(SCH_1):PVCCMCP_CPU1     I3 @BASEBOARD_FAB2_LIB.BASEBOARD_FAB2(SCH_1):PAGE76
     2    GND @BASEBOARD_FAB2_LIB.BASEBOARD_FAB2(SCH_1):GND     I3 @BASEBOARD_FAB2_LIB.BASEBOARD_FAB2(SCH_1):PAGE76

C3D6 CAP_A_0603V-22.0UF,4V,20%,X6S,A
     1 PVCCMCP_CPU1 @BASEBOARD_FAB2_LIB.BASEBOARD_FAB2(SCH_1):PVCCMCP_CPU1   I170 @BASEBOARD_FAB2_LIB.BASEBOARD_FAB2(SCH_1):PAGE76
     2    GND @BASEBOARD_FAB2_LIB.BASEBOARD_FAB2(SCH_1):GND   I170 @BASEBOARD_FAB2_LIB.BASEBOARD_FAB2(SCH_1):PAGE76

C3D7 CAP_A_0603V-22.0UF,4V,20%,X6S,A
     1 PVCCMCP_CPU1 @BASEBOARD_FAB2_LIB.BASEBOARD_FAB2(SCH_1):PVCCMCP_CPU1   I164 @BASEBOARD_FAB2_LIB.BASEBOARD_FAB2(SCH_1):PAGE76
     2    GND @BASEBOARD_FAB2_LIB.BASEBOARD_FAB2(SCH_1):GND   I164 @BASEBOARD_FAB2_LIB.BASEBOARD_FAB2(SCH_1):PAGE76

C3D8 CAP_A_0603V-22.0UF,4V,20%,X6S,A
     1 PVCCIO_CPU1 @BASEBOARD_FAB2_LIB.BASEBOARD_FAB2(SCH_1):PVCCIO_CPU1    I18 @BASEBOARD_FAB2_LIB.BASEBOARD_FAB2(SCH_1):PAGE76
     2    GND @BASEBOARD_FAB2_LIB.BASEBOARD_FAB2(SCH_1):GND    I18 @BASEBOARD_FAB2_LIB.BASEBOARD_FAB2(SCH_1):PAGE76

C3D9 CAP_A_0603V-22.0UF,4V,20%,X6S,A
     1 PVCCIO_CPU1 @BASEBOARD_FAB2_LIB.BASEBOARD_FAB2(SCH_1):PVCCIO_CPU1    I15 @BASEBOARD_FAB2_LIB.BASEBOARD_FAB2(SCH_1):PAGE76
     2    GND @BASEBOARD_FAB2_LIB.BASEBOARD_FAB2(SCH_1):GND    I15 @BASEBOARD_FAB2_LIB.BASEBOARD_FAB2(SCH_1):PAGE76

C3D10 CAP_A_0603V-22.0UF,4V,20%,X6S,A
     1 PVCCMCP_CPU1 @BASEBOARD_FAB2_LIB.BASEBOARD_FAB2(SCH_1):PVCCMCP_CPU1   I196 @BASEBOARD_FAB2_LIB.BASEBOARD_FAB2(SCH_1):PAGE76
     2    GND @BASEBOARD_FAB2_LIB.BASEBOARD_FAB2(SCH_1):GND   I196 @BASEBOARD_FAB2_LIB.BASEBOARD_FAB2(SCH_1):PAGE76

C3D11 CAP_A_0603V-22.0UF,4V,20%,X6S,A
     1 PVCCMCP_CPU1 @BASEBOARD_FAB2_LIB.BASEBOARD_FAB2(SCH_1):PVCCMCP_CPU1     I7 @BASEBOARD_FAB2_LIB.BASEBOARD_FAB2(SCH_1):PAGE76
     2    GND @BASEBOARD_FAB2_LIB.BASEBOARD_FAB2(SCH_1):GND     I7 @BASEBOARD_FAB2_LIB.BASEBOARD_FAB2(SCH_1):PAGE76

C3D12 CAP_A_0603V-22.0UF,4V,20%,X6S,A
     1 PVCCMCP_CPU1 @BASEBOARD_FAB2_LIB.BASEBOARD_FAB2(SCH_1):PVCCMCP_CPU1     I4 @BASEBOARD_FAB2_LIB.BASEBOARD_FAB2(SCH_1):PAGE76
     2    GND @BASEBOARD_FAB2_LIB.BASEBOARD_FAB2(SCH_1):GND     I4 @BASEBOARD_FAB2_LIB.BASEBOARD_FAB2(SCH_1):PAGE76

C3D13 CAP_A_0603V-22.0UF,4V,20%,X6S,A
     1 PVCCMCP_CPU1 @BASEBOARD_FAB2_LIB.BASEBOARD_FAB2(SCH_1):PVCCMCP_CPU1     I8 @BASEBOARD_FAB2_LIB.BASEBOARD_FAB2(SCH_1):PAGE76
     2    GND @BASEBOARD_FAB2_LIB.BASEBOARD_FAB2(SCH_1):GND     I8 @BASEBOARD_FAB2_LIB.BASEBOARD_FAB2(SCH_1):PAGE76

C3D14 CAP_A_0603V-22.0UF,4V,20%,X6S,A
     1 PVCCMCP_CPU1 @BASEBOARD_FAB2_LIB.BASEBOARD_FAB2(SCH_1):PVCCMCP_CPU1   I171 @BASEBOARD_FAB2_LIB.BASEBOARD_FAB2(SCH_1):PAGE76
     2    GND @BASEBOARD_FAB2_LIB.BASEBOARD_FAB2(SCH_1):GND   I171 @BASEBOARD_FAB2_LIB.BASEBOARD_FAB2(SCH_1):PAGE76

C3D15 CAP_A_0603V-22.0UF,4V,20%,X6S,A
     1 PVCCIO_CPU1 @BASEBOARD_FAB2_LIB.BASEBOARD_FAB2(SCH_1):PVCCIO_CPU1   I174 @BASEBOARD_FAB2_LIB.BASEBOARD_FAB2(SCH_1):PAGE76
     2    GND @BASEBOARD_FAB2_LIB.BASEBOARD_FAB2(SCH_1):GND   I174 @BASEBOARD_FAB2_LIB.BASEBOARD_FAB2(SCH_1):PAGE76

C3D16 CAP_A_0603V-22.0UF,4V,20%,X6S,A
     1 PVCCIO_CPU1 @BASEBOARD_FAB2_LIB.BASEBOARD_FAB2(SCH_1):PVCCIO_CPU1   I176 @BASEBOARD_FAB2_LIB.BASEBOARD_FAB2(SCH_1):PAGE76
     2    GND @BASEBOARD_FAB2_LIB.BASEBOARD_FAB2(SCH_1):GND   I176 @BASEBOARD_FAB2_LIB.BASEBOARD_FAB2(SCH_1):PAGE76

C3D17 CAP_A_0603V-22.0UF,4V,20%,X6S,A
     1 PVCCMCP_CPU1 @BASEBOARD_FAB2_LIB.BASEBOARD_FAB2(SCH_1):PVCCMCP_CPU1   I166 @BASEBOARD_FAB2_LIB.BASEBOARD_FAB2(SCH_1):PAGE76
     2    GND @BASEBOARD_FAB2_LIB.BASEBOARD_FAB2(SCH_1):GND   I166 @BASEBOARD_FAB2_LIB.BASEBOARD_FAB2(SCH_1):PAGE76

C3D18 CAP_A_0603V-22.0UF,4V,20%,X6S,A
     1 PVCCMCP_CPU1 @BASEBOARD_FAB2_LIB.BASEBOARD_FAB2(SCH_1):PVCCMCP_CPU1   I169 @BASEBOARD_FAB2_LIB.BASEBOARD_FAB2(SCH_1):PAGE76
     2    GND @BASEBOARD_FAB2_LIB.BASEBOARD_FAB2(SCH_1):GND   I169 @BASEBOARD_FAB2_LIB.BASEBOARD_FAB2(SCH_1):PAGE76

C3D19 CAP_A_0603V-22.0UF,4V,20%,X6S,A
     1 PVCCMCP_CPU1 @BASEBOARD_FAB2_LIB.BASEBOARD_FAB2(SCH_1):PVCCMCP_CPU1   I208 @BASEBOARD_FAB2_LIB.BASEBOARD_FAB2(SCH_1):PAGE76
     2    GND @BASEBOARD_FAB2_LIB.BASEBOARD_FAB2(SCH_1):GND   I208 @BASEBOARD_FAB2_LIB.BASEBOARD_FAB2(SCH_1):PAGE76

C3D20 CAP_A_0603V-22.0UF,4V,20%,X6S,A
     1 PVCCMCP_CPU1 @BASEBOARD_FAB2_LIB.BASEBOARD_FAB2(SCH_1):PVCCMCP_CPU1   I207 @BASEBOARD_FAB2_LIB.BASEBOARD_FAB2(SCH_1):PAGE76
     2    GND @BASEBOARD_FAB2_LIB.BASEBOARD_FAB2(SCH_1):GND   I207 @BASEBOARD_FAB2_LIB.BASEBOARD_FAB2(SCH_1):PAGE76

C3D21 CAP_A_0603V-22.0UF,4V,20%,X6S,A
     1 PVCCMCP_CPU1 @BASEBOARD_FAB2_LIB.BASEBOARD_FAB2(SCH_1):PVCCMCP_CPU1     I1 @BASEBOARD_FAB2_LIB.BASEBOARD_FAB2(SCH_1):PAGE76
     2    GND @BASEBOARD_FAB2_LIB.BASEBOARD_FAB2(SCH_1):GND     I1 @BASEBOARD_FAB2_LIB.BASEBOARD_FAB2(SCH_1):PAGE76

C3D22 CAP_0805-10UF,16V,10%,X7R,G106A
     1 P3V3_DB1200 @BASEBOARD_FAB2_LIB.BASEBOARD_FAB2(SCH_1):P3V3_DB1200    I10 @BASEBOARD_FAB2_LIB.BASEBOARD_FAB2(SCH_1):PAGE102
     2    GND @BASEBOARD_FAB2_LIB.BASEBOARD_FAB2(SCH_1):GND    I10 @BASEBOARD_FAB2_LIB.BASEBOARD_FAB2(SCH_1):PAGE102

C3D23 CAP_A_0603V-22.0UF,4V,20%,X6S,A
     1 PVCCIO_CPU1 @BASEBOARD_FAB2_LIB.BASEBOARD_FAB2(SCH_1):PVCCIO_CPU1   I172 @BASEBOARD_FAB2_LIB.BASEBOARD_FAB2(SCH_1):PAGE76
     2    GND @BASEBOARD_FAB2_LIB.BASEBOARD_FAB2(SCH_1):GND   I172 @BASEBOARD_FAB2_LIB.BASEBOARD_FAB2(SCH_1):PAGE76

C3D24 CAP_A_0603V-22.0UF,4V,20%,X6S,A
     1 PVCCIO_CPU1 @BASEBOARD_FAB2_LIB.BASEBOARD_FAB2(SCH_1):PVCCIO_CPU1   I175 @BASEBOARD_FAB2_LIB.BASEBOARD_FAB2(SCH_1):PAGE76
     2    GND @BASEBOARD_FAB2_LIB.BASEBOARD_FAB2(SCH_1):GND   I175 @BASEBOARD_FAB2_LIB.BASEBOARD_FAB2(SCH_1):PAGE76

C3D25 CAP_A_0603V-22.0UF,4V,20%,X6S,A
     1 PVCCIN_CPU1 @BASEBOARD_FAB2_LIB.BASEBOARD_FAB2(SCH_1):PVCCIN_CPU1   I205 @BASEBOARD_FAB2_LIB.BASEBOARD_FAB2(SCH_1):PAGE76
     2    GND @BASEBOARD_FAB2_LIB.BASEBOARD_FAB2(SCH_1):GND   I205 @BASEBOARD_FAB2_LIB.BASEBOARD_FAB2(SCH_1):PAGE76

C3D27 CAP_A_0402V-0.1UF,16V,10%,EMPTA
     1 VSENSE_PVCCIO_CPU1_SKT_VSEN @BASEBOARD_FAB2_LIB.BASEBOARD_FAB2(SCH_1):VSENSE_PVCCIO_CPU1_SKT_VSEN    I96 @BASEBOARD_FAB2_LIB.BASEBOARD_FAB2(SCH_1):PAGE214
     2 VSENSE_PVCCIO_CPU1_SKT_VRTN @BASEBOARD_FAB2_LIB.BASEBOARD_FAB2(SCH_1):VSENSE_PVCCIO_CPU1_SKT_VRTN    I96 @BASEBOARD_FAB2_LIB.BASEBOARD_FAB2(SCH_1):PAGE214

C3E1 CAP_A_0603V-22.0UF,4V,20%,X6S,A
     1 PVCCIO_CPU1 @BASEBOARD_FAB2_LIB.BASEBOARD_FAB2(SCH_1):PVCCIO_CPU1   I108 @BASEBOARD_FAB2_LIB.BASEBOARD_FAB2(SCH_1):PAGE214
     2    GND @BASEBOARD_FAB2_LIB.BASEBOARD_FAB2(SCH_1):GND   I108 @BASEBOARD_FAB2_LIB.BASEBOARD_FAB2(SCH_1):PAGE214

C3F1 CAP_A_0603V-47UF,4V,20%,X5R,60A
     1 P1V8_MCP_CPU1 @BASEBOARD_FAB2_LIB.BASEBOARD_FAB2(SCH_1):P1V8_MCP_CPU1   I140 @BASEBOARD_FAB2_LIB.BASEBOARD_FAB2(SCH_1):PAGE193
     2    GND @BASEBOARD_FAB2_LIB.BASEBOARD_FAB2(SCH_1):GND   I140 @BASEBOARD_FAB2_LIB.BASEBOARD_FAB2(SCH_1):PAGE193

C3F2 CAP_A_0402V-0.1UF,16V,10%,X7R,A
     1   P3V3 @BASEBOARD_FAB2_LIB.BASEBOARD_FAB2(SCH_1):P3V3    I34 @BASEBOARD_FAB2_LIB.BASEBOARD_FAB2(SCH_1):PAGE104
     2    GND @BASEBOARD_FAB2_LIB.BASEBOARD_FAB2(SCH_1):GND    I34 @BASEBOARD_FAB2_LIB.BASEBOARD_FAB2(SCH_1):PAGE104

C3F3 CAP_0603LF-10UF,4V,20%,X6S,E15A
     1 PVPP_GHJ @BASEBOARD_FAB2_LIB.BASEBOARD_FAB2(SCH_1):PVPP_GHJ   I116 @BASEBOARD_FAB2_LIB.BASEBOARD_FAB2(SCH_1):PAGE233
     2    GND @BASEBOARD_FAB2_LIB.BASEBOARD_FAB2(SCH_1):GND   I116 @BASEBOARD_FAB2_LIB.BASEBOARD_FAB2(SCH_1):PAGE233

C3F4 CAP_0603LF-10UF,4V,20%,X6S,E15A
     1 PVPP_GHJ @BASEBOARD_FAB2_LIB.BASEBOARD_FAB2(SCH_1):PVPP_GHJ   I117 @BASEBOARD_FAB2_LIB.BASEBOARD_FAB2(SCH_1):PAGE233
     2    GND @BASEBOARD_FAB2_LIB.BASEBOARD_FAB2(SCH_1):GND   I117 @BASEBOARD_FAB2_LIB.BASEBOARD_FAB2(SCH_1):PAGE233

C3G1 CAP_A_0603V-22.0UF,4V,20%,X6S,A
     1 PVDDQ_GHJ @BASEBOARD_FAB2_LIB.BASEBOARD_FAB2(SCH_1):PVDDQ_GHJ   I212 @BASEBOARD_FAB2_LIB.BASEBOARD_FAB2(SCH_1):PAGE225
     2    GND @BASEBOARD_FAB2_LIB.BASEBOARD_FAB2(SCH_1):GND   I212 @BASEBOARD_FAB2_LIB.BASEBOARD_FAB2(SCH_1):PAGE225

C3G2 CAP_A_0603V-22.0UF,4V,20%,X6S,A
     1 PVDDQ_GHJ @BASEBOARD_FAB2_LIB.BASEBOARD_FAB2(SCH_1):PVDDQ_GHJ   I211 @BASEBOARD_FAB2_LIB.BASEBOARD_FAB2(SCH_1):PAGE225
     2    GND @BASEBOARD_FAB2_LIB.BASEBOARD_FAB2(SCH_1):GND   I211 @BASEBOARD_FAB2_LIB.BASEBOARD_FAB2(SCH_1):PAGE225

C3G3 CAP_0603LF-10UF,4V,20%,X6S,E15A
     1 PVPP_GHJ @BASEBOARD_FAB2_LIB.BASEBOARD_FAB2(SCH_1):PVPP_GHJ   I118 @BASEBOARD_FAB2_LIB.BASEBOARD_FAB2(SCH_1):PAGE233
     2    GND @BASEBOARD_FAB2_LIB.BASEBOARD_FAB2(SCH_1):GND   I118 @BASEBOARD_FAB2_LIB.BASEBOARD_FAB2(SCH_1):PAGE233

C3G4 CAP_0603LF-10UF,4V,20%,X6S,E15A
     1 PVPP_GHJ @BASEBOARD_FAB2_LIB.BASEBOARD_FAB2(SCH_1):PVPP_GHJ   I133 @BASEBOARD_FAB2_LIB.BASEBOARD_FAB2(SCH_1):PAGE233
     2    GND @BASEBOARD_FAB2_LIB.BASEBOARD_FAB2(SCH_1):GND   I133 @BASEBOARD_FAB2_LIB.BASEBOARD_FAB2(SCH_1):PAGE233

C3G5 CAP_A_0603V-22.0UF,4V,20%,X6S,A
     1 PVDDQ_GHJ @BASEBOARD_FAB2_LIB.BASEBOARD_FAB2(SCH_1):PVDDQ_GHJ   I208 @BASEBOARD_FAB2_LIB.BASEBOARD_FAB2(SCH_1):PAGE225
     2    GND @BASEBOARD_FAB2_LIB.BASEBOARD_FAB2(SCH_1):GND   I208 @BASEBOARD_FAB2_LIB.BASEBOARD_FAB2(SCH_1):PAGE225

C3G6 CAP_A_0603V-22.0UF,4V,20%,X6S,A
     1 PVDDQ_GHJ @BASEBOARD_FAB2_LIB.BASEBOARD_FAB2(SCH_1):PVDDQ_GHJ   I207 @BASEBOARD_FAB2_LIB.BASEBOARD_FAB2(SCH_1):PAGE225
     2    GND @BASEBOARD_FAB2_LIB.BASEBOARD_FAB2(SCH_1):GND   I207 @BASEBOARD_FAB2_LIB.BASEBOARD_FAB2(SCH_1):PAGE225

C3G7 CAP_0603LF-10UF,4V,20%,X6S,E15A
     1 PVPP_GHJ @BASEBOARD_FAB2_LIB.BASEBOARD_FAB2(SCH_1):PVPP_GHJ   I132 @BASEBOARD_FAB2_LIB.BASEBOARD_FAB2(SCH_1):PAGE233
     2    GND @BASEBOARD_FAB2_LIB.BASEBOARD_FAB2(SCH_1):GND   I132 @BASEBOARD_FAB2_LIB.BASEBOARD_FAB2(SCH_1):PAGE233

C3G8 CAP_0603LF-10UF,4V,20%,X6S,E15A
     1 PVPP_GHJ @BASEBOARD_FAB2_LIB.BASEBOARD_FAB2(SCH_1):PVPP_GHJ   I135 @BASEBOARD_FAB2_LIB.BASEBOARD_FAB2(SCH_1):PAGE233
     2    GND @BASEBOARD_FAB2_LIB.BASEBOARD_FAB2(SCH_1):GND   I135 @BASEBOARD_FAB2_LIB.BASEBOARD_FAB2(SCH_1):PAGE233

C3L1 CAP_A_0402V-1.0UF,6.3V,10%,X6SA
     1 P5V_STBY @BASEBOARD_FAB2_LIB.BASEBOARD_FAB2(SCH_1):P5V_STBY    I17 @BASEBOARD_FAB2_LIB.BASEBOARD_FAB2(SCH_1):PAGE236
     2    GND @BASEBOARD_FAB2_LIB.BASEBOARD_FAB2(SCH_1):GND    I17 @BASEBOARD_FAB2_LIB.BASEBOARD_FAB2(SCH_1):PAGE236

C3L2 CAP_0805-10UF,16V,10%,X6S,C953A
     1 VR_FET_SW_P12V_STBY_PVDDQ_DEF @BASEBOARD_FAB2_LIB.BASEBOARD_FAB2(SCH_1):VR_FET_SW_P12V_STBY_PVDDQ_DEF    I45 @BASEBOARD_FAB2_LIB.BASEBOARD_FAB2(SCH_1):PAGE219
     2    GND @BASEBOARD_FAB2_LIB.BASEBOARD_FAB2(SCH_1):GND    I45 @BASEBOARD_FAB2_LIB.BASEBOARD_FAB2(SCH_1):PAGE219

C3L4 CAP_0805-10UF,16V,10%,X6S,C953A
     1 VR_FET_SW_P12V_STBY_PVDDQ_DEF @BASEBOARD_FAB2_LIB.BASEBOARD_FAB2(SCH_1):VR_FET_SW_P12V_STBY_PVDDQ_DEF    I46 @BASEBOARD_FAB2_LIB.BASEBOARD_FAB2(SCH_1):PAGE219
     2    GND @BASEBOARD_FAB2_LIB.BASEBOARD_FAB2(SCH_1):GND    I46 @BASEBOARD_FAB2_LIB.BASEBOARD_FAB2(SCH_1):PAGE219

C3L6 CAPP_3018-470UF,2.5V,20%,ALUM,A
     1 PVDDQ_DEF @BASEBOARD_FAB2_LIB.BASEBOARD_FAB2(SCH_1):PVDDQ_DEF    I75 @BASEBOARD_FAB2_LIB.BASEBOARD_FAB2(SCH_1):PAGE220
     2    GND @BASEBOARD_FAB2_LIB.BASEBOARD_FAB2(SCH_1):GND    I75 @BASEBOARD_FAB2_LIB.BASEBOARD_FAB2(SCH_1):PAGE220

C3L7 CAP_0805-10UF,16V,10%,X6S,C953A
     1 VR_FET_SW_P12V_STBY_PVDDQ_DEF @BASEBOARD_FAB2_LIB.BASEBOARD_FAB2(SCH_1):VR_FET_SW_P12V_STBY_PVDDQ_DEF    I31 @BASEBOARD_FAB2_LIB.BASEBOARD_FAB2(SCH_1):PAGE236
     2    GND @BASEBOARD_FAB2_LIB.BASEBOARD_FAB2(SCH_1):GND    I31 @BASEBOARD_FAB2_LIB.BASEBOARD_FAB2(SCH_1):PAGE236

C3L8 CAP_0805-10UF,16V,10%,X6S,C953A
     1 VR_FET_SW_P12V_STBY_PVDDQ_DEF @BASEBOARD_FAB2_LIB.BASEBOARD_FAB2(SCH_1):VR_FET_SW_P12V_STBY_PVDDQ_DEF    I26 @BASEBOARD_FAB2_LIB.BASEBOARD_FAB2(SCH_1):PAGE236
     2    GND @BASEBOARD_FAB2_LIB.BASEBOARD_FAB2(SCH_1):GND    I26 @BASEBOARD_FAB2_LIB.BASEBOARD_FAB2(SCH_1):PAGE236

C3L9 CAP_0805-10UF,16V,10%,X6S,C953A
     1 VR_FET_SW_P12V_STBY_PVDDQ_DEF @BASEBOARD_FAB2_LIB.BASEBOARD_FAB2(SCH_1):VR_FET_SW_P12V_STBY_PVDDQ_DEF    I29 @BASEBOARD_FAB2_LIB.BASEBOARD_FAB2(SCH_1):PAGE236
     2    GND @BASEBOARD_FAB2_LIB.BASEBOARD_FAB2(SCH_1):GND    I29 @BASEBOARD_FAB2_LIB.BASEBOARD_FAB2(SCH_1):PAGE236

C3L10 CAP_0805-10UF,16V,10%,X6S,C953A
     1 VR_FET_SW_P12V_STBY_PVDDQ_DEF @BASEBOARD_FAB2_LIB.BASEBOARD_FAB2(SCH_1):VR_FET_SW_P12V_STBY_PVDDQ_DEF    I32 @BASEBOARD_FAB2_LIB.BASEBOARD_FAB2(SCH_1):PAGE236
     2    GND @BASEBOARD_FAB2_LIB.BASEBOARD_FAB2(SCH_1):GND    I32 @BASEBOARD_FAB2_LIB.BASEBOARD_FAB2(SCH_1):PAGE236

C3L11 CAP_0805-10UF,16V,10%,X6S,C953A
     1 VR_FET_SW_P12V_STBY_PVDDQ_DEF @BASEBOARD_FAB2_LIB.BASEBOARD_FAB2(SCH_1):VR_FET_SW_P12V_STBY_PVDDQ_DEF    I24 @BASEBOARD_FAB2_LIB.BASEBOARD_FAB2(SCH_1):PAGE236
     2    GND @BASEBOARD_FAB2_LIB.BASEBOARD_FAB2(SCH_1):GND    I24 @BASEBOARD_FAB2_LIB.BASEBOARD_FAB2(SCH_1):PAGE236

C3L12 CAP_0805-10UF,16V,10%,X6S,C953A
     1 VR_FET_SW_P12V_STBY_PVDDQ_DEF @BASEBOARD_FAB2_LIB.BASEBOARD_FAB2(SCH_1):VR_FET_SW_P12V_STBY_PVDDQ_DEF    I23 @BASEBOARD_FAB2_LIB.BASEBOARD_FAB2(SCH_1):PAGE236
     2    GND @BASEBOARD_FAB2_LIB.BASEBOARD_FAB2(SCH_1):GND    I23 @BASEBOARD_FAB2_LIB.BASEBOARD_FAB2(SCH_1):PAGE236

C3L13 CAP_0805-10UF,16V,10%,X6S,C953A
     1 VR_FET_SW_P12V_STBY_PVDDQ_DEF @BASEBOARD_FAB2_LIB.BASEBOARD_FAB2(SCH_1):VR_FET_SW_P12V_STBY_PVDDQ_DEF    I47 @BASEBOARD_FAB2_LIB.BASEBOARD_FAB2(SCH_1):PAGE219
     2    GND @BASEBOARD_FAB2_LIB.BASEBOARD_FAB2(SCH_1):GND    I47 @BASEBOARD_FAB2_LIB.BASEBOARD_FAB2(SCH_1):PAGE219

C3L14 CAPP_3018-470UF,2.5V,20%,ALUM,A
     1 PVDDQ_DEF @BASEBOARD_FAB2_LIB.BASEBOARD_FAB2(SCH_1):PVDDQ_DEF    I76 @BASEBOARD_FAB2_LIB.BASEBOARD_FAB2(SCH_1):PAGE220
     2    GND @BASEBOARD_FAB2_LIB.BASEBOARD_FAB2(SCH_1):GND    I76 @BASEBOARD_FAB2_LIB.BASEBOARD_FAB2(SCH_1):PAGE220

C3L15 CAP_0805-10UF,16V,10%,X6S,C953A
     1 VR_FET_SW_P12V_STBY_PVDDQ_DEF @BASEBOARD_FAB2_LIB.BASEBOARD_FAB2(SCH_1):VR_FET_SW_P12V_STBY_PVDDQ_DEF    I84 @BASEBOARD_FAB2_LIB.BASEBOARD_FAB2(SCH_1):PAGE219
     2    GND @BASEBOARD_FAB2_LIB.BASEBOARD_FAB2(SCH_1):GND    I84 @BASEBOARD_FAB2_LIB.BASEBOARD_FAB2(SCH_1):PAGE219

C3L16 CAP_0805-10UF,16V,10%,X6S,C953A
     1 VR_FET_SW_P12V_STBY_PVDDQ_DEF @BASEBOARD_FAB2_LIB.BASEBOARD_FAB2(SCH_1):VR_FET_SW_P12V_STBY_PVDDQ_DEF    I81 @BASEBOARD_FAB2_LIB.BASEBOARD_FAB2(SCH_1):PAGE219
     2    GND @BASEBOARD_FAB2_LIB.BASEBOARD_FAB2(SCH_1):GND    I81 @BASEBOARD_FAB2_LIB.BASEBOARD_FAB2(SCH_1):PAGE219

C3L17 CAP_0805-10UF,16V,10%,X6S,C953A
     1 VR_FET_SW_P12V_STBY_PVDDQ_DEF @BASEBOARD_FAB2_LIB.BASEBOARD_FAB2(SCH_1):VR_FET_SW_P12V_STBY_PVDDQ_DEF    I80 @BASEBOARD_FAB2_LIB.BASEBOARD_FAB2(SCH_1):PAGE219
     2    GND @BASEBOARD_FAB2_LIB.BASEBOARD_FAB2(SCH_1):GND    I80 @BASEBOARD_FAB2_LIB.BASEBOARD_FAB2(SCH_1):PAGE219

C3L18 CAPP_SM-470UF,2V,20%,ALUM,6990A
     1 PVNN_PCH_STBY @BASEBOARD_FAB2_LIB.BASEBOARD_FAB2(SCH_1):PVNN_PCH_STBY    I71 @BASEBOARD_FAB2_LIB.BASEBOARD_FAB2(SCH_1):PAGE236
     2    GND @BASEBOARD_FAB2_LIB.BASEBOARD_FAB2(SCH_1):GND    I71 @BASEBOARD_FAB2_LIB.BASEBOARD_FAB2(SCH_1):PAGE236

C3L19 CAPP_SM-470UF,2V,20%,ALUM,6990A
     1 P1V05_PCH_STBY @BASEBOARD_FAB2_LIB.BASEBOARD_FAB2(SCH_1):P1V05_PCH_STBY    I76 @BASEBOARD_FAB2_LIB.BASEBOARD_FAB2(SCH_1):PAGE236
     2    GND @BASEBOARD_FAB2_LIB.BASEBOARD_FAB2(SCH_1):GND    I76 @BASEBOARD_FAB2_LIB.BASEBOARD_FAB2(SCH_1):PAGE236

C3L20 CAPP_SM-470UF,2V,20%,ALUM,6990A
     1 PVNN_PCH_STBY @BASEBOARD_FAB2_LIB.BASEBOARD_FAB2(SCH_1):PVNN_PCH_STBY    I73 @BASEBOARD_FAB2_LIB.BASEBOARD_FAB2(SCH_1):PAGE236
     2    GND @BASEBOARD_FAB2_LIB.BASEBOARD_FAB2(SCH_1):GND    I73 @BASEBOARD_FAB2_LIB.BASEBOARD_FAB2(SCH_1):PAGE236

C3L21 CAPP_SM-470UF,2V,20%,ALUM,6990A
     1 PVNN_PCH_STBY @BASEBOARD_FAB2_LIB.BASEBOARD_FAB2(SCH_1):PVNN_PCH_STBY    I74 @BASEBOARD_FAB2_LIB.BASEBOARD_FAB2(SCH_1):PAGE236
     2    GND @BASEBOARD_FAB2_LIB.BASEBOARD_FAB2(SCH_1):GND    I74 @BASEBOARD_FAB2_LIB.BASEBOARD_FAB2(SCH_1):PAGE236

C3L22 CAP_A_0603V-22.0UF,4V,20%,X6S,A
     1 PVNN_PCH_STBY @BASEBOARD_FAB2_LIB.BASEBOARD_FAB2(SCH_1):PVNN_PCH_STBY    I54 @BASEBOARD_FAB2_LIB.BASEBOARD_FAB2(SCH_1):PAGE132
     2    GND @BASEBOARD_FAB2_LIB.BASEBOARD_FAB2(SCH_1):GND    I54 @BASEBOARD_FAB2_LIB.BASEBOARD_FAB2(SCH_1):PAGE132

C3L23 CAP_A_0603V-22.0UF,4V,20%,X6S,A
     1 PVNN_PCH_STBY @BASEBOARD_FAB2_LIB.BASEBOARD_FAB2(SCH_1):PVNN_PCH_STBY    I52 @BASEBOARD_FAB2_LIB.BASEBOARD_FAB2(SCH_1):PAGE132
     2    GND @BASEBOARD_FAB2_LIB.BASEBOARD_FAB2(SCH_1):GND    I52 @BASEBOARD_FAB2_LIB.BASEBOARD_FAB2(SCH_1):PAGE132

C3L24 CAP_A_0603V-22.0UF,4V,20%,X6S,A
     1 PVNN_PCH_STBY @BASEBOARD_FAB2_LIB.BASEBOARD_FAB2(SCH_1):PVNN_PCH_STBY    I56 @BASEBOARD_FAB2_LIB.BASEBOARD_FAB2(SCH_1):PAGE132
     2    GND @BASEBOARD_FAB2_LIB.BASEBOARD_FAB2(SCH_1):GND    I56 @BASEBOARD_FAB2_LIB.BASEBOARD_FAB2(SCH_1):PAGE132

C3L25 CAP_A_0603V-22.0UF,4V,20%,X6S,A
     1 PVNN_PCH_STBY @BASEBOARD_FAB2_LIB.BASEBOARD_FAB2(SCH_1):PVNN_PCH_STBY     I1 @BASEBOARD_FAB2_LIB.BASEBOARD_FAB2(SCH_1):PAGE132
     2    GND @BASEBOARD_FAB2_LIB.BASEBOARD_FAB2(SCH_1):GND     I1 @BASEBOARD_FAB2_LIB.BASEBOARD_FAB2(SCH_1):PAGE132

C3L26 CAP_A_0603V-22.0UF,4V,20%,X6S,A
     1 PVNN_PCH_STBY @BASEBOARD_FAB2_LIB.BASEBOARD_FAB2(SCH_1):PVNN_PCH_STBY     I3 @BASEBOARD_FAB2_LIB.BASEBOARD_FAB2(SCH_1):PAGE132
     2    GND @BASEBOARD_FAB2_LIB.BASEBOARD_FAB2(SCH_1):GND     I3 @BASEBOARD_FAB2_LIB.BASEBOARD_FAB2(SCH_1):PAGE132

C3L27 CAP_A_0603V-22.0UF,4V,20%,X6S,A
     1 PVNN_PCH_STBY @BASEBOARD_FAB2_LIB.BASEBOARD_FAB2(SCH_1):PVNN_PCH_STBY     I4 @BASEBOARD_FAB2_LIB.BASEBOARD_FAB2(SCH_1):PAGE132
     2    GND @BASEBOARD_FAB2_LIB.BASEBOARD_FAB2(SCH_1):GND     I4 @BASEBOARD_FAB2_LIB.BASEBOARD_FAB2(SCH_1):PAGE132

C3L29 CAP_A_0402V-1.0UF,6.3V,10%,X6SA
     1 P5V_STBY @BASEBOARD_FAB2_LIB.BASEBOARD_FAB2(SCH_1):P5V_STBY    I38 @BASEBOARD_FAB2_LIB.BASEBOARD_FAB2(SCH_1):PAGE236
     2    GND @BASEBOARD_FAB2_LIB.BASEBOARD_FAB2(SCH_1):GND    I38 @BASEBOARD_FAB2_LIB.BASEBOARD_FAB2(SCH_1):PAGE236

C3L31 CAP_A_0402V-0.1UF,16V,10%,X7R,A
     1 VR_PVDDQ_DEF_AIINSEN @BASEBOARD_FAB2_LIB.BASEBOARD_FAB2(SCH_1):VR_PVDDQ_DEF_AIINSEN    I77 @BASEBOARD_FAB2_LIB.BASEBOARD_FAB2(SCH_1):PAGE218
     2    GND @BASEBOARD_FAB2_LIB.BASEBOARD_FAB2(SCH_1):GND    I77 @BASEBOARD_FAB2_LIB.BASEBOARD_FAB2(SCH_1):PAGE218

C3M1 CAP_0402-0.22UF,16V,10%,X7R,A3A
     1 P3E_CPU0_PE1_PCH_R_RXN<15> @BASEBOARD_FAB2_LIB.BASEBOARD_FAB2(SCH_1):P3E_CPU0_PE1_PCH_R_RXN(15)   I255 @BASEBOARD_FAB2_LIB.BASEBOARD_FAB2(SCH_1):PAGE105
     2 P3E_CPU0_PE1_PCH_RXN<15> @BASEBOARD_FAB2_LIB.BASEBOARD_FAB2(SCH_1):P3E_CPU0_PE1_PCH_RXN(15)   I255 @BASEBOARD_FAB2_LIB.BASEBOARD_FAB2(SCH_1):PAGE105

C3M2 CAP_0402-0.22UF,16V,10%,X7R,A3A
     1 P3E_CPU0_PE1_PCH_R_RXP<15> @BASEBOARD_FAB2_LIB.BASEBOARD_FAB2(SCH_1):P3E_CPU0_PE1_PCH_R_RXP(15)   I247 @BASEBOARD_FAB2_LIB.BASEBOARD_FAB2(SCH_1):PAGE105
     2 P3E_CPU0_PE1_PCH_RXP<15> @BASEBOARD_FAB2_LIB.BASEBOARD_FAB2(SCH_1):P3E_CPU0_PE1_PCH_RXP(15)   I247 @BASEBOARD_FAB2_LIB.BASEBOARD_FAB2(SCH_1):PAGE105

C3M3 CAP_0402-0.22UF,16V,10%,X7R,A3A
     1 P3E_CPU0_PE1_PCH_R_RXP<12> @BASEBOARD_FAB2_LIB.BASEBOARD_FAB2(SCH_1):P3E_CPU0_PE1_PCH_R_RXP(12)   I232 @BASEBOARD_FAB2_LIB.BASEBOARD_FAB2(SCH_1):PAGE105
     2 P3E_CPU0_PE1_PCH_RXP<12> @BASEBOARD_FAB2_LIB.BASEBOARD_FAB2(SCH_1):P3E_CPU0_PE1_PCH_RXP(12)   I232 @BASEBOARD_FAB2_LIB.BASEBOARD_FAB2(SCH_1):PAGE105

C3M4 CAP_0402-0.22UF,16V,10%,X7R,A3A
     1 P3E_CPU0_PE1_PCH_R_RXN<12> @BASEBOARD_FAB2_LIB.BASEBOARD_FAB2(SCH_1):P3E_CPU0_PE1_PCH_R_RXN(12)   I244 @BASEBOARD_FAB2_LIB.BASEBOARD_FAB2(SCH_1):PAGE105
     2 P3E_CPU0_PE1_PCH_RXN<12> @BASEBOARD_FAB2_LIB.BASEBOARD_FAB2(SCH_1):P3E_CPU0_PE1_PCH_RXN(12)   I244 @BASEBOARD_FAB2_LIB.BASEBOARD_FAB2(SCH_1):PAGE105

C3M6 CAP_A_0603V-22.0UF,4V,20%,X6S,A
     1 PVNN_PCH_STBY @BASEBOARD_FAB2_LIB.BASEBOARD_FAB2(SCH_1):PVNN_PCH_STBY     I6 @BASEBOARD_FAB2_LIB.BASEBOARD_FAB2(SCH_1):PAGE132
     2    GND @BASEBOARD_FAB2_LIB.BASEBOARD_FAB2(SCH_1):GND     I6 @BASEBOARD_FAB2_LIB.BASEBOARD_FAB2(SCH_1):PAGE132

C3M7 CAP_A_0603V-22.0UF,4V,20%,X6S,A
     1 PVNN_PCH_STBY @BASEBOARD_FAB2_LIB.BASEBOARD_FAB2(SCH_1):PVNN_PCH_STBY     I2 @BASEBOARD_FAB2_LIB.BASEBOARD_FAB2(SCH_1):PAGE132
     2    GND @BASEBOARD_FAB2_LIB.BASEBOARD_FAB2(SCH_1):GND     I2 @BASEBOARD_FAB2_LIB.BASEBOARD_FAB2(SCH_1):PAGE132

C3M8 CAP_0805-10UF,16V,10%,X6S,C953A
     1 VR_FET_SW_P12V_STBY_PVPP_DEF @BASEBOARD_FAB2_LIB.BASEBOARD_FAB2(SCH_1):VR_FET_SW_P12V_STBY_PVPP_DEF   I259 @BASEBOARD_FAB2_LIB.BASEBOARD_FAB2(SCH_1):PAGE232
     2    GND @BASEBOARD_FAB2_LIB.BASEBOARD_FAB2(SCH_1):GND   I259 @BASEBOARD_FAB2_LIB.BASEBOARD_FAB2(SCH_1):PAGE232

C3M9 CAP_0402-1.0UF,16V,10%,X6S,D97A
     1 VR_FET_SW_P12V_STBY_PVPP_DEF @BASEBOARD_FAB2_LIB.BASEBOARD_FAB2(SCH_1):VR_FET_SW_P12V_STBY_PVPP_DEF   I207 @BASEBOARD_FAB2_LIB.BASEBOARD_FAB2(SCH_1):PAGE232
     2    GND @BASEBOARD_FAB2_LIB.BASEBOARD_FAB2(SCH_1):GND   I207 @BASEBOARD_FAB2_LIB.BASEBOARD_FAB2(SCH_1):PAGE232

C3M10 CAP_0603-4.7UF,6.3V,10%,X6S,E1A
     1 VR_VB_PVPP_DEF @BASEBOARD_FAB2_LIB.BASEBOARD_FAB2(SCH_1):VR_VB_PVPP_DEF   I253 @BASEBOARD_FAB2_LIB.BASEBOARD_FAB2(SCH_1):PAGE232
     2 AGND_PVPP_DEF @BASEBOARD_FAB2_LIB.BASEBOARD_FAB2(SCH_1):AGND_PVPP_DEF   I253 @BASEBOARD_FAB2_LIB.BASEBOARD_FAB2(SCH_1):PAGE232

C3M11 CAP_0402-0.22UF,16V,10%,X7R,A3A
     1 P3E_CPU0_PE1_PCH_R_RXP<14> @BASEBOARD_FAB2_LIB.BASEBOARD_FAB2(SCH_1):P3E_CPU0_PE1_PCH_R_RXP(14)   I234 @BASEBOARD_FAB2_LIB.BASEBOARD_FAB2(SCH_1):PAGE105
     2 P3E_CPU0_PE1_PCH_RXP<14> @BASEBOARD_FAB2_LIB.BASEBOARD_FAB2(SCH_1):P3E_CPU0_PE1_PCH_RXP(14)   I234 @BASEBOARD_FAB2_LIB.BASEBOARD_FAB2(SCH_1):PAGE105

C3M12 CAP_0402-0.22UF,16V,10%,X7R,A3A
     1 P3E_CPU0_PE1_PCH_R_RXN<14> @BASEBOARD_FAB2_LIB.BASEBOARD_FAB2(SCH_1):P3E_CPU0_PE1_PCH_R_RXN(14)   I246 @BASEBOARD_FAB2_LIB.BASEBOARD_FAB2(SCH_1):PAGE105
     2 P3E_CPU0_PE1_PCH_RXN<14> @BASEBOARD_FAB2_LIB.BASEBOARD_FAB2(SCH_1):P3E_CPU0_PE1_PCH_RXN(14)   I246 @BASEBOARD_FAB2_LIB.BASEBOARD_FAB2(SCH_1):PAGE105

C3M13 CAP_0402-0.22UF,16V,10%,X7R,A3A
     1 P3E_CPU0_PE1_PCH_R_RXP<13> @BASEBOARD_FAB2_LIB.BASEBOARD_FAB2(SCH_1):P3E_CPU0_PE1_PCH_R_RXP(13)   I239 @BASEBOARD_FAB2_LIB.BASEBOARD_FAB2(SCH_1):PAGE105
     2 P3E_CPU0_PE1_PCH_RXP<13> @BASEBOARD_FAB2_LIB.BASEBOARD_FAB2(SCH_1):P3E_CPU0_PE1_PCH_RXP(13)   I239 @BASEBOARD_FAB2_LIB.BASEBOARD_FAB2(SCH_1):PAGE105

C3M14 CAP_0402-0.22UF,16V,10%,X7R,A3A
     1 P3E_CPU0_PE1_PCH_R_RXN<13> @BASEBOARD_FAB2_LIB.BASEBOARD_FAB2(SCH_1):P3E_CPU0_PE1_PCH_R_RXN(13)   I253 @BASEBOARD_FAB2_LIB.BASEBOARD_FAB2(SCH_1):PAGE105
     2 P3E_CPU0_PE1_PCH_RXN<13> @BASEBOARD_FAB2_LIB.BASEBOARD_FAB2(SCH_1):P3E_CPU0_PE1_PCH_RXN(13)   I253 @BASEBOARD_FAB2_LIB.BASEBOARD_FAB2(SCH_1):PAGE105

C3M15 CAP_0805-10UF,16V,10%,X6S,C953A
     1 VR_FET_SW_P12V_STBY_PVPP_DEF @BASEBOARD_FAB2_LIB.BASEBOARD_FAB2(SCH_1):VR_FET_SW_P12V_STBY_PVPP_DEF   I260 @BASEBOARD_FAB2_LIB.BASEBOARD_FAB2(SCH_1):PAGE232
     2    GND @BASEBOARD_FAB2_LIB.BASEBOARD_FAB2(SCH_1):GND   I260 @BASEBOARD_FAB2_LIB.BASEBOARD_FAB2(SCH_1):PAGE232

C3M16 CAP_0805-10UF,16V,10%,X6S,C953A
     1 VR_FET_SW_P12V_STBY_PVPP_DEF @BASEBOARD_FAB2_LIB.BASEBOARD_FAB2(SCH_1):VR_FET_SW_P12V_STBY_PVPP_DEF   I261 @BASEBOARD_FAB2_LIB.BASEBOARD_FAB2(SCH_1):PAGE232
     2    GND @BASEBOARD_FAB2_LIB.BASEBOARD_FAB2(SCH_1):GND   I261 @BASEBOARD_FAB2_LIB.BASEBOARD_FAB2(SCH_1):PAGE232

C3M17 CAP_0603LF-10UF,4V,20%,X6S,E15A
     1 P1V05_PCH_STBY_VCCA_PLL1 @BASEBOARD_FAB2_LIB.BASEBOARD_FAB2(SCH_1):P1V05_PCH_STBY_VCCA_PLL1    I86 @BASEBOARD_FAB2_LIB.BASEBOARD_FAB2(SCH_1):PAGE127
     2    GND @BASEBOARD_FAB2_LIB.BASEBOARD_FAB2(SCH_1):GND    I86 @BASEBOARD_FAB2_LIB.BASEBOARD_FAB2(SCH_1):PAGE127

C3M18 CAP_0603LF-10UF,4V,20%,X6S,E15A
     1 P1V05_PCH_STBY_VCCA_PLL0 @BASEBOARD_FAB2_LIB.BASEBOARD_FAB2(SCH_1):P1V05_PCH_STBY_VCCA_PLL0    I85 @BASEBOARD_FAB2_LIB.BASEBOARD_FAB2(SCH_1):PAGE127
     2    GND @BASEBOARD_FAB2_LIB.BASEBOARD_FAB2(SCH_1):GND    I85 @BASEBOARD_FAB2_LIB.BASEBOARD_FAB2(SCH_1):PAGE127

C3M19 CAP_A_0402V-1.0UF,6.3V,10%,X6SA
     1 P1V05_PCH_STBY_VCCA_PLL1 @BASEBOARD_FAB2_LIB.BASEBOARD_FAB2(SCH_1):P1V05_PCH_STBY_VCCA_PLL1    I87 @BASEBOARD_FAB2_LIB.BASEBOARD_FAB2(SCH_1):PAGE127
     2    GND @BASEBOARD_FAB2_LIB.BASEBOARD_FAB2(SCH_1):GND    I87 @BASEBOARD_FAB2_LIB.BASEBOARD_FAB2(SCH_1):PAGE127

C3M20 CAP_A_0402V-1.0UF,6.3V,10%,X6SA
     1 P1V05_PCH_STBY_VCCA_PLL0 @BASEBOARD_FAB2_LIB.BASEBOARD_FAB2(SCH_1):P1V05_PCH_STBY_VCCA_PLL0    I84 @BASEBOARD_FAB2_LIB.BASEBOARD_FAB2(SCH_1):PAGE127
     2    GND @BASEBOARD_FAB2_LIB.BASEBOARD_FAB2(SCH_1):GND    I84 @BASEBOARD_FAB2_LIB.BASEBOARD_FAB2(SCH_1):PAGE127

C3M21 CAP_A_0402V-1.0UF,6.3V,10%,X6SA
     1 P1V05_PCH_STBY @BASEBOARD_FAB2_LIB.BASEBOARD_FAB2(SCH_1):P1V05_PCH_STBY     I9 @BASEBOARD_FAB2_LIB.BASEBOARD_FAB2(SCH_1):PAGE127
     2    GND @BASEBOARD_FAB2_LIB.BASEBOARD_FAB2(SCH_1):GND     I9 @BASEBOARD_FAB2_LIB.BASEBOARD_FAB2(SCH_1):PAGE127

C3M22 CAP_A_0402V-1.0UF,6.3V,10%,X6SA
     1 P1V05_PCH_STBY @BASEBOARD_FAB2_LIB.BASEBOARD_FAB2(SCH_1):P1V05_PCH_STBY    I18 @BASEBOARD_FAB2_LIB.BASEBOARD_FAB2(SCH_1):PAGE127
     2    GND @BASEBOARD_FAB2_LIB.BASEBOARD_FAB2(SCH_1):GND    I18 @BASEBOARD_FAB2_LIB.BASEBOARD_FAB2(SCH_1):PAGE127

C3M23 CAP_0603LF-10UF,4V,20%,X6S,E15A
     1 P1V05_PCH_STBY_VCCA_XTAL @BASEBOARD_FAB2_LIB.BASEBOARD_FAB2(SCH_1):P1V05_PCH_STBY_VCCA_XTAL    I82 @BASEBOARD_FAB2_LIB.BASEBOARD_FAB2(SCH_1):PAGE127
     2    GND @BASEBOARD_FAB2_LIB.BASEBOARD_FAB2(SCH_1):GND    I82 @BASEBOARD_FAB2_LIB.BASEBOARD_FAB2(SCH_1):PAGE127

C3M24 CAP_0603LF-10UF,4V,20%,X6S,E15A
     1 P1V05_PCH_STBY_ISCLK_PLL @BASEBOARD_FAB2_LIB.BASEBOARD_FAB2(SCH_1):P1V05_PCH_STBY_ISCLK_PLL    I81 @BASEBOARD_FAB2_LIB.BASEBOARD_FAB2(SCH_1):PAGE127
     2    GND @BASEBOARD_FAB2_LIB.BASEBOARD_FAB2(SCH_1):GND    I81 @BASEBOARD_FAB2_LIB.BASEBOARD_FAB2(SCH_1):PAGE127

C3M25 CAP_0402-0.22UF,16V,10%,X7R,A3A
     1 P3E_CPU0_PE1_PCH_R_RXP<11> @BASEBOARD_FAB2_LIB.BASEBOARD_FAB2(SCH_1):P3E_CPU0_PE1_PCH_R_RXP(11)   I205 @BASEBOARD_FAB2_LIB.BASEBOARD_FAB2(SCH_1):PAGE105
     2 P3E_CPU0_PE1_PCH_RXP<11> @BASEBOARD_FAB2_LIB.BASEBOARD_FAB2(SCH_1):P3E_CPU0_PE1_PCH_RXP(11)   I205 @BASEBOARD_FAB2_LIB.BASEBOARD_FAB2(SCH_1):PAGE105

C3M26 CAP_0402-0.22UF,16V,10%,X7R,A3A
     1 P3E_CPU0_PE1_PCH_R_RXN<11> @BASEBOARD_FAB2_LIB.BASEBOARD_FAB2(SCH_1):P3E_CPU0_PE1_PCH_R_RXN(11)   I229 @BASEBOARD_FAB2_LIB.BASEBOARD_FAB2(SCH_1):PAGE105
     2 P3E_CPU0_PE1_PCH_RXN<11> @BASEBOARD_FAB2_LIB.BASEBOARD_FAB2(SCH_1):P3E_CPU0_PE1_PCH_RXN(11)   I229 @BASEBOARD_FAB2_LIB.BASEBOARD_FAB2(SCH_1):PAGE105

C3M27 CAP_A_0402V-1.0UF,6.3V,10%,X6SA
     1 P1V05_PCH_STBY_VCCA_XTAL @BASEBOARD_FAB2_LIB.BASEBOARD_FAB2(SCH_1):P1V05_PCH_STBY_VCCA_XTAL    I83 @BASEBOARD_FAB2_LIB.BASEBOARD_FAB2(SCH_1):PAGE127
     2    GND @BASEBOARD_FAB2_LIB.BASEBOARD_FAB2(SCH_1):GND    I83 @BASEBOARD_FAB2_LIB.BASEBOARD_FAB2(SCH_1):PAGE127

C3M28 CAP_0402-0.22UF,16V,10%,X7R,A3A
     1 P3E_CPU0_PE1_PCH_R_RXP<10> @BASEBOARD_FAB2_LIB.BASEBOARD_FAB2(SCH_1):P3E_CPU0_PE1_PCH_R_RXP(10)   I212 @BASEBOARD_FAB2_LIB.BASEBOARD_FAB2(SCH_1):PAGE105
     2 P3E_CPU0_PE1_PCH_RXP<10> @BASEBOARD_FAB2_LIB.BASEBOARD_FAB2(SCH_1):P3E_CPU0_PE1_PCH_RXP(10)   I212 @BASEBOARD_FAB2_LIB.BASEBOARD_FAB2(SCH_1):PAGE105

C3M29 CAP_A_0402V-1.0UF,6.3V,10%,X6SA
     1 P1V05_PCH_STBY_ISCLK_PLL @BASEBOARD_FAB2_LIB.BASEBOARD_FAB2(SCH_1):P1V05_PCH_STBY_ISCLK_PLL    I80 @BASEBOARD_FAB2_LIB.BASEBOARD_FAB2(SCH_1):PAGE127
     2    GND @BASEBOARD_FAB2_LIB.BASEBOARD_FAB2(SCH_1):GND    I80 @BASEBOARD_FAB2_LIB.BASEBOARD_FAB2(SCH_1):PAGE127

C3M30 CAP_A_0402V-1.0UF,6.3V,10%,X6SA
     1 P1V05_PCH_STBY @BASEBOARD_FAB2_LIB.BASEBOARD_FAB2(SCH_1):P1V05_PCH_STBY    I27 @BASEBOARD_FAB2_LIB.BASEBOARD_FAB2(SCH_1):PAGE127
     2    GND @BASEBOARD_FAB2_LIB.BASEBOARD_FAB2(SCH_1):GND    I27 @BASEBOARD_FAB2_LIB.BASEBOARD_FAB2(SCH_1):PAGE127

C3M31 CAP_A_0402V-1.0UF,6.3V,10%,X6SA
     1 P1V05_PCH_STBY @BASEBOARD_FAB2_LIB.BASEBOARD_FAB2(SCH_1):P1V05_PCH_STBY    I57 @BASEBOARD_FAB2_LIB.BASEBOARD_FAB2(SCH_1):PAGE127
     2    GND @BASEBOARD_FAB2_LIB.BASEBOARD_FAB2(SCH_1):GND    I57 @BASEBOARD_FAB2_LIB.BASEBOARD_FAB2(SCH_1):PAGE127

C3M32 CAP_0402-0.22UF,16V,10%,X7R,A3A
     1 P3E_CPU0_PE1_PCH_R_RXN<10> @BASEBOARD_FAB2_LIB.BASEBOARD_FAB2(SCH_1):P3E_CPU0_PE1_PCH_R_RXN(10)   I223 @BASEBOARD_FAB2_LIB.BASEBOARD_FAB2(SCH_1):PAGE105
     2 P3E_CPU0_PE1_PCH_RXN<10> @BASEBOARD_FAB2_LIB.BASEBOARD_FAB2(SCH_1):P3E_CPU0_PE1_PCH_RXN(10)   I223 @BASEBOARD_FAB2_LIB.BASEBOARD_FAB2(SCH_1):PAGE105

C3M33 CAP_0402-0.22UF,16V,10%,X7R,A3A
     1 P3E_CPU0_PE1_PCH_R_RXN<8> @BASEBOARD_FAB2_LIB.BASEBOARD_FAB2(SCH_1):P3E_CPU0_PE1_PCH_R_RXN(8)   I217 @BASEBOARD_FAB2_LIB.BASEBOARD_FAB2(SCH_1):PAGE105
     2 P3E_CPU0_PE1_PCH_RXN<8> @BASEBOARD_FAB2_LIB.BASEBOARD_FAB2(SCH_1):P3E_CPU0_PE1_PCH_RXN(8)   I217 @BASEBOARD_FAB2_LIB.BASEBOARD_FAB2(SCH_1):PAGE105

C3M34 CAP_0402-0.22UF,16V,10%,X7R,A3A
     1 P3E_CPU0_PE1_PCH_R_RXP<8> @BASEBOARD_FAB2_LIB.BASEBOARD_FAB2(SCH_1):P3E_CPU0_PE1_PCH_R_RXP(8)   I206 @BASEBOARD_FAB2_LIB.BASEBOARD_FAB2(SCH_1):PAGE105
     2 P3E_CPU0_PE1_PCH_RXP<8> @BASEBOARD_FAB2_LIB.BASEBOARD_FAB2(SCH_1):P3E_CPU0_PE1_PCH_RXP(8)   I206 @BASEBOARD_FAB2_LIB.BASEBOARD_FAB2(SCH_1):PAGE105

C3M35 CAP_0402-0.22UF,16V,10%,X7R,A3A
     1 P3E_CPU0_PE1_PCH_R_RXN<9> @BASEBOARD_FAB2_LIB.BASEBOARD_FAB2(SCH_1):P3E_CPU0_PE1_PCH_R_RXN(9)   I225 @BASEBOARD_FAB2_LIB.BASEBOARD_FAB2(SCH_1):PAGE105
     2 P3E_CPU0_PE1_PCH_RXN<9> @BASEBOARD_FAB2_LIB.BASEBOARD_FAB2(SCH_1):P3E_CPU0_PE1_PCH_RXN(9)   I225 @BASEBOARD_FAB2_LIB.BASEBOARD_FAB2(SCH_1):PAGE105

C3M36 CAP_0402-0.22UF,16V,10%,X7R,A3A
     1 P3E_CPU0_PE1_PCH_R_RXP<9> @BASEBOARD_FAB2_LIB.BASEBOARD_FAB2(SCH_1):P3E_CPU0_PE1_PCH_R_RXP(9)   I218 @BASEBOARD_FAB2_LIB.BASEBOARD_FAB2(SCH_1):PAGE105
     2 P3E_CPU0_PE1_PCH_RXP<9> @BASEBOARD_FAB2_LIB.BASEBOARD_FAB2(SCH_1):P3E_CPU0_PE1_PCH_RXP(9)   I218 @BASEBOARD_FAB2_LIB.BASEBOARD_FAB2(SCH_1):PAGE105

C3M37 CAP_0402-0.22UF,16V,10%,X7R,A3A
     1 DMI_CPU0_PCH_RX_DP<1> @BASEBOARD_FAB2_LIB.BASEBOARD_FAB2(SCH_1):DMI_CPU0_PCH_RX_DP(1)    I73 @BASEBOARD_FAB2_LIB.BASEBOARD_FAB2(SCH_1):PAGE129
     2 DMI_CPU0_PCH_RX_C_DP<1> @BASEBOARD_FAB2_LIB.BASEBOARD_FAB2(SCH_1):DMI_CPU0_PCH_RX_C_DP(1)    I73 @BASEBOARD_FAB2_LIB.BASEBOARD_FAB2(SCH_1):PAGE129

C3M38 CAP_A_0402V-1.0UF,6.3V,10%,X6SA
     1 P1V05_PCH_STBY @BASEBOARD_FAB2_LIB.BASEBOARD_FAB2(SCH_1):P1V05_PCH_STBY    I32 @BASEBOARD_FAB2_LIB.BASEBOARD_FAB2(SCH_1):PAGE131
     2    GND @BASEBOARD_FAB2_LIB.BASEBOARD_FAB2(SCH_1):GND    I32 @BASEBOARD_FAB2_LIB.BASEBOARD_FAB2(SCH_1):PAGE131

C3M39 CAP_A_0402V-1.0UF,6.3V,10%,X6SA
     1 P1V05_PCH_STBY @BASEBOARD_FAB2_LIB.BASEBOARD_FAB2(SCH_1):P1V05_PCH_STBY    I44 @BASEBOARD_FAB2_LIB.BASEBOARD_FAB2(SCH_1):PAGE131
     2    GND @BASEBOARD_FAB2_LIB.BASEBOARD_FAB2(SCH_1):GND    I44 @BASEBOARD_FAB2_LIB.BASEBOARD_FAB2(SCH_1):PAGE131

C3M40 CAP_0402-0.22UF,16V,10%,X7R,A3A
     1 DMI_CPU0_PCH_RX_DP<0> @BASEBOARD_FAB2_LIB.BASEBOARD_FAB2(SCH_1):DMI_CPU0_PCH_RX_DP(0)    I72 @BASEBOARD_FAB2_LIB.BASEBOARD_FAB2(SCH_1):PAGE129
     2 DMI_CPU0_PCH_RX_C_DP<0> @BASEBOARD_FAB2_LIB.BASEBOARD_FAB2(SCH_1):DMI_CPU0_PCH_RX_C_DP(0)    I72 @BASEBOARD_FAB2_LIB.BASEBOARD_FAB2(SCH_1):PAGE129

C3M41 CAP_0402-0.22UF,16V,10%,X7R,A3A
     1 DMI_CPU0_PCH_RX_DN<1> @BASEBOARD_FAB2_LIB.BASEBOARD_FAB2(SCH_1):DMI_CPU0_PCH_RX_DN(1)    I81 @BASEBOARD_FAB2_LIB.BASEBOARD_FAB2(SCH_1):PAGE129
     2 DMI_CPU0_PCH_RX_C_DN<1> @BASEBOARD_FAB2_LIB.BASEBOARD_FAB2(SCH_1):DMI_CPU0_PCH_RX_C_DN(1)    I81 @BASEBOARD_FAB2_LIB.BASEBOARD_FAB2(SCH_1):PAGE129

C3M42 CAP_A_0402V-1.0UF,6.3V,10%,X6SA
     1 P1V05_PCH_STBY @BASEBOARD_FAB2_LIB.BASEBOARD_FAB2(SCH_1):P1V05_PCH_STBY    I45 @BASEBOARD_FAB2_LIB.BASEBOARD_FAB2(SCH_1):PAGE131
     2    GND @BASEBOARD_FAB2_LIB.BASEBOARD_FAB2(SCH_1):GND    I45 @BASEBOARD_FAB2_LIB.BASEBOARD_FAB2(SCH_1):PAGE131

C3M43 CAP_A_0402V-1.0UF,6.3V,10%,X6SA
     1 P1V05_PCH_STBY @BASEBOARD_FAB2_LIB.BASEBOARD_FAB2(SCH_1):P1V05_PCH_STBY    I42 @BASEBOARD_FAB2_LIB.BASEBOARD_FAB2(SCH_1):PAGE131
     2    GND @BASEBOARD_FAB2_LIB.BASEBOARD_FAB2(SCH_1):GND    I42 @BASEBOARD_FAB2_LIB.BASEBOARD_FAB2(SCH_1):PAGE131

C3M44 CAP_0402-0.22UF,16V,10%,X7R,A3A
     1 DMI_CPU0_PCH_RX_DN<0> @BASEBOARD_FAB2_LIB.BASEBOARD_FAB2(SCH_1):DMI_CPU0_PCH_RX_DN(0)    I80 @BASEBOARD_FAB2_LIB.BASEBOARD_FAB2(SCH_1):PAGE129
     2 DMI_CPU0_PCH_RX_C_DN<0> @BASEBOARD_FAB2_LIB.BASEBOARD_FAB2(SCH_1):DMI_CPU0_PCH_RX_C_DN(0)    I80 @BASEBOARD_FAB2_LIB.BASEBOARD_FAB2(SCH_1):PAGE129

C3M45 CAP_0402-0.22UF,16V,10%,X7R,A3A
     1 DMI_CPU0_PCH_RX_DN<2> @BASEBOARD_FAB2_LIB.BASEBOARD_FAB2(SCH_1):DMI_CPU0_PCH_RX_DN(2)    I82 @BASEBOARD_FAB2_LIB.BASEBOARD_FAB2(SCH_1):PAGE129
     2 DMI_CPU0_PCH_RX_C_DN<2> @BASEBOARD_FAB2_LIB.BASEBOARD_FAB2(SCH_1):DMI_CPU0_PCH_RX_C_DN(2)    I82 @BASEBOARD_FAB2_LIB.BASEBOARD_FAB2(SCH_1):PAGE129

C3M46 CAP_A_0402V-1.0UF,6.3V,10%,X6SA
     1 PVCCIOMCP_CPU0 @BASEBOARD_FAB2_LIB.BASEBOARD_FAB2(SCH_1):PVCCIOMCP_CPU0    I99 @BASEBOARD_FAB2_LIB.BASEBOARD_FAB2(SCH_1):PAGE194
     2    GND @BASEBOARD_FAB2_LIB.BASEBOARD_FAB2(SCH_1):GND    I99 @BASEBOARD_FAB2_LIB.BASEBOARD_FAB2(SCH_1):PAGE194

C3N1 CAP_A_0402V-1.0UF,6.3V,10%,X6SA
     1 PVNN_PCH_STBY @BASEBOARD_FAB2_LIB.BASEBOARD_FAB2(SCH_1):PVNN_PCH_STBY    I34 @BASEBOARD_FAB2_LIB.BASEBOARD_FAB2(SCH_1):PAGE132
     2    GND @BASEBOARD_FAB2_LIB.BASEBOARD_FAB2(SCH_1):GND    I34 @BASEBOARD_FAB2_LIB.BASEBOARD_FAB2(SCH_1):PAGE132

C3N2 CAP_A_0402V-1.0UF,6.3V,10%,X6SA
     1 PVNN_PCH_STBY @BASEBOARD_FAB2_LIB.BASEBOARD_FAB2(SCH_1):PVNN_PCH_STBY    I43 @BASEBOARD_FAB2_LIB.BASEBOARD_FAB2(SCH_1):PAGE132
     2    GND @BASEBOARD_FAB2_LIB.BASEBOARD_FAB2(SCH_1):GND    I43 @BASEBOARD_FAB2_LIB.BASEBOARD_FAB2(SCH_1):PAGE132

C3N3 CAP_A_0402V-1.0UF,6.3V,10%,X6SA
     1 PVNN_PCH_STBY @BASEBOARD_FAB2_LIB.BASEBOARD_FAB2(SCH_1):PVNN_PCH_STBY    I32 @BASEBOARD_FAB2_LIB.BASEBOARD_FAB2(SCH_1):PAGE132
     2    GND @BASEBOARD_FAB2_LIB.BASEBOARD_FAB2(SCH_1):GND    I32 @BASEBOARD_FAB2_LIB.BASEBOARD_FAB2(SCH_1):PAGE132

C3N4 CAP_A_0402V-1.0UF,6.3V,10%,X6SA
     1 PVNN_PCH_STBY @BASEBOARD_FAB2_LIB.BASEBOARD_FAB2(SCH_1):PVNN_PCH_STBY    I46 @BASEBOARD_FAB2_LIB.BASEBOARD_FAB2(SCH_1):PAGE132
     2    GND @BASEBOARD_FAB2_LIB.BASEBOARD_FAB2(SCH_1):GND    I46 @BASEBOARD_FAB2_LIB.BASEBOARD_FAB2(SCH_1):PAGE132

C3N5 CAP_A_0402V-1.0UF,6.3V,10%,X6SA
     1 PVNN_PCH_STBY @BASEBOARD_FAB2_LIB.BASEBOARD_FAB2(SCH_1):PVNN_PCH_STBY    I48 @BASEBOARD_FAB2_LIB.BASEBOARD_FAB2(SCH_1):PAGE132
     2    GND @BASEBOARD_FAB2_LIB.BASEBOARD_FAB2(SCH_1):GND    I48 @BASEBOARD_FAB2_LIB.BASEBOARD_FAB2(SCH_1):PAGE132

C3N6 CAP_A_0402V-1.0UF,6.3V,10%,X6SA
     1 PVNN_PCH_STBY @BASEBOARD_FAB2_LIB.BASEBOARD_FAB2(SCH_1):PVNN_PCH_STBY    I44 @BASEBOARD_FAB2_LIB.BASEBOARD_FAB2(SCH_1):PAGE132
     2    GND @BASEBOARD_FAB2_LIB.BASEBOARD_FAB2(SCH_1):GND    I44 @BASEBOARD_FAB2_LIB.BASEBOARD_FAB2(SCH_1):PAGE132

C3N7 CAP_A_0402V-1.0UF,6.3V,10%,X6SA
     1 PVNN_PCH_STBY @BASEBOARD_FAB2_LIB.BASEBOARD_FAB2(SCH_1):PVNN_PCH_STBY    I35 @BASEBOARD_FAB2_LIB.BASEBOARD_FAB2(SCH_1):PAGE132
     2    GND @BASEBOARD_FAB2_LIB.BASEBOARD_FAB2(SCH_1):GND    I35 @BASEBOARD_FAB2_LIB.BASEBOARD_FAB2(SCH_1):PAGE132

C3N8 CAP_0402-0.22UF,16V,10%,X7R,A3A
     1 DMI_CPU0_PCH_RX_DP<3> @BASEBOARD_FAB2_LIB.BASEBOARD_FAB2(SCH_1):DMI_CPU0_PCH_RX_DP(3)    I75 @BASEBOARD_FAB2_LIB.BASEBOARD_FAB2(SCH_1):PAGE129
     2 DMI_CPU0_PCH_RX_C_DP<3> @BASEBOARD_FAB2_LIB.BASEBOARD_FAB2(SCH_1):DMI_CPU0_PCH_RX_C_DP(3)    I75 @BASEBOARD_FAB2_LIB.BASEBOARD_FAB2(SCH_1):PAGE129

C3N9 CAP_0402-0.22UF,16V,10%,X7R,A3A
     1 DMI_CPU0_PCH_RX_DP<2> @BASEBOARD_FAB2_LIB.BASEBOARD_FAB2(SCH_1):DMI_CPU0_PCH_RX_DP(2)    I74 @BASEBOARD_FAB2_LIB.BASEBOARD_FAB2(SCH_1):PAGE129
     2 DMI_CPU0_PCH_RX_C_DP<2> @BASEBOARD_FAB2_LIB.BASEBOARD_FAB2(SCH_1):DMI_CPU0_PCH_RX_C_DP(2)    I74 @BASEBOARD_FAB2_LIB.BASEBOARD_FAB2(SCH_1):PAGE129

C3N10 CAP_A_0603V-22.0UF,4V,20%,X6S,A
     1 PVNN_PCH_STBY @BASEBOARD_FAB2_LIB.BASEBOARD_FAB2(SCH_1):PVNN_PCH_STBY    I13 @BASEBOARD_FAB2_LIB.BASEBOARD_FAB2(SCH_1):PAGE132
     2    GND @BASEBOARD_FAB2_LIB.BASEBOARD_FAB2(SCH_1):GND    I13 @BASEBOARD_FAB2_LIB.BASEBOARD_FAB2(SCH_1):PAGE132

C3N11 CAP_A_0603V-22.0UF,4V,20%,X6S,A
     1 PVNN_PCH_STBY @BASEBOARD_FAB2_LIB.BASEBOARD_FAB2(SCH_1):PVNN_PCH_STBY    I19 @BASEBOARD_FAB2_LIB.BASEBOARD_FAB2(SCH_1):PAGE132
     2    GND @BASEBOARD_FAB2_LIB.BASEBOARD_FAB2(SCH_1):GND    I19 @BASEBOARD_FAB2_LIB.BASEBOARD_FAB2(SCH_1):PAGE132

C3N12 CAP_A_0603V-22.0UF,4V,20%,X6S,A
     1 PVNN_PCH_STBY @BASEBOARD_FAB2_LIB.BASEBOARD_FAB2(SCH_1):PVNN_PCH_STBY    I12 @BASEBOARD_FAB2_LIB.BASEBOARD_FAB2(SCH_1):PAGE132
     2    GND @BASEBOARD_FAB2_LIB.BASEBOARD_FAB2(SCH_1):GND    I12 @BASEBOARD_FAB2_LIB.BASEBOARD_FAB2(SCH_1):PAGE132

C3N13 CAP_0402-0.22UF,16V,10%,X7R,A3A
     1 DMI_CPU0_PCH_RX_DN<3> @BASEBOARD_FAB2_LIB.BASEBOARD_FAB2(SCH_1):DMI_CPU0_PCH_RX_DN(3)    I83 @BASEBOARD_FAB2_LIB.BASEBOARD_FAB2(SCH_1):PAGE129
     2 DMI_CPU0_PCH_RX_C_DN<3> @BASEBOARD_FAB2_LIB.BASEBOARD_FAB2(SCH_1):DMI_CPU0_PCH_RX_C_DN(3)    I83 @BASEBOARD_FAB2_LIB.BASEBOARD_FAB2(SCH_1):PAGE129

C3N14 CAPP_3018-470UF,2.5V,20%,ALUM,A
     1 PVCCIOMCP_CPU0 @BASEBOARD_FAB2_LIB.BASEBOARD_FAB2(SCH_1):PVCCIOMCP_CPU0   I101 @BASEBOARD_FAB2_LIB.BASEBOARD_FAB2(SCH_1):PAGE194
     2    GND @BASEBOARD_FAB2_LIB.BASEBOARD_FAB2(SCH_1):GND   I101 @BASEBOARD_FAB2_LIB.BASEBOARD_FAB2(SCH_1):PAGE194

C3N15 CAP_A_0402V-1.0UF,6.3V,10%,X6SA
     1 PVNN_PCH_STBY @BASEBOARD_FAB2_LIB.BASEBOARD_FAB2(SCH_1):PVNN_PCH_STBY    I49 @BASEBOARD_FAB2_LIB.BASEBOARD_FAB2(SCH_1):PAGE132
     2    GND @BASEBOARD_FAB2_LIB.BASEBOARD_FAB2(SCH_1):GND    I49 @BASEBOARD_FAB2_LIB.BASEBOARD_FAB2(SCH_1):PAGE132

C3N16 CAP_A_0402V-1.0UF,6.3V,10%,X6SA
     1 PVNN_PCH_STBY @BASEBOARD_FAB2_LIB.BASEBOARD_FAB2(SCH_1):PVNN_PCH_STBY    I36 @BASEBOARD_FAB2_LIB.BASEBOARD_FAB2(SCH_1):PAGE132
     2    GND @BASEBOARD_FAB2_LIB.BASEBOARD_FAB2(SCH_1):GND    I36 @BASEBOARD_FAB2_LIB.BASEBOARD_FAB2(SCH_1):PAGE132

C3N17 CAP_A_0402V-1.0UF,6.3V,10%,X6SA
     1 PVNN_PCH_STBY @BASEBOARD_FAB2_LIB.BASEBOARD_FAB2(SCH_1):PVNN_PCH_STBY    I45 @BASEBOARD_FAB2_LIB.BASEBOARD_FAB2(SCH_1):PAGE132
     2    GND @BASEBOARD_FAB2_LIB.BASEBOARD_FAB2(SCH_1):GND    I45 @BASEBOARD_FAB2_LIB.BASEBOARD_FAB2(SCH_1):PAGE132

C3N18 CAP_A_0402V-1.0UF,6.3V,10%,X6SA
     1 PVNN_PCH_STBY @BASEBOARD_FAB2_LIB.BASEBOARD_FAB2(SCH_1):PVNN_PCH_STBY    I42 @BASEBOARD_FAB2_LIB.BASEBOARD_FAB2(SCH_1):PAGE132
     2    GND @BASEBOARD_FAB2_LIB.BASEBOARD_FAB2(SCH_1):GND    I42 @BASEBOARD_FAB2_LIB.BASEBOARD_FAB2(SCH_1):PAGE132

C3N19 CAP_A_0402V-1.0UF,6.3V,10%,X6SA
     1 PVNN_PCH_STBY @BASEBOARD_FAB2_LIB.BASEBOARD_FAB2(SCH_1):PVNN_PCH_STBY    I31 @BASEBOARD_FAB2_LIB.BASEBOARD_FAB2(SCH_1):PAGE132
     2    GND @BASEBOARD_FAB2_LIB.BASEBOARD_FAB2(SCH_1):GND    I31 @BASEBOARD_FAB2_LIB.BASEBOARD_FAB2(SCH_1):PAGE132

C3N20 CAP_A_0402V-1.0UF,6.3V,10%,X6SA
     1 PVNN_PCH_STBY @BASEBOARD_FAB2_LIB.BASEBOARD_FAB2(SCH_1):PVNN_PCH_STBY    I51 @BASEBOARD_FAB2_LIB.BASEBOARD_FAB2(SCH_1):PAGE132
     2    GND @BASEBOARD_FAB2_LIB.BASEBOARD_FAB2(SCH_1):GND    I51 @BASEBOARD_FAB2_LIB.BASEBOARD_FAB2(SCH_1):PAGE132

C3N21 CAP_A_0402V-1.0UF,6.3V,10%,X6SA
     1 P1V8_PCH_STBY @BASEBOARD_FAB2_LIB.BASEBOARD_FAB2(SCH_1):P1V8_PCH_STBY    I49 @BASEBOARD_FAB2_LIB.BASEBOARD_FAB2(SCH_1):PAGE130
     2    GND @BASEBOARD_FAB2_LIB.BASEBOARD_FAB2(SCH_1):GND    I49 @BASEBOARD_FAB2_LIB.BASEBOARD_FAB2(SCH_1):PAGE130

C3N22 CAP_A_0402V-1.0UF,6.3V,10%,X6SA
     1 P1V8_PCH_STBY @BASEBOARD_FAB2_LIB.BASEBOARD_FAB2(SCH_1):P1V8_PCH_STBY    I53 @BASEBOARD_FAB2_LIB.BASEBOARD_FAB2(SCH_1):PAGE130
     2    GND @BASEBOARD_FAB2_LIB.BASEBOARD_FAB2(SCH_1):GND    I53 @BASEBOARD_FAB2_LIB.BASEBOARD_FAB2(SCH_1):PAGE130

C3N23 CAP_A_0402V-1.0UF,6.3V,10%,X6SA
     1 P3V3_STBY @BASEBOARD_FAB2_LIB.BASEBOARD_FAB2(SCH_1):P3V3_STBY    I42 @BASEBOARD_FAB2_LIB.BASEBOARD_FAB2(SCH_1):PAGE130
     2    GND @BASEBOARD_FAB2_LIB.BASEBOARD_FAB2(SCH_1):GND    I42 @BASEBOARD_FAB2_LIB.BASEBOARD_FAB2(SCH_1):PAGE130

C3N24 CAP_A_0603V-22.0UF,4V,20%,X6S,A
     1 PVNN_PCH_STBY @BASEBOARD_FAB2_LIB.BASEBOARD_FAB2(SCH_1):PVNN_PCH_STBY    I16 @BASEBOARD_FAB2_LIB.BASEBOARD_FAB2(SCH_1):PAGE132
     2    GND @BASEBOARD_FAB2_LIB.BASEBOARD_FAB2(SCH_1):GND    I16 @BASEBOARD_FAB2_LIB.BASEBOARD_FAB2(SCH_1):PAGE132

C3N25 CAP_A_0402V-1.0UF,6.3V,10%,X6SA
     1 P1V8_PCH_STBY @BASEBOARD_FAB2_LIB.BASEBOARD_FAB2(SCH_1):P1V8_PCH_STBY    I50 @BASEBOARD_FAB2_LIB.BASEBOARD_FAB2(SCH_1):PAGE130
     2    GND @BASEBOARD_FAB2_LIB.BASEBOARD_FAB2(SCH_1):GND    I50 @BASEBOARD_FAB2_LIB.BASEBOARD_FAB2(SCH_1):PAGE130

C3N26 CAPP_3018-470UF,2.5V,20%,ALUM,A
     1 PVCCIO_CPU0 @BASEBOARD_FAB2_LIB.BASEBOARD_FAB2(SCH_1):PVCCIO_CPU0    I17 @BASEBOARD_FAB2_LIB.BASEBOARD_FAB2(SCH_1):PAGE212
     2    GND @BASEBOARD_FAB2_LIB.BASEBOARD_FAB2(SCH_1):GND    I17 @BASEBOARD_FAB2_LIB.BASEBOARD_FAB2(SCH_1):PAGE212

C3N27 CAP_A_0603V-22.0UF,4V,20%,X6S,A
     1 PVNN_PCH_STBY @BASEBOARD_FAB2_LIB.BASEBOARD_FAB2(SCH_1):PVNN_PCH_STBY     I8 @BASEBOARD_FAB2_LIB.BASEBOARD_FAB2(SCH_1):PAGE132
     2    GND @BASEBOARD_FAB2_LIB.BASEBOARD_FAB2(SCH_1):GND     I8 @BASEBOARD_FAB2_LIB.BASEBOARD_FAB2(SCH_1):PAGE132

C3N28 CAP_A_0603V-22.0UF,4V,20%,X6S,A
     1 PVNN_PCH_STBY @BASEBOARD_FAB2_LIB.BASEBOARD_FAB2(SCH_1):PVNN_PCH_STBY    I17 @BASEBOARD_FAB2_LIB.BASEBOARD_FAB2(SCH_1):PAGE132
     2    GND @BASEBOARD_FAB2_LIB.BASEBOARD_FAB2(SCH_1):GND    I17 @BASEBOARD_FAB2_LIB.BASEBOARD_FAB2(SCH_1):PAGE132

C3N29 CAP_A_0402V-0.1UF,16V,10%,X7R,A
     1 A_PVCCRTC_EXT_CAP @BASEBOARD_FAB2_LIB.BASEBOARD_FAB2(SCH_1):A_PVCCRTC_EXT_CAP    I16 @BASEBOARD_FAB2_LIB.BASEBOARD_FAB2(SCH_1):PAGE130
     2    GND @BASEBOARD_FAB2_LIB.BASEBOARD_FAB2(SCH_1):GND    I16 @BASEBOARD_FAB2_LIB.BASEBOARD_FAB2(SCH_1):PAGE130

C3N30 CAP_A_0603V-22.0UF,4V,20%,X6S,A
     1 PVNN_PCH_STBY @BASEBOARD_FAB2_LIB.BASEBOARD_FAB2(SCH_1):PVNN_PCH_STBY     I9 @BASEBOARD_FAB2_LIB.BASEBOARD_FAB2(SCH_1):PAGE132
     2    GND @BASEBOARD_FAB2_LIB.BASEBOARD_FAB2(SCH_1):GND     I9 @BASEBOARD_FAB2_LIB.BASEBOARD_FAB2(SCH_1):PAGE132

C3N31 CAP_A_0603V-22.0UF,4V,20%,X6S,A
     1 PVNN_PCH_STBY @BASEBOARD_FAB2_LIB.BASEBOARD_FAB2(SCH_1):PVNN_PCH_STBY    I20 @BASEBOARD_FAB2_LIB.BASEBOARD_FAB2(SCH_1):PAGE132
     2    GND @BASEBOARD_FAB2_LIB.BASEBOARD_FAB2(SCH_1):GND    I20 @BASEBOARD_FAB2_LIB.BASEBOARD_FAB2(SCH_1):PAGE132

C3N32 CAP_A_0402V-1.0UF,6.3V,10%,X6SA
     1 RST_SRTCRST_N @BASEBOARD_FAB2_LIB.BASEBOARD_FAB2(SCH_1):RST_SRTCRST_N    I20 @BASEBOARD_FAB2_LIB.BASEBOARD_FAB2(SCH_1):PAGE137
     2    GND @BASEBOARD_FAB2_LIB.BASEBOARD_FAB2(SCH_1):GND    I20 @BASEBOARD_FAB2_LIB.BASEBOARD_FAB2(SCH_1):PAGE137

C3N33 CAP_0805-10UF,16V,10%,X6S,C953A
     1 VR_FET_SW_P12V_STBY_PVCCIO_CPU0 @BASEBOARD_FAB2_LIB.BASEBOARD_FAB2(SCH_1):VR_FET_SW_P12V_STBY_PVCCIO_CPU0    I41 @BASEBOARD_FAB2_LIB.BASEBOARD_FAB2(SCH_1):PAGE212
     2    GND @BASEBOARD_FAB2_LIB.BASEBOARD_FAB2(SCH_1):GND    I41 @BASEBOARD_FAB2_LIB.BASEBOARD_FAB2(SCH_1):PAGE212

C3N34 CAP_0805-10UF,16V,10%,X6S,C953A
     1 VR_FET_SW_P12V_STBY_PVCCIO_CPU0 @BASEBOARD_FAB2_LIB.BASEBOARD_FAB2(SCH_1):VR_FET_SW_P12V_STBY_PVCCIO_CPU0    I43 @BASEBOARD_FAB2_LIB.BASEBOARD_FAB2(SCH_1):PAGE212
     2    GND @BASEBOARD_FAB2_LIB.BASEBOARD_FAB2(SCH_1):GND    I43 @BASEBOARD_FAB2_LIB.BASEBOARD_FAB2(SCH_1):PAGE212

C3N35 CAPP_3018-470UF,2.5V,20%,ALUM,A
     1 PVCCIO_CPU0 @BASEBOARD_FAB2_LIB.BASEBOARD_FAB2(SCH_1):PVCCIO_CPU0    I18 @BASEBOARD_FAB2_LIB.BASEBOARD_FAB2(SCH_1):PAGE212
     2    GND @BASEBOARD_FAB2_LIB.BASEBOARD_FAB2(SCH_1):GND    I18 @BASEBOARD_FAB2_LIB.BASEBOARD_FAB2(SCH_1):PAGE212

C3N36 CAP_0805-10UF,16V,10%,X6S,C953A
     1 VR_FET_SW_P12V_STBY_PVCCIO_CPU0 @BASEBOARD_FAB2_LIB.BASEBOARD_FAB2(SCH_1):VR_FET_SW_P12V_STBY_PVCCIO_CPU0    I40 @BASEBOARD_FAB2_LIB.BASEBOARD_FAB2(SCH_1):PAGE212
     2    GND @BASEBOARD_FAB2_LIB.BASEBOARD_FAB2(SCH_1):GND    I40 @BASEBOARD_FAB2_LIB.BASEBOARD_FAB2(SCH_1):PAGE212

C3N38 CAPP_3018-470UF,2.5V,20%,ALUM,A
     1 PVCCIO_CPU0 @BASEBOARD_FAB2_LIB.BASEBOARD_FAB2(SCH_1):PVCCIO_CPU0    I16 @BASEBOARD_FAB2_LIB.BASEBOARD_FAB2(SCH_1):PAGE212
     2    GND @BASEBOARD_FAB2_LIB.BASEBOARD_FAB2(SCH_1):GND    I16 @BASEBOARD_FAB2_LIB.BASEBOARD_FAB2(SCH_1):PAGE212

C3N39 CAP_0402LF-220PF,50V,10%,X7R,AA
     1 VR_PVCCIO_CPU0_AVSP @BASEBOARD_FAB2_LIB.BASEBOARD_FAB2(SCH_1):VR_PVCCIO_CPU0_AVSP    I83 @BASEBOARD_FAB2_LIB.BASEBOARD_FAB2(SCH_1):PAGE211
     2 VSENSE_PVCCIO_CPU0_AVSN @BASEBOARD_FAB2_LIB.BASEBOARD_FAB2(SCH_1):VSENSE_PVCCIO_CPU0_AVSN    I83 @BASEBOARD_FAB2_LIB.BASEBOARD_FAB2(SCH_1):PAGE211

C3N40 CAP_A_0402V-1.0UF,6.3V,10%,X6SA
     1 PVCCIOMCP_CPU0 @BASEBOARD_FAB2_LIB.BASEBOARD_FAB2(SCH_1):PVCCIOMCP_CPU0    I86 @BASEBOARD_FAB2_LIB.BASEBOARD_FAB2(SCH_1):PAGE194
     2    GND @BASEBOARD_FAB2_LIB.BASEBOARD_FAB2(SCH_1):GND    I86 @BASEBOARD_FAB2_LIB.BASEBOARD_FAB2(SCH_1):PAGE194

C3P1 CAP_A_0402V-0.1UF,16V,10%,EMPTA
     1 VSENSE_PVCCIO_CPU0_SKT_VSEN @BASEBOARD_FAB2_LIB.BASEBOARD_FAB2(SCH_1):VSENSE_PVCCIO_CPU0_SKT_VSEN    I60 @BASEBOARD_FAB2_LIB.BASEBOARD_FAB2(SCH_1):PAGE212
     2 VSENSE_PVCCIO_CPU0_SKT_VRTN @BASEBOARD_FAB2_LIB.BASEBOARD_FAB2(SCH_1):VSENSE_PVCCIO_CPU0_SKT_VRTN    I60 @BASEBOARD_FAB2_LIB.BASEBOARD_FAB2(SCH_1):PAGE212

C3P2 CAP_0402LF-1000PF,50V,10%,X7R,A
     1 VR_PVCCIO_CPU0_VINSEN @BASEBOARD_FAB2_LIB.BASEBOARD_FAB2(SCH_1):VR_PVCCIO_CPU0_VINSEN    I33 @BASEBOARD_FAB2_LIB.BASEBOARD_FAB2(SCH_1):PAGE211
     2    GND @BASEBOARD_FAB2_LIB.BASEBOARD_FAB2(SCH_1):GND    I33 @BASEBOARD_FAB2_LIB.BASEBOARD_FAB2(SCH_1):PAGE211

C3P3 CAP_A_0402V-1.0UF,6.3V,10%,X6SA
     1 VR_PVCCIO_CPU0_VDD @BASEBOARD_FAB2_LIB.BASEBOARD_FAB2(SCH_1):VR_PVCCIO_CPU0_VDD    I20 @BASEBOARD_FAB2_LIB.BASEBOARD_FAB2(SCH_1):PAGE211
     2    GND @BASEBOARD_FAB2_LIB.BASEBOARD_FAB2(SCH_1):GND    I20 @BASEBOARD_FAB2_LIB.BASEBOARD_FAB2(SCH_1):PAGE211

C3P4 CAP_A_0402V-1.0UF,6.3V,10%,X6SA
     1 VR_PVCCIO_CPU0_VD12 @BASEBOARD_FAB2_LIB.BASEBOARD_FAB2(SCH_1):VR_PVCCIO_CPU0_VD12    I11 @BASEBOARD_FAB2_LIB.BASEBOARD_FAB2(SCH_1):PAGE211
     2    GND @BASEBOARD_FAB2_LIB.BASEBOARD_FAB2(SCH_1):GND    I11 @BASEBOARD_FAB2_LIB.BASEBOARD_FAB2(SCH_1):PAGE211

C3P5 CAP_A_0402V-0.1UF,16V,10%,X7R,A
     1 VR_PVCCIO_CPU0_VD12 @BASEBOARD_FAB2_LIB.BASEBOARD_FAB2(SCH_1):VR_PVCCIO_CPU0_VD12    I13 @BASEBOARD_FAB2_LIB.BASEBOARD_FAB2(SCH_1):PAGE211
     2    GND @BASEBOARD_FAB2_LIB.BASEBOARD_FAB2(SCH_1):GND    I13 @BASEBOARD_FAB2_LIB.BASEBOARD_FAB2(SCH_1):PAGE211

C3P6 CAP_0402LF-1000PF,50V,10%,X7R,A
     1 PWRGD_PVCCIO_CPU0_R @BASEBOARD_FAB2_LIB.BASEBOARD_FAB2(SCH_1):PWRGD_PVCCIO_CPU0_R    I71 @BASEBOARD_FAB2_LIB.BASEBOARD_FAB2(SCH_1):PAGE211
     2    GND @BASEBOARD_FAB2_LIB.BASEBOARD_FAB2(SCH_1):GND    I71 @BASEBOARD_FAB2_LIB.BASEBOARD_FAB2(SCH_1):PAGE211

C3P7 CAP_A_0402V-0.1UF,16V,10%,X7R,A
     1 VR_PVCCIO_CPU0_VDD @BASEBOARD_FAB2_LIB.BASEBOARD_FAB2(SCH_1):VR_PVCCIO_CPU0_VDD    I22 @BASEBOARD_FAB2_LIB.BASEBOARD_FAB2(SCH_1):PAGE211
     2    GND @BASEBOARD_FAB2_LIB.BASEBOARD_FAB2(SCH_1):GND    I22 @BASEBOARD_FAB2_LIB.BASEBOARD_FAB2(SCH_1):PAGE211

C3P10 CAP_0402-0.22UF,16V,10%,EMPTY,A
     1 P3E_CPU0_PE1_SS_TXP<0> @BASEBOARD_FAB2_LIB.BASEBOARD_FAB2(SCH_1):P3E_CPU0_PE1_SS_TXP(0)   I417 @BASEBOARD_FAB2_LIB.BASEBOARD_FAB2(SCH_1):PAGE107
     2 P3E_CPU0_PE1_SS_C_TXP<0> @BASEBOARD_FAB2_LIB.BASEBOARD_FAB2(SCH_1):P3E_CPU0_PE1_SS_C_TXP(0)   I417 @BASEBOARD_FAB2_LIB.BASEBOARD_FAB2(SCH_1):PAGE107

C3P11 CAP_0402-0.22UF,16V,10%,X7R,A3A
     1 P3E_CPU0_PE1_SS_TXP<0> @BASEBOARD_FAB2_LIB.BASEBOARD_FAB2(SCH_1):P3E_CPU0_PE1_SS_TXP(0)   I212 @BASEBOARD_FAB2_LIB.BASEBOARD_FAB2(SCH_1):PAGE107
     2 P3E_CPU0_PE1_PCH_TXP<0> @BASEBOARD_FAB2_LIB.BASEBOARD_FAB2(SCH_1):P3E_CPU0_PE1_PCH_TXP(0)   I212 @BASEBOARD_FAB2_LIB.BASEBOARD_FAB2(SCH_1):PAGE107

C3P12 CAP_0402-0.22UF,16V,10%,EMPTY,A
     1 P3E_CPU0_PE1_SS_TXN<0> @BASEBOARD_FAB2_LIB.BASEBOARD_FAB2(SCH_1):P3E_CPU0_PE1_SS_TXN(0)   I415 @BASEBOARD_FAB2_LIB.BASEBOARD_FAB2(SCH_1):PAGE107
     2 P3E_CPU0_PE1_SS_C_TXN<0> @BASEBOARD_FAB2_LIB.BASEBOARD_FAB2(SCH_1):P3E_CPU0_PE1_SS_C_TXN(0)   I415 @BASEBOARD_FAB2_LIB.BASEBOARD_FAB2(SCH_1):PAGE107

C3P13 CAP_0402-0.22UF,16V,10%,X7R,A3A
     1 P3E_CPU0_PE1_SS_TXN<0> @BASEBOARD_FAB2_LIB.BASEBOARD_FAB2(SCH_1):P3E_CPU0_PE1_SS_TXN(0)   I207 @BASEBOARD_FAB2_LIB.BASEBOARD_FAB2(SCH_1):PAGE107
     2 P3E_CPU0_PE1_PCH_TXN<0> @BASEBOARD_FAB2_LIB.BASEBOARD_FAB2(SCH_1):P3E_CPU0_PE1_PCH_TXN(0)   I207 @BASEBOARD_FAB2_LIB.BASEBOARD_FAB2(SCH_1):PAGE107

C3P14 CAP_0402-0.22UF,16V,10%,EMPTY,A
     1 P3E_CPU0_PE1_SS_TXP<1> @BASEBOARD_FAB2_LIB.BASEBOARD_FAB2(SCH_1):P3E_CPU0_PE1_SS_TXP(1)   I431 @BASEBOARD_FAB2_LIB.BASEBOARD_FAB2(SCH_1):PAGE107
     2 P3E_CPU0_PE1_SS_C_TXP<1> @BASEBOARD_FAB2_LIB.BASEBOARD_FAB2(SCH_1):P3E_CPU0_PE1_SS_C_TXP(1)   I431 @BASEBOARD_FAB2_LIB.BASEBOARD_FAB2(SCH_1):PAGE107

C3P15 CAP_0402-0.22UF,16V,10%,X7R,A3A
     1 P3E_CPU0_PE1_SS_TXP<1> @BASEBOARD_FAB2_LIB.BASEBOARD_FAB2(SCH_1):P3E_CPU0_PE1_SS_TXP(1)   I226 @BASEBOARD_FAB2_LIB.BASEBOARD_FAB2(SCH_1):PAGE107
     2 P3E_CPU0_PE1_PCH_TXP<1> @BASEBOARD_FAB2_LIB.BASEBOARD_FAB2(SCH_1):P3E_CPU0_PE1_PCH_TXP(1)   I226 @BASEBOARD_FAB2_LIB.BASEBOARD_FAB2(SCH_1):PAGE107

C3P16 CAP_0402-0.22UF,16V,10%,EMPTY,A
     1 P3E_CPU0_PE1_SS_TXN<1> @BASEBOARD_FAB2_LIB.BASEBOARD_FAB2(SCH_1):P3E_CPU0_PE1_SS_TXN(1)   I422 @BASEBOARD_FAB2_LIB.BASEBOARD_FAB2(SCH_1):PAGE107
     2 P3E_CPU0_PE1_SS_C_TXN<1> @BASEBOARD_FAB2_LIB.BASEBOARD_FAB2(SCH_1):P3E_CPU0_PE1_SS_C_TXN(1)   I422 @BASEBOARD_FAB2_LIB.BASEBOARD_FAB2(SCH_1):PAGE107

C3P17 CAP_0402-0.22UF,16V,10%,X7R,A3A
     1 P3E_CPU0_PE1_SS_TXN<1> @BASEBOARD_FAB2_LIB.BASEBOARD_FAB2(SCH_1):P3E_CPU0_PE1_SS_TXN(1)   I208 @BASEBOARD_FAB2_LIB.BASEBOARD_FAB2(SCH_1):PAGE107
     2 P3E_CPU0_PE1_PCH_TXN<1> @BASEBOARD_FAB2_LIB.BASEBOARD_FAB2(SCH_1):P3E_CPU0_PE1_PCH_TXN(1)   I208 @BASEBOARD_FAB2_LIB.BASEBOARD_FAB2(SCH_1):PAGE107

C3P18 CAP_0402-0.22UF,16V,10%,X7R,A3A
     1 P3E_CPU0_PE1_SS_TXP<2> @BASEBOARD_FAB2_LIB.BASEBOARD_FAB2(SCH_1):P3E_CPU0_PE1_SS_TXP(2)   I219 @BASEBOARD_FAB2_LIB.BASEBOARD_FAB2(SCH_1):PAGE107
     2 P3E_CPU0_PE1_PCH_TXP<2> @BASEBOARD_FAB2_LIB.BASEBOARD_FAB2(SCH_1):P3E_CPU0_PE1_PCH_TXP(2)   I219 @BASEBOARD_FAB2_LIB.BASEBOARD_FAB2(SCH_1):PAGE107

C3P19 CAP_0402-0.22UF,16V,10%,EMPTY,A
     1 P3E_CPU0_PE1_SS_TXP<2> @BASEBOARD_FAB2_LIB.BASEBOARD_FAB2(SCH_1):P3E_CPU0_PE1_SS_TXP(2)   I427 @BASEBOARD_FAB2_LIB.BASEBOARD_FAB2(SCH_1):PAGE107
     2 P3E_CPU0_PE1_SS_C_TXP<2> @BASEBOARD_FAB2_LIB.BASEBOARD_FAB2(SCH_1):P3E_CPU0_PE1_SS_C_TXP(2)   I427 @BASEBOARD_FAB2_LIB.BASEBOARD_FAB2(SCH_1):PAGE107

C3P20 CAP_0402-0.22UF,16V,10%,X7R,A3A
     1 P3E_CPU0_PE1_SS_TXN<2> @BASEBOARD_FAB2_LIB.BASEBOARD_FAB2(SCH_1):P3E_CPU0_PE1_SS_TXN(2)   I215 @BASEBOARD_FAB2_LIB.BASEBOARD_FAB2(SCH_1):PAGE107
     2 P3E_CPU0_PE1_PCH_TXN<2> @BASEBOARD_FAB2_LIB.BASEBOARD_FAB2(SCH_1):P3E_CPU0_PE1_PCH_TXN(2)   I215 @BASEBOARD_FAB2_LIB.BASEBOARD_FAB2(SCH_1):PAGE107

C3P21 CAP_0402-0.22UF,16V,10%,EMPTY,A
     1 P3E_CPU0_PE1_SS_TXN<2> @BASEBOARD_FAB2_LIB.BASEBOARD_FAB2(SCH_1):P3E_CPU0_PE1_SS_TXN(2)   I423 @BASEBOARD_FAB2_LIB.BASEBOARD_FAB2(SCH_1):PAGE107
     2 P3E_CPU0_PE1_SS_C_TXN<2> @BASEBOARD_FAB2_LIB.BASEBOARD_FAB2(SCH_1):P3E_CPU0_PE1_SS_C_TXN(2)   I423 @BASEBOARD_FAB2_LIB.BASEBOARD_FAB2(SCH_1):PAGE107

C3P22 CAP_0402-0.22UF,16V,10%,EMPTY,A
     1 P3E_CPU0_PE1_SS_TXP<3> @BASEBOARD_FAB2_LIB.BASEBOARD_FAB2(SCH_1):P3E_CPU0_PE1_SS_TXP(3)   I435 @BASEBOARD_FAB2_LIB.BASEBOARD_FAB2(SCH_1):PAGE107
     2 P3E_CPU0_PE1_SS_C_TXP<3> @BASEBOARD_FAB2_LIB.BASEBOARD_FAB2(SCH_1):P3E_CPU0_PE1_SS_C_TXP(3)   I435 @BASEBOARD_FAB2_LIB.BASEBOARD_FAB2(SCH_1):PAGE107

C3P23 CAP_0402-0.22UF,16V,10%,X7R,A3A
     1 P3E_CPU0_PE1_SS_TXP<3> @BASEBOARD_FAB2_LIB.BASEBOARD_FAB2(SCH_1):P3E_CPU0_PE1_SS_TXP(3)   I229 @BASEBOARD_FAB2_LIB.BASEBOARD_FAB2(SCH_1):PAGE107
     2 P3E_CPU0_PE1_PCH_TXP<3> @BASEBOARD_FAB2_LIB.BASEBOARD_FAB2(SCH_1):P3E_CPU0_PE1_PCH_TXP(3)   I229 @BASEBOARD_FAB2_LIB.BASEBOARD_FAB2(SCH_1):PAGE107

C3P24 CAP_0402-0.22UF,16V,10%,EMPTY,A
     1 P3E_CPU0_PE1_SS_TXN<3> @BASEBOARD_FAB2_LIB.BASEBOARD_FAB2(SCH_1):P3E_CPU0_PE1_SS_TXN(3)   I424 @BASEBOARD_FAB2_LIB.BASEBOARD_FAB2(SCH_1):PAGE107
     2 P3E_CPU0_PE1_SS_C_TXN<3> @BASEBOARD_FAB2_LIB.BASEBOARD_FAB2(SCH_1):P3E_CPU0_PE1_SS_C_TXN(3)   I424 @BASEBOARD_FAB2_LIB.BASEBOARD_FAB2(SCH_1):PAGE107

C3P25 CAP_0402-0.22UF,16V,10%,X7R,A3A
     1 P3E_CPU0_PE1_SS_TXN<3> @BASEBOARD_FAB2_LIB.BASEBOARD_FAB2(SCH_1):P3E_CPU0_PE1_SS_TXN(3)   I216 @BASEBOARD_FAB2_LIB.BASEBOARD_FAB2(SCH_1):PAGE107
     2 P3E_CPU0_PE1_PCH_TXN<3> @BASEBOARD_FAB2_LIB.BASEBOARD_FAB2(SCH_1):P3E_CPU0_PE1_PCH_TXN(3)   I216 @BASEBOARD_FAB2_LIB.BASEBOARD_FAB2(SCH_1):PAGE107

C3P26 CAP_0402-0.22UF,16V,10%,EMPTY,A
     1 P3E_CPU0_PE1_SS_TXP<4> @BASEBOARD_FAB2_LIB.BASEBOARD_FAB2(SCH_1):P3E_CPU0_PE1_SS_TXP(4)   I444 @BASEBOARD_FAB2_LIB.BASEBOARD_FAB2(SCH_1):PAGE107
     2 P3E_CPU0_PE1_SS_C_TXP<4> @BASEBOARD_FAB2_LIB.BASEBOARD_FAB2(SCH_1):P3E_CPU0_PE1_SS_C_TXP(4)   I444 @BASEBOARD_FAB2_LIB.BASEBOARD_FAB2(SCH_1):PAGE107

C3P27 CAP_0402-0.22UF,16V,10%,X7R,A3A
     1 P3E_CPU0_PE1_SS_TXP<4> @BASEBOARD_FAB2_LIB.BASEBOARD_FAB2(SCH_1):P3E_CPU0_PE1_SS_TXP(4)   I223 @BASEBOARD_FAB2_LIB.BASEBOARD_FAB2(SCH_1):PAGE107
     2 P3E_CPU0_PE1_PCH_TXP<4> @BASEBOARD_FAB2_LIB.BASEBOARD_FAB2(SCH_1):P3E_CPU0_PE1_PCH_TXP(4)   I223 @BASEBOARD_FAB2_LIB.BASEBOARD_FAB2(SCH_1):PAGE107

C3P28 CAP_0402-0.22UF,16V,10%,X7R,A3A
     1 P3E_CPU0_PE1_SS_TXN<4> @BASEBOARD_FAB2_LIB.BASEBOARD_FAB2(SCH_1):P3E_CPU0_PE1_SS_TXN(4)   I232 @BASEBOARD_FAB2_LIB.BASEBOARD_FAB2(SCH_1):PAGE107
     2 P3E_CPU0_PE1_PCH_TXN<4> @BASEBOARD_FAB2_LIB.BASEBOARD_FAB2(SCH_1):P3E_CPU0_PE1_PCH_TXN(4)   I232 @BASEBOARD_FAB2_LIB.BASEBOARD_FAB2(SCH_1):PAGE107

C3P29 CAP_0402-0.22UF,16V,10%,EMPTY,A
     1 P3E_CPU0_PE1_SS_TXN<4> @BASEBOARD_FAB2_LIB.BASEBOARD_FAB2(SCH_1):P3E_CPU0_PE1_SS_TXN(4)   I437 @BASEBOARD_FAB2_LIB.BASEBOARD_FAB2(SCH_1):PAGE107
     2 P3E_CPU0_PE1_SS_C_TXN<4> @BASEBOARD_FAB2_LIB.BASEBOARD_FAB2(SCH_1):P3E_CPU0_PE1_SS_C_TXN(4)   I437 @BASEBOARD_FAB2_LIB.BASEBOARD_FAB2(SCH_1):PAGE107

C3P30 CAP_0402-0.22UF,16V,10%,X7R,A3A
     1 P3E_CPU0_PE1_SS_TXP<5> @BASEBOARD_FAB2_LIB.BASEBOARD_FAB2(SCH_1):P3E_CPU0_PE1_SS_TXP(5)   I245 @BASEBOARD_FAB2_LIB.BASEBOARD_FAB2(SCH_1):PAGE107
     2 P3E_CPU0_PE1_PCH_TXP<5> @BASEBOARD_FAB2_LIB.BASEBOARD_FAB2(SCH_1):P3E_CPU0_PE1_PCH_TXP(5)   I245 @BASEBOARD_FAB2_LIB.BASEBOARD_FAB2(SCH_1):PAGE107

C3P31 CAP_0402-0.22UF,16V,10%,EMPTY,A
     1 P3E_CPU0_PE1_SS_TXP<5> @BASEBOARD_FAB2_LIB.BASEBOARD_FAB2(SCH_1):P3E_CPU0_PE1_SS_TXP(5)   I452 @BASEBOARD_FAB2_LIB.BASEBOARD_FAB2(SCH_1):PAGE107
     2 P3E_CPU0_PE1_SS_C_TXP<5> @BASEBOARD_FAB2_LIB.BASEBOARD_FAB2(SCH_1):P3E_CPU0_PE1_SS_C_TXP(5)   I452 @BASEBOARD_FAB2_LIB.BASEBOARD_FAB2(SCH_1):PAGE107

C3P32 CAP_0402-0.22UF,16V,10%,X7R,A3A
     1 P3E_CPU0_PE1_SS_TXN<5> @BASEBOARD_FAB2_LIB.BASEBOARD_FAB2(SCH_1):P3E_CPU0_PE1_SS_TXN(5)   I234 @BASEBOARD_FAB2_LIB.BASEBOARD_FAB2(SCH_1):PAGE107
     2 P3E_CPU0_PE1_PCH_TXN<5> @BASEBOARD_FAB2_LIB.BASEBOARD_FAB2(SCH_1):P3E_CPU0_PE1_PCH_TXN(5)   I234 @BASEBOARD_FAB2_LIB.BASEBOARD_FAB2(SCH_1):PAGE107

C3P33 CAP_0402-0.22UF,16V,10%,EMPTY,A
     1 P3E_CPU0_PE1_SS_TXN<5> @BASEBOARD_FAB2_LIB.BASEBOARD_FAB2(SCH_1):P3E_CPU0_PE1_SS_TXN(5)   I439 @BASEBOARD_FAB2_LIB.BASEBOARD_FAB2(SCH_1):PAGE107
     2 P3E_CPU0_PE1_SS_C_TXN<5> @BASEBOARD_FAB2_LIB.BASEBOARD_FAB2(SCH_1):P3E_CPU0_PE1_SS_C_TXN(5)   I439 @BASEBOARD_FAB2_LIB.BASEBOARD_FAB2(SCH_1):PAGE107

C3P34 CAP_0402-0.22UF,16V,10%,EMPTY,A
     1 P3E_CPU0_PE1_SS_TXP<6> @BASEBOARD_FAB2_LIB.BASEBOARD_FAB2(SCH_1):P3E_CPU0_PE1_SS_TXP(6)   I447 @BASEBOARD_FAB2_LIB.BASEBOARD_FAB2(SCH_1):PAGE107
     2 P3E_CPU0_PE1_SS_C_TXP<6> @BASEBOARD_FAB2_LIB.BASEBOARD_FAB2(SCH_1):P3E_CPU0_PE1_SS_C_TXP(6)   I447 @BASEBOARD_FAB2_LIB.BASEBOARD_FAB2(SCH_1):PAGE107

C3P35 CAP_0402-0.22UF,16V,10%,X7R,A3A
     1 P3E_CPU0_PE1_SS_TXP<6> @BASEBOARD_FAB2_LIB.BASEBOARD_FAB2(SCH_1):P3E_CPU0_PE1_SS_TXP(6)   I240 @BASEBOARD_FAB2_LIB.BASEBOARD_FAB2(SCH_1):PAGE107
     2 P3E_CPU0_PE1_PCH_TXP<6> @BASEBOARD_FAB2_LIB.BASEBOARD_FAB2(SCH_1):P3E_CPU0_PE1_PCH_TXP(6)   I240 @BASEBOARD_FAB2_LIB.BASEBOARD_FAB2(SCH_1):PAGE107

C3P36 CAP_0402-0.22UF,16V,10%,EMPTY,A
     1 P3E_CPU0_PE1_SS_TXN<6> @BASEBOARD_FAB2_LIB.BASEBOARD_FAB2(SCH_1):P3E_CPU0_PE1_SS_TXN(6)   I438 @BASEBOARD_FAB2_LIB.BASEBOARD_FAB2(SCH_1):PAGE107
     2 P3E_CPU0_PE1_SS_C_TXN<6> @BASEBOARD_FAB2_LIB.BASEBOARD_FAB2(SCH_1):P3E_CPU0_PE1_SS_C_TXN(6)   I438 @BASEBOARD_FAB2_LIB.BASEBOARD_FAB2(SCH_1):PAGE107

C3P37 CAP_0402-0.22UF,16V,10%,X7R,A3A
     1 P3E_CPU0_PE1_SS_TXN<6> @BASEBOARD_FAB2_LIB.BASEBOARD_FAB2(SCH_1):P3E_CPU0_PE1_SS_TXN(6)   I235 @BASEBOARD_FAB2_LIB.BASEBOARD_FAB2(SCH_1):PAGE107
     2 P3E_CPU0_PE1_PCH_TXN<6> @BASEBOARD_FAB2_LIB.BASEBOARD_FAB2(SCH_1):P3E_CPU0_PE1_PCH_TXN(6)   I235 @BASEBOARD_FAB2_LIB.BASEBOARD_FAB2(SCH_1):PAGE107

C3P38 CAP_0402-0.22UF,16V,10%,EMPTY,A
     1 P3E_CPU0_PE1_SS_TXP<7> @BASEBOARD_FAB2_LIB.BASEBOARD_FAB2(SCH_1):P3E_CPU0_PE1_SS_TXP(7)   I455 @BASEBOARD_FAB2_LIB.BASEBOARD_FAB2(SCH_1):PAGE107
     2 P3E_CPU0_PE1_SS_C_TXP<7> @BASEBOARD_FAB2_LIB.BASEBOARD_FAB2(SCH_1):P3E_CPU0_PE1_SS_C_TXP(7)   I455 @BASEBOARD_FAB2_LIB.BASEBOARD_FAB2(SCH_1):PAGE107

C3P39 CAP_0402-0.22UF,16V,10%,X7R,A3A
     1 P3E_CPU0_PE1_SS_TXP<7> @BASEBOARD_FAB2_LIB.BASEBOARD_FAB2(SCH_1):P3E_CPU0_PE1_SS_TXP(7)   I248 @BASEBOARD_FAB2_LIB.BASEBOARD_FAB2(SCH_1):PAGE107
     2 P3E_CPU0_PE1_PCH_TXP<7> @BASEBOARD_FAB2_LIB.BASEBOARD_FAB2(SCH_1):P3E_CPU0_PE1_PCH_TXP(7)   I248 @BASEBOARD_FAB2_LIB.BASEBOARD_FAB2(SCH_1):PAGE107

C3P40 CAP_0402-0.22UF,16V,10%,X7R,A3A
     1 P3E_CPU0_PE1_SS_TXN<7> @BASEBOARD_FAB2_LIB.BASEBOARD_FAB2(SCH_1):P3E_CPU0_PE1_SS_TXN(7)   I241 @BASEBOARD_FAB2_LIB.BASEBOARD_FAB2(SCH_1):PAGE107
     2 P3E_CPU0_PE1_PCH_TXN<7> @BASEBOARD_FAB2_LIB.BASEBOARD_FAB2(SCH_1):P3E_CPU0_PE1_PCH_TXN(7)   I241 @BASEBOARD_FAB2_LIB.BASEBOARD_FAB2(SCH_1):PAGE107

C3P41 CAP_0402-0.22UF,16V,10%,EMPTY,A
     1 P3E_CPU0_PE1_SS_TXN<7> @BASEBOARD_FAB2_LIB.BASEBOARD_FAB2(SCH_1):P3E_CPU0_PE1_SS_TXN(7)   I448 @BASEBOARD_FAB2_LIB.BASEBOARD_FAB2(SCH_1):PAGE107
     2 P3E_CPU0_PE1_SS_C_TXN<7> @BASEBOARD_FAB2_LIB.BASEBOARD_FAB2(SCH_1):P3E_CPU0_PE1_SS_C_TXN(7)   I448 @BASEBOARD_FAB2_LIB.BASEBOARD_FAB2(SCH_1):PAGE107

C3P42 CAP_A_0402V-1.0UF,6.3V,10%,X6SA
     1 P3V3_STBY @BASEBOARD_FAB2_LIB.BASEBOARD_FAB2(SCH_1):P3V3_STBY    I73 @BASEBOARD_FAB2_LIB.BASEBOARD_FAB2(SCH_1):PAGE96
     2    GND @BASEBOARD_FAB2_LIB.BASEBOARD_FAB2(SCH_1):GND    I73 @BASEBOARD_FAB2_LIB.BASEBOARD_FAB2(SCH_1):PAGE96

C3P43 CAP_A_0402V-0.1UF,16V,10%,X7R,A
     1 P3V3_STBY @BASEBOARD_FAB2_LIB.BASEBOARD_FAB2(SCH_1):P3V3_STBY     I6 @BASEBOARD_FAB2_LIB.BASEBOARD_FAB2(SCH_1):PAGE192
     2    GND @BASEBOARD_FAB2_LIB.BASEBOARD_FAB2(SCH_1):GND     I6 @BASEBOARD_FAB2_LIB.BASEBOARD_FAB2(SCH_1):PAGE192

C3P44 CAP_A_0402V-0.1UF,16V,10%,X7R,A
     1 P3V3_STBY @BASEBOARD_FAB2_LIB.BASEBOARD_FAB2(SCH_1):P3V3_STBY    I23 @BASEBOARD_FAB2_LIB.BASEBOARD_FAB2(SCH_1):PAGE192
     2    GND @BASEBOARD_FAB2_LIB.BASEBOARD_FAB2(SCH_1):GND    I23 @BASEBOARD_FAB2_LIB.BASEBOARD_FAB2(SCH_1):PAGE192

C3P45 CAP_0402-0.047UF,25V,10%,X7R,AA
     1 A_ADM1085_CEXT @BASEBOARD_FAB2_LIB.BASEBOARD_FAB2(SCH_1):A_ADM1085_CEXT    I60 @BASEBOARD_FAB2_LIB.BASEBOARD_FAB2(SCH_1):PAGE196
     2    GND @BASEBOARD_FAB2_LIB.BASEBOARD_FAB2(SCH_1):GND    I60 @BASEBOARD_FAB2_LIB.BASEBOARD_FAB2(SCH_1):PAGE196

C3P46 CAP_A_0402V-0.1UF,16V,10%,X7R,A
     1 P3V3_STBY @BASEBOARD_FAB2_LIB.BASEBOARD_FAB2(SCH_1):P3V3_STBY    I72 @BASEBOARD_FAB2_LIB.BASEBOARD_FAB2(SCH_1):PAGE196
     2    GND @BASEBOARD_FAB2_LIB.BASEBOARD_FAB2(SCH_1):GND    I72 @BASEBOARD_FAB2_LIB.BASEBOARD_FAB2(SCH_1):PAGE196

C3P47 CAP_A_0402V-0.1UF,16V,10%,X7R,A
     1 P3V3_STBY @BASEBOARD_FAB2_LIB.BASEBOARD_FAB2(SCH_1):P3V3_STBY    I12 @BASEBOARD_FAB2_LIB.BASEBOARD_FAB2(SCH_1):PAGE192
     2    GND @BASEBOARD_FAB2_LIB.BASEBOARD_FAB2(SCH_1):GND    I12 @BASEBOARD_FAB2_LIB.BASEBOARD_FAB2(SCH_1):PAGE192

C3P48 CAP_A_0402V-0.1UF,16V,10%,X7R,A
     1 P3V3_STBY @BASEBOARD_FAB2_LIB.BASEBOARD_FAB2(SCH_1):P3V3_STBY    I25 @BASEBOARD_FAB2_LIB.BASEBOARD_FAB2(SCH_1):PAGE192
     2    GND @BASEBOARD_FAB2_LIB.BASEBOARD_FAB2(SCH_1):GND    I25 @BASEBOARD_FAB2_LIB.BASEBOARD_FAB2(SCH_1):PAGE192

C3P49 CAP_A_0402V-0.1UF,16V,10%,X7R,A
     1 P0V7_GTL2104_VREF_1 @BASEBOARD_FAB2_LIB.BASEBOARD_FAB2(SCH_1):P0V7_GTL2104_VREF_1    I37 @BASEBOARD_FAB2_LIB.BASEBOARD_FAB2(SCH_1):PAGE92
     2    GND @BASEBOARD_FAB2_LIB.BASEBOARD_FAB2(SCH_1):GND    I37 @BASEBOARD_FAB2_LIB.BASEBOARD_FAB2(SCH_1):PAGE92

C3P50 CAP_0402-1.0UF,16V,10%,X6S,D97A
     1   P3V3 @BASEBOARD_FAB2_LIB.BASEBOARD_FAB2(SCH_1):P3V3    I84 @BASEBOARD_FAB2_LIB.BASEBOARD_FAB2(SCH_1):PAGE92
     2    GND @BASEBOARD_FAB2_LIB.BASEBOARD_FAB2(SCH_1):GND    I84 @BASEBOARD_FAB2_LIB.BASEBOARD_FAB2(SCH_1):PAGE92

C3P51 CAP_A_0402V-0.1UF,16V,10%,X7R,A
     1 P3V3_STBY @BASEBOARD_FAB2_LIB.BASEBOARD_FAB2(SCH_1):P3V3_STBY    I11 @BASEBOARD_FAB2_LIB.BASEBOARD_FAB2(SCH_1):PAGE192
     2    GND @BASEBOARD_FAB2_LIB.BASEBOARD_FAB2(SCH_1):GND    I11 @BASEBOARD_FAB2_LIB.BASEBOARD_FAB2(SCH_1):PAGE192

C3P52 CAP_A_0402V-0.1UF,16V,10%,X7R,A
     1 P3V3_STBY @BASEBOARD_FAB2_LIB.BASEBOARD_FAB2(SCH_1):P3V3_STBY    I17 @BASEBOARD_FAB2_LIB.BASEBOARD_FAB2(SCH_1):PAGE192
     2    GND @BASEBOARD_FAB2_LIB.BASEBOARD_FAB2(SCH_1):GND    I17 @BASEBOARD_FAB2_LIB.BASEBOARD_FAB2(SCH_1):PAGE192

C3R1 CAP_A_0402V-0.1UF,16V,10%,X7R,A
     1 P3V3_STBY @BASEBOARD_FAB2_LIB.BASEBOARD_FAB2(SCH_1):P3V3_STBY     I4 @BASEBOARD_FAB2_LIB.BASEBOARD_FAB2(SCH_1):PAGE192
     2    GND @BASEBOARD_FAB2_LIB.BASEBOARD_FAB2(SCH_1):GND     I4 @BASEBOARD_FAB2_LIB.BASEBOARD_FAB2(SCH_1):PAGE192

C3R2 CAP_A_0402V-0.1UF,16V,10%,X7R,A
     1 P3V3_STBY @BASEBOARD_FAB2_LIB.BASEBOARD_FAB2(SCH_1):P3V3_STBY    I10 @BASEBOARD_FAB2_LIB.BASEBOARD_FAB2(SCH_1):PAGE192
     2    GND @BASEBOARD_FAB2_LIB.BASEBOARD_FAB2(SCH_1):GND    I10 @BASEBOARD_FAB2_LIB.BASEBOARD_FAB2(SCH_1):PAGE192

C3R3 CAP_A_0402V-0.1UF,16V,10%,X7R,A
     1 P3V3_STBY @BASEBOARD_FAB2_LIB.BASEBOARD_FAB2(SCH_1):P3V3_STBY     I7 @BASEBOARD_FAB2_LIB.BASEBOARD_FAB2(SCH_1):PAGE192
     2    GND @BASEBOARD_FAB2_LIB.BASEBOARD_FAB2(SCH_1):GND     I7 @BASEBOARD_FAB2_LIB.BASEBOARD_FAB2(SCH_1):PAGE192

C3R4 CAPP_3018-470UF,2.5V,20%,ALUM,A
     1 PVCCMCP_CPU0 @BASEBOARD_FAB2_LIB.BASEBOARD_FAB2(SCH_1):PVCCMCP_CPU0    I31 @BASEBOARD_FAB2_LIB.BASEBOARD_FAB2(SCH_1):PAGE194
     2    GND @BASEBOARD_FAB2_LIB.BASEBOARD_FAB2(SCH_1):GND    I31 @BASEBOARD_FAB2_LIB.BASEBOARD_FAB2(SCH_1):PAGE194

C3T1 CAP_A_0603V-47UF,4V,20%,X5R,60A
     1 P1V8_MCP_CPU0 @BASEBOARD_FAB2_LIB.BASEBOARD_FAB2(SCH_1):P1V8_MCP_CPU0   I149 @BASEBOARD_FAB2_LIB.BASEBOARD_FAB2(SCH_1):PAGE194
     2    GND @BASEBOARD_FAB2_LIB.BASEBOARD_FAB2(SCH_1):GND   I149 @BASEBOARD_FAB2_LIB.BASEBOARD_FAB2(SCH_1):PAGE194

C3T2 CAP_A_0603V-47UF,4V,20%,X5R,60A
     1 P1V8_MCP_CPU0 @BASEBOARD_FAB2_LIB.BASEBOARD_FAB2(SCH_1):P1V8_MCP_CPU0   I150 @BASEBOARD_FAB2_LIB.BASEBOARD_FAB2(SCH_1):PAGE194
     2    GND @BASEBOARD_FAB2_LIB.BASEBOARD_FAB2(SCH_1):GND   I150 @BASEBOARD_FAB2_LIB.BASEBOARD_FAB2(SCH_1):PAGE194

C3T3 CAPP_3018-68UF,16V,20%,TANT,72A
     1 P12V_STBY @BASEBOARD_FAB2_LIB.BASEBOARD_FAB2(SCH_1):P12V_STBY   I113 @BASEBOARD_FAB2_LIB.BASEBOARD_FAB2(SCH_1):PAGE195
     2    GND @BASEBOARD_FAB2_LIB.BASEBOARD_FAB2(SCH_1):GND   I113 @BASEBOARD_FAB2_LIB.BASEBOARD_FAB2(SCH_1):PAGE195

C3T4 CAP_A_0402V-1.0UF,6.3V,10%,X6SA
     1 P3V3_STBY @BASEBOARD_FAB2_LIB.BASEBOARD_FAB2(SCH_1):P3V3_STBY   I138 @BASEBOARD_FAB2_LIB.BASEBOARD_FAB2(SCH_1):PAGE153
     2    GND @BASEBOARD_FAB2_LIB.BASEBOARD_FAB2(SCH_1):GND   I138 @BASEBOARD_FAB2_LIB.BASEBOARD_FAB2(SCH_1):PAGE153

C3T5 CAP_A_0402V-0.01UF,25V,10%,X7RA
     1 P3V3_STBY @BASEBOARD_FAB2_LIB.BASEBOARD_FAB2(SCH_1):P3V3_STBY   I136 @BASEBOARD_FAB2_LIB.BASEBOARD_FAB2(SCH_1):PAGE153
     2    GND @BASEBOARD_FAB2_LIB.BASEBOARD_FAB2(SCH_1):GND   I136 @BASEBOARD_FAB2_LIB.BASEBOARD_FAB2(SCH_1):PAGE153

C3T6 CAPP_3018-68UF,16V,20%,TANT,72A
     1 P12V_STBY @BASEBOARD_FAB2_LIB.BASEBOARD_FAB2(SCH_1):P12V_STBY    I98 @BASEBOARD_FAB2_LIB.BASEBOARD_FAB2(SCH_1):PAGE195
     2    GND @BASEBOARD_FAB2_LIB.BASEBOARD_FAB2(SCH_1):GND    I98 @BASEBOARD_FAB2_LIB.BASEBOARD_FAB2(SCH_1):PAGE195

C3T7 CAP_0805-47UF,4V,20%,X6S,C9533A
     1 PVPP_ABC @BASEBOARD_FAB2_LIB.BASEBOARD_FAB2(SCH_1):PVPP_ABC   I184 @BASEBOARD_FAB2_LIB.BASEBOARD_FAB2(SCH_1):PAGE231
     2    GND @BASEBOARD_FAB2_LIB.BASEBOARD_FAB2(SCH_1):GND   I184 @BASEBOARD_FAB2_LIB.BASEBOARD_FAB2(SCH_1):PAGE231

C3T8 CAP_0805-10UF,16V,10%,X6S,C953A
     1 VR_FET_SW_P12V_STBY_PVPP_ABC @BASEBOARD_FAB2_LIB.BASEBOARD_FAB2(SCH_1):VR_FET_SW_P12V_STBY_PVPP_ABC   I210 @BASEBOARD_FAB2_LIB.BASEBOARD_FAB2(SCH_1):PAGE231
     2    GND @BASEBOARD_FAB2_LIB.BASEBOARD_FAB2(SCH_1):GND   I210 @BASEBOARD_FAB2_LIB.BASEBOARD_FAB2(SCH_1):PAGE231

C3T9 CAP_0805-47UF,4V,20%,X6S,C9533A
     1 PVPP_ABC @BASEBOARD_FAB2_LIB.BASEBOARD_FAB2(SCH_1):PVPP_ABC   I186 @BASEBOARD_FAB2_LIB.BASEBOARD_FAB2(SCH_1):PAGE231
     2    GND @BASEBOARD_FAB2_LIB.BASEBOARD_FAB2(SCH_1):GND   I186 @BASEBOARD_FAB2_LIB.BASEBOARD_FAB2(SCH_1):PAGE231

C3T10 CAP_0402-1.0UF,16V,10%,X6S,D97A
     1 VR_FET_SW_P12V_STBY_PVPP_ABC @BASEBOARD_FAB2_LIB.BASEBOARD_FAB2(SCH_1):VR_FET_SW_P12V_STBY_PVPP_ABC   I161 @BASEBOARD_FAB2_LIB.BASEBOARD_FAB2(SCH_1):PAGE231
     2    GND @BASEBOARD_FAB2_LIB.BASEBOARD_FAB2(SCH_1):GND   I161 @BASEBOARD_FAB2_LIB.BASEBOARD_FAB2(SCH_1):PAGE231

C3T11 CAP_0603-4.7UF,6.3V,10%,X6S,E1A
     1 VR_VB_PVPP_ABC @BASEBOARD_FAB2_LIB.BASEBOARD_FAB2(SCH_1):VR_VB_PVPP_ABC   I202 @BASEBOARD_FAB2_LIB.BASEBOARD_FAB2(SCH_1):PAGE231
     2 AGND_PVPP_ABC @BASEBOARD_FAB2_LIB.BASEBOARD_FAB2(SCH_1):AGND_PVPP_ABC   I202 @BASEBOARD_FAB2_LIB.BASEBOARD_FAB2(SCH_1):PAGE231

C3T12 CAP_0805-10UF,16V,10%,X6S,C953A
     1 VR_FET_SW_P12V_STBY_PVPP_ABC @BASEBOARD_FAB2_LIB.BASEBOARD_FAB2(SCH_1):VR_FET_SW_P12V_STBY_PVPP_ABC   I215 @BASEBOARD_FAB2_LIB.BASEBOARD_FAB2(SCH_1):PAGE231
     2    GND @BASEBOARD_FAB2_LIB.BASEBOARD_FAB2(SCH_1):GND   I215 @BASEBOARD_FAB2_LIB.BASEBOARD_FAB2(SCH_1):PAGE231

C3T13 CAPP_3018-68UF,16V,20%,TANT,72A
     1 P12V_STBY @BASEBOARD_FAB2_LIB.BASEBOARD_FAB2(SCH_1):P12V_STBY   I104 @BASEBOARD_FAB2_LIB.BASEBOARD_FAB2(SCH_1):PAGE195
     2    GND @BASEBOARD_FAB2_LIB.BASEBOARD_FAB2(SCH_1):GND   I104 @BASEBOARD_FAB2_LIB.BASEBOARD_FAB2(SCH_1):PAGE195

C3T14 CAP_0805-10UF,16V,10%,X6S,C953A
     1 VR_FET_SW_P12V_STBY_PVPP_ABC @BASEBOARD_FAB2_LIB.BASEBOARD_FAB2(SCH_1):VR_FET_SW_P12V_STBY_PVPP_ABC   I211 @BASEBOARD_FAB2_LIB.BASEBOARD_FAB2(SCH_1):PAGE231
     2    GND @BASEBOARD_FAB2_LIB.BASEBOARD_FAB2(SCH_1):GND   I211 @BASEBOARD_FAB2_LIB.BASEBOARD_FAB2(SCH_1):PAGE231

C3T15 CAPP_3018-68UF,16V,20%,TANT,72A
     1 P12V_STBY @BASEBOARD_FAB2_LIB.BASEBOARD_FAB2(SCH_1):P12V_STBY   I106 @BASEBOARD_FAB2_LIB.BASEBOARD_FAB2(SCH_1):PAGE195
     2    GND @BASEBOARD_FAB2_LIB.BASEBOARD_FAB2(SCH_1):GND   I106 @BASEBOARD_FAB2_LIB.BASEBOARD_FAB2(SCH_1):PAGE195

C3U1 CAPP_3018-470UF,2.5V,20%,ALUM,A
     1 PVDDQ_ABC @BASEBOARD_FAB2_LIB.BASEBOARD_FAB2(SCH_1):PVDDQ_ABC    I76 @BASEBOARD_FAB2_LIB.BASEBOARD_FAB2(SCH_1):PAGE217
     2    GND @BASEBOARD_FAB2_LIB.BASEBOARD_FAB2(SCH_1):GND    I76 @BASEBOARD_FAB2_LIB.BASEBOARD_FAB2(SCH_1):PAGE217

C3U2 CAP_0805-10UF,16V,10%,X6S,C953A
     1 VR_FET_SW_P12V_STBY_PVDDQ_ABC @BASEBOARD_FAB2_LIB.BASEBOARD_FAB2(SCH_1):VR_FET_SW_P12V_STBY_PVDDQ_ABC    I45 @BASEBOARD_FAB2_LIB.BASEBOARD_FAB2(SCH_1):PAGE216
     2    GND @BASEBOARD_FAB2_LIB.BASEBOARD_FAB2(SCH_1):GND    I45 @BASEBOARD_FAB2_LIB.BASEBOARD_FAB2(SCH_1):PAGE216

C3U3 CAP_0805-10UF,16V,10%,X6S,C953A
     1 VR_FET_SW_P12V_STBY_PVDDQ_ABC @BASEBOARD_FAB2_LIB.BASEBOARD_FAB2(SCH_1):VR_FET_SW_P12V_STBY_PVDDQ_ABC    I46 @BASEBOARD_FAB2_LIB.BASEBOARD_FAB2(SCH_1):PAGE216
     2    GND @BASEBOARD_FAB2_LIB.BASEBOARD_FAB2(SCH_1):GND    I46 @BASEBOARD_FAB2_LIB.BASEBOARD_FAB2(SCH_1):PAGE216

C3U4 CAP_0805-10UF,16V,10%,X6S,C953A
     1 VR_FET_SW_P12V_STBY_PVDDQ_ABC @BASEBOARD_FAB2_LIB.BASEBOARD_FAB2(SCH_1):VR_FET_SW_P12V_STBY_PVDDQ_ABC    I47 @BASEBOARD_FAB2_LIB.BASEBOARD_FAB2(SCH_1):PAGE216
     2    GND @BASEBOARD_FAB2_LIB.BASEBOARD_FAB2(SCH_1):GND    I47 @BASEBOARD_FAB2_LIB.BASEBOARD_FAB2(SCH_1):PAGE216

C3U5 CAPP_3018-470UF,2.5V,20%,ALUM,A
     1 PVDDQ_ABC @BASEBOARD_FAB2_LIB.BASEBOARD_FAB2(SCH_1):PVDDQ_ABC    I77 @BASEBOARD_FAB2_LIB.BASEBOARD_FAB2(SCH_1):PAGE217
     2    GND @BASEBOARD_FAB2_LIB.BASEBOARD_FAB2(SCH_1):GND    I77 @BASEBOARD_FAB2_LIB.BASEBOARD_FAB2(SCH_1):PAGE217

C3U6 CAP_0805-10UF,16V,10%,X6S,C953A
     1 VR_FET_SW_P12V_STBY_PVDDQ_ABC @BASEBOARD_FAB2_LIB.BASEBOARD_FAB2(SCH_1):VR_FET_SW_P12V_STBY_PVDDQ_ABC    I84 @BASEBOARD_FAB2_LIB.BASEBOARD_FAB2(SCH_1):PAGE216
     2    GND @BASEBOARD_FAB2_LIB.BASEBOARD_FAB2(SCH_1):GND    I84 @BASEBOARD_FAB2_LIB.BASEBOARD_FAB2(SCH_1):PAGE216

C3U7 CAP_0805-10UF,16V,10%,X6S,C953A
     1 VR_FET_SW_P12V_STBY_PVDDQ_ABC @BASEBOARD_FAB2_LIB.BASEBOARD_FAB2(SCH_1):VR_FET_SW_P12V_STBY_PVDDQ_ABC    I81 @BASEBOARD_FAB2_LIB.BASEBOARD_FAB2(SCH_1):PAGE216
     2    GND @BASEBOARD_FAB2_LIB.BASEBOARD_FAB2(SCH_1):GND    I81 @BASEBOARD_FAB2_LIB.BASEBOARD_FAB2(SCH_1):PAGE216

C3U8 CAPP_3018-470UF,2.5V,20%,ALUM,A
     1 PVDDQ_ABC @BASEBOARD_FAB2_LIB.BASEBOARD_FAB2(SCH_1):PVDDQ_ABC    I78 @BASEBOARD_FAB2_LIB.BASEBOARD_FAB2(SCH_1):PAGE217
     2    GND @BASEBOARD_FAB2_LIB.BASEBOARD_FAB2(SCH_1):GND    I78 @BASEBOARD_FAB2_LIB.BASEBOARD_FAB2(SCH_1):PAGE217

C3U9 CAP_0805-10UF,16V,10%,X6S,C953A
     1 VR_FET_SW_P12V_STBY_PVDDQ_ABC @BASEBOARD_FAB2_LIB.BASEBOARD_FAB2(SCH_1):VR_FET_SW_P12V_STBY_PVDDQ_ABC    I80 @BASEBOARD_FAB2_LIB.BASEBOARD_FAB2(SCH_1):PAGE216
     2    GND @BASEBOARD_FAB2_LIB.BASEBOARD_FAB2(SCH_1):GND    I80 @BASEBOARD_FAB2_LIB.BASEBOARD_FAB2(SCH_1):PAGE216

C3U10 CAP_A_0402V-0.1UF,16V,10%,X7R,A
     1 VR_PVDDQ_ABC_AIINSEN @BASEBOARD_FAB2_LIB.BASEBOARD_FAB2(SCH_1):VR_PVDDQ_ABC_AIINSEN   I360 @BASEBOARD_FAB2_LIB.BASEBOARD_FAB2(SCH_1):PAGE215
     2    GND @BASEBOARD_FAB2_LIB.BASEBOARD_FAB2(SCH_1):GND   I360 @BASEBOARD_FAB2_LIB.BASEBOARD_FAB2(SCH_1):PAGE215

C4A1 CAP_0805LF-22UF,4V,20%,X6S,C95A
     1 PVTT_DEF @BASEBOARD_FAB2_LIB.BASEBOARD_FAB2(SCH_1):PVTT_DEF    I16 @BASEBOARD_FAB2_LIB.BASEBOARD_FAB2(SCH_1):PAGE222
     2    GND @BASEBOARD_FAB2_LIB.BASEBOARD_FAB2(SCH_1):GND    I16 @BASEBOARD_FAB2_LIB.BASEBOARD_FAB2(SCH_1):PAGE222

C4A2 CAP_0402LF-1000PF,50V,10%,EMPTA
     1 FM_PVTT_DEF_EN_R @BASEBOARD_FAB2_LIB.BASEBOARD_FAB2(SCH_1):FM_PVTT_DEF_EN_R    I40 @BASEBOARD_FAB2_LIB.BASEBOARD_FAB2(SCH_1):PAGE222
     2    GND @BASEBOARD_FAB2_LIB.BASEBOARD_FAB2(SCH_1):GND    I40 @BASEBOARD_FAB2_LIB.BASEBOARD_FAB2(SCH_1):PAGE222

C4A3 CAP_0402LF-1000PF,50V,10%,X7R,A
     1 PWRGD_PVTT_KLM_CPU1_R @BASEBOARD_FAB2_LIB.BASEBOARD_FAB2(SCH_1):PWRGD_PVTT_KLM_CPU1_R    I16 @BASEBOARD_FAB2_LIB.BASEBOARD_FAB2(SCH_1):PAGE230
     2    GND @BASEBOARD_FAB2_LIB.BASEBOARD_FAB2(SCH_1):GND    I16 @BASEBOARD_FAB2_LIB.BASEBOARD_FAB2(SCH_1):PAGE230

C4A4 CAP_0805-10UF,16V,10%,X7R,G106A
     1 P12V_NVDIMM_DEF @BASEBOARD_FAB2_LIB.BASEBOARD_FAB2(SCH_1):P12V_NVDIMM_DEF    I62 @BASEBOARD_FAB2_LIB.BASEBOARD_FAB2(SCH_1):PAGE197
     2    GND @BASEBOARD_FAB2_LIB.BASEBOARD_FAB2(SCH_1):GND    I62 @BASEBOARD_FAB2_LIB.BASEBOARD_FAB2(SCH_1):PAGE197

C4A5 CAP_A_0402V-0.01UF,25V,10%,X7RA
     1 M_F_VREF @BASEBOARD_FAB2_LIB.BASEBOARD_FAB2(SCH_1):M_F_VREF   I179 @BASEBOARD_FAB2_LIB.BASEBOARD_FAB2(SCH_1):PAGE54
     2    GND @BASEBOARD_FAB2_LIB.BASEBOARD_FAB2(SCH_1):GND   I179 @BASEBOARD_FAB2_LIB.BASEBOARD_FAB2(SCH_1):PAGE54

C4A6 CAP_0402LF-1000PF,50V,10%,EMPTA
     1 FM_PVTT_KLM_EN_R @BASEBOARD_FAB2_LIB.BASEBOARD_FAB2(SCH_1):FM_PVTT_KLM_EN_R    I39 @BASEBOARD_FAB2_LIB.BASEBOARD_FAB2(SCH_1):PAGE230
     2    GND @BASEBOARD_FAB2_LIB.BASEBOARD_FAB2(SCH_1):GND    I39 @BASEBOARD_FAB2_LIB.BASEBOARD_FAB2(SCH_1):PAGE230

C4A7 CAP_0603-4.7UF,6.3V,10%,X6S,E1A
     1 VSENSE_PVDDQ_KLM_VTT @BASEBOARD_FAB2_LIB.BASEBOARD_FAB2(SCH_1):VSENSE_PVDDQ_KLM_VTT    I46 @BASEBOARD_FAB2_LIB.BASEBOARD_FAB2(SCH_1):PAGE230
     2    GND @BASEBOARD_FAB2_LIB.BASEBOARD_FAB2(SCH_1):GND    I46 @BASEBOARD_FAB2_LIB.BASEBOARD_FAB2(SCH_1):PAGE230

C4A8 CAP_0402-1.0UF,16V,10%,X6S,D97A
     1 VR_PVTT_KLM_BIAS @BASEBOARD_FAB2_LIB.BASEBOARD_FAB2(SCH_1):VR_PVTT_KLM_BIAS    I28 @BASEBOARD_FAB2_LIB.BASEBOARD_FAB2(SCH_1):PAGE230
     2    GND @BASEBOARD_FAB2_LIB.BASEBOARD_FAB2(SCH_1):GND    I28 @BASEBOARD_FAB2_LIB.BASEBOARD_FAB2(SCH_1):PAGE230

C4A9 CAP_0402-1.0UF,16V,10%,X6S,D97A
     1 VR_PVTT_DEF_VREF @BASEBOARD_FAB2_LIB.BASEBOARD_FAB2(SCH_1):VR_PVTT_DEF_VREF    I21 @BASEBOARD_FAB2_LIB.BASEBOARD_FAB2(SCH_1):PAGE222
     2    GND @BASEBOARD_FAB2_LIB.BASEBOARD_FAB2(SCH_1):GND    I21 @BASEBOARD_FAB2_LIB.BASEBOARD_FAB2(SCH_1):PAGE222

C4A10 CAP_0402-1.0UF,16V,10%,X6S,D97A
     1 VR_PVTT_DEF_BIAS @BASEBOARD_FAB2_LIB.BASEBOARD_FAB2(SCH_1):VR_PVTT_DEF_BIAS    I28 @BASEBOARD_FAB2_LIB.BASEBOARD_FAB2(SCH_1):PAGE222
     2    GND @BASEBOARD_FAB2_LIB.BASEBOARD_FAB2(SCH_1):GND    I28 @BASEBOARD_FAB2_LIB.BASEBOARD_FAB2(SCH_1):PAGE222

C4A11 CAP_0603-4.7UF,6.3V,10%,X6S,E1A
     1 VSENSE_PVDDQ_DEF_VTT @BASEBOARD_FAB2_LIB.BASEBOARD_FAB2(SCH_1):VSENSE_PVDDQ_DEF_VTT    I46 @BASEBOARD_FAB2_LIB.BASEBOARD_FAB2(SCH_1):PAGE222
     2    GND @BASEBOARD_FAB2_LIB.BASEBOARD_FAB2(SCH_1):GND    I46 @BASEBOARD_FAB2_LIB.BASEBOARD_FAB2(SCH_1):PAGE222

C4A12 CAP_0402LF-1000PF,50V,10%,X7R,A
     1 PWRGD_PVTT_DEF_CPU0_R @BASEBOARD_FAB2_LIB.BASEBOARD_FAB2(SCH_1):PWRGD_PVTT_DEF_CPU0_R    I12 @BASEBOARD_FAB2_LIB.BASEBOARD_FAB2(SCH_1):PAGE222
     2    GND @BASEBOARD_FAB2_LIB.BASEBOARD_FAB2(SCH_1):GND    I12 @BASEBOARD_FAB2_LIB.BASEBOARD_FAB2(SCH_1):PAGE222

C4A13 CAP_0805LF-22UF,4V,20%,X6S,C95A
     1 PVTT_KLM @BASEBOARD_FAB2_LIB.BASEBOARD_FAB2(SCH_1):PVTT_KLM    I18 @BASEBOARD_FAB2_LIB.BASEBOARD_FAB2(SCH_1):PAGE230
     2    GND @BASEBOARD_FAB2_LIB.BASEBOARD_FAB2(SCH_1):GND    I18 @BASEBOARD_FAB2_LIB.BASEBOARD_FAB2(SCH_1):PAGE230

C4A14 CAP_0402-1.0UF,16V,10%,X6S,D97A
     1 VR_PVTT_KLM_VREF @BASEBOARD_FAB2_LIB.BASEBOARD_FAB2(SCH_1):VR_PVTT_KLM_VREF    I21 @BASEBOARD_FAB2_LIB.BASEBOARD_FAB2(SCH_1):PAGE230
     2    GND @BASEBOARD_FAB2_LIB.BASEBOARD_FAB2(SCH_1):GND    I21 @BASEBOARD_FAB2_LIB.BASEBOARD_FAB2(SCH_1):PAGE230

C4A15 CAP_0603LF-10UF,4V,20%,X6S,E15A
     1 PVDDQ_KLM @BASEBOARD_FAB2_LIB.BASEBOARD_FAB2(SCH_1):PVDDQ_KLM    I25 @BASEBOARD_FAB2_LIB.BASEBOARD_FAB2(SCH_1):PAGE230
     2    GND @BASEBOARD_FAB2_LIB.BASEBOARD_FAB2(SCH_1):GND    I25 @BASEBOARD_FAB2_LIB.BASEBOARD_FAB2(SCH_1):PAGE230

C4A16 CAP_0402LF-3300PF,50V,10%,EMPTA
     1 VR_PVPP_KLM_PHASE @BASEBOARD_FAB2_LIB.BASEBOARD_FAB2(SCH_1):VR_PVPP_KLM_PHASE   I163 @BASEBOARD_FAB2_LIB.BASEBOARD_FAB2(SCH_1):PAGE234
     2 VR_PVPP_KLM_SNUB @BASEBOARD_FAB2_LIB.BASEBOARD_FAB2(SCH_1):VR_PVPP_KLM_SNUB   I163 @BASEBOARD_FAB2_LIB.BASEBOARD_FAB2(SCH_1):PAGE234

C4A17 CAP_0805-10UF,16V,10%,X7R,G106A
     1 P12V_NVDIMM_DEF @BASEBOARD_FAB2_LIB.BASEBOARD_FAB2(SCH_1):P12V_NVDIMM_DEF    I67 @BASEBOARD_FAB2_LIB.BASEBOARD_FAB2(SCH_1):PAGE197
     2    GND @BASEBOARD_FAB2_LIB.BASEBOARD_FAB2(SCH_1):GND    I67 @BASEBOARD_FAB2_LIB.BASEBOARD_FAB2(SCH_1):PAGE197

C4A18 CAP_A_0402V-0.01UF,25V,10%,X7RA
     1 M_E_VREF @BASEBOARD_FAB2_LIB.BASEBOARD_FAB2(SCH_1):M_E_VREF     I3 @BASEBOARD_FAB2_LIB.BASEBOARD_FAB2(SCH_1):PAGE52
     2    GND @BASEBOARD_FAB2_LIB.BASEBOARD_FAB2(SCH_1):GND     I3 @BASEBOARD_FAB2_LIB.BASEBOARD_FAB2(SCH_1):PAGE52

C4A19 CAP_0805-10UF,16V,10%,X6S,C953A
     1 VR_FET_SW_P12V_STBY_PVPP_KLM @BASEBOARD_FAB2_LIB.BASEBOARD_FAB2(SCH_1):VR_FET_SW_P12V_STBY_PVPP_KLM   I205 @BASEBOARD_FAB2_LIB.BASEBOARD_FAB2(SCH_1):PAGE234
     2    GND @BASEBOARD_FAB2_LIB.BASEBOARD_FAB2(SCH_1):GND   I205 @BASEBOARD_FAB2_LIB.BASEBOARD_FAB2(SCH_1):PAGE234

C4A20 CAP_A_0402V-0.1UF,16V,10%,X7R,A
     1 VR_FET_SW_P12V_STBY_PVPP_KLM @BASEBOARD_FAB2_LIB.BASEBOARD_FAB2(SCH_1):VR_FET_SW_P12V_STBY_PVPP_KLM   I199 @BASEBOARD_FAB2_LIB.BASEBOARD_FAB2(SCH_1):PAGE234
     2    GND @BASEBOARD_FAB2_LIB.BASEBOARD_FAB2(SCH_1):GND   I199 @BASEBOARD_FAB2_LIB.BASEBOARD_FAB2(SCH_1):PAGE234

C4B1 CAP_1210-47UF,16V,20%,X6S,D384A
     1 VR_FET_SW_P12V_STBY_PVPP_KLM @BASEBOARD_FAB2_LIB.BASEBOARD_FAB2(SCH_1):VR_FET_SW_P12V_STBY_PVPP_KLM   I130 @BASEBOARD_FAB2_LIB.BASEBOARD_FAB2(SCH_1):PAGE234
     2    GND @BASEBOARD_FAB2_LIB.BASEBOARD_FAB2(SCH_1):GND   I130 @BASEBOARD_FAB2_LIB.BASEBOARD_FAB2(SCH_1):PAGE234

C4B2 CAP_0805-47UF,4V,20%,X6S,C9533A
     1 PVPP_KLM @BASEBOARD_FAB2_LIB.BASEBOARD_FAB2(SCH_1):PVPP_KLM   I180 @BASEBOARD_FAB2_LIB.BASEBOARD_FAB2(SCH_1):PAGE234
     2    GND @BASEBOARD_FAB2_LIB.BASEBOARD_FAB2(SCH_1):GND   I180 @BASEBOARD_FAB2_LIB.BASEBOARD_FAB2(SCH_1):PAGE234

C4B3 CAP_0805-47UF,4V,20%,X6S,C9533A
     1 PVPP_KLM @BASEBOARD_FAB2_LIB.BASEBOARD_FAB2(SCH_1):PVPP_KLM   I177 @BASEBOARD_FAB2_LIB.BASEBOARD_FAB2(SCH_1):PAGE234
     2    GND @BASEBOARD_FAB2_LIB.BASEBOARD_FAB2(SCH_1):GND   I177 @BASEBOARD_FAB2_LIB.BASEBOARD_FAB2(SCH_1):PAGE234

C4B4 CAP_0402LF-100.0PF,50V,5%,COG,A
     1 VR_FB_PVPP_KLM @BASEBOARD_FAB2_LIB.BASEBOARD_FAB2(SCH_1):VR_FB_PVPP_KLM   I212 @BASEBOARD_FAB2_LIB.BASEBOARD_FAB2(SCH_1):PAGE234
     2 VR_COMP_PVPP_KLM_3 @BASEBOARD_FAB2_LIB.BASEBOARD_FAB2(SCH_1):VR_COMP_PVPP_KLM_3   I212 @BASEBOARD_FAB2_LIB.BASEBOARD_FAB2(SCH_1):PAGE234

C4B5 CAP_0402LF-1000PF,50V,10%,EMPTA
     1 FM_PVPP_CPU1_EN @BASEBOARD_FAB2_LIB.BASEBOARD_FAB2(SCH_1):FM_PVPP_CPU1_EN   I129 @BASEBOARD_FAB2_LIB.BASEBOARD_FAB2(SCH_1):PAGE234
     2 AGND_PVPP_KLM @BASEBOARD_FAB2_LIB.BASEBOARD_FAB2(SCH_1):AGND_PVPP_KLM   I129 @BASEBOARD_FAB2_LIB.BASEBOARD_FAB2(SCH_1):PAGE234

C4B6 CAP_0402-0.027UF,16V,10%,X7R,AA
     1 VR_PVPP_KLM_SS @BASEBOARD_FAB2_LIB.BASEBOARD_FAB2(SCH_1):VR_PVPP_KLM_SS   I146 @BASEBOARD_FAB2_LIB.BASEBOARD_FAB2(SCH_1):PAGE234
     2 AGND_PVPP_KLM @BASEBOARD_FAB2_LIB.BASEBOARD_FAB2(SCH_1):AGND_PVPP_KLM   I146 @BASEBOARD_FAB2_LIB.BASEBOARD_FAB2(SCH_1):PAGE234

C4B7 CAP_0402LF-2200PF,50V,10%,X7R,A
     1 VR_COMP_PVPP_KLM @BASEBOARD_FAB2_LIB.BASEBOARD_FAB2(SCH_1):VR_COMP_PVPP_KLM   I218 @BASEBOARD_FAB2_LIB.BASEBOARD_FAB2(SCH_1):PAGE234
     2 VR_FB_PVPP_KLM @BASEBOARD_FAB2_LIB.BASEBOARD_FAB2(SCH_1):VR_FB_PVPP_KLM   I218 @BASEBOARD_FAB2_LIB.BASEBOARD_FAB2(SCH_1):PAGE234

C4B8 CAP_0402LF-1000PF,50V,10%,X7R,A
     1 PWRGD_PVPP_KLM_R @BASEBOARD_FAB2_LIB.BASEBOARD_FAB2(SCH_1):PWRGD_PVPP_KLM_R   I139 @BASEBOARD_FAB2_LIB.BASEBOARD_FAB2(SCH_1):PAGE234
     2    GND @BASEBOARD_FAB2_LIB.BASEBOARD_FAB2(SCH_1):GND   I139 @BASEBOARD_FAB2_LIB.BASEBOARD_FAB2(SCH_1):PAGE234

C4B9 CAP_0402LF-2200PF,50V,10%,X7R,A
     1 VR_COMP_RC_PVPP_KLM @BASEBOARD_FAB2_LIB.BASEBOARD_FAB2(SCH_1):VR_COMP_RC_PVPP_KLM   I211 @BASEBOARD_FAB2_LIB.BASEBOARD_FAB2(SCH_1):PAGE234
     2 VR_COMP_PVPP_KLM_3 @BASEBOARD_FAB2_LIB.BASEBOARD_FAB2(SCH_1):VR_COMP_PVPP_KLM_3   I211 @BASEBOARD_FAB2_LIB.BASEBOARD_FAB2(SCH_1):PAGE234

C4B11 CAP_0805-10UF,16V,10%,X7R,G106A
     1 P12V_NVDIMM_DEF @BASEBOARD_FAB2_LIB.BASEBOARD_FAB2(SCH_1):P12V_NVDIMM_DEF    I59 @BASEBOARD_FAB2_LIB.BASEBOARD_FAB2(SCH_1):PAGE197
     2    GND @BASEBOARD_FAB2_LIB.BASEBOARD_FAB2(SCH_1):GND    I59 @BASEBOARD_FAB2_LIB.BASEBOARD_FAB2(SCH_1):PAGE197

C4B12 CAP_A_0402V-0.01UF,25V,10%,X7RA
     1 M_D_VREF @BASEBOARD_FAB2_LIB.BASEBOARD_FAB2(SCH_1):M_D_VREF   I179 @BASEBOARD_FAB2_LIB.BASEBOARD_FAB2(SCH_1):PAGE49
     2    GND @BASEBOARD_FAB2_LIB.BASEBOARD_FAB2(SCH_1):GND   I179 @BASEBOARD_FAB2_LIB.BASEBOARD_FAB2(SCH_1):PAGE49

C4B13 CAPP_4040LF-470UF,16V,20%,ALUMA
     1 P12V_STBY @BASEBOARD_FAB2_LIB.BASEBOARD_FAB2(SCH_1):P12V_STBY    I83 @BASEBOARD_FAB2_LIB.BASEBOARD_FAB2(SCH_1):PAGE195
     2    GND @BASEBOARD_FAB2_LIB.BASEBOARD_FAB2(SCH_1):GND    I83 @BASEBOARD_FAB2_LIB.BASEBOARD_FAB2(SCH_1):PAGE195

C4B14 CAPP_3018-68UF,16V,20%,TANT,72A
     1 P12V_STBY @BASEBOARD_FAB2_LIB.BASEBOARD_FAB2(SCH_1):P12V_STBY    I97 @BASEBOARD_FAB2_LIB.BASEBOARD_FAB2(SCH_1):PAGE195
     2    GND @BASEBOARD_FAB2_LIB.BASEBOARD_FAB2(SCH_1):GND    I97 @BASEBOARD_FAB2_LIB.BASEBOARD_FAB2(SCH_1):PAGE195

C4B15 CAP_0603LF-0.1UF,25V,10%,X7R,6A
     1 VR_PVPP_KLM_PHASE @BASEBOARD_FAB2_LIB.BASEBOARD_FAB2(SCH_1):VR_PVPP_KLM_PHASE   I182 @BASEBOARD_FAB2_LIB.BASEBOARD_FAB2(SCH_1):PAGE234
     2 VR_PVPP_KLM_BOOT_R @BASEBOARD_FAB2_LIB.BASEBOARD_FAB2(SCH_1):VR_PVPP_KLM_BOOT_R   I182 @BASEBOARD_FAB2_LIB.BASEBOARD_FAB2(SCH_1):PAGE234

C4C1 CAPP_3018-470UF,2.5V,20%,ALUM,A
     1 PVCCIOMCP_CPU1 @BASEBOARD_FAB2_LIB.BASEBOARD_FAB2(SCH_1):PVCCIOMCP_CPU1    I29 @BASEBOARD_FAB2_LIB.BASEBOARD_FAB2(SCH_1):PAGE193
     2    GND @BASEBOARD_FAB2_LIB.BASEBOARD_FAB2(SCH_1):GND    I29 @BASEBOARD_FAB2_LIB.BASEBOARD_FAB2(SCH_1):PAGE193

C4C2 CAP_A_0402V-0.1UF,16V,10%,EMPTA
     1 VR_FET_SW_P12V_PVCCIN_CPU0_R @BASEBOARD_FAB2_LIB.BASEBOARD_FAB2(SCH_1):VR_FET_SW_P12V_PVCCIN_CPU0_R    I51 @BASEBOARD_FAB2_LIB.BASEBOARD_FAB2(SCH_1):PAGE204
     2    GND @BASEBOARD_FAB2_LIB.BASEBOARD_FAB2(SCH_1):GND    I51 @BASEBOARD_FAB2_LIB.BASEBOARD_FAB2(SCH_1):PAGE204

C4C3 CAP_A_0402V-1.0UF,6.3V,10%,X6SA
     1 P3V3_STBY @BASEBOARD_FAB2_LIB.BASEBOARD_FAB2(SCH_1):P3V3_STBY    I75 @BASEBOARD_FAB2_LIB.BASEBOARD_FAB2(SCH_1):PAGE96
     2    GND @BASEBOARD_FAB2_LIB.BASEBOARD_FAB2(SCH_1):GND    I75 @BASEBOARD_FAB2_LIB.BASEBOARD_FAB2(SCH_1):PAGE96

C4C4 CAP_A_0402V-1.0UF,6.3V,10%,X6SA
     1 P5V_STBY @BASEBOARD_FAB2_LIB.BASEBOARD_FAB2(SCH_1):P5V_STBY    I18 @BASEBOARD_FAB2_LIB.BASEBOARD_FAB2(SCH_1):PAGE205
     2    GND @BASEBOARD_FAB2_LIB.BASEBOARD_FAB2(SCH_1):GND    I18 @BASEBOARD_FAB2_LIB.BASEBOARD_FAB2(SCH_1):PAGE205

C4C5 CAP_0402-0.22UF,16V,10%,X7R,A3A
     1 P5V_STBY @BASEBOARD_FAB2_LIB.BASEBOARD_FAB2(SCH_1):P5V_STBY    I16 @BASEBOARD_FAB2_LIB.BASEBOARD_FAB2(SCH_1):PAGE205
     2    GND @BASEBOARD_FAB2_LIB.BASEBOARD_FAB2(SCH_1):GND    I16 @BASEBOARD_FAB2_LIB.BASEBOARD_FAB2(SCH_1):PAGE205

C4C6 CAP_0402-1.0UF,16V,10%,X6S,D97A
     1 VR_PVSA_CPU0_VCIN @BASEBOARD_FAB2_LIB.BASEBOARD_FAB2(SCH_1):VR_PVSA_CPU0_VCIN    I20 @BASEBOARD_FAB2_LIB.BASEBOARD_FAB2(SCH_1):PAGE205
     2    GND @BASEBOARD_FAB2_LIB.BASEBOARD_FAB2(SCH_1):GND    I20 @BASEBOARD_FAB2_LIB.BASEBOARD_FAB2(SCH_1):PAGE205

C4C8 CAP_0402-0.220UF,16V,10%,X7R,AA
     1 VR_PVSA_CPU0_BOOT @BASEBOARD_FAB2_LIB.BASEBOARD_FAB2(SCH_1):VR_PVSA_CPU0_BOOT    I25 @BASEBOARD_FAB2_LIB.BASEBOARD_FAB2(SCH_1):PAGE205
     2 VR_PVSA_CPU0_PHASE @BASEBOARD_FAB2_LIB.BASEBOARD_FAB2(SCH_1):VR_PVSA_CPU0_PHASE    I25 @BASEBOARD_FAB2_LIB.BASEBOARD_FAB2(SCH_1):PAGE205

C4C9 CAP_0402-1.0UF,16V,10%,X6S,D97A
     1 VR_FET_SW_P12V_STBY_PVCCIN_CPU0 @BASEBOARD_FAB2_LIB.BASEBOARD_FAB2(SCH_1):VR_FET_SW_P12V_STBY_PVCCIN_CPU0    I32 @BASEBOARD_FAB2_LIB.BASEBOARD_FAB2(SCH_1):PAGE205
     2    GND @BASEBOARD_FAB2_LIB.BASEBOARD_FAB2(SCH_1):GND    I32 @BASEBOARD_FAB2_LIB.BASEBOARD_FAB2(SCH_1):PAGE205

C4C10 CAP_A_0402V-0.1UF,16V,10%,X7R,A
     1 VR_FET_SW_P12V_STBY_PVCCIN_CPU0 @BASEBOARD_FAB2_LIB.BASEBOARD_FAB2(SCH_1):VR_FET_SW_P12V_STBY_PVCCIN_CPU0    I31 @BASEBOARD_FAB2_LIB.BASEBOARD_FAB2(SCH_1):PAGE205
     2    GND @BASEBOARD_FAB2_LIB.BASEBOARD_FAB2(SCH_1):GND    I31 @BASEBOARD_FAB2_LIB.BASEBOARD_FAB2(SCH_1):PAGE205

C4C11 CAP_A_0603V-22.0UF,4V,20%,X6S,A
     1 PVSA_CPU0 @BASEBOARD_FAB2_LIB.BASEBOARD_FAB2(SCH_1):PVSA_CPU0    I43 @BASEBOARD_FAB2_LIB.BASEBOARD_FAB2(SCH_1):PAGE205
     2    GND @BASEBOARD_FAB2_LIB.BASEBOARD_FAB2(SCH_1):GND    I43 @BASEBOARD_FAB2_LIB.BASEBOARD_FAB2(SCH_1):PAGE205

C4C12 CAPP_2626-270UF,16V,20%,OSCON,A
     1 VR_FET_SW_P12V_STBY_PVCCIN_CPU0 @BASEBOARD_FAB2_LIB.BASEBOARD_FAB2(SCH_1):VR_FET_SW_P12V_STBY_PVCCIN_CPU0    I67 @BASEBOARD_FAB2_LIB.BASEBOARD_FAB2(SCH_1):PAGE204
     2    GND @BASEBOARD_FAB2_LIB.BASEBOARD_FAB2(SCH_1):GND    I67 @BASEBOARD_FAB2_LIB.BASEBOARD_FAB2(SCH_1):PAGE204

C4C14 CAP_A_0402V-1.0UF,6.3V,10%,X6SA
     1 P5V_STBY @BASEBOARD_FAB2_LIB.BASEBOARD_FAB2(SCH_1):P5V_STBY    I19 @BASEBOARD_FAB2_LIB.BASEBOARD_FAB2(SCH_1):PAGE204
     2    GND @BASEBOARD_FAB2_LIB.BASEBOARD_FAB2(SCH_1):GND    I19 @BASEBOARD_FAB2_LIB.BASEBOARD_FAB2(SCH_1):PAGE204

C4C17 CAP_0402-0.220UF,16V,10%,X7R,AA
     1 VR_PVCCIN_CPU0_PH5_BOOT @BASEBOARD_FAB2_LIB.BASEBOARD_FAB2(SCH_1):VR_PVCCIN_CPU0_PH5_BOOT    I22 @BASEBOARD_FAB2_LIB.BASEBOARD_FAB2(SCH_1):PAGE204
     2 VR_PVCCIN_CPU0_PH5_PHASE @BASEBOARD_FAB2_LIB.BASEBOARD_FAB2(SCH_1):VR_PVCCIN_CPU0_PH5_PHASE    I22 @BASEBOARD_FAB2_LIB.BASEBOARD_FAB2(SCH_1):PAGE204

C4C18 CAP_0402-1.0UF,16V,10%,X6S,D97A
     1 VR_FET_SW_P12V_STBY_PVCCIN_CPU0 @BASEBOARD_FAB2_LIB.BASEBOARD_FAB2(SCH_1):VR_FET_SW_P12V_STBY_PVCCIN_CPU0    I36 @BASEBOARD_FAB2_LIB.BASEBOARD_FAB2(SCH_1):PAGE204
     2    GND @BASEBOARD_FAB2_LIB.BASEBOARD_FAB2(SCH_1):GND    I36 @BASEBOARD_FAB2_LIB.BASEBOARD_FAB2(SCH_1):PAGE204

C4C19 CAP_A_0402V-0.1UF,16V,10%,X7R,A
     1 VR_FET_SW_P12V_STBY_PVCCIN_CPU0 @BASEBOARD_FAB2_LIB.BASEBOARD_FAB2(SCH_1):VR_FET_SW_P12V_STBY_PVCCIN_CPU0    I35 @BASEBOARD_FAB2_LIB.BASEBOARD_FAB2(SCH_1):PAGE204
     2    GND @BASEBOARD_FAB2_LIB.BASEBOARD_FAB2(SCH_1):GND    I35 @BASEBOARD_FAB2_LIB.BASEBOARD_FAB2(SCH_1):PAGE204

C4D2 CAPP_2626-270UF,16V,20%,OSCON,A
     1 VR_FET_SW_P12V_STBY_PVCCIN_CPU0 @BASEBOARD_FAB2_LIB.BASEBOARD_FAB2(SCH_1):VR_FET_SW_P12V_STBY_PVCCIN_CPU0    I48 @BASEBOARD_FAB2_LIB.BASEBOARD_FAB2(SCH_1):PAGE204
     2    GND @BASEBOARD_FAB2_LIB.BASEBOARD_FAB2(SCH_1):GND    I48 @BASEBOARD_FAB2_LIB.BASEBOARD_FAB2(SCH_1):PAGE204

C4D4 CAP_A_0603V-22.0UF,4V,20%,X6S,A
     1 PVCCIN_CPU0 @BASEBOARD_FAB2_LIB.BASEBOARD_FAB2(SCH_1):PVCCIN_CPU0    I69 @BASEBOARD_FAB2_LIB.BASEBOARD_FAB2(SCH_1):PAGE203
     2    GND @BASEBOARD_FAB2_LIB.BASEBOARD_FAB2(SCH_1):GND    I69 @BASEBOARD_FAB2_LIB.BASEBOARD_FAB2(SCH_1):PAGE203

C4D5 CAP_0402-0.22UF,16V,10%,X7R,A3A
     1 P5V_STBY @BASEBOARD_FAB2_LIB.BASEBOARD_FAB2(SCH_1):P5V_STBY    I48 @BASEBOARD_FAB2_LIB.BASEBOARD_FAB2(SCH_1):PAGE203
     2    GND @BASEBOARD_FAB2_LIB.BASEBOARD_FAB2(SCH_1):GND    I48 @BASEBOARD_FAB2_LIB.BASEBOARD_FAB2(SCH_1):PAGE203

C4D6 CAP_A_0402V-1.0UF,6.3V,10%,X6SA
     1 P5V_STBY @BASEBOARD_FAB2_LIB.BASEBOARD_FAB2(SCH_1):P5V_STBY    I49 @BASEBOARD_FAB2_LIB.BASEBOARD_FAB2(SCH_1):PAGE203
     2    GND @BASEBOARD_FAB2_LIB.BASEBOARD_FAB2(SCH_1):GND    I49 @BASEBOARD_FAB2_LIB.BASEBOARD_FAB2(SCH_1):PAGE203

C4D7 CAP_0402-1.0UF,16V,10%,X6S,D97A
     1 VR_PVCCIN_CPU0_PH4_VCIN @BASEBOARD_FAB2_LIB.BASEBOARD_FAB2(SCH_1):VR_PVCCIN_CPU0_PH4_VCIN    I51 @BASEBOARD_FAB2_LIB.BASEBOARD_FAB2(SCH_1):PAGE203
     2    GND @BASEBOARD_FAB2_LIB.BASEBOARD_FAB2(SCH_1):GND    I51 @BASEBOARD_FAB2_LIB.BASEBOARD_FAB2(SCH_1):PAGE203

C4D9 CAP_0402-0.220UF,16V,10%,X7R,AA
     1 VR_PVCCIN_CPU0_PH4_BOOT @BASEBOARD_FAB2_LIB.BASEBOARD_FAB2(SCH_1):VR_PVCCIN_CPU0_PH4_BOOT     I3 @BASEBOARD_FAB2_LIB.BASEBOARD_FAB2(SCH_1):PAGE203
     2 VR_PVCCIN_CPU0_PH4_PHASE @BASEBOARD_FAB2_LIB.BASEBOARD_FAB2(SCH_1):VR_PVCCIN_CPU0_PH4_PHASE     I3 @BASEBOARD_FAB2_LIB.BASEBOARD_FAB2(SCH_1):PAGE203

C4D10 CAP_0402-1.0UF,16V,10%,X6S,D97A
     1 VR_FET_SW_P12V_STBY_PVCCIN_CPU0 @BASEBOARD_FAB2_LIB.BASEBOARD_FAB2(SCH_1):VR_FET_SW_P12V_STBY_PVCCIN_CPU0    I53 @BASEBOARD_FAB2_LIB.BASEBOARD_FAB2(SCH_1):PAGE203
     2    GND @BASEBOARD_FAB2_LIB.BASEBOARD_FAB2(SCH_1):GND    I53 @BASEBOARD_FAB2_LIB.BASEBOARD_FAB2(SCH_1):PAGE203

C4D11 CAP_A_0402V-0.1UF,16V,10%,X7R,A
     1 VR_FET_SW_P12V_STBY_PVCCIN_CPU0 @BASEBOARD_FAB2_LIB.BASEBOARD_FAB2(SCH_1):VR_FET_SW_P12V_STBY_PVCCIN_CPU0    I52 @BASEBOARD_FAB2_LIB.BASEBOARD_FAB2(SCH_1):PAGE203
     2    GND @BASEBOARD_FAB2_LIB.BASEBOARD_FAB2(SCH_1):GND    I52 @BASEBOARD_FAB2_LIB.BASEBOARD_FAB2(SCH_1):PAGE203

C4D12 CAP_A_0603V-22.0UF,4V,20%,X6S,A
     1 PVCCIN_CPU0 @BASEBOARD_FAB2_LIB.BASEBOARD_FAB2(SCH_1):PVCCIN_CPU0     I9 @BASEBOARD_FAB2_LIB.BASEBOARD_FAB2(SCH_1):PAGE204
     2    GND @BASEBOARD_FAB2_LIB.BASEBOARD_FAB2(SCH_1):GND     I9 @BASEBOARD_FAB2_LIB.BASEBOARD_FAB2(SCH_1):PAGE204

C4D13 CAP_0402-0.22UF,16V,10%,X7R,A3A
     1 P5V_STBY @BASEBOARD_FAB2_LIB.BASEBOARD_FAB2(SCH_1):P5V_STBY    I40 @BASEBOARD_FAB2_LIB.BASEBOARD_FAB2(SCH_1):PAGE203
     2    GND @BASEBOARD_FAB2_LIB.BASEBOARD_FAB2(SCH_1):GND    I40 @BASEBOARD_FAB2_LIB.BASEBOARD_FAB2(SCH_1):PAGE203

C4D14 CAP_A_0402V-1.0UF,6.3V,10%,X6SA
     1 P5V_STBY @BASEBOARD_FAB2_LIB.BASEBOARD_FAB2(SCH_1):P5V_STBY    I41 @BASEBOARD_FAB2_LIB.BASEBOARD_FAB2(SCH_1):PAGE203
     2    GND @BASEBOARD_FAB2_LIB.BASEBOARD_FAB2(SCH_1):GND    I41 @BASEBOARD_FAB2_LIB.BASEBOARD_FAB2(SCH_1):PAGE203

C4D15 CAP_A_0402V-1.0UF,6.3V,10%,X6SA
     1 VR_PVCCIN_CPU0_VDD @BASEBOARD_FAB2_LIB.BASEBOARD_FAB2(SCH_1):VR_PVCCIN_CPU0_VDD    I37 @BASEBOARD_FAB2_LIB.BASEBOARD_FAB2(SCH_1):PAGE201
     2    GND @BASEBOARD_FAB2_LIB.BASEBOARD_FAB2(SCH_1):GND    I37 @BASEBOARD_FAB2_LIB.BASEBOARD_FAB2(SCH_1):PAGE201

C4D16 CAP_0402-1.0UF,16V,10%,X6S,D97A
     1 VR_PVCCIN_CPU0_PH3_VCIN @BASEBOARD_FAB2_LIB.BASEBOARD_FAB2(SCH_1):VR_PVCCIN_CPU0_PH3_VCIN    I45 @BASEBOARD_FAB2_LIB.BASEBOARD_FAB2(SCH_1):PAGE203
     2    GND @BASEBOARD_FAB2_LIB.BASEBOARD_FAB2(SCH_1):GND    I45 @BASEBOARD_FAB2_LIB.BASEBOARD_FAB2(SCH_1):PAGE203

C4D17 CAP_0402LF-220PF,50V,10%,X7R,AA
     1 A_TSENSE_PVCCIN_CPU0 @BASEBOARD_FAB2_LIB.BASEBOARD_FAB2(SCH_1):A_TSENSE_PVCCIN_CPU0    I66 @BASEBOARD_FAB2_LIB.BASEBOARD_FAB2(SCH_1):PAGE201
     2    GND @BASEBOARD_FAB2_LIB.BASEBOARD_FAB2(SCH_1):GND    I66 @BASEBOARD_FAB2_LIB.BASEBOARD_FAB2(SCH_1):PAGE201

C4D18 CAP_0402LF-220PF,50V,10%,X7R,AA
     1 A_TSENSE_PVSA_CPU0 @BASEBOARD_FAB2_LIB.BASEBOARD_FAB2(SCH_1):A_TSENSE_PVSA_CPU0    I68 @BASEBOARD_FAB2_LIB.BASEBOARD_FAB2(SCH_1):PAGE201
     2    GND @BASEBOARD_FAB2_LIB.BASEBOARD_FAB2(SCH_1):GND    I68 @BASEBOARD_FAB2_LIB.BASEBOARD_FAB2(SCH_1):PAGE201

C4D19 CAP_A_0402V-0.1UF,16V,10%,X7R,A
     1 VR_PVCCIN_CPU0_VDD @BASEBOARD_FAB2_LIB.BASEBOARD_FAB2(SCH_1):VR_PVCCIN_CPU0_VDD    I39 @BASEBOARD_FAB2_LIB.BASEBOARD_FAB2(SCH_1):PAGE201
     2    GND @BASEBOARD_FAB2_LIB.BASEBOARD_FAB2(SCH_1):GND    I39 @BASEBOARD_FAB2_LIB.BASEBOARD_FAB2(SCH_1):PAGE201

C4D20 CAP_0402LF-1000PF,50V,10%,X7R,A
     1 VR_PVCCIN_CPU0_AVINSEN @BASEBOARD_FAB2_LIB.BASEBOARD_FAB2(SCH_1):VR_PVCCIN_CPU0_AVINSEN    I60 @BASEBOARD_FAB2_LIB.BASEBOARD_FAB2(SCH_1):PAGE201
     2    GND @BASEBOARD_FAB2_LIB.BASEBOARD_FAB2(SCH_1):GND    I60 @BASEBOARD_FAB2_LIB.BASEBOARD_FAB2(SCH_1):PAGE201

C4D22 CAP_A_0402V-0.1UF,16V,10%,X7R,A
     1 P3V3_DB1200_R @BASEBOARD_FAB2_LIB.BASEBOARD_FAB2(SCH_1):P3V3_DB1200_R    I28 @BASEBOARD_FAB2_LIB.BASEBOARD_FAB2(SCH_1):PAGE102
     2    GND @BASEBOARD_FAB2_LIB.BASEBOARD_FAB2(SCH_1):GND    I28 @BASEBOARD_FAB2_LIB.BASEBOARD_FAB2(SCH_1):PAGE102

C4D23 CAP_A_0402V-1.0UF,6.3V,10%,X6SA
     1 P3V3_DB1200_A @BASEBOARD_FAB2_LIB.BASEBOARD_FAB2(SCH_1):P3V3_DB1200_A    I19 @BASEBOARD_FAB2_LIB.BASEBOARD_FAB2(SCH_1):PAGE102
     2    GND @BASEBOARD_FAB2_LIB.BASEBOARD_FAB2(SCH_1):GND    I19 @BASEBOARD_FAB2_LIB.BASEBOARD_FAB2(SCH_1):PAGE102

C4D24 CAP_A_0402V-0.1UF,16V,10%,X7R,A
     1 P3V3_DB1200_A @BASEBOARD_FAB2_LIB.BASEBOARD_FAB2(SCH_1):P3V3_DB1200_A    I18 @BASEBOARD_FAB2_LIB.BASEBOARD_FAB2(SCH_1):PAGE102
     2    GND @BASEBOARD_FAB2_LIB.BASEBOARD_FAB2(SCH_1):GND    I18 @BASEBOARD_FAB2_LIB.BASEBOARD_FAB2(SCH_1):PAGE102

C4D25 CAP_A_0402V-1.0UF,6.3V,10%,X6SA
     1 VR_PVCCIN_CPU0_VD12 @BASEBOARD_FAB2_LIB.BASEBOARD_FAB2(SCH_1):VR_PVCCIN_CPU0_VD12    I30 @BASEBOARD_FAB2_LIB.BASEBOARD_FAB2(SCH_1):PAGE201
     2    GND @BASEBOARD_FAB2_LIB.BASEBOARD_FAB2(SCH_1):GND    I30 @BASEBOARD_FAB2_LIB.BASEBOARD_FAB2(SCH_1):PAGE201

C4D26 CAP_A_0402V-0.1UF,16V,10%,X7R,A
     1 VR_PVCCIN_CPU0_VD12 @BASEBOARD_FAB2_LIB.BASEBOARD_FAB2(SCH_1):VR_PVCCIN_CPU0_VD12    I32 @BASEBOARD_FAB2_LIB.BASEBOARD_FAB2(SCH_1):PAGE201
     2    GND @BASEBOARD_FAB2_LIB.BASEBOARD_FAB2(SCH_1):GND    I32 @BASEBOARD_FAB2_LIB.BASEBOARD_FAB2(SCH_1):PAGE201

C4D27 CAP_A_0402V-1.0UF,6.3V,10%,X6SA
     1 P3V3_DB1200_R @BASEBOARD_FAB2_LIB.BASEBOARD_FAB2(SCH_1):P3V3_DB1200_R    I30 @BASEBOARD_FAB2_LIB.BASEBOARD_FAB2(SCH_1):PAGE102
     2    GND @BASEBOARD_FAB2_LIB.BASEBOARD_FAB2(SCH_1):GND    I30 @BASEBOARD_FAB2_LIB.BASEBOARD_FAB2(SCH_1):PAGE102

C4D28 CAP_0402-0.220UF,16V,10%,X7R,AA
     1 VR_PVCCIN_CPU0_PH3_BOOT @BASEBOARD_FAB2_LIB.BASEBOARD_FAB2(SCH_1):VR_PVCCIN_CPU0_PH3_BOOT    I42 @BASEBOARD_FAB2_LIB.BASEBOARD_FAB2(SCH_1):PAGE203
     2 VR_PVCCIN_CPU0_PH3_PHASE @BASEBOARD_FAB2_LIB.BASEBOARD_FAB2(SCH_1):VR_PVCCIN_CPU0_PH3_PHASE    I42 @BASEBOARD_FAB2_LIB.BASEBOARD_FAB2(SCH_1):PAGE203

C4D29 CAP_0402LF-220PF,50V,10%,X7R,AA
     1 VSENSE_PVSA_CPU0_BVSP @BASEBOARD_FAB2_LIB.BASEBOARD_FAB2(SCH_1):VSENSE_PVSA_CPU0_BVSP    I64 @BASEBOARD_FAB2_LIB.BASEBOARD_FAB2(SCH_1):PAGE201
     2 VSENSE_PVSA_CPU0_N @BASEBOARD_FAB2_LIB.BASEBOARD_FAB2(SCH_1):VSENSE_PVSA_CPU0_N    I64 @BASEBOARD_FAB2_LIB.BASEBOARD_FAB2(SCH_1):PAGE201

C4D30 CAP_0402-1.0UF,16V,10%,X6S,D97A
     1 VR_FET_SW_P12V_STBY_PVCCIN_CPU0 @BASEBOARD_FAB2_LIB.BASEBOARD_FAB2(SCH_1):VR_FET_SW_P12V_STBY_PVCCIN_CPU0    I47 @BASEBOARD_FAB2_LIB.BASEBOARD_FAB2(SCH_1):PAGE203
     2    GND @BASEBOARD_FAB2_LIB.BASEBOARD_FAB2(SCH_1):GND    I47 @BASEBOARD_FAB2_LIB.BASEBOARD_FAB2(SCH_1):PAGE203

C4D31 CAP_A_0402V-1.0UF,6.3V,10%,X6SA
     1 VR_PVCCIO_CPU1_VD12 @BASEBOARD_FAB2_LIB.BASEBOARD_FAB2(SCH_1):VR_PVCCIO_CPU1_VD12     I9 @BASEBOARD_FAB2_LIB.BASEBOARD_FAB2(SCH_1):PAGE213
     2    GND @BASEBOARD_FAB2_LIB.BASEBOARD_FAB2(SCH_1):GND     I9 @BASEBOARD_FAB2_LIB.BASEBOARD_FAB2(SCH_1):PAGE213

C4D32 CAP_A_0402V-0.1UF,16V,10%,X7R,A
     1 VR_PVCCIO_CPU1_VD12 @BASEBOARD_FAB2_LIB.BASEBOARD_FAB2(SCH_1):VR_PVCCIO_CPU1_VD12    I11 @BASEBOARD_FAB2_LIB.BASEBOARD_FAB2(SCH_1):PAGE213
     2    GND @BASEBOARD_FAB2_LIB.BASEBOARD_FAB2(SCH_1):GND    I11 @BASEBOARD_FAB2_LIB.BASEBOARD_FAB2(SCH_1):PAGE213

C4D33 CAP_0402LF-1000PF,50V,10%,X7R,A
     1 PWRGD_PVCCIO_CPU1_R @BASEBOARD_FAB2_LIB.BASEBOARD_FAB2(SCH_1):PWRGD_PVCCIO_CPU1_R    I73 @BASEBOARD_FAB2_LIB.BASEBOARD_FAB2(SCH_1):PAGE213
     2    GND @BASEBOARD_FAB2_LIB.BASEBOARD_FAB2(SCH_1):GND    I73 @BASEBOARD_FAB2_LIB.BASEBOARD_FAB2(SCH_1):PAGE213

C4D34 CAP_A_0603V-22.0UF,4V,20%,X6S,A
     1 PVCCIN_CPU0 @BASEBOARD_FAB2_LIB.BASEBOARD_FAB2(SCH_1):PVCCIN_CPU0    I68 @BASEBOARD_FAB2_LIB.BASEBOARD_FAB2(SCH_1):PAGE203
     2    GND @BASEBOARD_FAB2_LIB.BASEBOARD_FAB2(SCH_1):GND    I68 @BASEBOARD_FAB2_LIB.BASEBOARD_FAB2(SCH_1):PAGE203

C4D35 CAP_A_0402V-0.1UF,16V,10%,X7R,A
     1 VR_FET_SW_P12V_STBY_PVCCIN_CPU0 @BASEBOARD_FAB2_LIB.BASEBOARD_FAB2(SCH_1):VR_FET_SW_P12V_STBY_PVCCIN_CPU0    I46 @BASEBOARD_FAB2_LIB.BASEBOARD_FAB2(SCH_1):PAGE203
     2    GND @BASEBOARD_FAB2_LIB.BASEBOARD_FAB2(SCH_1):GND    I46 @BASEBOARD_FAB2_LIB.BASEBOARD_FAB2(SCH_1):PAGE203

C4D36 CAP_A_0402V-1.0UF,6.3V,10%,X6SA
     1 VR_PVCCIO_CPU1_VDD @BASEBOARD_FAB2_LIB.BASEBOARD_FAB2(SCH_1):VR_PVCCIO_CPU1_VDD    I17 @BASEBOARD_FAB2_LIB.BASEBOARD_FAB2(SCH_1):PAGE213
     2    GND @BASEBOARD_FAB2_LIB.BASEBOARD_FAB2(SCH_1):GND    I17 @BASEBOARD_FAB2_LIB.BASEBOARD_FAB2(SCH_1):PAGE213

C4D38 CAP_A_0402V-0.1UF,16V,10%,X7R,A
     1 VR_PVCCIO_CPU1_VDD @BASEBOARD_FAB2_LIB.BASEBOARD_FAB2(SCH_1):VR_PVCCIO_CPU1_VDD    I35 @BASEBOARD_FAB2_LIB.BASEBOARD_FAB2(SCH_1):PAGE213
     2    GND @BASEBOARD_FAB2_LIB.BASEBOARD_FAB2(SCH_1):GND    I35 @BASEBOARD_FAB2_LIB.BASEBOARD_FAB2(SCH_1):PAGE213

C4D40 CAP_0402LF-1000PF,50V,10%,X7R,A
     1 VR_PVCCIO_CPU1_VINSEN @BASEBOARD_FAB2_LIB.BASEBOARD_FAB2(SCH_1):VR_PVCCIO_CPU1_VINSEN    I33 @BASEBOARD_FAB2_LIB.BASEBOARD_FAB2(SCH_1):PAGE213
     2    GND @BASEBOARD_FAB2_LIB.BASEBOARD_FAB2(SCH_1):GND    I33 @BASEBOARD_FAB2_LIB.BASEBOARD_FAB2(SCH_1):PAGE213

C4D42 CAP_0402LF-1000PF,50V,10%,X7R,A
     1 VR_VRRDY_PVCCIN_CPU0 @BASEBOARD_FAB2_LIB.BASEBOARD_FAB2(SCH_1):VR_VRRDY_PVCCIN_CPU0   I125 @BASEBOARD_FAB2_LIB.BASEBOARD_FAB2(SCH_1):PAGE201
     2    GND @BASEBOARD_FAB2_LIB.BASEBOARD_FAB2(SCH_1):GND   I125 @BASEBOARD_FAB2_LIB.BASEBOARD_FAB2(SCH_1):PAGE201

C4D44 CAP_0402LF-220PF,50V,10%,X7R,AA
     1 VR_PVCCIO_CPU1_AVSP @BASEBOARD_FAB2_LIB.BASEBOARD_FAB2(SCH_1):VR_PVCCIO_CPU1_AVSP    I83 @BASEBOARD_FAB2_LIB.BASEBOARD_FAB2(SCH_1):PAGE213
     2 VSENSE_PVCCIO_CPU1_AVSN @BASEBOARD_FAB2_LIB.BASEBOARD_FAB2(SCH_1):VSENSE_PVCCIO_CPU1_AVSN    I83 @BASEBOARD_FAB2_LIB.BASEBOARD_FAB2(SCH_1):PAGE213

C4D45 CAP_0402LF-220PF,50V,10%,X7R,AA
     1 VSENSE_PVCCIN_CPU0_AVSP @BASEBOARD_FAB2_LIB.BASEBOARD_FAB2(SCH_1):VSENSE_PVCCIN_CPU0_AVSP    I70 @BASEBOARD_FAB2_LIB.BASEBOARD_FAB2(SCH_1):PAGE201
     2 VSENSE_PVCCIN_CPU0_N @BASEBOARD_FAB2_LIB.BASEBOARD_FAB2(SCH_1):VSENSE_PVCCIN_CPU0_N    I70 @BASEBOARD_FAB2_LIB.BASEBOARD_FAB2(SCH_1):PAGE201

C4D46 CAP_0402-1.0UF,16V,10%,X6S,D97A
     1 VR_PVCCIN_CPU0_PH5_VCIN @BASEBOARD_FAB2_LIB.BASEBOARD_FAB2(SCH_1):VR_PVCCIN_CPU0_PH5_VCIN    I34 @BASEBOARD_FAB2_LIB.BASEBOARD_FAB2(SCH_1):PAGE204
     2    GND @BASEBOARD_FAB2_LIB.BASEBOARD_FAB2(SCH_1):GND    I34 @BASEBOARD_FAB2_LIB.BASEBOARD_FAB2(SCH_1):PAGE204

C4D47 CAP_0402-0.22UF,16V,10%,X7R,A3A
     1 P5V_STBY @BASEBOARD_FAB2_LIB.BASEBOARD_FAB2(SCH_1):P5V_STBY    I18 @BASEBOARD_FAB2_LIB.BASEBOARD_FAB2(SCH_1):PAGE204
     2    GND @BASEBOARD_FAB2_LIB.BASEBOARD_FAB2(SCH_1):GND    I18 @BASEBOARD_FAB2_LIB.BASEBOARD_FAB2(SCH_1):PAGE204

C4D48 CAP_0402-1.0UF,16V,10%,X6S,D97A
     1 VR_FET_SW_P12V_STBY_PVCCIN_CPU0 @BASEBOARD_FAB2_LIB.BASEBOARD_FAB2(SCH_1):VR_FET_SW_P12V_STBY_PVCCIN_CPU0    I47 @BASEBOARD_FAB2_LIB.BASEBOARD_FAB2(SCH_1):PAGE202
     2    GND @BASEBOARD_FAB2_LIB.BASEBOARD_FAB2(SCH_1):GND    I47 @BASEBOARD_FAB2_LIB.BASEBOARD_FAB2(SCH_1):PAGE202

C4D49 CAP_A_0402V-0.1UF,16V,10%,X7R,A
     1 VR_FET_SW_P12V_STBY_PVCCIN_CPU0 @BASEBOARD_FAB2_LIB.BASEBOARD_FAB2(SCH_1):VR_FET_SW_P12V_STBY_PVCCIN_CPU0    I46 @BASEBOARD_FAB2_LIB.BASEBOARD_FAB2(SCH_1):PAGE202
     2    GND @BASEBOARD_FAB2_LIB.BASEBOARD_FAB2(SCH_1):GND    I46 @BASEBOARD_FAB2_LIB.BASEBOARD_FAB2(SCH_1):PAGE202

C4D50 CAP_0402-0.220UF,16V,10%,X7R,AA
     1 VR_PVCCIN_CPU0_PH2_BOOT @BASEBOARD_FAB2_LIB.BASEBOARD_FAB2(SCH_1):VR_PVCCIN_CPU0_PH2_BOOT    I32 @BASEBOARD_FAB2_LIB.BASEBOARD_FAB2(SCH_1):PAGE202
     2 VR_PVCCIN_CPU0_PH2_PHASE @BASEBOARD_FAB2_LIB.BASEBOARD_FAB2(SCH_1):VR_PVCCIN_CPU0_PH2_PHASE    I32 @BASEBOARD_FAB2_LIB.BASEBOARD_FAB2(SCH_1):PAGE202

C4E3 CAP_A_0603V-22.0UF,4V,20%,X6S,A
     1 PVCCIN_CPU0 @BASEBOARD_FAB2_LIB.BASEBOARD_FAB2(SCH_1):PVCCIN_CPU0    I61 @BASEBOARD_FAB2_LIB.BASEBOARD_FAB2(SCH_1):PAGE202
     2    GND @BASEBOARD_FAB2_LIB.BASEBOARD_FAB2(SCH_1):GND    I61 @BASEBOARD_FAB2_LIB.BASEBOARD_FAB2(SCH_1):PAGE202

C4E5 CAP_0402-0.22UF,16V,10%,X7R,A3A
     1 P5V_STBY @BASEBOARD_FAB2_LIB.BASEBOARD_FAB2(SCH_1):P5V_STBY    I18 @BASEBOARD_FAB2_LIB.BASEBOARD_FAB2(SCH_1):PAGE202
     2    GND @BASEBOARD_FAB2_LIB.BASEBOARD_FAB2(SCH_1):GND    I18 @BASEBOARD_FAB2_LIB.BASEBOARD_FAB2(SCH_1):PAGE202

C4E6 CAP_A_0402V-1.0UF,6.3V,10%,X6SA
     1 P5V_STBY @BASEBOARD_FAB2_LIB.BASEBOARD_FAB2(SCH_1):P5V_STBY    I19 @BASEBOARD_FAB2_LIB.BASEBOARD_FAB2(SCH_1):PAGE202
     2    GND @BASEBOARD_FAB2_LIB.BASEBOARD_FAB2(SCH_1):GND    I19 @BASEBOARD_FAB2_LIB.BASEBOARD_FAB2(SCH_1):PAGE202

C4E7 CAPP_3018-470UF,2.5V,20%,ALUM,A
     1 PVCCIO_CPU1 @BASEBOARD_FAB2_LIB.BASEBOARD_FAB2(SCH_1):PVCCIO_CPU1    I20 @BASEBOARD_FAB2_LIB.BASEBOARD_FAB2(SCH_1):PAGE214
     2    GND @BASEBOARD_FAB2_LIB.BASEBOARD_FAB2(SCH_1):GND    I20 @BASEBOARD_FAB2_LIB.BASEBOARD_FAB2(SCH_1):PAGE214

C4E8 CAP_1210-100UF,16V,20%,X5R,644A
     1 VR_FET_SW_P12V_STBY_PVCCIN_CPU0 @BASEBOARD_FAB2_LIB.BASEBOARD_FAB2(SCH_1):VR_FET_SW_P12V_STBY_PVCCIN_CPU0    I29 @BASEBOARD_FAB2_LIB.BASEBOARD_FAB2(SCH_1):PAGE214
     2    GND @BASEBOARD_FAB2_LIB.BASEBOARD_FAB2(SCH_1):GND    I29 @BASEBOARD_FAB2_LIB.BASEBOARD_FAB2(SCH_1):PAGE214

C4E9 CAP_1210-100UF,16V,20%,X5R,644A
     1 VR_FET_SW_P12V_STBY_PVCCIN_CPU0 @BASEBOARD_FAB2_LIB.BASEBOARD_FAB2(SCH_1):VR_FET_SW_P12V_STBY_PVCCIN_CPU0     I8 @BASEBOARD_FAB2_LIB.BASEBOARD_FAB2(SCH_1):PAGE214
     2    GND @BASEBOARD_FAB2_LIB.BASEBOARD_FAB2(SCH_1):GND     I8 @BASEBOARD_FAB2_LIB.BASEBOARD_FAB2(SCH_1):PAGE214

C4E10 CAP_0402-1.0UF,16V,10%,X6S,D97A
     1 VR_PVCCIN_CPU0_PH1_VCIN @BASEBOARD_FAB2_LIB.BASEBOARD_FAB2(SCH_1):VR_PVCCIN_CPU0_PH1_VCIN    I34 @BASEBOARD_FAB2_LIB.BASEBOARD_FAB2(SCH_1):PAGE202
     2    GND @BASEBOARD_FAB2_LIB.BASEBOARD_FAB2(SCH_1):GND    I34 @BASEBOARD_FAB2_LIB.BASEBOARD_FAB2(SCH_1):PAGE202

C4E11 CAP_A_0603V-22.0UF,4V,20%,X6S,A
     1 PVCCIN_CPU0 @BASEBOARD_FAB2_LIB.BASEBOARD_FAB2(SCH_1):PVCCIN_CPU0    I27 @BASEBOARD_FAB2_LIB.BASEBOARD_FAB2(SCH_1):PAGE202
     2    GND @BASEBOARD_FAB2_LIB.BASEBOARD_FAB2(SCH_1):GND    I27 @BASEBOARD_FAB2_LIB.BASEBOARD_FAB2(SCH_1):PAGE202

C4E13 CAP_A_0402V-0.1UF,16V,10%,X7R,A
     1 VR_FET_SW_P12V_STBY_PVCCIN_CPU0 @BASEBOARD_FAB2_LIB.BASEBOARD_FAB2(SCH_1):VR_FET_SW_P12V_STBY_PVCCIN_CPU0    I77 @BASEBOARD_FAB2_LIB.BASEBOARD_FAB2(SCH_1):PAGE214
     2    GND @BASEBOARD_FAB2_LIB.BASEBOARD_FAB2(SCH_1):GND    I77 @BASEBOARD_FAB2_LIB.BASEBOARD_FAB2(SCH_1):PAGE214

C4E14 CAP_1210-100UF,16V,20%,X5R,644A
     1 VR_FET_SW_P12V_STBY_PVCCIN_CPU0 @BASEBOARD_FAB2_LIB.BASEBOARD_FAB2(SCH_1):VR_FET_SW_P12V_STBY_PVCCIN_CPU0    I31 @BASEBOARD_FAB2_LIB.BASEBOARD_FAB2(SCH_1):PAGE214
     2    GND @BASEBOARD_FAB2_LIB.BASEBOARD_FAB2(SCH_1):GND    I31 @BASEBOARD_FAB2_LIB.BASEBOARD_FAB2(SCH_1):PAGE214

C4E15 CAP_0402-1.0UF,16V,10%,X6S,D97A
     1 VR_FET_SW_P12V_STBY_PVCCIN_CPU0 @BASEBOARD_FAB2_LIB.BASEBOARD_FAB2(SCH_1):VR_FET_SW_P12V_STBY_PVCCIN_CPU0    I79 @BASEBOARD_FAB2_LIB.BASEBOARD_FAB2(SCH_1):PAGE214
     2    GND @BASEBOARD_FAB2_LIB.BASEBOARD_FAB2(SCH_1):GND    I79 @BASEBOARD_FAB2_LIB.BASEBOARD_FAB2(SCH_1):PAGE214

C4E16 CAPP_2626-270UF,16V,20%,OSCON,A
     1 VR_FET_SW_P12V_STBY_PVCCIN_CPU0 @BASEBOARD_FAB2_LIB.BASEBOARD_FAB2(SCH_1):VR_FET_SW_P12V_STBY_PVCCIN_CPU0    I50 @BASEBOARD_FAB2_LIB.BASEBOARD_FAB2(SCH_1):PAGE204
     2    GND @BASEBOARD_FAB2_LIB.BASEBOARD_FAB2(SCH_1):GND    I50 @BASEBOARD_FAB2_LIB.BASEBOARD_FAB2(SCH_1):PAGE204

C4E17 CAP_0402-0.220UF,16V,10%,X7R,AA
     1 VR_PVCCIN_CPU0_PH1_BOOT @BASEBOARD_FAB2_LIB.BASEBOARD_FAB2(SCH_1):VR_PVCCIN_CPU0_PH1_BOOT    I22 @BASEBOARD_FAB2_LIB.BASEBOARD_FAB2(SCH_1):PAGE202
     2 VR_PVCCIN_CPU0_PH1_PHASE @BASEBOARD_FAB2_LIB.BASEBOARD_FAB2(SCH_1):VR_PVCCIN_CPU0_PH1_PHASE    I22 @BASEBOARD_FAB2_LIB.BASEBOARD_FAB2(SCH_1):PAGE202

C4E18 CAP_0402-0.220UF,16V,10%,X7R,AA
     1 VR_PVCCIO_CPU1_PH1_BOOT @BASEBOARD_FAB2_LIB.BASEBOARD_FAB2(SCH_1):VR_PVCCIO_CPU1_PH1_BOOT    I78 @BASEBOARD_FAB2_LIB.BASEBOARD_FAB2(SCH_1):PAGE214
     2 VR_PVCCIO_CPU1_PH1_PHASE @BASEBOARD_FAB2_LIB.BASEBOARD_FAB2(SCH_1):VR_PVCCIO_CPU1_PH1_PHASE    I78 @BASEBOARD_FAB2_LIB.BASEBOARD_FAB2(SCH_1):PAGE214

C4E19 CAP_0402-1.0UF,16V,10%,X6S,D97A
     1 VR_FET_SW_P12V_STBY_PVCCIN_CPU0 @BASEBOARD_FAB2_LIB.BASEBOARD_FAB2(SCH_1):VR_FET_SW_P12V_STBY_PVCCIN_CPU0    I36 @BASEBOARD_FAB2_LIB.BASEBOARD_FAB2(SCH_1):PAGE202
     2    GND @BASEBOARD_FAB2_LIB.BASEBOARD_FAB2(SCH_1):GND    I36 @BASEBOARD_FAB2_LIB.BASEBOARD_FAB2(SCH_1):PAGE202

C4E20 CAP_A_0402V-0.1UF,16V,10%,X7R,A
     1 VR_FET_SW_P12V_STBY_PVCCIN_CPU0 @BASEBOARD_FAB2_LIB.BASEBOARD_FAB2(SCH_1):VR_FET_SW_P12V_STBY_PVCCIN_CPU0    I35 @BASEBOARD_FAB2_LIB.BASEBOARD_FAB2(SCH_1):PAGE202
     2    GND @BASEBOARD_FAB2_LIB.BASEBOARD_FAB2(SCH_1):GND    I35 @BASEBOARD_FAB2_LIB.BASEBOARD_FAB2(SCH_1):PAGE202

C4E22 CAP_0402-1.0UF,16V,10%,X6S,D97A
     1 VR_PVCCIO_CPU1_PH1_VCIN @BASEBOARD_FAB2_LIB.BASEBOARD_FAB2(SCH_1):VR_PVCCIO_CPU1_PH1_VCIN    I76 @BASEBOARD_FAB2_LIB.BASEBOARD_FAB2(SCH_1):PAGE214
     2    GND @BASEBOARD_FAB2_LIB.BASEBOARD_FAB2(SCH_1):GND    I76 @BASEBOARD_FAB2_LIB.BASEBOARD_FAB2(SCH_1):PAGE214

C4E23 CAP_0402-0.22UF,16V,10%,X7R,A3A
     1 P5V_STBY @BASEBOARD_FAB2_LIB.BASEBOARD_FAB2(SCH_1):P5V_STBY    I73 @BASEBOARD_FAB2_LIB.BASEBOARD_FAB2(SCH_1):PAGE214
     2    GND @BASEBOARD_FAB2_LIB.BASEBOARD_FAB2(SCH_1):GND    I73 @BASEBOARD_FAB2_LIB.BASEBOARD_FAB2(SCH_1):PAGE214

C4E24 CAPP_3018-470UF,2.5V,20%,ALUM,A
     1 PVCCMCP_CPU1 @BASEBOARD_FAB2_LIB.BASEBOARD_FAB2(SCH_1):PVCCMCP_CPU1    I61 @BASEBOARD_FAB2_LIB.BASEBOARD_FAB2(SCH_1):PAGE193
     2    GND @BASEBOARD_FAB2_LIB.BASEBOARD_FAB2(SCH_1):GND    I61 @BASEBOARD_FAB2_LIB.BASEBOARD_FAB2(SCH_1):PAGE193

C4E25 CAP_A_0402V-1.0UF,6.3V,10%,X6SA
     1 P5V_STBY @BASEBOARD_FAB2_LIB.BASEBOARD_FAB2(SCH_1):P5V_STBY    I25 @BASEBOARD_FAB2_LIB.BASEBOARD_FAB2(SCH_1):PAGE202
     2    GND @BASEBOARD_FAB2_LIB.BASEBOARD_FAB2(SCH_1):GND    I25 @BASEBOARD_FAB2_LIB.BASEBOARD_FAB2(SCH_1):PAGE202

C4E26 CAP_0402-1.0UF,16V,10%,X6S,D97A
     1 VR_PVCCIN_CPU0_PH2_VCIN @BASEBOARD_FAB2_LIB.BASEBOARD_FAB2(SCH_1):VR_PVCCIN_CPU0_PH2_VCIN    I45 @BASEBOARD_FAB2_LIB.BASEBOARD_FAB2(SCH_1):PAGE202
     2    GND @BASEBOARD_FAB2_LIB.BASEBOARD_FAB2(SCH_1):GND    I45 @BASEBOARD_FAB2_LIB.BASEBOARD_FAB2(SCH_1):PAGE202

C4E27 CAP_0402-0.22UF,16V,10%,X7R,A3A
     1 P5V_STBY @BASEBOARD_FAB2_LIB.BASEBOARD_FAB2(SCH_1):P5V_STBY    I24 @BASEBOARD_FAB2_LIB.BASEBOARD_FAB2(SCH_1):PAGE202
     2    GND @BASEBOARD_FAB2_LIB.BASEBOARD_FAB2(SCH_1):GND    I24 @BASEBOARD_FAB2_LIB.BASEBOARD_FAB2(SCH_1):PAGE202

C4E28 CAP_A_0402V-1.0UF,6.3V,10%,X6SA
     1 P5V_STBY @BASEBOARD_FAB2_LIB.BASEBOARD_FAB2(SCH_1):P5V_STBY    I74 @BASEBOARD_FAB2_LIB.BASEBOARD_FAB2(SCH_1):PAGE214
     2    GND @BASEBOARD_FAB2_LIB.BASEBOARD_FAB2(SCH_1):GND    I74 @BASEBOARD_FAB2_LIB.BASEBOARD_FAB2(SCH_1):PAGE214

C4F1 CAP_A_0402V-1.0UF,6.3V,10%,X6SA
     1 P1V8_MCP_CPU1 @BASEBOARD_FAB2_LIB.BASEBOARD_FAB2(SCH_1):P1V8_MCP_CPU1    I68 @BASEBOARD_FAB2_LIB.BASEBOARD_FAB2(SCH_1):PAGE193
     2    GND @BASEBOARD_FAB2_LIB.BASEBOARD_FAB2(SCH_1):GND    I68 @BASEBOARD_FAB2_LIB.BASEBOARD_FAB2(SCH_1):PAGE193

C4F2 CAP_A_0603V-47UF,4V,20%,X5R,60A
     1 P1V8_MCP_CPU1 @BASEBOARD_FAB2_LIB.BASEBOARD_FAB2(SCH_1):P1V8_MCP_CPU1   I141 @BASEBOARD_FAB2_LIB.BASEBOARD_FAB2(SCH_1):PAGE193
     2    GND @BASEBOARD_FAB2_LIB.BASEBOARD_FAB2(SCH_1):GND   I141 @BASEBOARD_FAB2_LIB.BASEBOARD_FAB2(SCH_1):PAGE193

C4F3 CAP_A_0402V-1.0UF,6.3V,10%,X6SA
     1 P1V8_MCP_CPU1 @BASEBOARD_FAB2_LIB.BASEBOARD_FAB2(SCH_1):P1V8_MCP_CPU1    I70 @BASEBOARD_FAB2_LIB.BASEBOARD_FAB2(SCH_1):PAGE193
     2    GND @BASEBOARD_FAB2_LIB.BASEBOARD_FAB2(SCH_1):GND    I70 @BASEBOARD_FAB2_LIB.BASEBOARD_FAB2(SCH_1):PAGE193

C4F4 CAPP_3018-68UF,16V,20%,TANT,72A
     1 P12V_STBY @BASEBOARD_FAB2_LIB.BASEBOARD_FAB2(SCH_1):P12V_STBY   I112 @BASEBOARD_FAB2_LIB.BASEBOARD_FAB2(SCH_1):PAGE195
     2    GND @BASEBOARD_FAB2_LIB.BASEBOARD_FAB2(SCH_1):GND   I112 @BASEBOARD_FAB2_LIB.BASEBOARD_FAB2(SCH_1):PAGE195

C4F5 CAPP_3018-68UF,16V,20%,TANT,72A
     1 P12V_STBY @BASEBOARD_FAB2_LIB.BASEBOARD_FAB2(SCH_1):P12V_STBY    I96 @BASEBOARD_FAB2_LIB.BASEBOARD_FAB2(SCH_1):PAGE195
     2    GND @BASEBOARD_FAB2_LIB.BASEBOARD_FAB2(SCH_1):GND    I96 @BASEBOARD_FAB2_LIB.BASEBOARD_FAB2(SCH_1):PAGE195

C4F6 CAPP_4040LF-470UF,16V,20%,ALUMA
     1 P12V_STBY @BASEBOARD_FAB2_LIB.BASEBOARD_FAB2(SCH_1):P12V_STBY    I82 @BASEBOARD_FAB2_LIB.BASEBOARD_FAB2(SCH_1):PAGE195
     2    GND @BASEBOARD_FAB2_LIB.BASEBOARD_FAB2(SCH_1):GND    I82 @BASEBOARD_FAB2_LIB.BASEBOARD_FAB2(SCH_1):PAGE195

C4F7 CAPP_7343LF-330UF,6.3V,20%,POSA
     1 PVPP_GHJ @BASEBOARD_FAB2_LIB.BASEBOARD_FAB2(SCH_1):PVPP_GHJ   I217 @BASEBOARD_FAB2_LIB.BASEBOARD_FAB2(SCH_1):PAGE233
     2    GND @BASEBOARD_FAB2_LIB.BASEBOARD_FAB2(SCH_1):GND   I217 @BASEBOARD_FAB2_LIB.BASEBOARD_FAB2(SCH_1):PAGE233

C4F9 CAP_A_0402V-0.01UF,25V,10%,X7RA
     1 M_A_CPU_VREF @BASEBOARD_FAB2_LIB.BASEBOARD_FAB2(SCH_1):M_A_CPU_VREF     I7 @BASEBOARD_FAB2_LIB.BASEBOARD_FAB2(SCH_1):PAGE98
     2    GND @BASEBOARD_FAB2_LIB.BASEBOARD_FAB2(SCH_1):GND     I7 @BASEBOARD_FAB2_LIB.BASEBOARD_FAB2(SCH_1):PAGE98

C4F10 CAP_A_0402V-0.01UF,25V,10%,X7RA
     1 M_A_VREF @BASEBOARD_FAB2_LIB.BASEBOARD_FAB2(SCH_1):M_A_VREF   I272 @BASEBOARD_FAB2_LIB.BASEBOARD_FAB2(SCH_1):PAGE43
     2    GND @BASEBOARD_FAB2_LIB.BASEBOARD_FAB2(SCH_1):GND   I272 @BASEBOARD_FAB2_LIB.BASEBOARD_FAB2(SCH_1):PAGE43

C4F11 CAPP_7343-220UF,4V,20%,POSCAP,A
     1 PVPP_GHJ @BASEBOARD_FAB2_LIB.BASEBOARD_FAB2(SCH_1):PVPP_GHJ   I256 @BASEBOARD_FAB2_LIB.BASEBOARD_FAB2(SCH_1):PAGE233
     2    GND @BASEBOARD_FAB2_LIB.BASEBOARD_FAB2(SCH_1):GND   I256 @BASEBOARD_FAB2_LIB.BASEBOARD_FAB2(SCH_1):PAGE233

C4F12 CAP_0402LF-3300PF,50V,10%,EMPTA
     1 VR_PVPP_GHJ_PHASE @BASEBOARD_FAB2_LIB.BASEBOARD_FAB2(SCH_1):VR_PVPP_GHJ_PHASE   I209 @BASEBOARD_FAB2_LIB.BASEBOARD_FAB2(SCH_1):PAGE233
     2 VR_PVPP_GHJ_SNUB @BASEBOARD_FAB2_LIB.BASEBOARD_FAB2(SCH_1):VR_PVPP_GHJ_SNUB   I209 @BASEBOARD_FAB2_LIB.BASEBOARD_FAB2(SCH_1):PAGE233

C4G1 CAP_A_0402V-0.01UF,25V,10%,X7RA
     1 M_B_CPU_VREF @BASEBOARD_FAB2_LIB.BASEBOARD_FAB2(SCH_1):M_B_CPU_VREF    I43 @BASEBOARD_FAB2_LIB.BASEBOARD_FAB2(SCH_1):PAGE98
     2    GND @BASEBOARD_FAB2_LIB.BASEBOARD_FAB2(SCH_1):GND    I43 @BASEBOARD_FAB2_LIB.BASEBOARD_FAB2(SCH_1):PAGE98

C4G2 CAP_0805-10UF,16V,10%,X6S,C953A
     1 VR_FET_SW_P12V_STBY_PVPP_GHJ @BASEBOARD_FAB2_LIB.BASEBOARD_FAB2(SCH_1):VR_FET_SW_P12V_STBY_PVPP_GHJ   I253 @BASEBOARD_FAB2_LIB.BASEBOARD_FAB2(SCH_1):PAGE233
     2    GND @BASEBOARD_FAB2_LIB.BASEBOARD_FAB2(SCH_1):GND   I253 @BASEBOARD_FAB2_LIB.BASEBOARD_FAB2(SCH_1):PAGE233

C4G3 CAP_A_0402V-0.01UF,25V,10%,X7RA
     1 M_B_VREF @BASEBOARD_FAB2_LIB.BASEBOARD_FAB2(SCH_1):M_B_VREF   I179 @BASEBOARD_FAB2_LIB.BASEBOARD_FAB2(SCH_1):PAGE45
     2    GND @BASEBOARD_FAB2_LIB.BASEBOARD_FAB2(SCH_1):GND   I179 @BASEBOARD_FAB2_LIB.BASEBOARD_FAB2(SCH_1):PAGE45

C4G4 CAP_0402-1.0UF,16V,10%,X6S,D97A
     1 VR_FET_SW_P12V_STBY_PVPP_GHJ @BASEBOARD_FAB2_LIB.BASEBOARD_FAB2(SCH_1):VR_FET_SW_P12V_STBY_PVPP_GHJ   I196 @BASEBOARD_FAB2_LIB.BASEBOARD_FAB2(SCH_1):PAGE233
     2    GND @BASEBOARD_FAB2_LIB.BASEBOARD_FAB2(SCH_1):GND   I196 @BASEBOARD_FAB2_LIB.BASEBOARD_FAB2(SCH_1):PAGE233

C4G5 CAP_1210-47UF,16V,20%,X6S,D384A
     1 VR_FET_SW_P12V_STBY_PVPP_GHJ @BASEBOARD_FAB2_LIB.BASEBOARD_FAB2(SCH_1):VR_FET_SW_P12V_STBY_PVPP_GHJ   I189 @BASEBOARD_FAB2_LIB.BASEBOARD_FAB2(SCH_1):PAGE233
     2    GND @BASEBOARD_FAB2_LIB.BASEBOARD_FAB2(SCH_1):GND   I189 @BASEBOARD_FAB2_LIB.BASEBOARD_FAB2(SCH_1):PAGE233

C4G6 CAP_0402LF-100.0PF,50V,5%,COG,A
     1 VR_FB_PVPP_GHJ @BASEBOARD_FAB2_LIB.BASEBOARD_FAB2(SCH_1):VR_FB_PVPP_GHJ   I273 @BASEBOARD_FAB2_LIB.BASEBOARD_FAB2(SCH_1):PAGE233
     2 VR_COMP_PVPP_GHJ_3 @BASEBOARD_FAB2_LIB.BASEBOARD_FAB2(SCH_1):VR_COMP_PVPP_GHJ_3   I273 @BASEBOARD_FAB2_LIB.BASEBOARD_FAB2(SCH_1):PAGE233

C4G7 CAP_0402LF-1000PF,50V,10%,EMPTA
     1 FM_PVPP_CPU1_EN @BASEBOARD_FAB2_LIB.BASEBOARD_FAB2(SCH_1):FM_PVPP_CPU1_EN   I183 @BASEBOARD_FAB2_LIB.BASEBOARD_FAB2(SCH_1):PAGE233
     2 AGND_PVPP_GHJ @BASEBOARD_FAB2_LIB.BASEBOARD_FAB2(SCH_1):AGND_PVPP_GHJ   I183 @BASEBOARD_FAB2_LIB.BASEBOARD_FAB2(SCH_1):PAGE233

C4G8 CAP_0402-0.027UF,16V,10%,X7R,AA
     1 VR_PVPP_GHJ_SS @BASEBOARD_FAB2_LIB.BASEBOARD_FAB2(SCH_1):VR_PVPP_GHJ_SS   I194 @BASEBOARD_FAB2_LIB.BASEBOARD_FAB2(SCH_1):PAGE233
     2 AGND_PVPP_GHJ @BASEBOARD_FAB2_LIB.BASEBOARD_FAB2(SCH_1):AGND_PVPP_GHJ   I194 @BASEBOARD_FAB2_LIB.BASEBOARD_FAB2(SCH_1):PAGE233

C4G9 CAP_0402LF-1000PF,50V,10%,X7R,A
     1 PWRGD_PVPP_GHJ_R @BASEBOARD_FAB2_LIB.BASEBOARD_FAB2(SCH_1):PWRGD_PVPP_GHJ_R   I201 @BASEBOARD_FAB2_LIB.BASEBOARD_FAB2(SCH_1):PAGE233
     2    GND @BASEBOARD_FAB2_LIB.BASEBOARD_FAB2(SCH_1):GND   I201 @BASEBOARD_FAB2_LIB.BASEBOARD_FAB2(SCH_1):PAGE233

C4G10 CAP_0402LF-2200PF,50V,10%,X7R,A
     1 VR_COMP_RC_PVPP_GHJ @BASEBOARD_FAB2_LIB.BASEBOARD_FAB2(SCH_1):VR_COMP_RC_PVPP_GHJ   I274 @BASEBOARD_FAB2_LIB.BASEBOARD_FAB2(SCH_1):PAGE233
     2 VR_COMP_PVPP_GHJ_3 @BASEBOARD_FAB2_LIB.BASEBOARD_FAB2(SCH_1):VR_COMP_PVPP_GHJ_3   I274 @BASEBOARD_FAB2_LIB.BASEBOARD_FAB2(SCH_1):PAGE233

C4G11 CAP_0402LF-2200PF,50V,10%,X7R,A
     1 VR_COMP_PVPP_GHJ @BASEBOARD_FAB2_LIB.BASEBOARD_FAB2(SCH_1):VR_COMP_PVPP_GHJ   I267 @BASEBOARD_FAB2_LIB.BASEBOARD_FAB2(SCH_1):PAGE233
     2 VR_FB_PVPP_GHJ @BASEBOARD_FAB2_LIB.BASEBOARD_FAB2(SCH_1):VR_FB_PVPP_GHJ   I267 @BASEBOARD_FAB2_LIB.BASEBOARD_FAB2(SCH_1):PAGE233

C4G12 CAP_0402LF-1000PF,50V,10%,EMPTA
     1 FM_PVTT_GHJ_EN_R @BASEBOARD_FAB2_LIB.BASEBOARD_FAB2(SCH_1):FM_PVTT_GHJ_EN_R    I36 @BASEBOARD_FAB2_LIB.BASEBOARD_FAB2(SCH_1):PAGE229
     2    GND @BASEBOARD_FAB2_LIB.BASEBOARD_FAB2(SCH_1):GND    I36 @BASEBOARD_FAB2_LIB.BASEBOARD_FAB2(SCH_1):PAGE229

C4G13 CAP_0402LF-1000PF,50V,10%,X7R,A
     1 PWRGD_PVTT_GHJ_CPU1_R @BASEBOARD_FAB2_LIB.BASEBOARD_FAB2(SCH_1):PWRGD_PVTT_GHJ_CPU1_R    I15 @BASEBOARD_FAB2_LIB.BASEBOARD_FAB2(SCH_1):PAGE229
     2    GND @BASEBOARD_FAB2_LIB.BASEBOARD_FAB2(SCH_1):GND    I15 @BASEBOARD_FAB2_LIB.BASEBOARD_FAB2(SCH_1):PAGE229

C4G14 CAP_0402LF-1000PF,50V,10%,X7R,A
     1 PWRGD_PVTT_ABC_CPU0_R @BASEBOARD_FAB2_LIB.BASEBOARD_FAB2(SCH_1):PWRGD_PVTT_ABC_CPU0_R    I15 @BASEBOARD_FAB2_LIB.BASEBOARD_FAB2(SCH_1):PAGE221
     2    GND @BASEBOARD_FAB2_LIB.BASEBOARD_FAB2(SCH_1):GND    I15 @BASEBOARD_FAB2_LIB.BASEBOARD_FAB2(SCH_1):PAGE221

C4G15 CAP_0402-1.0UF,16V,10%,X6S,D97A
     1 VR_PVTT_ABC_BIAS @BASEBOARD_FAB2_LIB.BASEBOARD_FAB2(SCH_1):VR_PVTT_ABC_BIAS    I24 @BASEBOARD_FAB2_LIB.BASEBOARD_FAB2(SCH_1):PAGE221
     2    GND @BASEBOARD_FAB2_LIB.BASEBOARD_FAB2(SCH_1):GND    I24 @BASEBOARD_FAB2_LIB.BASEBOARD_FAB2(SCH_1):PAGE221

C4G16 CAP_0402-1.0UF,16V,10%,X6S,D97A
     1 VR_PVTT_ABC_VREF @BASEBOARD_FAB2_LIB.BASEBOARD_FAB2(SCH_1):VR_PVTT_ABC_VREF    I34 @BASEBOARD_FAB2_LIB.BASEBOARD_FAB2(SCH_1):PAGE221
     2    GND @BASEBOARD_FAB2_LIB.BASEBOARD_FAB2(SCH_1):GND    I34 @BASEBOARD_FAB2_LIB.BASEBOARD_FAB2(SCH_1):PAGE221

C4G17 CAP_A_0402V-0.01UF,25V,10%,X7RA
     1 M_C_CPU_VREF @BASEBOARD_FAB2_LIB.BASEBOARD_FAB2(SCH_1):M_C_CPU_VREF    I51 @BASEBOARD_FAB2_LIB.BASEBOARD_FAB2(SCH_1):PAGE98
     2    GND @BASEBOARD_FAB2_LIB.BASEBOARD_FAB2(SCH_1):GND    I51 @BASEBOARD_FAB2_LIB.BASEBOARD_FAB2(SCH_1):PAGE98

C4G18 CAP_0402-1.0UF,16V,10%,X6S,D97A
     1 VR_PVTT_GHJ_BIAS @BASEBOARD_FAB2_LIB.BASEBOARD_FAB2(SCH_1):VR_PVTT_GHJ_BIAS    I27 @BASEBOARD_FAB2_LIB.BASEBOARD_FAB2(SCH_1):PAGE229
     2    GND @BASEBOARD_FAB2_LIB.BASEBOARD_FAB2(SCH_1):GND    I27 @BASEBOARD_FAB2_LIB.BASEBOARD_FAB2(SCH_1):PAGE229

C4G19 CAP_A_0402V-0.01UF,25V,10%,X7RA
     1 M_C_VREF @BASEBOARD_FAB2_LIB.BASEBOARD_FAB2(SCH_1):M_C_VREF   I188 @BASEBOARD_FAB2_LIB.BASEBOARD_FAB2(SCH_1):PAGE47
     2    GND @BASEBOARD_FAB2_LIB.BASEBOARD_FAB2(SCH_1):GND   I188 @BASEBOARD_FAB2_LIB.BASEBOARD_FAB2(SCH_1):PAGE47

C4G20 CAP_0805LF-22UF,4V,20%,X6S,C95A
     1 PVTT_GHJ @BASEBOARD_FAB2_LIB.BASEBOARD_FAB2(SCH_1):PVTT_GHJ    I17 @BASEBOARD_FAB2_LIB.BASEBOARD_FAB2(SCH_1):PAGE229
     2    GND @BASEBOARD_FAB2_LIB.BASEBOARD_FAB2(SCH_1):GND    I17 @BASEBOARD_FAB2_LIB.BASEBOARD_FAB2(SCH_1):PAGE229

C4G21 CAP_0402-1.0UF,16V,10%,X6S,D97A
     1 VR_PVTT_GHJ_VREF @BASEBOARD_FAB2_LIB.BASEBOARD_FAB2(SCH_1):VR_PVTT_GHJ_VREF    I21 @BASEBOARD_FAB2_LIB.BASEBOARD_FAB2(SCH_1):PAGE229
     2    GND @BASEBOARD_FAB2_LIB.BASEBOARD_FAB2(SCH_1):GND    I21 @BASEBOARD_FAB2_LIB.BASEBOARD_FAB2(SCH_1):PAGE229

C4G22 CAP_A_0402V-0.1UF,16V,10%,X7R,A
     1 PVCCIO_CPU1 @BASEBOARD_FAB2_LIB.BASEBOARD_FAB2(SCH_1):PVCCIO_CPU1    I27 @BASEBOARD_FAB2_LIB.BASEBOARD_FAB2(SCH_1):PAGE99
     2    GND @BASEBOARD_FAB2_LIB.BASEBOARD_FAB2(SCH_1):GND    I27 @BASEBOARD_FAB2_LIB.BASEBOARD_FAB2(SCH_1):PAGE99

C4G23 CAP_0402LF-1000PF,50V,10%,EMPTA
     1 FM_PVTT_ABC_EN_R @BASEBOARD_FAB2_LIB.BASEBOARD_FAB2(SCH_1):FM_PVTT_ABC_EN_R    I39 @BASEBOARD_FAB2_LIB.BASEBOARD_FAB2(SCH_1):PAGE221
     2    GND @BASEBOARD_FAB2_LIB.BASEBOARD_FAB2(SCH_1):GND    I39 @BASEBOARD_FAB2_LIB.BASEBOARD_FAB2(SCH_1):PAGE221

C4G24 CAP_0805LF-22UF,4V,20%,X6S,C95A
     1 PVTT_ABC @BASEBOARD_FAB2_LIB.BASEBOARD_FAB2(SCH_1):PVTT_ABC    I20 @BASEBOARD_FAB2_LIB.BASEBOARD_FAB2(SCH_1):PAGE221
     2    GND @BASEBOARD_FAB2_LIB.BASEBOARD_FAB2(SCH_1):GND    I20 @BASEBOARD_FAB2_LIB.BASEBOARD_FAB2(SCH_1):PAGE221

C4G25 CAP_A_0402V-0.1UF,16V,10%,X7R,A
     1 PVPP_GHJ @BASEBOARD_FAB2_LIB.BASEBOARD_FAB2(SCH_1):PVPP_GHJ    I41 @BASEBOARD_FAB2_LIB.BASEBOARD_FAB2(SCH_1):PAGE99
     2    GND @BASEBOARD_FAB2_LIB.BASEBOARD_FAB2(SCH_1):GND    I41 @BASEBOARD_FAB2_LIB.BASEBOARD_FAB2(SCH_1):PAGE99

C4G26 CAP_0603LF-0.1UF,25V,10%,X7R,6A
     1 VR_PVPP_GHJ_PHASE @BASEBOARD_FAB2_LIB.BASEBOARD_FAB2(SCH_1):VR_PVPP_GHJ_PHASE   I224 @BASEBOARD_FAB2_LIB.BASEBOARD_FAB2(SCH_1):PAGE233
     2 VR_PVPP_GHJ_BOOT_R @BASEBOARD_FAB2_LIB.BASEBOARD_FAB2(SCH_1):VR_PVPP_GHJ_BOOT_R   I224 @BASEBOARD_FAB2_LIB.BASEBOARD_FAB2(SCH_1):PAGE233

C4L1 CAP_0603LF-10UF,4V,20%,X6S,E15A
     1 PVPP_DEF @BASEBOARD_FAB2_LIB.BASEBOARD_FAB2(SCH_1):PVPP_DEF   I129 @BASEBOARD_FAB2_LIB.BASEBOARD_FAB2(SCH_1):PAGE232
     2    GND @BASEBOARD_FAB2_LIB.BASEBOARD_FAB2(SCH_1):GND   I129 @BASEBOARD_FAB2_LIB.BASEBOARD_FAB2(SCH_1):PAGE232

C4L2 CAP_0603LF-10UF,4V,20%,X6S,E15A
     1 PVPP_DEF @BASEBOARD_FAB2_LIB.BASEBOARD_FAB2(SCH_1):PVPP_DEF   I102 @BASEBOARD_FAB2_LIB.BASEBOARD_FAB2(SCH_1):PAGE232
     2    GND @BASEBOARD_FAB2_LIB.BASEBOARD_FAB2(SCH_1):GND   I102 @BASEBOARD_FAB2_LIB.BASEBOARD_FAB2(SCH_1):PAGE232

C4L3 CAP_0603LF-10UF,4V,20%,X6S,E15A
     1 PVPP_DEF @BASEBOARD_FAB2_LIB.BASEBOARD_FAB2(SCH_1):PVPP_DEF   I106 @BASEBOARD_FAB2_LIB.BASEBOARD_FAB2(SCH_1):PAGE232
     2    GND @BASEBOARD_FAB2_LIB.BASEBOARD_FAB2(SCH_1):GND   I106 @BASEBOARD_FAB2_LIB.BASEBOARD_FAB2(SCH_1):PAGE232

C4L4 CAP_0603LF-10UF,4V,20%,X6S,E15A
     1 PVPP_DEF @BASEBOARD_FAB2_LIB.BASEBOARD_FAB2(SCH_1):PVPP_DEF   I108 @BASEBOARD_FAB2_LIB.BASEBOARD_FAB2(SCH_1):PAGE232
     2    GND @BASEBOARD_FAB2_LIB.BASEBOARD_FAB2(SCH_1):GND   I108 @BASEBOARD_FAB2_LIB.BASEBOARD_FAB2(SCH_1):PAGE232

C4L5 CAPP_3018-470UF,2.5V,20%,ALUM,A
     1 PVDDQ_DEF @BASEBOARD_FAB2_LIB.BASEBOARD_FAB2(SCH_1):PVDDQ_DEF    I78 @BASEBOARD_FAB2_LIB.BASEBOARD_FAB2(SCH_1):PAGE220
     2    GND @BASEBOARD_FAB2_LIB.BASEBOARD_FAB2(SCH_1):GND    I78 @BASEBOARD_FAB2_LIB.BASEBOARD_FAB2(SCH_1):PAGE220

C4M1 CAPP_7343-220UF,4V,20%,POSCAP,A
     1 PVPP_DEF @BASEBOARD_FAB2_LIB.BASEBOARD_FAB2(SCH_1):PVPP_DEF   I267 @BASEBOARD_FAB2_LIB.BASEBOARD_FAB2(SCH_1):PAGE232
     2    GND @BASEBOARD_FAB2_LIB.BASEBOARD_FAB2(SCH_1):GND   I267 @BASEBOARD_FAB2_LIB.BASEBOARD_FAB2(SCH_1):PAGE232

C4M2 CAP_A_0603V-22.0UF,4V,20%,X6S,A
     1 PVDDQ_DEF @BASEBOARD_FAB2_LIB.BASEBOARD_FAB2(SCH_1):PVDDQ_DEF   I222 @BASEBOARD_FAB2_LIB.BASEBOARD_FAB2(SCH_1):PAGE220
     2    GND @BASEBOARD_FAB2_LIB.BASEBOARD_FAB2(SCH_1):GND   I222 @BASEBOARD_FAB2_LIB.BASEBOARD_FAB2(SCH_1):PAGE220

C4M3 CAP_0603LF-10UF,4V,20%,X6S,E15A
     1 PVPP_DEF @BASEBOARD_FAB2_LIB.BASEBOARD_FAB2(SCH_1):PVPP_DEF   I111 @BASEBOARD_FAB2_LIB.BASEBOARD_FAB2(SCH_1):PAGE232
     2    GND @BASEBOARD_FAB2_LIB.BASEBOARD_FAB2(SCH_1):GND   I111 @BASEBOARD_FAB2_LIB.BASEBOARD_FAB2(SCH_1):PAGE232

C4M4 CAP_0603LF-10UF,4V,20%,X6S,E15A
     1 PVPP_DEF @BASEBOARD_FAB2_LIB.BASEBOARD_FAB2(SCH_1):PVPP_DEF   I125 @BASEBOARD_FAB2_LIB.BASEBOARD_FAB2(SCH_1):PAGE232
     2    GND @BASEBOARD_FAB2_LIB.BASEBOARD_FAB2(SCH_1):GND   I125 @BASEBOARD_FAB2_LIB.BASEBOARD_FAB2(SCH_1):PAGE232

C4M5 CAP_A_0603V-47UF,4V,20%,X5R,60A
     1 PVDDQ_DEF @BASEBOARD_FAB2_LIB.BASEBOARD_FAB2(SCH_1):PVDDQ_DEF   I196 @BASEBOARD_FAB2_LIB.BASEBOARD_FAB2(SCH_1):PAGE220
     2    GND @BASEBOARD_FAB2_LIB.BASEBOARD_FAB2(SCH_1):GND   I196 @BASEBOARD_FAB2_LIB.BASEBOARD_FAB2(SCH_1):PAGE220

C4M6 CAPP_3018-68UF,16V,20%,TANT,72A
     1 P12V_STBY @BASEBOARD_FAB2_LIB.BASEBOARD_FAB2(SCH_1):P12V_STBY   I102 @BASEBOARD_FAB2_LIB.BASEBOARD_FAB2(SCH_1):PAGE195
     2    GND @BASEBOARD_FAB2_LIB.BASEBOARD_FAB2(SCH_1):GND   I102 @BASEBOARD_FAB2_LIB.BASEBOARD_FAB2(SCH_1):PAGE195

C4M7 CAPP_3018-68UF,16V,20%,TANT,72A
     1 P12V_STBY @BASEBOARD_FAB2_LIB.BASEBOARD_FAB2(SCH_1):P12V_STBY   I105 @BASEBOARD_FAB2_LIB.BASEBOARD_FAB2(SCH_1):PAGE195
     2    GND @BASEBOARD_FAB2_LIB.BASEBOARD_FAB2(SCH_1):GND   I105 @BASEBOARD_FAB2_LIB.BASEBOARD_FAB2(SCH_1):PAGE195

C4P1 CAP_0805-47UF,4V,20%,X6S,C9533A
     1 PVCCIO_CPU0 @BASEBOARD_FAB2_LIB.BASEBOARD_FAB2(SCH_1):PVCCIO_CPU0    I10 @BASEBOARD_FAB2_LIB.BASEBOARD_FAB2(SCH_1):PAGE42
     2    GND @BASEBOARD_FAB2_LIB.BASEBOARD_FAB2(SCH_1):GND    I10 @BASEBOARD_FAB2_LIB.BASEBOARD_FAB2(SCH_1):PAGE42

C4P2 CAP_0805-47UF,4V,20%,X6S,C9533A
     1 PVCCMCP_CPU0 @BASEBOARD_FAB2_LIB.BASEBOARD_FAB2(SCH_1):PVCCMCP_CPU0   I163 @BASEBOARD_FAB2_LIB.BASEBOARD_FAB2(SCH_1):PAGE42
     2    GND @BASEBOARD_FAB2_LIB.BASEBOARD_FAB2(SCH_1):GND   I163 @BASEBOARD_FAB2_LIB.BASEBOARD_FAB2(SCH_1):PAGE42

C4P3 CAP_0805-47UF,4V,20%,X6S,C9533A
     1 PVCCMCP_CPU0 @BASEBOARD_FAB2_LIB.BASEBOARD_FAB2(SCH_1):PVCCMCP_CPU0     I8 @BASEBOARD_FAB2_LIB.BASEBOARD_FAB2(SCH_1):PAGE42
     2    GND @BASEBOARD_FAB2_LIB.BASEBOARD_FAB2(SCH_1):GND     I8 @BASEBOARD_FAB2_LIB.BASEBOARD_FAB2(SCH_1):PAGE42

C4P4 CAP_0805-47UF,4V,20%,X6S,C9533A
     1 PVCCMCP_CPU0 @BASEBOARD_FAB2_LIB.BASEBOARD_FAB2(SCH_1):PVCCMCP_CPU0    I14 @BASEBOARD_FAB2_LIB.BASEBOARD_FAB2(SCH_1):PAGE42
     2    GND @BASEBOARD_FAB2_LIB.BASEBOARD_FAB2(SCH_1):GND    I14 @BASEBOARD_FAB2_LIB.BASEBOARD_FAB2(SCH_1):PAGE42

C4P5 CAP_0805-47UF,4V,20%,X6S,C9533A
     1 PVCCMCP_CPU0 @BASEBOARD_FAB2_LIB.BASEBOARD_FAB2(SCH_1):PVCCMCP_CPU0   I172 @BASEBOARD_FAB2_LIB.BASEBOARD_FAB2(SCH_1):PAGE42
     2    GND @BASEBOARD_FAB2_LIB.BASEBOARD_FAB2(SCH_1):GND   I172 @BASEBOARD_FAB2_LIB.BASEBOARD_FAB2(SCH_1):PAGE42

C4P6 CAP_A_0603V-22.0UF,4V,20%,X6S,A
     1 PVCCIO_CPU0 @BASEBOARD_FAB2_LIB.BASEBOARD_FAB2(SCH_1):PVCCIO_CPU0   I164 @BASEBOARD_FAB2_LIB.BASEBOARD_FAB2(SCH_1):PAGE42
     2    GND @BASEBOARD_FAB2_LIB.BASEBOARD_FAB2(SCH_1):GND   I164 @BASEBOARD_FAB2_LIB.BASEBOARD_FAB2(SCH_1):PAGE42

C4P7 CAP_0805-47UF,4V,20%,X6S,C9533A
     1 PVCCMCP_CPU0 @BASEBOARD_FAB2_LIB.BASEBOARD_FAB2(SCH_1):PVCCMCP_CPU0     I9 @BASEBOARD_FAB2_LIB.BASEBOARD_FAB2(SCH_1):PAGE42
     2    GND @BASEBOARD_FAB2_LIB.BASEBOARD_FAB2(SCH_1):GND     I9 @BASEBOARD_FAB2_LIB.BASEBOARD_FAB2(SCH_1):PAGE42

C4P8 CAP_A_0603V-22.0UF,4V,20%,X6S,A
     1 PVCCIO_CPU0 @BASEBOARD_FAB2_LIB.BASEBOARD_FAB2(SCH_1):PVCCIO_CPU0   I178 @BASEBOARD_FAB2_LIB.BASEBOARD_FAB2(SCH_1):PAGE42
     2    GND @BASEBOARD_FAB2_LIB.BASEBOARD_FAB2(SCH_1):GND   I178 @BASEBOARD_FAB2_LIB.BASEBOARD_FAB2(SCH_1):PAGE42

C4P9 CAP_0805-47UF,4V,20%,X6S,C9533A
     1 PVCCIO_CPU0 @BASEBOARD_FAB2_LIB.BASEBOARD_FAB2(SCH_1):PVCCIO_CPU0    I12 @BASEBOARD_FAB2_LIB.BASEBOARD_FAB2(SCH_1):PAGE42
     2    GND @BASEBOARD_FAB2_LIB.BASEBOARD_FAB2(SCH_1):GND    I12 @BASEBOARD_FAB2_LIB.BASEBOARD_FAB2(SCH_1):PAGE42

C4P10 CAP_0805-47UF,4V,20%,X6S,C9533A
     1 PVCCIO_CPU0 @BASEBOARD_FAB2_LIB.BASEBOARD_FAB2(SCH_1):PVCCIO_CPU0    I17 @BASEBOARD_FAB2_LIB.BASEBOARD_FAB2(SCH_1):PAGE42
     2    GND @BASEBOARD_FAB2_LIB.BASEBOARD_FAB2(SCH_1):GND    I17 @BASEBOARD_FAB2_LIB.BASEBOARD_FAB2(SCH_1):PAGE42

C4R1 CAPP_3018-470UF,2.5V,20%,ALUM,A
     1 PVCCMCP_CPU0 @BASEBOARD_FAB2_LIB.BASEBOARD_FAB2(SCH_1):PVCCMCP_CPU0    I29 @BASEBOARD_FAB2_LIB.BASEBOARD_FAB2(SCH_1):PAGE194
     2    GND @BASEBOARD_FAB2_LIB.BASEBOARD_FAB2(SCH_1):GND    I29 @BASEBOARD_FAB2_LIB.BASEBOARD_FAB2(SCH_1):PAGE194

C4R2 CAP_A_0402V-0.1UF,16V,10%,X7R,A
     1 JTAG_MCP_CPU0_TDI_R @BASEBOARD_FAB2_LIB.BASEBOARD_FAB2(SCH_1):JTAG_MCP_CPU0_TDI_R   I246 @BASEBOARD_FAB2_LIB.BASEBOARD_FAB2(SCH_1):PAGE113
     2    GND @BASEBOARD_FAB2_LIB.BASEBOARD_FAB2(SCH_1):GND   I246 @BASEBOARD_FAB2_LIB.BASEBOARD_FAB2(SCH_1):PAGE113

C4T1 CAP_A_0402V-1.0UF,6.3V,10%,X6SA
     1 P1V8_MCP_CPU0 @BASEBOARD_FAB2_LIB.BASEBOARD_FAB2(SCH_1):P1V8_MCP_CPU0    I16 @BASEBOARD_FAB2_LIB.BASEBOARD_FAB2(SCH_1):PAGE194
     2    GND @BASEBOARD_FAB2_LIB.BASEBOARD_FAB2(SCH_1):GND    I16 @BASEBOARD_FAB2_LIB.BASEBOARD_FAB2(SCH_1):PAGE194

C4T2 CAP_A_0402V-1.0UF,6.3V,10%,X6SA
     1 P1V8_MCP_CPU0 @BASEBOARD_FAB2_LIB.BASEBOARD_FAB2(SCH_1):P1V8_MCP_CPU0     I9 @BASEBOARD_FAB2_LIB.BASEBOARD_FAB2(SCH_1):PAGE194
     2    GND @BASEBOARD_FAB2_LIB.BASEBOARD_FAB2(SCH_1):GND     I9 @BASEBOARD_FAB2_LIB.BASEBOARD_FAB2(SCH_1):PAGE194

C4T3 CAPP_7343-220UF,4V,20%,POSCAP,A
     1 PVPP_ABC @BASEBOARD_FAB2_LIB.BASEBOARD_FAB2(SCH_1):PVPP_ABC   I217 @BASEBOARD_FAB2_LIB.BASEBOARD_FAB2(SCH_1):PAGE231
     2    GND @BASEBOARD_FAB2_LIB.BASEBOARD_FAB2(SCH_1):GND   I217 @BASEBOARD_FAB2_LIB.BASEBOARD_FAB2(SCH_1):PAGE231

C4T4 CAP_0805-100UF,4V,20%,X5R,6024A
     1 PVDDQ_ABC @BASEBOARD_FAB2_LIB.BASEBOARD_FAB2(SCH_1):PVDDQ_ABC    I91 @BASEBOARD_FAB2_LIB.BASEBOARD_FAB2(SCH_1):PAGE217
     2    GND @BASEBOARD_FAB2_LIB.BASEBOARD_FAB2(SCH_1):GND    I91 @BASEBOARD_FAB2_LIB.BASEBOARD_FAB2(SCH_1):PAGE217

C4T5 CAP_0603LF-10UF,4V,20%,X6S,E15A
     1 PVPP_ABC @BASEBOARD_FAB2_LIB.BASEBOARD_FAB2(SCH_1):PVPP_ABC   I125 @BASEBOARD_FAB2_LIB.BASEBOARD_FAB2(SCH_1):PAGE231
     2    GND @BASEBOARD_FAB2_LIB.BASEBOARD_FAB2(SCH_1):GND   I125 @BASEBOARD_FAB2_LIB.BASEBOARD_FAB2(SCH_1):PAGE231

C4T6 CAP_0603LF-10UF,4V,20%,X6S,E15A
     1 PVPP_ABC @BASEBOARD_FAB2_LIB.BASEBOARD_FAB2(SCH_1):PVPP_ABC   I124 @BASEBOARD_FAB2_LIB.BASEBOARD_FAB2(SCH_1):PAGE231
     2    GND @BASEBOARD_FAB2_LIB.BASEBOARD_FAB2(SCH_1):GND   I124 @BASEBOARD_FAB2_LIB.BASEBOARD_FAB2(SCH_1):PAGE231

C4U1 CAP_0603LF-10UF,4V,20%,X6S,E15A
     1 PVPP_ABC @BASEBOARD_FAB2_LIB.BASEBOARD_FAB2(SCH_1):PVPP_ABC   I130 @BASEBOARD_FAB2_LIB.BASEBOARD_FAB2(SCH_1):PAGE231
     2    GND @BASEBOARD_FAB2_LIB.BASEBOARD_FAB2(SCH_1):GND   I130 @BASEBOARD_FAB2_LIB.BASEBOARD_FAB2(SCH_1):PAGE231

C4U2 CAP_0603LF-10UF,4V,20%,X6S,E15A
     1 PVPP_ABC @BASEBOARD_FAB2_LIB.BASEBOARD_FAB2(SCH_1):PVPP_ABC   I129 @BASEBOARD_FAB2_LIB.BASEBOARD_FAB2(SCH_1):PAGE231
     2    GND @BASEBOARD_FAB2_LIB.BASEBOARD_FAB2(SCH_1):GND   I129 @BASEBOARD_FAB2_LIB.BASEBOARD_FAB2(SCH_1):PAGE231

C4U3 CAP_0603LF-10UF,4V,20%,X6S,E15A
     1 PVPP_ABC @BASEBOARD_FAB2_LIB.BASEBOARD_FAB2(SCH_1):PVPP_ABC   I148 @BASEBOARD_FAB2_LIB.BASEBOARD_FAB2(SCH_1):PAGE231
     2    GND @BASEBOARD_FAB2_LIB.BASEBOARD_FAB2(SCH_1):GND   I148 @BASEBOARD_FAB2_LIB.BASEBOARD_FAB2(SCH_1):PAGE231

C4U4 CAP_0603LF-10UF,4V,20%,X6S,E15A
     1 PVPP_ABC @BASEBOARD_FAB2_LIB.BASEBOARD_FAB2(SCH_1):PVPP_ABC   I146 @BASEBOARD_FAB2_LIB.BASEBOARD_FAB2(SCH_1):PAGE231
     2    GND @BASEBOARD_FAB2_LIB.BASEBOARD_FAB2(SCH_1):GND   I146 @BASEBOARD_FAB2_LIB.BASEBOARD_FAB2(SCH_1):PAGE231

C5A1 CAP_A_0603V-22.0UF,4V,20%,X6S,A
     1 PVDDQ_DEF @BASEBOARD_FAB2_LIB.BASEBOARD_FAB2(SCH_1):PVDDQ_DEF   I219 @BASEBOARD_FAB2_LIB.BASEBOARD_FAB2(SCH_1):PAGE220
     2    GND @BASEBOARD_FAB2_LIB.BASEBOARD_FAB2(SCH_1):GND   I219 @BASEBOARD_FAB2_LIB.BASEBOARD_FAB2(SCH_1):PAGE220

C5A2 CAP_A_0603V-22.0UF,4V,20%,X6S,A
     1 PVDDQ_DEF @BASEBOARD_FAB2_LIB.BASEBOARD_FAB2(SCH_1):PVDDQ_DEF   I214 @BASEBOARD_FAB2_LIB.BASEBOARD_FAB2(SCH_1):PAGE220
     2    GND @BASEBOARD_FAB2_LIB.BASEBOARD_FAB2(SCH_1):GND   I214 @BASEBOARD_FAB2_LIB.BASEBOARD_FAB2(SCH_1):PAGE220

C5A3 CAP_A_0603V-22.0UF,4V,20%,X6S,A
     1 PVDDQ_DEF @BASEBOARD_FAB2_LIB.BASEBOARD_FAB2(SCH_1):PVDDQ_DEF   I210 @BASEBOARD_FAB2_LIB.BASEBOARD_FAB2(SCH_1):PAGE220
     2    GND @BASEBOARD_FAB2_LIB.BASEBOARD_FAB2(SCH_1):GND   I210 @BASEBOARD_FAB2_LIB.BASEBOARD_FAB2(SCH_1):PAGE220

C5A4 CAP_A_0603V-22.0UF,4V,20%,X6S,A
     1 PVDDQ_DEF @BASEBOARD_FAB2_LIB.BASEBOARD_FAB2(SCH_1):PVDDQ_DEF   I206 @BASEBOARD_FAB2_LIB.BASEBOARD_FAB2(SCH_1):PAGE220
     2    GND @BASEBOARD_FAB2_LIB.BASEBOARD_FAB2(SCH_1):GND   I206 @BASEBOARD_FAB2_LIB.BASEBOARD_FAB2(SCH_1):PAGE220

C5A5 CAP_A_0603V-47UF,4V,20%,X5R,60A
     1 PVDDQ_DEF @BASEBOARD_FAB2_LIB.BASEBOARD_FAB2(SCH_1):PVDDQ_DEF   I193 @BASEBOARD_FAB2_LIB.BASEBOARD_FAB2(SCH_1):PAGE220
     2    GND @BASEBOARD_FAB2_LIB.BASEBOARD_FAB2(SCH_1):GND   I193 @BASEBOARD_FAB2_LIB.BASEBOARD_FAB2(SCH_1):PAGE220

C5A6 CAP_A_0603V-22.0UF,4V,20%,X6S,A
     1 PVDDQ_DEF @BASEBOARD_FAB2_LIB.BASEBOARD_FAB2(SCH_1):PVDDQ_DEF   I212 @BASEBOARD_FAB2_LIB.BASEBOARD_FAB2(SCH_1):PAGE220
     2    GND @BASEBOARD_FAB2_LIB.BASEBOARD_FAB2(SCH_1):GND   I212 @BASEBOARD_FAB2_LIB.BASEBOARD_FAB2(SCH_1):PAGE220

C5A7 CAP_A_0603V-22.0UF,4V,20%,X6S,A
     1 PVDDQ_DEF @BASEBOARD_FAB2_LIB.BASEBOARD_FAB2(SCH_1):PVDDQ_DEF   I211 @BASEBOARD_FAB2_LIB.BASEBOARD_FAB2(SCH_1):PAGE220
     2    GND @BASEBOARD_FAB2_LIB.BASEBOARD_FAB2(SCH_1):GND   I211 @BASEBOARD_FAB2_LIB.BASEBOARD_FAB2(SCH_1):PAGE220

C5A8 CAP_A_0603V-22.0UF,4V,20%,X6S,A
     1 PVDDQ_DEF @BASEBOARD_FAB2_LIB.BASEBOARD_FAB2(SCH_1):PVDDQ_DEF   I209 @BASEBOARD_FAB2_LIB.BASEBOARD_FAB2(SCH_1):PAGE220
     2    GND @BASEBOARD_FAB2_LIB.BASEBOARD_FAB2(SCH_1):GND   I209 @BASEBOARD_FAB2_LIB.BASEBOARD_FAB2(SCH_1):PAGE220

C5A9 CAP_A_0603V-22.0UF,4V,20%,X6S,A
     1 PVDDQ_DEF @BASEBOARD_FAB2_LIB.BASEBOARD_FAB2(SCH_1):PVDDQ_DEF   I208 @BASEBOARD_FAB2_LIB.BASEBOARD_FAB2(SCH_1):PAGE220
     2    GND @BASEBOARD_FAB2_LIB.BASEBOARD_FAB2(SCH_1):GND   I208 @BASEBOARD_FAB2_LIB.BASEBOARD_FAB2(SCH_1):PAGE220

C5A10 CAP_0805-100UF,4V,20%,X5R,6024A
     1 PVDDQ_DEF @BASEBOARD_FAB2_LIB.BASEBOARD_FAB2(SCH_1):PVDDQ_DEF   I110 @BASEBOARD_FAB2_LIB.BASEBOARD_FAB2(SCH_1):PAGE220
     2    GND @BASEBOARD_FAB2_LIB.BASEBOARD_FAB2(SCH_1):GND   I110 @BASEBOARD_FAB2_LIB.BASEBOARD_FAB2(SCH_1):PAGE220

C5A11 CAP_A_0603V-22.0UF,4V,20%,X6S,A
     1 PVDDQ_DEF @BASEBOARD_FAB2_LIB.BASEBOARD_FAB2(SCH_1):PVDDQ_DEF   I221 @BASEBOARD_FAB2_LIB.BASEBOARD_FAB2(SCH_1):PAGE220
     2    GND @BASEBOARD_FAB2_LIB.BASEBOARD_FAB2(SCH_1):GND   I221 @BASEBOARD_FAB2_LIB.BASEBOARD_FAB2(SCH_1):PAGE220

C5A12 CAP_A_0603V-22.0UF,4V,20%,X6S,A
     1 PVDDQ_DEF @BASEBOARD_FAB2_LIB.BASEBOARD_FAB2(SCH_1):PVDDQ_DEF   I216 @BASEBOARD_FAB2_LIB.BASEBOARD_FAB2(SCH_1):PAGE220
     2    GND @BASEBOARD_FAB2_LIB.BASEBOARD_FAB2(SCH_1):GND   I216 @BASEBOARD_FAB2_LIB.BASEBOARD_FAB2(SCH_1):PAGE220

C5A13 CAP_A_0603V-22.0UF,4V,20%,X6S,A
     1 PVDDQ_DEF @BASEBOARD_FAB2_LIB.BASEBOARD_FAB2(SCH_1):PVDDQ_DEF   I215 @BASEBOARD_FAB2_LIB.BASEBOARD_FAB2(SCH_1):PAGE220
     2    GND @BASEBOARD_FAB2_LIB.BASEBOARD_FAB2(SCH_1):GND   I215 @BASEBOARD_FAB2_LIB.BASEBOARD_FAB2(SCH_1):PAGE220

C5A14 CAP_A_0603V-22.0UF,4V,20%,X6S,A
     1 PVDDQ_DEF @BASEBOARD_FAB2_LIB.BASEBOARD_FAB2(SCH_1):PVDDQ_DEF   I213 @BASEBOARD_FAB2_LIB.BASEBOARD_FAB2(SCH_1):PAGE220
     2    GND @BASEBOARD_FAB2_LIB.BASEBOARD_FAB2(SCH_1):GND   I213 @BASEBOARD_FAB2_LIB.BASEBOARD_FAB2(SCH_1):PAGE220

C5A15 CAP_A_0603V-22.0UF,4V,20%,X6S,A
     1 PVDDQ_DEF @BASEBOARD_FAB2_LIB.BASEBOARD_FAB2(SCH_1):PVDDQ_DEF   I217 @BASEBOARD_FAB2_LIB.BASEBOARD_FAB2(SCH_1):PAGE220
     2    GND @BASEBOARD_FAB2_LIB.BASEBOARD_FAB2(SCH_1):GND   I217 @BASEBOARD_FAB2_LIB.BASEBOARD_FAB2(SCH_1):PAGE220

C5A16 CAP_A_0603V-22.0UF,4V,20%,X6S,A
     1 PVDDQ_DEF @BASEBOARD_FAB2_LIB.BASEBOARD_FAB2(SCH_1):PVDDQ_DEF   I207 @BASEBOARD_FAB2_LIB.BASEBOARD_FAB2(SCH_1):PAGE220
     2    GND @BASEBOARD_FAB2_LIB.BASEBOARD_FAB2(SCH_1):GND   I207 @BASEBOARD_FAB2_LIB.BASEBOARD_FAB2(SCH_1):PAGE220

C5A17 CAP_A_0603V-22.0UF,4V,20%,X6S,A
     1 PVDDQ_DEF @BASEBOARD_FAB2_LIB.BASEBOARD_FAB2(SCH_1):PVDDQ_DEF   I205 @BASEBOARD_FAB2_LIB.BASEBOARD_FAB2(SCH_1):PAGE220
     2    GND @BASEBOARD_FAB2_LIB.BASEBOARD_FAB2(SCH_1):GND   I205 @BASEBOARD_FAB2_LIB.BASEBOARD_FAB2(SCH_1):PAGE220

C5A18 CAP_A_0603V-22.0UF,4V,20%,X6S,A
     1 PVDDQ_DEF @BASEBOARD_FAB2_LIB.BASEBOARD_FAB2(SCH_1):PVDDQ_DEF   I204 @BASEBOARD_FAB2_LIB.BASEBOARD_FAB2(SCH_1):PAGE220
     2    GND @BASEBOARD_FAB2_LIB.BASEBOARD_FAB2(SCH_1):GND   I204 @BASEBOARD_FAB2_LIB.BASEBOARD_FAB2(SCH_1):PAGE220

C5A19 CAP_A_0603V-22.0UF,4V,20%,X6S,A
     1 PVDDQ_DEF @BASEBOARD_FAB2_LIB.BASEBOARD_FAB2(SCH_1):PVDDQ_DEF   I203 @BASEBOARD_FAB2_LIB.BASEBOARD_FAB2(SCH_1):PAGE220
     2    GND @BASEBOARD_FAB2_LIB.BASEBOARD_FAB2(SCH_1):GND   I203 @BASEBOARD_FAB2_LIB.BASEBOARD_FAB2(SCH_1):PAGE220

C5A20 CAP_0805-100UF,4V,20%,X5R,6024A
     1 PVDDQ_DEF @BASEBOARD_FAB2_LIB.BASEBOARD_FAB2(SCH_1):PVDDQ_DEF    I92 @BASEBOARD_FAB2_LIB.BASEBOARD_FAB2(SCH_1):PAGE220
     2    GND @BASEBOARD_FAB2_LIB.BASEBOARD_FAB2(SCH_1):GND    I92 @BASEBOARD_FAB2_LIB.BASEBOARD_FAB2(SCH_1):PAGE220

C5B1 CAP_A_0603V-47UF,4V,20%,X5R,60A
     1 PVDDQ_DEF @BASEBOARD_FAB2_LIB.BASEBOARD_FAB2(SCH_1):PVDDQ_DEF   I194 @BASEBOARD_FAB2_LIB.BASEBOARD_FAB2(SCH_1):PAGE220
     2    GND @BASEBOARD_FAB2_LIB.BASEBOARD_FAB2(SCH_1):GND   I194 @BASEBOARD_FAB2_LIB.BASEBOARD_FAB2(SCH_1):PAGE220

C5B2 CAP_A_0603V-47UF,4V,20%,X5R,60A
     1 PVDDQ_DEF @BASEBOARD_FAB2_LIB.BASEBOARD_FAB2(SCH_1):PVDDQ_DEF   I197 @BASEBOARD_FAB2_LIB.BASEBOARD_FAB2(SCH_1):PAGE220
     2    GND @BASEBOARD_FAB2_LIB.BASEBOARD_FAB2(SCH_1):GND   I197 @BASEBOARD_FAB2_LIB.BASEBOARD_FAB2(SCH_1):PAGE220

C5D1 CAP_A_0603V-22.0UF,4V,20%,X6S,A
     1 PVCCIN_CPU0 @BASEBOARD_FAB2_LIB.BASEBOARD_FAB2(SCH_1):PVCCIN_CPU0   I126 @BASEBOARD_FAB2_LIB.BASEBOARD_FAB2(SCH_1):PAGE42
     2    GND @BASEBOARD_FAB2_LIB.BASEBOARD_FAB2(SCH_1):GND   I126 @BASEBOARD_FAB2_LIB.BASEBOARD_FAB2(SCH_1):PAGE42

C5D2 CAP_A_0603V-22.0UF,4V,20%,X6S,A
     1 PVCCIN_CPU0 @BASEBOARD_FAB2_LIB.BASEBOARD_FAB2(SCH_1):PVCCIN_CPU0   I136 @BASEBOARD_FAB2_LIB.BASEBOARD_FAB2(SCH_1):PAGE42
     2    GND @BASEBOARD_FAB2_LIB.BASEBOARD_FAB2(SCH_1):GND   I136 @BASEBOARD_FAB2_LIB.BASEBOARD_FAB2(SCH_1):PAGE42

C5D3 CAP_A_0603V-22.0UF,4V,20%,X6S,A
     1 PVCCIN_CPU0 @BASEBOARD_FAB2_LIB.BASEBOARD_FAB2(SCH_1):PVCCIN_CPU0   I130 @BASEBOARD_FAB2_LIB.BASEBOARD_FAB2(SCH_1):PAGE42
     2    GND @BASEBOARD_FAB2_LIB.BASEBOARD_FAB2(SCH_1):GND   I130 @BASEBOARD_FAB2_LIB.BASEBOARD_FAB2(SCH_1):PAGE42

C5D4 CAP_A_0603V-22.0UF,4V,20%,X6S,A
     1 PVCCIN_CPU0 @BASEBOARD_FAB2_LIB.BASEBOARD_FAB2(SCH_1):PVCCIN_CPU0   I127 @BASEBOARD_FAB2_LIB.BASEBOARD_FAB2(SCH_1):PAGE42
     2    GND @BASEBOARD_FAB2_LIB.BASEBOARD_FAB2(SCH_1):GND   I127 @BASEBOARD_FAB2_LIB.BASEBOARD_FAB2(SCH_1):PAGE42

C5D5 CAP_A_0603V-22.0UF,4V,20%,X6S,A
     1 PVCCIN_CPU0 @BASEBOARD_FAB2_LIB.BASEBOARD_FAB2(SCH_1):PVCCIN_CPU0   I125 @BASEBOARD_FAB2_LIB.BASEBOARD_FAB2(SCH_1):PAGE42
     2    GND @BASEBOARD_FAB2_LIB.BASEBOARD_FAB2(SCH_1):GND   I125 @BASEBOARD_FAB2_LIB.BASEBOARD_FAB2(SCH_1):PAGE42

C5D6 CAP_0603LF-10UF,4V,20%,X6S,E15A
     1 PVDDQ_DEF @BASEBOARD_FAB2_LIB.BASEBOARD_FAB2(SCH_1):PVDDQ_DEF   I182 @BASEBOARD_FAB2_LIB.BASEBOARD_FAB2(SCH_1):PAGE220
     2    GND @BASEBOARD_FAB2_LIB.BASEBOARD_FAB2(SCH_1):GND   I182 @BASEBOARD_FAB2_LIB.BASEBOARD_FAB2(SCH_1):PAGE220

C5D7 CAP_0603LF-10UF,4V,20%,X6S,E15A
     1 PVDDQ_DEF @BASEBOARD_FAB2_LIB.BASEBOARD_FAB2(SCH_1):PVDDQ_DEF   I183 @BASEBOARD_FAB2_LIB.BASEBOARD_FAB2(SCH_1):PAGE220
     2    GND @BASEBOARD_FAB2_LIB.BASEBOARD_FAB2(SCH_1):GND   I183 @BASEBOARD_FAB2_LIB.BASEBOARD_FAB2(SCH_1):PAGE220

C5D8 CAP_0603LF-10UF,4V,20%,X6S,E15A
     1 PVDDQ_DEF @BASEBOARD_FAB2_LIB.BASEBOARD_FAB2(SCH_1):PVDDQ_DEF   I184 @BASEBOARD_FAB2_LIB.BASEBOARD_FAB2(SCH_1):PAGE220
     2    GND @BASEBOARD_FAB2_LIB.BASEBOARD_FAB2(SCH_1):GND   I184 @BASEBOARD_FAB2_LIB.BASEBOARD_FAB2(SCH_1):PAGE220

C5D9 CAP_0603LF-10UF,4V,20%,X6S,E15A
     1 PVDDQ_DEF @BASEBOARD_FAB2_LIB.BASEBOARD_FAB2(SCH_1):PVDDQ_DEF   I180 @BASEBOARD_FAB2_LIB.BASEBOARD_FAB2(SCH_1):PAGE220
     2    GND @BASEBOARD_FAB2_LIB.BASEBOARD_FAB2(SCH_1):GND   I180 @BASEBOARD_FAB2_LIB.BASEBOARD_FAB2(SCH_1):PAGE220

C5D10 CAP_0603LF-10UF,4V,20%,X6S,E15A
     1 PVSA_CPU0 @BASEBOARD_FAB2_LIB.BASEBOARD_FAB2(SCH_1):PVSA_CPU0   I108 @BASEBOARD_FAB2_LIB.BASEBOARD_FAB2(SCH_1):PAGE42
     2    GND @BASEBOARD_FAB2_LIB.BASEBOARD_FAB2(SCH_1):GND   I108 @BASEBOARD_FAB2_LIB.BASEBOARD_FAB2(SCH_1):PAGE42

C5D11 CAP_0603LF-10UF,4V,20%,X6S,E15A
     1 PVSA_CPU0 @BASEBOARD_FAB2_LIB.BASEBOARD_FAB2(SCH_1):PVSA_CPU0    I93 @BASEBOARD_FAB2_LIB.BASEBOARD_FAB2(SCH_1):PAGE42
     2    GND @BASEBOARD_FAB2_LIB.BASEBOARD_FAB2(SCH_1):GND    I93 @BASEBOARD_FAB2_LIB.BASEBOARD_FAB2(SCH_1):PAGE42

C5D12 CAP_0603LF-10UF,4V,20%,X6S,E15A
     1 PVSA_CPU0 @BASEBOARD_FAB2_LIB.BASEBOARD_FAB2(SCH_1):PVSA_CPU0    I94 @BASEBOARD_FAB2_LIB.BASEBOARD_FAB2(SCH_1):PAGE42
     2    GND @BASEBOARD_FAB2_LIB.BASEBOARD_FAB2(SCH_1):GND    I94 @BASEBOARD_FAB2_LIB.BASEBOARD_FAB2(SCH_1):PAGE42

C5D13 CAP_0603LF-10UF,4V,20%,X6S,E15A
     1 PVSA_CPU0 @BASEBOARD_FAB2_LIB.BASEBOARD_FAB2(SCH_1):PVSA_CPU0    I91 @BASEBOARD_FAB2_LIB.BASEBOARD_FAB2(SCH_1):PAGE42
     2    GND @BASEBOARD_FAB2_LIB.BASEBOARD_FAB2(SCH_1):GND    I91 @BASEBOARD_FAB2_LIB.BASEBOARD_FAB2(SCH_1):PAGE42

C5D14 CAP_A_0603V-22.0UF,4V,20%,X6S,A
     1 PVCCIN_CPU0 @BASEBOARD_FAB2_LIB.BASEBOARD_FAB2(SCH_1):PVCCIN_CPU0   I117 @BASEBOARD_FAB2_LIB.BASEBOARD_FAB2(SCH_1):PAGE42
     2    GND @BASEBOARD_FAB2_LIB.BASEBOARD_FAB2(SCH_1):GND   I117 @BASEBOARD_FAB2_LIB.BASEBOARD_FAB2(SCH_1):PAGE42

C5D15 CAP_A_0603V-22.0UF,4V,20%,X6S,A
     1 PVCCIN_CPU0 @BASEBOARD_FAB2_LIB.BASEBOARD_FAB2(SCH_1):PVCCIN_CPU0   I132 @BASEBOARD_FAB2_LIB.BASEBOARD_FAB2(SCH_1):PAGE42
     2    GND @BASEBOARD_FAB2_LIB.BASEBOARD_FAB2(SCH_1):GND   I132 @BASEBOARD_FAB2_LIB.BASEBOARD_FAB2(SCH_1):PAGE42

C5D16 CAP_A_0603V-22.0UF,4V,20%,X6S,A
     1 PVCCIN_CPU0 @BASEBOARD_FAB2_LIB.BASEBOARD_FAB2(SCH_1):PVCCIN_CPU0   I123 @BASEBOARD_FAB2_LIB.BASEBOARD_FAB2(SCH_1):PAGE42
     2    GND @BASEBOARD_FAB2_LIB.BASEBOARD_FAB2(SCH_1):GND   I123 @BASEBOARD_FAB2_LIB.BASEBOARD_FAB2(SCH_1):PAGE42

C5D17 CAP_A_0603V-22.0UF,4V,20%,X6S,A
     1 PVCCIN_CPU0 @BASEBOARD_FAB2_LIB.BASEBOARD_FAB2(SCH_1):PVCCIN_CPU0   I118 @BASEBOARD_FAB2_LIB.BASEBOARD_FAB2(SCH_1):PAGE42
     2    GND @BASEBOARD_FAB2_LIB.BASEBOARD_FAB2(SCH_1):GND   I118 @BASEBOARD_FAB2_LIB.BASEBOARD_FAB2(SCH_1):PAGE42

C5D18 CAP_A_0603V-22.0UF,4V,20%,X6S,A
     1 PVCCIN_CPU0 @BASEBOARD_FAB2_LIB.BASEBOARD_FAB2(SCH_1):PVCCIN_CPU0   I134 @BASEBOARD_FAB2_LIB.BASEBOARD_FAB2(SCH_1):PAGE42
     2    GND @BASEBOARD_FAB2_LIB.BASEBOARD_FAB2(SCH_1):GND   I134 @BASEBOARD_FAB2_LIB.BASEBOARD_FAB2(SCH_1):PAGE42

C5D19 CAP_A_0603V-22.0UF,4V,20%,X6S,A
     1 PVCCIN_CPU0 @BASEBOARD_FAB2_LIB.BASEBOARD_FAB2(SCH_1):PVCCIN_CPU0   I128 @BASEBOARD_FAB2_LIB.BASEBOARD_FAB2(SCH_1):PAGE42
     2    GND @BASEBOARD_FAB2_LIB.BASEBOARD_FAB2(SCH_1):GND   I128 @BASEBOARD_FAB2_LIB.BASEBOARD_FAB2(SCH_1):PAGE42

C5D20 CAP_A_0603V-22.0UF,4V,20%,X6S,A
     1 PVCCMCP_CPU0 @BASEBOARD_FAB2_LIB.BASEBOARD_FAB2(SCH_1):PVCCMCP_CPU0   I173 @BASEBOARD_FAB2_LIB.BASEBOARD_FAB2(SCH_1):PAGE42
     2    GND @BASEBOARD_FAB2_LIB.BASEBOARD_FAB2(SCH_1):GND   I173 @BASEBOARD_FAB2_LIB.BASEBOARD_FAB2(SCH_1):PAGE42

C5D21 CAP_A_0603V-22.0UF,4V,20%,X6S,A
     1 PVCCMCP_CPU0 @BASEBOARD_FAB2_LIB.BASEBOARD_FAB2(SCH_1):PVCCMCP_CPU0    I88 @BASEBOARD_FAB2_LIB.BASEBOARD_FAB2(SCH_1):PAGE42
     2    GND @BASEBOARD_FAB2_LIB.BASEBOARD_FAB2(SCH_1):GND    I88 @BASEBOARD_FAB2_LIB.BASEBOARD_FAB2(SCH_1):PAGE42

C5D22 CAP_A_0603V-22.0UF,4V,20%,X6S,A
     1 PVCCMCP_CPU0 @BASEBOARD_FAB2_LIB.BASEBOARD_FAB2(SCH_1):PVCCMCP_CPU0   I153 @BASEBOARD_FAB2_LIB.BASEBOARD_FAB2(SCH_1):PAGE42
     2    GND @BASEBOARD_FAB2_LIB.BASEBOARD_FAB2(SCH_1):GND   I153 @BASEBOARD_FAB2_LIB.BASEBOARD_FAB2(SCH_1):PAGE42

C5D23 CAP_A_0603V-22.0UF,4V,20%,X6S,A
     1 PVCCMCP_CPU0 @BASEBOARD_FAB2_LIB.BASEBOARD_FAB2(SCH_1):PVCCMCP_CPU0    I98 @BASEBOARD_FAB2_LIB.BASEBOARD_FAB2(SCH_1):PAGE42
     2    GND @BASEBOARD_FAB2_LIB.BASEBOARD_FAB2(SCH_1):GND    I98 @BASEBOARD_FAB2_LIB.BASEBOARD_FAB2(SCH_1):PAGE42

C5D24 CAP_A_0603V-22.0UF,4V,20%,X6S,A
     1 PVCCIN_CPU0 @BASEBOARD_FAB2_LIB.BASEBOARD_FAB2(SCH_1):PVCCIN_CPU0   I138 @BASEBOARD_FAB2_LIB.BASEBOARD_FAB2(SCH_1):PAGE42
     2    GND @BASEBOARD_FAB2_LIB.BASEBOARD_FAB2(SCH_1):GND   I138 @BASEBOARD_FAB2_LIB.BASEBOARD_FAB2(SCH_1):PAGE42

C5D25 CAP_A_0603V-22.0UF,4V,20%,X6S,A
     1 PVCCIN_CPU0 @BASEBOARD_FAB2_LIB.BASEBOARD_FAB2(SCH_1):PVCCIN_CPU0   I155 @BASEBOARD_FAB2_LIB.BASEBOARD_FAB2(SCH_1):PAGE42
     2    GND @BASEBOARD_FAB2_LIB.BASEBOARD_FAB2(SCH_1):GND   I155 @BASEBOARD_FAB2_LIB.BASEBOARD_FAB2(SCH_1):PAGE42

C5D26 CAP_A_0603V-22.0UF,4V,20%,X6S,A
     1 PVCCIN_CPU0 @BASEBOARD_FAB2_LIB.BASEBOARD_FAB2(SCH_1):PVCCIN_CPU0   I154 @BASEBOARD_FAB2_LIB.BASEBOARD_FAB2(SCH_1):PAGE42
     2    GND @BASEBOARD_FAB2_LIB.BASEBOARD_FAB2(SCH_1):GND   I154 @BASEBOARD_FAB2_LIB.BASEBOARD_FAB2(SCH_1):PAGE42

C5D27 CAP_A_0603V-22.0UF,4V,20%,X6S,A
     1 PVCCIN_CPU0 @BASEBOARD_FAB2_LIB.BASEBOARD_FAB2(SCH_1):PVCCIN_CPU0   I109 @BASEBOARD_FAB2_LIB.BASEBOARD_FAB2(SCH_1):PAGE42
     2    GND @BASEBOARD_FAB2_LIB.BASEBOARD_FAB2(SCH_1):GND   I109 @BASEBOARD_FAB2_LIB.BASEBOARD_FAB2(SCH_1):PAGE42

C5D28 CAP_A_0603V-22.0UF,4V,20%,X6S,A
     1 PVCCIN_CPU0 @BASEBOARD_FAB2_LIB.BASEBOARD_FAB2(SCH_1):PVCCIN_CPU0   I100 @BASEBOARD_FAB2_LIB.BASEBOARD_FAB2(SCH_1):PAGE42
     2    GND @BASEBOARD_FAB2_LIB.BASEBOARD_FAB2(SCH_1):GND   I100 @BASEBOARD_FAB2_LIB.BASEBOARD_FAB2(SCH_1):PAGE42

C5D29 CAP_A_0603V-22.0UF,4V,20%,X6S,A
     1 PVCCIN_CPU0 @BASEBOARD_FAB2_LIB.BASEBOARD_FAB2(SCH_1):PVCCIN_CPU0   I102 @BASEBOARD_FAB2_LIB.BASEBOARD_FAB2(SCH_1):PAGE42
     2    GND @BASEBOARD_FAB2_LIB.BASEBOARD_FAB2(SCH_1):GND   I102 @BASEBOARD_FAB2_LIB.BASEBOARD_FAB2(SCH_1):PAGE42

C5D30 CAP_A_0603V-22.0UF,4V,20%,X6S,A
     1 PVCCIN_CPU0 @BASEBOARD_FAB2_LIB.BASEBOARD_FAB2(SCH_1):PVCCIN_CPU0   I111 @BASEBOARD_FAB2_LIB.BASEBOARD_FAB2(SCH_1):PAGE42
     2    GND @BASEBOARD_FAB2_LIB.BASEBOARD_FAB2(SCH_1):GND   I111 @BASEBOARD_FAB2_LIB.BASEBOARD_FAB2(SCH_1):PAGE42

C5D31 CAP_A_0603V-22.0UF,4V,20%,X6S,A
     1 PVCCIN_CPU0 @BASEBOARD_FAB2_LIB.BASEBOARD_FAB2(SCH_1):PVCCIN_CPU0   I106 @BASEBOARD_FAB2_LIB.BASEBOARD_FAB2(SCH_1):PAGE42
     2    GND @BASEBOARD_FAB2_LIB.BASEBOARD_FAB2(SCH_1):GND   I106 @BASEBOARD_FAB2_LIB.BASEBOARD_FAB2(SCH_1):PAGE42

C5D32 CAP_A_0603V-22.0UF,4V,20%,X6S,A
     1 PVCCIN_CPU0 @BASEBOARD_FAB2_LIB.BASEBOARD_FAB2(SCH_1):PVCCIN_CPU0   I103 @BASEBOARD_FAB2_LIB.BASEBOARD_FAB2(SCH_1):PAGE42
     2    GND @BASEBOARD_FAB2_LIB.BASEBOARD_FAB2(SCH_1):GND   I103 @BASEBOARD_FAB2_LIB.BASEBOARD_FAB2(SCH_1):PAGE42

C5D33 CAP_A_0603V-22.0UF,4V,20%,X6S,A
     1 PVCCMCP_CPU0 @BASEBOARD_FAB2_LIB.BASEBOARD_FAB2(SCH_1):PVCCMCP_CPU0   I174 @BASEBOARD_FAB2_LIB.BASEBOARD_FAB2(SCH_1):PAGE42
     2    GND @BASEBOARD_FAB2_LIB.BASEBOARD_FAB2(SCH_1):GND   I174 @BASEBOARD_FAB2_LIB.BASEBOARD_FAB2(SCH_1):PAGE42

C5D34 CAP_A_0603V-22.0UF,4V,20%,X6S,A
     1 PVCCMCP_CPU0 @BASEBOARD_FAB2_LIB.BASEBOARD_FAB2(SCH_1):PVCCMCP_CPU0   I175 @BASEBOARD_FAB2_LIB.BASEBOARD_FAB2(SCH_1):PAGE42
     2    GND @BASEBOARD_FAB2_LIB.BASEBOARD_FAB2(SCH_1):GND   I175 @BASEBOARD_FAB2_LIB.BASEBOARD_FAB2(SCH_1):PAGE42

C5D35 CAP_A_0603V-22.0UF,4V,20%,X6S,A
     1 PVCCMCP_CPU0 @BASEBOARD_FAB2_LIB.BASEBOARD_FAB2(SCH_1):PVCCMCP_CPU0   I176 @BASEBOARD_FAB2_LIB.BASEBOARD_FAB2(SCH_1):PAGE42
     2    GND @BASEBOARD_FAB2_LIB.BASEBOARD_FAB2(SCH_1):GND   I176 @BASEBOARD_FAB2_LIB.BASEBOARD_FAB2(SCH_1):PAGE42

C5D36 CAP_A_0603V-22.0UF,4V,20%,X6S,A
     1 PVCCMCP_CPU0 @BASEBOARD_FAB2_LIB.BASEBOARD_FAB2(SCH_1):PVCCMCP_CPU0   I151 @BASEBOARD_FAB2_LIB.BASEBOARD_FAB2(SCH_1):PAGE42
     2    GND @BASEBOARD_FAB2_LIB.BASEBOARD_FAB2(SCH_1):GND   I151 @BASEBOARD_FAB2_LIB.BASEBOARD_FAB2(SCH_1):PAGE42

C5D37 CAP_A_0603V-22.0UF,4V,20%,X6S,A
     1 PVCCMCP_CPU0 @BASEBOARD_FAB2_LIB.BASEBOARD_FAB2(SCH_1):PVCCMCP_CPU0    I70 @BASEBOARD_FAB2_LIB.BASEBOARD_FAB2(SCH_1):PAGE42
     2    GND @BASEBOARD_FAB2_LIB.BASEBOARD_FAB2(SCH_1):GND    I70 @BASEBOARD_FAB2_LIB.BASEBOARD_FAB2(SCH_1):PAGE42

C5D38 CAP_A_0603V-22.0UF,4V,20%,X6S,A
     1 PVCCMCP_CPU0 @BASEBOARD_FAB2_LIB.BASEBOARD_FAB2(SCH_1):PVCCMCP_CPU0    I69 @BASEBOARD_FAB2_LIB.BASEBOARD_FAB2(SCH_1):PAGE42
     2    GND @BASEBOARD_FAB2_LIB.BASEBOARD_FAB2(SCH_1):GND    I69 @BASEBOARD_FAB2_LIB.BASEBOARD_FAB2(SCH_1):PAGE42

C5D39 CAP_A_0603V-22.0UF,4V,20%,X6S,A
     1 PVCCIN_CPU0 @BASEBOARD_FAB2_LIB.BASEBOARD_FAB2(SCH_1):PVCCIN_CPU0   I140 @BASEBOARD_FAB2_LIB.BASEBOARD_FAB2(SCH_1):PAGE42
     2    GND @BASEBOARD_FAB2_LIB.BASEBOARD_FAB2(SCH_1):GND   I140 @BASEBOARD_FAB2_LIB.BASEBOARD_FAB2(SCH_1):PAGE42

C5D40 CAP_A_0603V-22.0UF,4V,20%,X6S,A
     1 PVCCIN_CPU0 @BASEBOARD_FAB2_LIB.BASEBOARD_FAB2(SCH_1):PVCCIN_CPU0   I115 @BASEBOARD_FAB2_LIB.BASEBOARD_FAB2(SCH_1):PAGE42
     2    GND @BASEBOARD_FAB2_LIB.BASEBOARD_FAB2(SCH_1):GND   I115 @BASEBOARD_FAB2_LIB.BASEBOARD_FAB2(SCH_1):PAGE42

C5D41 CAP_A_0603V-22.0UF,4V,20%,X6S,A
     1 PVCCIN_CPU0 @BASEBOARD_FAB2_LIB.BASEBOARD_FAB2(SCH_1):PVCCIN_CPU0   I114 @BASEBOARD_FAB2_LIB.BASEBOARD_FAB2(SCH_1):PAGE42
     2    GND @BASEBOARD_FAB2_LIB.BASEBOARD_FAB2(SCH_1):GND   I114 @BASEBOARD_FAB2_LIB.BASEBOARD_FAB2(SCH_1):PAGE42

C5D42 CAP_A_0603V-22.0UF,4V,20%,X6S,A
     1 PVCCIN_CPU0 @BASEBOARD_FAB2_LIB.BASEBOARD_FAB2(SCH_1):PVCCIN_CPU0   I135 @BASEBOARD_FAB2_LIB.BASEBOARD_FAB2(SCH_1):PAGE42
     2    GND @BASEBOARD_FAB2_LIB.BASEBOARD_FAB2(SCH_1):GND   I135 @BASEBOARD_FAB2_LIB.BASEBOARD_FAB2(SCH_1):PAGE42

C5D43 CAP_A_0603V-22.0UF,4V,20%,X6S,A
     1 PVCCIN_CPU0 @BASEBOARD_FAB2_LIB.BASEBOARD_FAB2(SCH_1):PVCCIN_CPU0   I131 @BASEBOARD_FAB2_LIB.BASEBOARD_FAB2(SCH_1):PAGE42
     2    GND @BASEBOARD_FAB2_LIB.BASEBOARD_FAB2(SCH_1):GND   I131 @BASEBOARD_FAB2_LIB.BASEBOARD_FAB2(SCH_1):PAGE42

C5D44 CAP_A_0603V-22.0UF,4V,20%,X6S,A
     1 PVCCIN_CPU0 @BASEBOARD_FAB2_LIB.BASEBOARD_FAB2(SCH_1):PVCCIN_CPU0   I142 @BASEBOARD_FAB2_LIB.BASEBOARD_FAB2(SCH_1):PAGE42
     2    GND @BASEBOARD_FAB2_LIB.BASEBOARD_FAB2(SCH_1):GND   I142 @BASEBOARD_FAB2_LIB.BASEBOARD_FAB2(SCH_1):PAGE42

C5D45 CAP_A_0603V-22.0UF,4V,20%,X6S,A
     1 PVCCIN_CPU0 @BASEBOARD_FAB2_LIB.BASEBOARD_FAB2(SCH_1):PVCCIN_CPU0   I156 @BASEBOARD_FAB2_LIB.BASEBOARD_FAB2(SCH_1):PAGE42
     2    GND @BASEBOARD_FAB2_LIB.BASEBOARD_FAB2(SCH_1):GND   I156 @BASEBOARD_FAB2_LIB.BASEBOARD_FAB2(SCH_1):PAGE42

C5D46 CAP_A_0603V-22.0UF,4V,20%,X6S,A
     1 PVCCIN_CPU0 @BASEBOARD_FAB2_LIB.BASEBOARD_FAB2(SCH_1):PVCCIN_CPU0   I107 @BASEBOARD_FAB2_LIB.BASEBOARD_FAB2(SCH_1):PAGE42
     2    GND @BASEBOARD_FAB2_LIB.BASEBOARD_FAB2(SCH_1):GND   I107 @BASEBOARD_FAB2_LIB.BASEBOARD_FAB2(SCH_1):PAGE42

C5D47 CAP_A_0603V-22.0UF,4V,20%,X6S,A
     1 PVCCIN_CPU0 @BASEBOARD_FAB2_LIB.BASEBOARD_FAB2(SCH_1):PVCCIN_CPU0   I104 @BASEBOARD_FAB2_LIB.BASEBOARD_FAB2(SCH_1):PAGE42
     2    GND @BASEBOARD_FAB2_LIB.BASEBOARD_FAB2(SCH_1):GND   I104 @BASEBOARD_FAB2_LIB.BASEBOARD_FAB2(SCH_1):PAGE42

C5D48 CAP_A_0603V-22.0UF,4V,20%,X6S,A
     1 PVCCMCP_CPU0 @BASEBOARD_FAB2_LIB.BASEBOARD_FAB2(SCH_1):PVCCMCP_CPU0    I90 @BASEBOARD_FAB2_LIB.BASEBOARD_FAB2(SCH_1):PAGE42
     2    GND @BASEBOARD_FAB2_LIB.BASEBOARD_FAB2(SCH_1):GND    I90 @BASEBOARD_FAB2_LIB.BASEBOARD_FAB2(SCH_1):PAGE42

C5D49 CAP_A_0603V-22.0UF,4V,20%,X6S,A
     1 PVCCMCP_CPU0 @BASEBOARD_FAB2_LIB.BASEBOARD_FAB2(SCH_1):PVCCMCP_CPU0   I152 @BASEBOARD_FAB2_LIB.BASEBOARD_FAB2(SCH_1):PAGE42
     2    GND @BASEBOARD_FAB2_LIB.BASEBOARD_FAB2(SCH_1):GND   I152 @BASEBOARD_FAB2_LIB.BASEBOARD_FAB2(SCH_1):PAGE42

C5D50 CAP_A_0603V-22.0UF,4V,20%,X6S,A
     1 PVCCMCP_CPU0 @BASEBOARD_FAB2_LIB.BASEBOARD_FAB2(SCH_1):PVCCMCP_CPU0    I89 @BASEBOARD_FAB2_LIB.BASEBOARD_FAB2(SCH_1):PAGE42
     2    GND @BASEBOARD_FAB2_LIB.BASEBOARD_FAB2(SCH_1):GND    I89 @BASEBOARD_FAB2_LIB.BASEBOARD_FAB2(SCH_1):PAGE42

C5D51 CAP_A_0603V-22.0UF,4V,20%,X6S,A
     1 PVCCMCP_CPU0 @BASEBOARD_FAB2_LIB.BASEBOARD_FAB2(SCH_1):PVCCMCP_CPU0    I83 @BASEBOARD_FAB2_LIB.BASEBOARD_FAB2(SCH_1):PAGE42
     2    GND @BASEBOARD_FAB2_LIB.BASEBOARD_FAB2(SCH_1):GND    I83 @BASEBOARD_FAB2_LIB.BASEBOARD_FAB2(SCH_1):PAGE42

C5D52 CAP_A_0603V-22.0UF,4V,20%,X6S,A
     1 PVCCMCP_CPU0 @BASEBOARD_FAB2_LIB.BASEBOARD_FAB2(SCH_1):PVCCMCP_CPU0   I180 @BASEBOARD_FAB2_LIB.BASEBOARD_FAB2(SCH_1):PAGE42
     2    GND @BASEBOARD_FAB2_LIB.BASEBOARD_FAB2(SCH_1):GND   I180 @BASEBOARD_FAB2_LIB.BASEBOARD_FAB2(SCH_1):PAGE42

C5D53 CAP_A_0603V-22.0UF,4V,20%,X6S,A
     1 PVCCMCP_CPU0 @BASEBOARD_FAB2_LIB.BASEBOARD_FAB2(SCH_1):PVCCMCP_CPU0   I179 @BASEBOARD_FAB2_LIB.BASEBOARD_FAB2(SCH_1):PAGE42
     2    GND @BASEBOARD_FAB2_LIB.BASEBOARD_FAB2(SCH_1):GND   I179 @BASEBOARD_FAB2_LIB.BASEBOARD_FAB2(SCH_1):PAGE42

C5D54 CAP_0603LF-10UF,4V,20%,X6S,E15A
     1 PVDDQ_ABC @BASEBOARD_FAB2_LIB.BASEBOARD_FAB2(SCH_1):PVDDQ_ABC   I190 @BASEBOARD_FAB2_LIB.BASEBOARD_FAB2(SCH_1):PAGE217
     2    GND @BASEBOARD_FAB2_LIB.BASEBOARD_FAB2(SCH_1):GND   I190 @BASEBOARD_FAB2_LIB.BASEBOARD_FAB2(SCH_1):PAGE217

C5D55 CAP_0603LF-10UF,4V,20%,X6S,E15A
     1 PVDDQ_ABC @BASEBOARD_FAB2_LIB.BASEBOARD_FAB2(SCH_1):PVDDQ_ABC   I189 @BASEBOARD_FAB2_LIB.BASEBOARD_FAB2(SCH_1):PAGE217
     2    GND @BASEBOARD_FAB2_LIB.BASEBOARD_FAB2(SCH_1):GND   I189 @BASEBOARD_FAB2_LIB.BASEBOARD_FAB2(SCH_1):PAGE217

C5D56 CAP_0603LF-10UF,4V,20%,X6S,E15A
     1 PVDDQ_ABC @BASEBOARD_FAB2_LIB.BASEBOARD_FAB2(SCH_1):PVDDQ_ABC   I188 @BASEBOARD_FAB2_LIB.BASEBOARD_FAB2(SCH_1):PAGE217
     2    GND @BASEBOARD_FAB2_LIB.BASEBOARD_FAB2(SCH_1):GND   I188 @BASEBOARD_FAB2_LIB.BASEBOARD_FAB2(SCH_1):PAGE217

C5D57 CAP_0603LF-10UF,4V,20%,X6S,E15A
     1 PVDDQ_ABC @BASEBOARD_FAB2_LIB.BASEBOARD_FAB2(SCH_1):PVDDQ_ABC   I186 @BASEBOARD_FAB2_LIB.BASEBOARD_FAB2(SCH_1):PAGE217
     2    GND @BASEBOARD_FAB2_LIB.BASEBOARD_FAB2(SCH_1):GND   I186 @BASEBOARD_FAB2_LIB.BASEBOARD_FAB2(SCH_1):PAGE217

C5D58 CAP_A_0603V-22.0UF,4V,20%,X6S,A
     1 PVCCIN_CPU0 @BASEBOARD_FAB2_LIB.BASEBOARD_FAB2(SCH_1):PVCCIN_CPU0   I120 @BASEBOARD_FAB2_LIB.BASEBOARD_FAB2(SCH_1):PAGE42
     2    GND @BASEBOARD_FAB2_LIB.BASEBOARD_FAB2(SCH_1):GND   I120 @BASEBOARD_FAB2_LIB.BASEBOARD_FAB2(SCH_1):PAGE42

C5D59 CAP_A_0603V-22.0UF,4V,20%,X6S,A
     1 PVCCIN_CPU0 @BASEBOARD_FAB2_LIB.BASEBOARD_FAB2(SCH_1):PVCCIN_CPU0   I129 @BASEBOARD_FAB2_LIB.BASEBOARD_FAB2(SCH_1):PAGE42
     2    GND @BASEBOARD_FAB2_LIB.BASEBOARD_FAB2(SCH_1):GND   I129 @BASEBOARD_FAB2_LIB.BASEBOARD_FAB2(SCH_1):PAGE42

C5D60 CAP_A_0603V-22.0UF,4V,20%,X6S,A
     1 PVCCIN_CPU0 @BASEBOARD_FAB2_LIB.BASEBOARD_FAB2(SCH_1):PVCCIN_CPU0   I112 @BASEBOARD_FAB2_LIB.BASEBOARD_FAB2(SCH_1):PAGE42
     2    GND @BASEBOARD_FAB2_LIB.BASEBOARD_FAB2(SCH_1):GND   I112 @BASEBOARD_FAB2_LIB.BASEBOARD_FAB2(SCH_1):PAGE42

C5D61 CAP_A_0603V-22.0UF,4V,20%,X6S,A
     1 PVCCIN_CPU0 @BASEBOARD_FAB2_LIB.BASEBOARD_FAB2(SCH_1):PVCCIN_CPU0   I113 @BASEBOARD_FAB2_LIB.BASEBOARD_FAB2(SCH_1):PAGE42
     2    GND @BASEBOARD_FAB2_LIB.BASEBOARD_FAB2(SCH_1):GND   I113 @BASEBOARD_FAB2_LIB.BASEBOARD_FAB2(SCH_1):PAGE42

C5F1 CAP_A_0603V-47UF,4V,20%,X5R,60A
     1 PVDDQ_ABC @BASEBOARD_FAB2_LIB.BASEBOARD_FAB2(SCH_1):PVDDQ_ABC   I206 @BASEBOARD_FAB2_LIB.BASEBOARD_FAB2(SCH_1):PAGE217
     2    GND @BASEBOARD_FAB2_LIB.BASEBOARD_FAB2(SCH_1):GND   I206 @BASEBOARD_FAB2_LIB.BASEBOARD_FAB2(SCH_1):PAGE217

C5F2 CAP_A_0603V-47UF,4V,20%,X5R,60A
     1 PVDDQ_ABC @BASEBOARD_FAB2_LIB.BASEBOARD_FAB2(SCH_1):PVDDQ_ABC   I205 @BASEBOARD_FAB2_LIB.BASEBOARD_FAB2(SCH_1):PAGE217
     2    GND @BASEBOARD_FAB2_LIB.BASEBOARD_FAB2(SCH_1):GND   I205 @BASEBOARD_FAB2_LIB.BASEBOARD_FAB2(SCH_1):PAGE217

C5G1 CAP_A_0603V-22.0UF,4V,20%,X6S,A
     1 PVDDQ_ABC @BASEBOARD_FAB2_LIB.BASEBOARD_FAB2(SCH_1):PVDDQ_ABC   I231 @BASEBOARD_FAB2_LIB.BASEBOARD_FAB2(SCH_1):PAGE217
     2    GND @BASEBOARD_FAB2_LIB.BASEBOARD_FAB2(SCH_1):GND   I231 @BASEBOARD_FAB2_LIB.BASEBOARD_FAB2(SCH_1):PAGE217

C5G2 CAP_A_0603V-22.0UF,4V,20%,X6S,A
     1 PVDDQ_ABC @BASEBOARD_FAB2_LIB.BASEBOARD_FAB2(SCH_1):PVDDQ_ABC   I245 @BASEBOARD_FAB2_LIB.BASEBOARD_FAB2(SCH_1):PAGE217
     2    GND @BASEBOARD_FAB2_LIB.BASEBOARD_FAB2(SCH_1):GND   I245 @BASEBOARD_FAB2_LIB.BASEBOARD_FAB2(SCH_1):PAGE217

C5G3 CAP_A_0603V-22.0UF,4V,20%,X6S,A
     1 PVDDQ_ABC @BASEBOARD_FAB2_LIB.BASEBOARD_FAB2(SCH_1):PVDDQ_ABC   I217 @BASEBOARD_FAB2_LIB.BASEBOARD_FAB2(SCH_1):PAGE217
     2    GND @BASEBOARD_FAB2_LIB.BASEBOARD_FAB2(SCH_1):GND   I217 @BASEBOARD_FAB2_LIB.BASEBOARD_FAB2(SCH_1):PAGE217

C5G4 CAP_A_0603V-22.0UF,4V,20%,X6S,A
     1 PVDDQ_ABC @BASEBOARD_FAB2_LIB.BASEBOARD_FAB2(SCH_1):PVDDQ_ABC   I241 @BASEBOARD_FAB2_LIB.BASEBOARD_FAB2(SCH_1):PAGE217
     2    GND @BASEBOARD_FAB2_LIB.BASEBOARD_FAB2(SCH_1):GND   I241 @BASEBOARD_FAB2_LIB.BASEBOARD_FAB2(SCH_1):PAGE217

C5G5 CAP_A_0603V-22.0UF,4V,20%,X6S,A
     1 PVDDQ_ABC @BASEBOARD_FAB2_LIB.BASEBOARD_FAB2(SCH_1):PVDDQ_ABC   I235 @BASEBOARD_FAB2_LIB.BASEBOARD_FAB2(SCH_1):PAGE217
     2    GND @BASEBOARD_FAB2_LIB.BASEBOARD_FAB2(SCH_1):GND   I235 @BASEBOARD_FAB2_LIB.BASEBOARD_FAB2(SCH_1):PAGE217

C5G6 CAP_A_0603V-22.0UF,4V,20%,X6S,A
     1 PVDDQ_ABC @BASEBOARD_FAB2_LIB.BASEBOARD_FAB2(SCH_1):PVDDQ_ABC   I237 @BASEBOARD_FAB2_LIB.BASEBOARD_FAB2(SCH_1):PAGE217
     2    GND @BASEBOARD_FAB2_LIB.BASEBOARD_FAB2(SCH_1):GND   I237 @BASEBOARD_FAB2_LIB.BASEBOARD_FAB2(SCH_1):PAGE217

C5G7 CAP_A_0603V-22.0UF,4V,20%,X6S,A
     1 PVDDQ_ABC @BASEBOARD_FAB2_LIB.BASEBOARD_FAB2(SCH_1):PVDDQ_ABC   I234 @BASEBOARD_FAB2_LIB.BASEBOARD_FAB2(SCH_1):PAGE217
     2    GND @BASEBOARD_FAB2_LIB.BASEBOARD_FAB2(SCH_1):GND   I234 @BASEBOARD_FAB2_LIB.BASEBOARD_FAB2(SCH_1):PAGE217

C5G8 CAP_A_0603V-22.0UF,4V,20%,X6S,A
     1 PVDDQ_ABC @BASEBOARD_FAB2_LIB.BASEBOARD_FAB2(SCH_1):PVDDQ_ABC   I230 @BASEBOARD_FAB2_LIB.BASEBOARD_FAB2(SCH_1):PAGE217
     2    GND @BASEBOARD_FAB2_LIB.BASEBOARD_FAB2(SCH_1):GND   I230 @BASEBOARD_FAB2_LIB.BASEBOARD_FAB2(SCH_1):PAGE217

C5G9 CAP_0805-100UF,4V,20%,X5R,6024A
     1 PVDDQ_ABC @BASEBOARD_FAB2_LIB.BASEBOARD_FAB2(SCH_1):PVDDQ_ABC    I92 @BASEBOARD_FAB2_LIB.BASEBOARD_FAB2(SCH_1):PAGE217
     2    GND @BASEBOARD_FAB2_LIB.BASEBOARD_FAB2(SCH_1):GND    I92 @BASEBOARD_FAB2_LIB.BASEBOARD_FAB2(SCH_1):PAGE217

C5G10 CAP_A_0603V-47UF,4V,20%,X5R,60A
     1 PVDDQ_ABC @BASEBOARD_FAB2_LIB.BASEBOARD_FAB2(SCH_1):PVDDQ_ABC   I207 @BASEBOARD_FAB2_LIB.BASEBOARD_FAB2(SCH_1):PAGE217
     2    GND @BASEBOARD_FAB2_LIB.BASEBOARD_FAB2(SCH_1):GND   I207 @BASEBOARD_FAB2_LIB.BASEBOARD_FAB2(SCH_1):PAGE217

C5G11 CAP_A_0603V-22.0UF,4V,20%,X6S,A
     1 PVDDQ_ABC @BASEBOARD_FAB2_LIB.BASEBOARD_FAB2(SCH_1):PVDDQ_ABC   I250 @BASEBOARD_FAB2_LIB.BASEBOARD_FAB2(SCH_1):PAGE217
     2    GND @BASEBOARD_FAB2_LIB.BASEBOARD_FAB2(SCH_1):GND   I250 @BASEBOARD_FAB2_LIB.BASEBOARD_FAB2(SCH_1):PAGE217

C5G12 CAP_A_0603V-22.0UF,4V,20%,X6S,A
     1 PVDDQ_ABC @BASEBOARD_FAB2_LIB.BASEBOARD_FAB2(SCH_1):PVDDQ_ABC   I246 @BASEBOARD_FAB2_LIB.BASEBOARD_FAB2(SCH_1):PAGE217
     2    GND @BASEBOARD_FAB2_LIB.BASEBOARD_FAB2(SCH_1):GND   I246 @BASEBOARD_FAB2_LIB.BASEBOARD_FAB2(SCH_1):PAGE217

C5G13 CAP_A_0603V-22.0UF,4V,20%,X6S,A
     1 PVDDQ_ABC @BASEBOARD_FAB2_LIB.BASEBOARD_FAB2(SCH_1):PVDDQ_ABC   I240 @BASEBOARD_FAB2_LIB.BASEBOARD_FAB2(SCH_1):PAGE217
     2    GND @BASEBOARD_FAB2_LIB.BASEBOARD_FAB2(SCH_1):GND   I240 @BASEBOARD_FAB2_LIB.BASEBOARD_FAB2(SCH_1):PAGE217

C5G14 CAP_A_0603V-22.0UF,4V,20%,X6S,A
     1 PVDDQ_ABC @BASEBOARD_FAB2_LIB.BASEBOARD_FAB2(SCH_1):PVDDQ_ABC   I223 @BASEBOARD_FAB2_LIB.BASEBOARD_FAB2(SCH_1):PAGE217
     2    GND @BASEBOARD_FAB2_LIB.BASEBOARD_FAB2(SCH_1):GND   I223 @BASEBOARD_FAB2_LIB.BASEBOARD_FAB2(SCH_1):PAGE217

C5G15 CAP_A_0603V-22.0UF,4V,20%,X6S,A
     1 PVDDQ_ABC @BASEBOARD_FAB2_LIB.BASEBOARD_FAB2(SCH_1):PVDDQ_ABC   I220 @BASEBOARD_FAB2_LIB.BASEBOARD_FAB2(SCH_1):PAGE217
     2    GND @BASEBOARD_FAB2_LIB.BASEBOARD_FAB2(SCH_1):GND   I220 @BASEBOARD_FAB2_LIB.BASEBOARD_FAB2(SCH_1):PAGE217

C5G16 CAP_A_0603V-22.0UF,4V,20%,X6S,A
     1 PVDDQ_ABC @BASEBOARD_FAB2_LIB.BASEBOARD_FAB2(SCH_1):PVDDQ_ABC   I221 @BASEBOARD_FAB2_LIB.BASEBOARD_FAB2(SCH_1):PAGE217
     2    GND @BASEBOARD_FAB2_LIB.BASEBOARD_FAB2(SCH_1):GND   I221 @BASEBOARD_FAB2_LIB.BASEBOARD_FAB2(SCH_1):PAGE217

C5G17 CAP_A_0603V-22.0UF,4V,20%,X6S,A
     1 PVDDQ_ABC @BASEBOARD_FAB2_LIB.BASEBOARD_FAB2(SCH_1):PVDDQ_ABC   I226 @BASEBOARD_FAB2_LIB.BASEBOARD_FAB2(SCH_1):PAGE217
     2    GND @BASEBOARD_FAB2_LIB.BASEBOARD_FAB2(SCH_1):GND   I226 @BASEBOARD_FAB2_LIB.BASEBOARD_FAB2(SCH_1):PAGE217

C5G18 CAP_A_0603V-22.0UF,4V,20%,X6S,A
     1 PVDDQ_ABC @BASEBOARD_FAB2_LIB.BASEBOARD_FAB2(SCH_1):PVDDQ_ABC   I227 @BASEBOARD_FAB2_LIB.BASEBOARD_FAB2(SCH_1):PAGE217
     2    GND @BASEBOARD_FAB2_LIB.BASEBOARD_FAB2(SCH_1):GND   I227 @BASEBOARD_FAB2_LIB.BASEBOARD_FAB2(SCH_1):PAGE217

C5G19 CAP_A_0603V-47UF,4V,20%,X5R,60A
     1 PVDDQ_ABC @BASEBOARD_FAB2_LIB.BASEBOARD_FAB2(SCH_1):PVDDQ_ABC   I213 @BASEBOARD_FAB2_LIB.BASEBOARD_FAB2(SCH_1):PAGE217
     2    GND @BASEBOARD_FAB2_LIB.BASEBOARD_FAB2(SCH_1):GND   I213 @BASEBOARD_FAB2_LIB.BASEBOARD_FAB2(SCH_1):PAGE217

C5G20 CAP_0805-100UF,4V,20%,X5R,6024A
     1 PVDDQ_ABC @BASEBOARD_FAB2_LIB.BASEBOARD_FAB2(SCH_1):PVDDQ_ABC   I110 @BASEBOARD_FAB2_LIB.BASEBOARD_FAB2(SCH_1):PAGE217
     2    GND @BASEBOARD_FAB2_LIB.BASEBOARD_FAB2(SCH_1):GND   I110 @BASEBOARD_FAB2_LIB.BASEBOARD_FAB2(SCH_1):PAGE217

C5G21 CAP_0805-100UF,4V,20%,X5R,6024A
     1 PVDDQ_ABC @BASEBOARD_FAB2_LIB.BASEBOARD_FAB2(SCH_1):PVDDQ_ABC    I11 @BASEBOARD_FAB2_LIB.BASEBOARD_FAB2(SCH_1):PAGE242
     2    GND @BASEBOARD_FAB2_LIB.BASEBOARD_FAB2(SCH_1):GND    I11 @BASEBOARD_FAB2_LIB.BASEBOARD_FAB2(SCH_1):PAGE242

C5G22 CAP_0805-100UF,4V,20%,X5R,6024A
     1 PVDDQ_ABC @BASEBOARD_FAB2_LIB.BASEBOARD_FAB2(SCH_1):PVDDQ_ABC    I15 @BASEBOARD_FAB2_LIB.BASEBOARD_FAB2(SCH_1):PAGE242
     2    GND @BASEBOARD_FAB2_LIB.BASEBOARD_FAB2(SCH_1):GND    I15 @BASEBOARD_FAB2_LIB.BASEBOARD_FAB2(SCH_1):PAGE242

C5G41 CAP_A_0603V-22.0UF,4V,20%,X6S,A
     1 PVDDQ_ABC @BASEBOARD_FAB2_LIB.BASEBOARD_FAB2(SCH_1):PVDDQ_ABC    I53 @BASEBOARD_FAB2_LIB.BASEBOARD_FAB2(SCH_1):PAGE242
     2    GND @BASEBOARD_FAB2_LIB.BASEBOARD_FAB2(SCH_1):GND    I53 @BASEBOARD_FAB2_LIB.BASEBOARD_FAB2(SCH_1):PAGE242

C5G42 CAP_A_0603V-22.0UF,4V,20%,X6S,A
     1 PVDDQ_ABC @BASEBOARD_FAB2_LIB.BASEBOARD_FAB2(SCH_1):PVDDQ_ABC    I54 @BASEBOARD_FAB2_LIB.BASEBOARD_FAB2(SCH_1):PAGE242
     2    GND @BASEBOARD_FAB2_LIB.BASEBOARD_FAB2(SCH_1):GND    I54 @BASEBOARD_FAB2_LIB.BASEBOARD_FAB2(SCH_1):PAGE242

C5G43 CAP_A_0603V-22.0UF,4V,20%,X6S,A
     1 PVDDQ_ABC @BASEBOARD_FAB2_LIB.BASEBOARD_FAB2(SCH_1):PVDDQ_ABC    I56 @BASEBOARD_FAB2_LIB.BASEBOARD_FAB2(SCH_1):PAGE242
     2    GND @BASEBOARD_FAB2_LIB.BASEBOARD_FAB2(SCH_1):GND    I56 @BASEBOARD_FAB2_LIB.BASEBOARD_FAB2(SCH_1):PAGE242

C5G44 CAP_A_0603V-22.0UF,4V,20%,X6S,A
     1 PVDDQ_ABC @BASEBOARD_FAB2_LIB.BASEBOARD_FAB2(SCH_1):PVDDQ_ABC    I55 @BASEBOARD_FAB2_LIB.BASEBOARD_FAB2(SCH_1):PAGE242
     2    GND @BASEBOARD_FAB2_LIB.BASEBOARD_FAB2(SCH_1):GND    I55 @BASEBOARD_FAB2_LIB.BASEBOARD_FAB2(SCH_1):PAGE242

C5G45 CAP_A_0603V-22.0UF,4V,20%,X6S,A
     1 PVDDQ_ABC @BASEBOARD_FAB2_LIB.BASEBOARD_FAB2(SCH_1):PVDDQ_ABC    I60 @BASEBOARD_FAB2_LIB.BASEBOARD_FAB2(SCH_1):PAGE242
     2    GND @BASEBOARD_FAB2_LIB.BASEBOARD_FAB2(SCH_1):GND    I60 @BASEBOARD_FAB2_LIB.BASEBOARD_FAB2(SCH_1):PAGE242

C5G46 CAP_A_0603V-22.0UF,4V,20%,X6S,A
     1 PVDDQ_ABC @BASEBOARD_FAB2_LIB.BASEBOARD_FAB2(SCH_1):PVDDQ_ABC    I59 @BASEBOARD_FAB2_LIB.BASEBOARD_FAB2(SCH_1):PAGE242
     2    GND @BASEBOARD_FAB2_LIB.BASEBOARD_FAB2(SCH_1):GND    I59 @BASEBOARD_FAB2_LIB.BASEBOARD_FAB2(SCH_1):PAGE242

C5G47 CAP_A_0603V-22.0UF,4V,20%,X6S,A
     1 PVDDQ_ABC @BASEBOARD_FAB2_LIB.BASEBOARD_FAB2(SCH_1):PVDDQ_ABC    I58 @BASEBOARD_FAB2_LIB.BASEBOARD_FAB2(SCH_1):PAGE242
     2    GND @BASEBOARD_FAB2_LIB.BASEBOARD_FAB2(SCH_1):GND    I58 @BASEBOARD_FAB2_LIB.BASEBOARD_FAB2(SCH_1):PAGE242

C5G48 CAP_A_0603V-22.0UF,4V,20%,X6S,A
     1 PVDDQ_ABC @BASEBOARD_FAB2_LIB.BASEBOARD_FAB2(SCH_1):PVDDQ_ABC    I57 @BASEBOARD_FAB2_LIB.BASEBOARD_FAB2(SCH_1):PAGE242
     2    GND @BASEBOARD_FAB2_LIB.BASEBOARD_FAB2(SCH_1):GND    I57 @BASEBOARD_FAB2_LIB.BASEBOARD_FAB2(SCH_1):PAGE242

C5G49 CAP_A_0603V-22.0UF,4V,20%,X6S,A
     1 PVDDQ_ABC @BASEBOARD_FAB2_LIB.BASEBOARD_FAB2(SCH_1):PVDDQ_ABC    I61 @BASEBOARD_FAB2_LIB.BASEBOARD_FAB2(SCH_1):PAGE242
     2    GND @BASEBOARD_FAB2_LIB.BASEBOARD_FAB2(SCH_1):GND    I61 @BASEBOARD_FAB2_LIB.BASEBOARD_FAB2(SCH_1):PAGE242

C5G50 CAP_A_0603V-22.0UF,4V,20%,X6S,A
     1 PVDDQ_ABC @BASEBOARD_FAB2_LIB.BASEBOARD_FAB2(SCH_1):PVDDQ_ABC    I70 @BASEBOARD_FAB2_LIB.BASEBOARD_FAB2(SCH_1):PAGE242
     2    GND @BASEBOARD_FAB2_LIB.BASEBOARD_FAB2(SCH_1):GND    I70 @BASEBOARD_FAB2_LIB.BASEBOARD_FAB2(SCH_1):PAGE242

C5G51 CAP_A_0603V-22.0UF,4V,20%,X6S,A
     1 PVDDQ_ABC @BASEBOARD_FAB2_LIB.BASEBOARD_FAB2(SCH_1):PVDDQ_ABC    I69 @BASEBOARD_FAB2_LIB.BASEBOARD_FAB2(SCH_1):PAGE242
     2    GND @BASEBOARD_FAB2_LIB.BASEBOARD_FAB2(SCH_1):GND    I69 @BASEBOARD_FAB2_LIB.BASEBOARD_FAB2(SCH_1):PAGE242

C5G52 CAP_A_0603V-22.0UF,4V,20%,X6S,A
     1 PVDDQ_ABC @BASEBOARD_FAB2_LIB.BASEBOARD_FAB2(SCH_1):PVDDQ_ABC    I68 @BASEBOARD_FAB2_LIB.BASEBOARD_FAB2(SCH_1):PAGE242
     2    GND @BASEBOARD_FAB2_LIB.BASEBOARD_FAB2(SCH_1):GND    I68 @BASEBOARD_FAB2_LIB.BASEBOARD_FAB2(SCH_1):PAGE242

C5G53 CAP_A_0603V-22.0UF,4V,20%,X6S,A
     1 PVDDQ_ABC @BASEBOARD_FAB2_LIB.BASEBOARD_FAB2(SCH_1):PVDDQ_ABC    I67 @BASEBOARD_FAB2_LIB.BASEBOARD_FAB2(SCH_1):PAGE242
     2    GND @BASEBOARD_FAB2_LIB.BASEBOARD_FAB2(SCH_1):GND    I67 @BASEBOARD_FAB2_LIB.BASEBOARD_FAB2(SCH_1):PAGE242

C5G54 CAP_A_0603V-22.0UF,4V,20%,X6S,A
     1 PVDDQ_ABC @BASEBOARD_FAB2_LIB.BASEBOARD_FAB2(SCH_1):PVDDQ_ABC    I62 @BASEBOARD_FAB2_LIB.BASEBOARD_FAB2(SCH_1):PAGE242
     2    GND @BASEBOARD_FAB2_LIB.BASEBOARD_FAB2(SCH_1):GND    I62 @BASEBOARD_FAB2_LIB.BASEBOARD_FAB2(SCH_1):PAGE242

C5G55 CAP_A_0603V-22.0UF,4V,20%,X6S,A
     1 PVDDQ_ABC @BASEBOARD_FAB2_LIB.BASEBOARD_FAB2(SCH_1):PVDDQ_ABC    I66 @BASEBOARD_FAB2_LIB.BASEBOARD_FAB2(SCH_1):PAGE242
     2    GND @BASEBOARD_FAB2_LIB.BASEBOARD_FAB2(SCH_1):GND    I66 @BASEBOARD_FAB2_LIB.BASEBOARD_FAB2(SCH_1):PAGE242

C5G56 CAP_A_0603V-22.0UF,4V,20%,X6S,A
     1 PVDDQ_ABC @BASEBOARD_FAB2_LIB.BASEBOARD_FAB2(SCH_1):PVDDQ_ABC    I65 @BASEBOARD_FAB2_LIB.BASEBOARD_FAB2(SCH_1):PAGE242
     2    GND @BASEBOARD_FAB2_LIB.BASEBOARD_FAB2(SCH_1):GND    I65 @BASEBOARD_FAB2_LIB.BASEBOARD_FAB2(SCH_1):PAGE242

C5G57 CAP_A_0603V-22.0UF,4V,20%,X6S,A
     1 PVDDQ_ABC @BASEBOARD_FAB2_LIB.BASEBOARD_FAB2(SCH_1):PVDDQ_ABC    I64 @BASEBOARD_FAB2_LIB.BASEBOARD_FAB2(SCH_1):PAGE242
     2    GND @BASEBOARD_FAB2_LIB.BASEBOARD_FAB2(SCH_1):GND    I64 @BASEBOARD_FAB2_LIB.BASEBOARD_FAB2(SCH_1):PAGE242

C5G58 CAP_A_0603V-22.0UF,4V,20%,X6S,A
     1 PVDDQ_ABC @BASEBOARD_FAB2_LIB.BASEBOARD_FAB2(SCH_1):PVDDQ_ABC    I63 @BASEBOARD_FAB2_LIB.BASEBOARD_FAB2(SCH_1):PAGE242
     2    GND @BASEBOARD_FAB2_LIB.BASEBOARD_FAB2(SCH_1):GND    I63 @BASEBOARD_FAB2_LIB.BASEBOARD_FAB2(SCH_1):PAGE242

C5G59 CAP_A_0603V-22.0UF,4V,20%,X6S,A
     1 PVDDQ_DEF @BASEBOARD_FAB2_LIB.BASEBOARD_FAB2(SCH_1):PVDDQ_DEF    I79 @BASEBOARD_FAB2_LIB.BASEBOARD_FAB2(SCH_1):PAGE242
     2    GND @BASEBOARD_FAB2_LIB.BASEBOARD_FAB2(SCH_1):GND    I79 @BASEBOARD_FAB2_LIB.BASEBOARD_FAB2(SCH_1):PAGE242

C5G60 CAP_A_0603V-22.0UF,4V,20%,X6S,A
     1 PVDDQ_DEF @BASEBOARD_FAB2_LIB.BASEBOARD_FAB2(SCH_1):PVDDQ_DEF    I78 @BASEBOARD_FAB2_LIB.BASEBOARD_FAB2(SCH_1):PAGE242
     2    GND @BASEBOARD_FAB2_LIB.BASEBOARD_FAB2(SCH_1):GND    I78 @BASEBOARD_FAB2_LIB.BASEBOARD_FAB2(SCH_1):PAGE242

C5G61 CAP_A_0603V-22.0UF,4V,20%,X6S,A
     1 PVDDQ_DEF @BASEBOARD_FAB2_LIB.BASEBOARD_FAB2(SCH_1):PVDDQ_DEF    I77 @BASEBOARD_FAB2_LIB.BASEBOARD_FAB2(SCH_1):PAGE242
     2    GND @BASEBOARD_FAB2_LIB.BASEBOARD_FAB2(SCH_1):GND    I77 @BASEBOARD_FAB2_LIB.BASEBOARD_FAB2(SCH_1):PAGE242

C5G62 CAP_A_0603V-22.0UF,4V,20%,X6S,A
     1 PVDDQ_DEF @BASEBOARD_FAB2_LIB.BASEBOARD_FAB2(SCH_1):PVDDQ_DEF    I76 @BASEBOARD_FAB2_LIB.BASEBOARD_FAB2(SCH_1):PAGE242
     2    GND @BASEBOARD_FAB2_LIB.BASEBOARD_FAB2(SCH_1):GND    I76 @BASEBOARD_FAB2_LIB.BASEBOARD_FAB2(SCH_1):PAGE242

C5G63 CAP_A_0603V-22.0UF,4V,20%,X6S,A
     1 PVDDQ_DEF @BASEBOARD_FAB2_LIB.BASEBOARD_FAB2(SCH_1):PVDDQ_DEF    I75 @BASEBOARD_FAB2_LIB.BASEBOARD_FAB2(SCH_1):PAGE242
     2    GND @BASEBOARD_FAB2_LIB.BASEBOARD_FAB2(SCH_1):GND    I75 @BASEBOARD_FAB2_LIB.BASEBOARD_FAB2(SCH_1):PAGE242

C5G64 CAP_A_0603V-22.0UF,4V,20%,X6S,A
     1 PVDDQ_DEF @BASEBOARD_FAB2_LIB.BASEBOARD_FAB2(SCH_1):PVDDQ_DEF    I74 @BASEBOARD_FAB2_LIB.BASEBOARD_FAB2(SCH_1):PAGE242
     2    GND @BASEBOARD_FAB2_LIB.BASEBOARD_FAB2(SCH_1):GND    I74 @BASEBOARD_FAB2_LIB.BASEBOARD_FAB2(SCH_1):PAGE242

C5G65 CAP_A_0603V-22.0UF,4V,20%,X6S,A
     1 PVDDQ_DEF @BASEBOARD_FAB2_LIB.BASEBOARD_FAB2(SCH_1):PVDDQ_DEF    I73 @BASEBOARD_FAB2_LIB.BASEBOARD_FAB2(SCH_1):PAGE242
     2    GND @BASEBOARD_FAB2_LIB.BASEBOARD_FAB2(SCH_1):GND    I73 @BASEBOARD_FAB2_LIB.BASEBOARD_FAB2(SCH_1):PAGE242

C5G66 CAP_A_0603V-22.0UF,4V,20%,X6S,A
     1 PVDDQ_DEF @BASEBOARD_FAB2_LIB.BASEBOARD_FAB2(SCH_1):PVDDQ_DEF    I72 @BASEBOARD_FAB2_LIB.BASEBOARD_FAB2(SCH_1):PAGE242
     2    GND @BASEBOARD_FAB2_LIB.BASEBOARD_FAB2(SCH_1):GND    I72 @BASEBOARD_FAB2_LIB.BASEBOARD_FAB2(SCH_1):PAGE242

C5G67 CAP_A_0603V-22.0UF,4V,20%,X6S,A
     1 PVDDQ_DEF @BASEBOARD_FAB2_LIB.BASEBOARD_FAB2(SCH_1):PVDDQ_DEF    I71 @BASEBOARD_FAB2_LIB.BASEBOARD_FAB2(SCH_1):PAGE242
     2    GND @BASEBOARD_FAB2_LIB.BASEBOARD_FAB2(SCH_1):GND    I71 @BASEBOARD_FAB2_LIB.BASEBOARD_FAB2(SCH_1):PAGE242

C5G68 CAP_A_0603V-22.0UF,4V,20%,X6S,A
     1 PVDDQ_DEF @BASEBOARD_FAB2_LIB.BASEBOARD_FAB2(SCH_1):PVDDQ_DEF    I88 @BASEBOARD_FAB2_LIB.BASEBOARD_FAB2(SCH_1):PAGE242
     2    GND @BASEBOARD_FAB2_LIB.BASEBOARD_FAB2(SCH_1):GND    I88 @BASEBOARD_FAB2_LIB.BASEBOARD_FAB2(SCH_1):PAGE242

C5G69 CAP_A_0603V-22.0UF,4V,20%,X6S,A
     1 PVDDQ_DEF @BASEBOARD_FAB2_LIB.BASEBOARD_FAB2(SCH_1):PVDDQ_DEF    I87 @BASEBOARD_FAB2_LIB.BASEBOARD_FAB2(SCH_1):PAGE242
     2    GND @BASEBOARD_FAB2_LIB.BASEBOARD_FAB2(SCH_1):GND    I87 @BASEBOARD_FAB2_LIB.BASEBOARD_FAB2(SCH_1):PAGE242

C5G70 CAP_A_0603V-22.0UF,4V,20%,X6S,A
     1 PVDDQ_DEF @BASEBOARD_FAB2_LIB.BASEBOARD_FAB2(SCH_1):PVDDQ_DEF    I86 @BASEBOARD_FAB2_LIB.BASEBOARD_FAB2(SCH_1):PAGE242
     2    GND @BASEBOARD_FAB2_LIB.BASEBOARD_FAB2(SCH_1):GND    I86 @BASEBOARD_FAB2_LIB.BASEBOARD_FAB2(SCH_1):PAGE242

C5G71 CAP_A_0603V-22.0UF,4V,20%,X6S,A
     1 PVDDQ_DEF @BASEBOARD_FAB2_LIB.BASEBOARD_FAB2(SCH_1):PVDDQ_DEF    I85 @BASEBOARD_FAB2_LIB.BASEBOARD_FAB2(SCH_1):PAGE242
     2    GND @BASEBOARD_FAB2_LIB.BASEBOARD_FAB2(SCH_1):GND    I85 @BASEBOARD_FAB2_LIB.BASEBOARD_FAB2(SCH_1):PAGE242

C5G72 CAP_A_0603V-22.0UF,4V,20%,X6S,A
     1 PVDDQ_DEF @BASEBOARD_FAB2_LIB.BASEBOARD_FAB2(SCH_1):PVDDQ_DEF    I84 @BASEBOARD_FAB2_LIB.BASEBOARD_FAB2(SCH_1):PAGE242
     2    GND @BASEBOARD_FAB2_LIB.BASEBOARD_FAB2(SCH_1):GND    I84 @BASEBOARD_FAB2_LIB.BASEBOARD_FAB2(SCH_1):PAGE242

C5G73 CAP_A_0603V-22.0UF,4V,20%,X6S,A
     1 PVDDQ_DEF @BASEBOARD_FAB2_LIB.BASEBOARD_FAB2(SCH_1):PVDDQ_DEF    I83 @BASEBOARD_FAB2_LIB.BASEBOARD_FAB2(SCH_1):PAGE242
     2    GND @BASEBOARD_FAB2_LIB.BASEBOARD_FAB2(SCH_1):GND    I83 @BASEBOARD_FAB2_LIB.BASEBOARD_FAB2(SCH_1):PAGE242

C5G74 CAP_A_0603V-22.0UF,4V,20%,X6S,A
     1 PVDDQ_DEF @BASEBOARD_FAB2_LIB.BASEBOARD_FAB2(SCH_1):PVDDQ_DEF    I82 @BASEBOARD_FAB2_LIB.BASEBOARD_FAB2(SCH_1):PAGE242
     2    GND @BASEBOARD_FAB2_LIB.BASEBOARD_FAB2(SCH_1):GND    I82 @BASEBOARD_FAB2_LIB.BASEBOARD_FAB2(SCH_1):PAGE242

C5G75 CAP_A_0603V-22.0UF,4V,20%,X6S,A
     1 PVDDQ_DEF @BASEBOARD_FAB2_LIB.BASEBOARD_FAB2(SCH_1):PVDDQ_DEF    I81 @BASEBOARD_FAB2_LIB.BASEBOARD_FAB2(SCH_1):PAGE242
     2    GND @BASEBOARD_FAB2_LIB.BASEBOARD_FAB2(SCH_1):GND    I81 @BASEBOARD_FAB2_LIB.BASEBOARD_FAB2(SCH_1):PAGE242

C5G76 CAP_A_0603V-22.0UF,4V,20%,X6S,A
     1 PVDDQ_DEF @BASEBOARD_FAB2_LIB.BASEBOARD_FAB2(SCH_1):PVDDQ_DEF    I80 @BASEBOARD_FAB2_LIB.BASEBOARD_FAB2(SCH_1):PAGE242
     2    GND @BASEBOARD_FAB2_LIB.BASEBOARD_FAB2(SCH_1):GND    I80 @BASEBOARD_FAB2_LIB.BASEBOARD_FAB2(SCH_1):PAGE242

C5G77 CAP_0805-100UF,4V,20%,X5R,6024A
     1 PVDDQ_DEF @BASEBOARD_FAB2_LIB.BASEBOARD_FAB2(SCH_1):PVDDQ_DEF    I37 @BASEBOARD_FAB2_LIB.BASEBOARD_FAB2(SCH_1):PAGE242
     2    GND @BASEBOARD_FAB2_LIB.BASEBOARD_FAB2(SCH_1):GND    I37 @BASEBOARD_FAB2_LIB.BASEBOARD_FAB2(SCH_1):PAGE242

C5G78 CAP_0805-100UF,4V,20%,X5R,6024A
     1 PVDDQ_DEF @BASEBOARD_FAB2_LIB.BASEBOARD_FAB2(SCH_1):PVDDQ_DEF    I41 @BASEBOARD_FAB2_LIB.BASEBOARD_FAB2(SCH_1):PAGE242
     2    GND @BASEBOARD_FAB2_LIB.BASEBOARD_FAB2(SCH_1):GND    I41 @BASEBOARD_FAB2_LIB.BASEBOARD_FAB2(SCH_1):PAGE242

C5G79 CAP_A_0603V-22.0UF,4V,20%,X6S,A
     1 PVDDQ_GHJ @BASEBOARD_FAB2_LIB.BASEBOARD_FAB2(SCH_1):PVDDQ_GHJ    I53 @BASEBOARD_FAB2_LIB.BASEBOARD_FAB2(SCH_1):PAGE243
     2    GND @BASEBOARD_FAB2_LIB.BASEBOARD_FAB2(SCH_1):GND    I53 @BASEBOARD_FAB2_LIB.BASEBOARD_FAB2(SCH_1):PAGE243

C5G80 CAP_A_0603V-22.0UF,4V,20%,X6S,A
     1 PVDDQ_GHJ @BASEBOARD_FAB2_LIB.BASEBOARD_FAB2(SCH_1):PVDDQ_GHJ    I61 @BASEBOARD_FAB2_LIB.BASEBOARD_FAB2(SCH_1):PAGE243
     2    GND @BASEBOARD_FAB2_LIB.BASEBOARD_FAB2(SCH_1):GND    I61 @BASEBOARD_FAB2_LIB.BASEBOARD_FAB2(SCH_1):PAGE243

C5G81 CAP_A_0603V-22.0UF,4V,20%,X6S,A
     1 PVDDQ_GHJ @BASEBOARD_FAB2_LIB.BASEBOARD_FAB2(SCH_1):PVDDQ_GHJ    I60 @BASEBOARD_FAB2_LIB.BASEBOARD_FAB2(SCH_1):PAGE243
     2    GND @BASEBOARD_FAB2_LIB.BASEBOARD_FAB2(SCH_1):GND    I60 @BASEBOARD_FAB2_LIB.BASEBOARD_FAB2(SCH_1):PAGE243

C5G82 CAP_A_0603V-22.0UF,4V,20%,X6S,A
     1 PVDDQ_GHJ @BASEBOARD_FAB2_LIB.BASEBOARD_FAB2(SCH_1):PVDDQ_GHJ    I59 @BASEBOARD_FAB2_LIB.BASEBOARD_FAB2(SCH_1):PAGE243
     2    GND @BASEBOARD_FAB2_LIB.BASEBOARD_FAB2(SCH_1):GND    I59 @BASEBOARD_FAB2_LIB.BASEBOARD_FAB2(SCH_1):PAGE243

C5G83 CAP_A_0603V-22.0UF,4V,20%,X6S,A
     1 PVDDQ_GHJ @BASEBOARD_FAB2_LIB.BASEBOARD_FAB2(SCH_1):PVDDQ_GHJ    I58 @BASEBOARD_FAB2_LIB.BASEBOARD_FAB2(SCH_1):PAGE243
     2    GND @BASEBOARD_FAB2_LIB.BASEBOARD_FAB2(SCH_1):GND    I58 @BASEBOARD_FAB2_LIB.BASEBOARD_FAB2(SCH_1):PAGE243

C5G84 CAP_A_0603V-22.0UF,4V,20%,X6S,A
     1 PVDDQ_GHJ @BASEBOARD_FAB2_LIB.BASEBOARD_FAB2(SCH_1):PVDDQ_GHJ    I57 @BASEBOARD_FAB2_LIB.BASEBOARD_FAB2(SCH_1):PAGE243
     2    GND @BASEBOARD_FAB2_LIB.BASEBOARD_FAB2(SCH_1):GND    I57 @BASEBOARD_FAB2_LIB.BASEBOARD_FAB2(SCH_1):PAGE243

C5G85 CAP_A_0603V-22.0UF,4V,20%,X6S,A
     1 PVDDQ_GHJ @BASEBOARD_FAB2_LIB.BASEBOARD_FAB2(SCH_1):PVDDQ_GHJ    I56 @BASEBOARD_FAB2_LIB.BASEBOARD_FAB2(SCH_1):PAGE243
     2    GND @BASEBOARD_FAB2_LIB.BASEBOARD_FAB2(SCH_1):GND    I56 @BASEBOARD_FAB2_LIB.BASEBOARD_FAB2(SCH_1):PAGE243

C5G86 CAP_A_0603V-22.0UF,4V,20%,X6S,A
     1 PVDDQ_GHJ @BASEBOARD_FAB2_LIB.BASEBOARD_FAB2(SCH_1):PVDDQ_GHJ    I55 @BASEBOARD_FAB2_LIB.BASEBOARD_FAB2(SCH_1):PAGE243
     2    GND @BASEBOARD_FAB2_LIB.BASEBOARD_FAB2(SCH_1):GND    I55 @BASEBOARD_FAB2_LIB.BASEBOARD_FAB2(SCH_1):PAGE243

C5G87 CAP_A_0603V-22.0UF,4V,20%,X6S,A
     1 PVDDQ_GHJ @BASEBOARD_FAB2_LIB.BASEBOARD_FAB2(SCH_1):PVDDQ_GHJ    I54 @BASEBOARD_FAB2_LIB.BASEBOARD_FAB2(SCH_1):PAGE243
     2    GND @BASEBOARD_FAB2_LIB.BASEBOARD_FAB2(SCH_1):GND    I54 @BASEBOARD_FAB2_LIB.BASEBOARD_FAB2(SCH_1):PAGE243

C5G88 CAP_A_0603V-22.0UF,4V,20%,X6S,A
     1 PVDDQ_GHJ @BASEBOARD_FAB2_LIB.BASEBOARD_FAB2(SCH_1):PVDDQ_GHJ    I70 @BASEBOARD_FAB2_LIB.BASEBOARD_FAB2(SCH_1):PAGE243
     2    GND @BASEBOARD_FAB2_LIB.BASEBOARD_FAB2(SCH_1):GND    I70 @BASEBOARD_FAB2_LIB.BASEBOARD_FAB2(SCH_1):PAGE243

C5G89 CAP_A_0603V-22.0UF,4V,20%,X6S,A
     1 PVDDQ_GHJ @BASEBOARD_FAB2_LIB.BASEBOARD_FAB2(SCH_1):PVDDQ_GHJ    I69 @BASEBOARD_FAB2_LIB.BASEBOARD_FAB2(SCH_1):PAGE243
     2    GND @BASEBOARD_FAB2_LIB.BASEBOARD_FAB2(SCH_1):GND    I69 @BASEBOARD_FAB2_LIB.BASEBOARD_FAB2(SCH_1):PAGE243

C5G90 CAP_A_0603V-22.0UF,4V,20%,X6S,A
     1 PVDDQ_GHJ @BASEBOARD_FAB2_LIB.BASEBOARD_FAB2(SCH_1):PVDDQ_GHJ    I68 @BASEBOARD_FAB2_LIB.BASEBOARD_FAB2(SCH_1):PAGE243
     2    GND @BASEBOARD_FAB2_LIB.BASEBOARD_FAB2(SCH_1):GND    I68 @BASEBOARD_FAB2_LIB.BASEBOARD_FAB2(SCH_1):PAGE243

C5G91 CAP_A_0603V-22.0UF,4V,20%,X6S,A
     1 PVDDQ_GHJ @BASEBOARD_FAB2_LIB.BASEBOARD_FAB2(SCH_1):PVDDQ_GHJ    I67 @BASEBOARD_FAB2_LIB.BASEBOARD_FAB2(SCH_1):PAGE243
     2    GND @BASEBOARD_FAB2_LIB.BASEBOARD_FAB2(SCH_1):GND    I67 @BASEBOARD_FAB2_LIB.BASEBOARD_FAB2(SCH_1):PAGE243

C5G92 CAP_A_0603V-22.0UF,4V,20%,X6S,A
     1 PVDDQ_GHJ @BASEBOARD_FAB2_LIB.BASEBOARD_FAB2(SCH_1):PVDDQ_GHJ    I66 @BASEBOARD_FAB2_LIB.BASEBOARD_FAB2(SCH_1):PAGE243
     2    GND @BASEBOARD_FAB2_LIB.BASEBOARD_FAB2(SCH_1):GND    I66 @BASEBOARD_FAB2_LIB.BASEBOARD_FAB2(SCH_1):PAGE243

C5G93 CAP_A_0603V-22.0UF,4V,20%,X6S,A
     1 PVDDQ_GHJ @BASEBOARD_FAB2_LIB.BASEBOARD_FAB2(SCH_1):PVDDQ_GHJ    I65 @BASEBOARD_FAB2_LIB.BASEBOARD_FAB2(SCH_1):PAGE243
     2    GND @BASEBOARD_FAB2_LIB.BASEBOARD_FAB2(SCH_1):GND    I65 @BASEBOARD_FAB2_LIB.BASEBOARD_FAB2(SCH_1):PAGE243

C5G94 CAP_A_0603V-22.0UF,4V,20%,X6S,A
     1 PVDDQ_GHJ @BASEBOARD_FAB2_LIB.BASEBOARD_FAB2(SCH_1):PVDDQ_GHJ    I64 @BASEBOARD_FAB2_LIB.BASEBOARD_FAB2(SCH_1):PAGE243
     2    GND @BASEBOARD_FAB2_LIB.BASEBOARD_FAB2(SCH_1):GND    I64 @BASEBOARD_FAB2_LIB.BASEBOARD_FAB2(SCH_1):PAGE243

C5G95 CAP_A_0603V-22.0UF,4V,20%,X6S,A
     1 PVDDQ_GHJ @BASEBOARD_FAB2_LIB.BASEBOARD_FAB2(SCH_1):PVDDQ_GHJ    I63 @BASEBOARD_FAB2_LIB.BASEBOARD_FAB2(SCH_1):PAGE243
     2    GND @BASEBOARD_FAB2_LIB.BASEBOARD_FAB2(SCH_1):GND    I63 @BASEBOARD_FAB2_LIB.BASEBOARD_FAB2(SCH_1):PAGE243

C5G96 CAP_A_0603V-22.0UF,4V,20%,X6S,A
     1 PVDDQ_GHJ @BASEBOARD_FAB2_LIB.BASEBOARD_FAB2(SCH_1):PVDDQ_GHJ    I62 @BASEBOARD_FAB2_LIB.BASEBOARD_FAB2(SCH_1):PAGE243
     2    GND @BASEBOARD_FAB2_LIB.BASEBOARD_FAB2(SCH_1):GND    I62 @BASEBOARD_FAB2_LIB.BASEBOARD_FAB2(SCH_1):PAGE243

C5G97 CAP_A_0603V-22.0UF,4V,20%,X6S,A
     1 PVDDQ_KLM @BASEBOARD_FAB2_LIB.BASEBOARD_FAB2(SCH_1):PVDDQ_KLM    I79 @BASEBOARD_FAB2_LIB.BASEBOARD_FAB2(SCH_1):PAGE243
     2    GND @BASEBOARD_FAB2_LIB.BASEBOARD_FAB2(SCH_1):GND    I79 @BASEBOARD_FAB2_LIB.BASEBOARD_FAB2(SCH_1):PAGE243

C5G98 CAP_A_0603V-22.0UF,4V,20%,X6S,A
     1 PVDDQ_KLM @BASEBOARD_FAB2_LIB.BASEBOARD_FAB2(SCH_1):PVDDQ_KLM    I78 @BASEBOARD_FAB2_LIB.BASEBOARD_FAB2(SCH_1):PAGE243
     2    GND @BASEBOARD_FAB2_LIB.BASEBOARD_FAB2(SCH_1):GND    I78 @BASEBOARD_FAB2_LIB.BASEBOARD_FAB2(SCH_1):PAGE243

C5G99 CAP_A_0603V-22.0UF,4V,20%,X6S,A
     1 PVDDQ_KLM @BASEBOARD_FAB2_LIB.BASEBOARD_FAB2(SCH_1):PVDDQ_KLM    I77 @BASEBOARD_FAB2_LIB.BASEBOARD_FAB2(SCH_1):PAGE243
     2    GND @BASEBOARD_FAB2_LIB.BASEBOARD_FAB2(SCH_1):GND    I77 @BASEBOARD_FAB2_LIB.BASEBOARD_FAB2(SCH_1):PAGE243

C5G100 CAP_A_0603V-22.0UF,4V,20%,X6S,A
     1 PVDDQ_KLM @BASEBOARD_FAB2_LIB.BASEBOARD_FAB2(SCH_1):PVDDQ_KLM    I76 @BASEBOARD_FAB2_LIB.BASEBOARD_FAB2(SCH_1):PAGE243
     2    GND @BASEBOARD_FAB2_LIB.BASEBOARD_FAB2(SCH_1):GND    I76 @BASEBOARD_FAB2_LIB.BASEBOARD_FAB2(SCH_1):PAGE243

C5G101 CAP_A_0603V-22.0UF,4V,20%,X6S,A
     1 PVDDQ_KLM @BASEBOARD_FAB2_LIB.BASEBOARD_FAB2(SCH_1):PVDDQ_KLM    I75 @BASEBOARD_FAB2_LIB.BASEBOARD_FAB2(SCH_1):PAGE243
     2    GND @BASEBOARD_FAB2_LIB.BASEBOARD_FAB2(SCH_1):GND    I75 @BASEBOARD_FAB2_LIB.BASEBOARD_FAB2(SCH_1):PAGE243

C5G102 CAP_A_0603V-22.0UF,4V,20%,X6S,A
     1 PVDDQ_KLM @BASEBOARD_FAB2_LIB.BASEBOARD_FAB2(SCH_1):PVDDQ_KLM    I74 @BASEBOARD_FAB2_LIB.BASEBOARD_FAB2(SCH_1):PAGE243
     2    GND @BASEBOARD_FAB2_LIB.BASEBOARD_FAB2(SCH_1):GND    I74 @BASEBOARD_FAB2_LIB.BASEBOARD_FAB2(SCH_1):PAGE243

C5G103 CAP_A_0603V-22.0UF,4V,20%,X6S,A
     1 PVDDQ_KLM @BASEBOARD_FAB2_LIB.BASEBOARD_FAB2(SCH_1):PVDDQ_KLM    I71 @BASEBOARD_FAB2_LIB.BASEBOARD_FAB2(SCH_1):PAGE243
     2    GND @BASEBOARD_FAB2_LIB.BASEBOARD_FAB2(SCH_1):GND    I71 @BASEBOARD_FAB2_LIB.BASEBOARD_FAB2(SCH_1):PAGE243

C5G104 CAP_A_0603V-22.0UF,4V,20%,X6S,A
     1 PVDDQ_KLM @BASEBOARD_FAB2_LIB.BASEBOARD_FAB2(SCH_1):PVDDQ_KLM    I72 @BASEBOARD_FAB2_LIB.BASEBOARD_FAB2(SCH_1):PAGE243
     2    GND @BASEBOARD_FAB2_LIB.BASEBOARD_FAB2(SCH_1):GND    I72 @BASEBOARD_FAB2_LIB.BASEBOARD_FAB2(SCH_1):PAGE243

C5G105 CAP_A_0603V-22.0UF,4V,20%,X6S,A
     1 PVDDQ_KLM @BASEBOARD_FAB2_LIB.BASEBOARD_FAB2(SCH_1):PVDDQ_KLM    I73 @BASEBOARD_FAB2_LIB.BASEBOARD_FAB2(SCH_1):PAGE243
     2    GND @BASEBOARD_FAB2_LIB.BASEBOARD_FAB2(SCH_1):GND    I73 @BASEBOARD_FAB2_LIB.BASEBOARD_FAB2(SCH_1):PAGE243

C5G106 CAP_A_0603V-22.0UF,4V,20%,X6S,A
     1 PVDDQ_KLM @BASEBOARD_FAB2_LIB.BASEBOARD_FAB2(SCH_1):PVDDQ_KLM    I88 @BASEBOARD_FAB2_LIB.BASEBOARD_FAB2(SCH_1):PAGE243
     2    GND @BASEBOARD_FAB2_LIB.BASEBOARD_FAB2(SCH_1):GND    I88 @BASEBOARD_FAB2_LIB.BASEBOARD_FAB2(SCH_1):PAGE243

C5G107 CAP_A_0603V-22.0UF,4V,20%,X6S,A
     1 PVDDQ_KLM @BASEBOARD_FAB2_LIB.BASEBOARD_FAB2(SCH_1):PVDDQ_KLM    I87 @BASEBOARD_FAB2_LIB.BASEBOARD_FAB2(SCH_1):PAGE243
     2    GND @BASEBOARD_FAB2_LIB.BASEBOARD_FAB2(SCH_1):GND    I87 @BASEBOARD_FAB2_LIB.BASEBOARD_FAB2(SCH_1):PAGE243

C5G108 CAP_A_0603V-22.0UF,4V,20%,X6S,A
     1 PVDDQ_KLM @BASEBOARD_FAB2_LIB.BASEBOARD_FAB2(SCH_1):PVDDQ_KLM    I86 @BASEBOARD_FAB2_LIB.BASEBOARD_FAB2(SCH_1):PAGE243
     2    GND @BASEBOARD_FAB2_LIB.BASEBOARD_FAB2(SCH_1):GND    I86 @BASEBOARD_FAB2_LIB.BASEBOARD_FAB2(SCH_1):PAGE243

C5G109 CAP_A_0603V-22.0UF,4V,20%,X6S,A
     1 PVDDQ_KLM @BASEBOARD_FAB2_LIB.BASEBOARD_FAB2(SCH_1):PVDDQ_KLM    I85 @BASEBOARD_FAB2_LIB.BASEBOARD_FAB2(SCH_1):PAGE243
     2    GND @BASEBOARD_FAB2_LIB.BASEBOARD_FAB2(SCH_1):GND    I85 @BASEBOARD_FAB2_LIB.BASEBOARD_FAB2(SCH_1):PAGE243

C5G110 CAP_A_0603V-22.0UF,4V,20%,X6S,A
     1 PVDDQ_KLM @BASEBOARD_FAB2_LIB.BASEBOARD_FAB2(SCH_1):PVDDQ_KLM    I84 @BASEBOARD_FAB2_LIB.BASEBOARD_FAB2(SCH_1):PAGE243
     2    GND @BASEBOARD_FAB2_LIB.BASEBOARD_FAB2(SCH_1):GND    I84 @BASEBOARD_FAB2_LIB.BASEBOARD_FAB2(SCH_1):PAGE243

C5G111 CAP_A_0603V-22.0UF,4V,20%,X6S,A
     1 PVDDQ_KLM @BASEBOARD_FAB2_LIB.BASEBOARD_FAB2(SCH_1):PVDDQ_KLM    I83 @BASEBOARD_FAB2_LIB.BASEBOARD_FAB2(SCH_1):PAGE243
     2    GND @BASEBOARD_FAB2_LIB.BASEBOARD_FAB2(SCH_1):GND    I83 @BASEBOARD_FAB2_LIB.BASEBOARD_FAB2(SCH_1):PAGE243

C5G112 CAP_A_0603V-22.0UF,4V,20%,X6S,A
     1 PVDDQ_KLM @BASEBOARD_FAB2_LIB.BASEBOARD_FAB2(SCH_1):PVDDQ_KLM    I82 @BASEBOARD_FAB2_LIB.BASEBOARD_FAB2(SCH_1):PAGE243
     2    GND @BASEBOARD_FAB2_LIB.BASEBOARD_FAB2(SCH_1):GND    I82 @BASEBOARD_FAB2_LIB.BASEBOARD_FAB2(SCH_1):PAGE243

C5G113 CAP_A_0603V-22.0UF,4V,20%,X6S,A
     1 PVDDQ_KLM @BASEBOARD_FAB2_LIB.BASEBOARD_FAB2(SCH_1):PVDDQ_KLM    I81 @BASEBOARD_FAB2_LIB.BASEBOARD_FAB2(SCH_1):PAGE243
     2    GND @BASEBOARD_FAB2_LIB.BASEBOARD_FAB2(SCH_1):GND    I81 @BASEBOARD_FAB2_LIB.BASEBOARD_FAB2(SCH_1):PAGE243

C5G114 CAP_A_0603V-22.0UF,4V,20%,X6S,A
     1 PVDDQ_KLM @BASEBOARD_FAB2_LIB.BASEBOARD_FAB2(SCH_1):PVDDQ_KLM    I80 @BASEBOARD_FAB2_LIB.BASEBOARD_FAB2(SCH_1):PAGE243
     2    GND @BASEBOARD_FAB2_LIB.BASEBOARD_FAB2(SCH_1):GND    I80 @BASEBOARD_FAB2_LIB.BASEBOARD_FAB2(SCH_1):PAGE243

C5G115 CAP_0805-100UF,4V,20%,X5R,6024A
     1 PVDDQ_KLM @BASEBOARD_FAB2_LIB.BASEBOARD_FAB2(SCH_1):PVDDQ_KLM    I39 @BASEBOARD_FAB2_LIB.BASEBOARD_FAB2(SCH_1):PAGE243
     2    GND @BASEBOARD_FAB2_LIB.BASEBOARD_FAB2(SCH_1):GND    I39 @BASEBOARD_FAB2_LIB.BASEBOARD_FAB2(SCH_1):PAGE243

C5G116 CAP_0805-100UF,4V,20%,X5R,6024A
     1 PVDDQ_KLM @BASEBOARD_FAB2_LIB.BASEBOARD_FAB2(SCH_1):PVDDQ_KLM    I43 @BASEBOARD_FAB2_LIB.BASEBOARD_FAB2(SCH_1):PAGE243
     2    GND @BASEBOARD_FAB2_LIB.BASEBOARD_FAB2(SCH_1):GND    I43 @BASEBOARD_FAB2_LIB.BASEBOARD_FAB2(SCH_1):PAGE243

C5G117 CAP_0805-100UF,4V,20%,X5R,6024A
     1 PVDDQ_GHJ @BASEBOARD_FAB2_LIB.BASEBOARD_FAB2(SCH_1):PVDDQ_GHJ    I12 @BASEBOARD_FAB2_LIB.BASEBOARD_FAB2(SCH_1):PAGE243
     2    GND @BASEBOARD_FAB2_LIB.BASEBOARD_FAB2(SCH_1):GND    I12 @BASEBOARD_FAB2_LIB.BASEBOARD_FAB2(SCH_1):PAGE243

C5G118 CAP_0805-100UF,4V,20%,X5R,6024A
     1 PVDDQ_GHJ @BASEBOARD_FAB2_LIB.BASEBOARD_FAB2(SCH_1):PVDDQ_GHJ    I13 @BASEBOARD_FAB2_LIB.BASEBOARD_FAB2(SCH_1):PAGE243
     2    GND @BASEBOARD_FAB2_LIB.BASEBOARD_FAB2(SCH_1):GND    I13 @BASEBOARD_FAB2_LIB.BASEBOARD_FAB2(SCH_1):PAGE243

C5L1 CAP_0805-100UF,4V,20%,X5R,6024A
     1 PVDDQ_DEF @BASEBOARD_FAB2_LIB.BASEBOARD_FAB2(SCH_1):PVDDQ_DEF    I91 @BASEBOARD_FAB2_LIB.BASEBOARD_FAB2(SCH_1):PAGE220
     2    GND @BASEBOARD_FAB2_LIB.BASEBOARD_FAB2(SCH_1):GND    I91 @BASEBOARD_FAB2_LIB.BASEBOARD_FAB2(SCH_1):PAGE220

C5L2 CAP_0805-100UF,4V,20%,X5R,6024A
     1 PVDDQ_DEF @BASEBOARD_FAB2_LIB.BASEBOARD_FAB2(SCH_1):PVDDQ_DEF    I90 @BASEBOARD_FAB2_LIB.BASEBOARD_FAB2(SCH_1):PAGE220
     2    GND @BASEBOARD_FAB2_LIB.BASEBOARD_FAB2(SCH_1):GND    I90 @BASEBOARD_FAB2_LIB.BASEBOARD_FAB2(SCH_1):PAGE220

C5L3 CAP_0805-100UF,4V,20%,X5R,6024A
     1 PVDDQ_DEF @BASEBOARD_FAB2_LIB.BASEBOARD_FAB2(SCH_1):PVDDQ_DEF    I89 @BASEBOARD_FAB2_LIB.BASEBOARD_FAB2(SCH_1):PAGE220
     2    GND @BASEBOARD_FAB2_LIB.BASEBOARD_FAB2(SCH_1):GND    I89 @BASEBOARD_FAB2_LIB.BASEBOARD_FAB2(SCH_1):PAGE220

C5L4 CAP_A_0603V-47UF,4V,20%,X5R,60A
     1 PVTT_DEF @BASEBOARD_FAB2_LIB.BASEBOARD_FAB2(SCH_1):PVTT_DEF    I47 @BASEBOARD_FAB2_LIB.BASEBOARD_FAB2(SCH_1):PAGE222
     2    GND @BASEBOARD_FAB2_LIB.BASEBOARD_FAB2(SCH_1):GND    I47 @BASEBOARD_FAB2_LIB.BASEBOARD_FAB2(SCH_1):PAGE222

C5L5 CAP_A_0603V-47UF,4V,20%,X5R,60A
     1 PVTT_DEF @BASEBOARD_FAB2_LIB.BASEBOARD_FAB2(SCH_1):PVTT_DEF    I49 @BASEBOARD_FAB2_LIB.BASEBOARD_FAB2(SCH_1):PAGE222
     2    GND @BASEBOARD_FAB2_LIB.BASEBOARD_FAB2(SCH_1):GND    I49 @BASEBOARD_FAB2_LIB.BASEBOARD_FAB2(SCH_1):PAGE222

C5L6 CAP_A_0603V-22.0UF,4V,20%,X6S,A
     1 PVDDQ_DEF @BASEBOARD_FAB2_LIB.BASEBOARD_FAB2(SCH_1):PVDDQ_DEF   I237 @BASEBOARD_FAB2_LIB.BASEBOARD_FAB2(SCH_1):PAGE220
     2    GND @BASEBOARD_FAB2_LIB.BASEBOARD_FAB2(SCH_1):GND   I237 @BASEBOARD_FAB2_LIB.BASEBOARD_FAB2(SCH_1):PAGE220

C5L7 CAP_A_0603V-22.0UF,4V,20%,X6S,A
     1 PVDDQ_DEF @BASEBOARD_FAB2_LIB.BASEBOARD_FAB2(SCH_1):PVDDQ_DEF   I236 @BASEBOARD_FAB2_LIB.BASEBOARD_FAB2(SCH_1):PAGE220
     2    GND @BASEBOARD_FAB2_LIB.BASEBOARD_FAB2(SCH_1):GND   I236 @BASEBOARD_FAB2_LIB.BASEBOARD_FAB2(SCH_1):PAGE220

C5L8 CAP_A_0603V-22.0UF,4V,20%,X6S,A
     1 PVDDQ_DEF @BASEBOARD_FAB2_LIB.BASEBOARD_FAB2(SCH_1):PVDDQ_DEF   I234 @BASEBOARD_FAB2_LIB.BASEBOARD_FAB2(SCH_1):PAGE220
     2    GND @BASEBOARD_FAB2_LIB.BASEBOARD_FAB2(SCH_1):GND   I234 @BASEBOARD_FAB2_LIB.BASEBOARD_FAB2(SCH_1):PAGE220

C5L9 CAP_A_0603V-22.0UF,4V,20%,X6S,A
     1 PVDDQ_DEF @BASEBOARD_FAB2_LIB.BASEBOARD_FAB2(SCH_1):PVDDQ_DEF   I233 @BASEBOARD_FAB2_LIB.BASEBOARD_FAB2(SCH_1):PAGE220
     2    GND @BASEBOARD_FAB2_LIB.BASEBOARD_FAB2(SCH_1):GND   I233 @BASEBOARD_FAB2_LIB.BASEBOARD_FAB2(SCH_1):PAGE220

C5L10 CAP_A_0603V-22.0UF,4V,20%,X6S,A
     1 PVDDQ_DEF @BASEBOARD_FAB2_LIB.BASEBOARD_FAB2(SCH_1):PVDDQ_DEF   I232 @BASEBOARD_FAB2_LIB.BASEBOARD_FAB2(SCH_1):PAGE220
     2    GND @BASEBOARD_FAB2_LIB.BASEBOARD_FAB2(SCH_1):GND   I232 @BASEBOARD_FAB2_LIB.BASEBOARD_FAB2(SCH_1):PAGE220

C5L11 CAP_A_0603V-22.0UF,4V,20%,X6S,A
     1 PVDDQ_DEF @BASEBOARD_FAB2_LIB.BASEBOARD_FAB2(SCH_1):PVDDQ_DEF   I231 @BASEBOARD_FAB2_LIB.BASEBOARD_FAB2(SCH_1):PAGE220
     2    GND @BASEBOARD_FAB2_LIB.BASEBOARD_FAB2(SCH_1):GND   I231 @BASEBOARD_FAB2_LIB.BASEBOARD_FAB2(SCH_1):PAGE220

C5L12 CAP_A_0603V-22.0UF,4V,20%,X6S,A
     1 PVDDQ_DEF @BASEBOARD_FAB2_LIB.BASEBOARD_FAB2(SCH_1):PVDDQ_DEF   I230 @BASEBOARD_FAB2_LIB.BASEBOARD_FAB2(SCH_1):PAGE220
     2    GND @BASEBOARD_FAB2_LIB.BASEBOARD_FAB2(SCH_1):GND   I230 @BASEBOARD_FAB2_LIB.BASEBOARD_FAB2(SCH_1):PAGE220

C5L13 CAP_A_0603V-22.0UF,4V,20%,X6S,A
     1 PVDDQ_DEF @BASEBOARD_FAB2_LIB.BASEBOARD_FAB2(SCH_1):PVDDQ_DEF   I229 @BASEBOARD_FAB2_LIB.BASEBOARD_FAB2(SCH_1):PAGE220
     2    GND @BASEBOARD_FAB2_LIB.BASEBOARD_FAB2(SCH_1):GND   I229 @BASEBOARD_FAB2_LIB.BASEBOARD_FAB2(SCH_1):PAGE220

C5L14 CAP_0805-100UF,4V,20%,X5R,6024A
     1 PVDDQ_DEF @BASEBOARD_FAB2_LIB.BASEBOARD_FAB2(SCH_1):PVDDQ_DEF    I83 @BASEBOARD_FAB2_LIB.BASEBOARD_FAB2(SCH_1):PAGE220
     2    GND @BASEBOARD_FAB2_LIB.BASEBOARD_FAB2(SCH_1):GND    I83 @BASEBOARD_FAB2_LIB.BASEBOARD_FAB2(SCH_1):PAGE220

C5L15 CAP_A_0603V-47UF,4V,20%,X5R,60A
     1 PVDDQ_DEF @BASEBOARD_FAB2_LIB.BASEBOARD_FAB2(SCH_1):PVDDQ_DEF   I192 @BASEBOARD_FAB2_LIB.BASEBOARD_FAB2(SCH_1):PAGE220
     2    GND @BASEBOARD_FAB2_LIB.BASEBOARD_FAB2(SCH_1):GND   I192 @BASEBOARD_FAB2_LIB.BASEBOARD_FAB2(SCH_1):PAGE220

C5M1 CAP_A_0603V-22.0UF,4V,20%,X6S,A
     1 PVDDQ_DEF @BASEBOARD_FAB2_LIB.BASEBOARD_FAB2(SCH_1):PVDDQ_DEF   I223 @BASEBOARD_FAB2_LIB.BASEBOARD_FAB2(SCH_1):PAGE220
     2    GND @BASEBOARD_FAB2_LIB.BASEBOARD_FAB2(SCH_1):GND   I223 @BASEBOARD_FAB2_LIB.BASEBOARD_FAB2(SCH_1):PAGE220

C5M2 CAP_A_0603V-22.0UF,4V,20%,X6S,A
     1 PVDDQ_DEF @BASEBOARD_FAB2_LIB.BASEBOARD_FAB2(SCH_1):PVDDQ_DEF   I224 @BASEBOARD_FAB2_LIB.BASEBOARD_FAB2(SCH_1):PAGE220
     2    GND @BASEBOARD_FAB2_LIB.BASEBOARD_FAB2(SCH_1):GND   I224 @BASEBOARD_FAB2_LIB.BASEBOARD_FAB2(SCH_1):PAGE220

C5M3 CAP_A_0603V-47UF,4V,20%,X5R,60A
     1 PVDDQ_DEF @BASEBOARD_FAB2_LIB.BASEBOARD_FAB2(SCH_1):PVDDQ_DEF   I199 @BASEBOARD_FAB2_LIB.BASEBOARD_FAB2(SCH_1):PAGE220
     2    GND @BASEBOARD_FAB2_LIB.BASEBOARD_FAB2(SCH_1):GND   I199 @BASEBOARD_FAB2_LIB.BASEBOARD_FAB2(SCH_1):PAGE220

C5M4 CAP_A_0603V-22.0UF,4V,20%,X6S,A
     1 PVDDQ_DEF @BASEBOARD_FAB2_LIB.BASEBOARD_FAB2(SCH_1):PVDDQ_DEF   I225 @BASEBOARD_FAB2_LIB.BASEBOARD_FAB2(SCH_1):PAGE220
     2    GND @BASEBOARD_FAB2_LIB.BASEBOARD_FAB2(SCH_1):GND   I225 @BASEBOARD_FAB2_LIB.BASEBOARD_FAB2(SCH_1):PAGE220

C5M5 CAP_A_0603V-22.0UF,4V,20%,X6S,A
     1 PVDDQ_DEF @BASEBOARD_FAB2_LIB.BASEBOARD_FAB2(SCH_1):PVDDQ_DEF   I226 @BASEBOARD_FAB2_LIB.BASEBOARD_FAB2(SCH_1):PAGE220
     2    GND @BASEBOARD_FAB2_LIB.BASEBOARD_FAB2(SCH_1):GND   I226 @BASEBOARD_FAB2_LIB.BASEBOARD_FAB2(SCH_1):PAGE220

C5M6 CAP_A_0603V-22.0UF,4V,20%,X6S,A
     1 PVDDQ_DEF @BASEBOARD_FAB2_LIB.BASEBOARD_FAB2(SCH_1):PVDDQ_DEF   I227 @BASEBOARD_FAB2_LIB.BASEBOARD_FAB2(SCH_1):PAGE220
     2    GND @BASEBOARD_FAB2_LIB.BASEBOARD_FAB2(SCH_1):GND   I227 @BASEBOARD_FAB2_LIB.BASEBOARD_FAB2(SCH_1):PAGE220

C5M7 CAP_A_0603V-22.0UF,4V,20%,X6S,A
     1 PVDDQ_DEF @BASEBOARD_FAB2_LIB.BASEBOARD_FAB2(SCH_1):PVDDQ_DEF   I228 @BASEBOARD_FAB2_LIB.BASEBOARD_FAB2(SCH_1):PAGE220
     2    GND @BASEBOARD_FAB2_LIB.BASEBOARD_FAB2(SCH_1):GND   I228 @BASEBOARD_FAB2_LIB.BASEBOARD_FAB2(SCH_1):PAGE220

C5M8 CAP_0805-100UF,4V,20%,X5R,6024A
     1 PVDDQ_DEF @BASEBOARD_FAB2_LIB.BASEBOARD_FAB2(SCH_1):PVDDQ_DEF    I82 @BASEBOARD_FAB2_LIB.BASEBOARD_FAB2(SCH_1):PAGE220
     2    GND @BASEBOARD_FAB2_LIB.BASEBOARD_FAB2(SCH_1):GND    I82 @BASEBOARD_FAB2_LIB.BASEBOARD_FAB2(SCH_1):PAGE220

C5M9 CAP_A_0603V-47UF,4V,20%,X5R,60A
     1 PVDDQ_DEF @BASEBOARD_FAB2_LIB.BASEBOARD_FAB2(SCH_1):PVDDQ_DEF   I195 @BASEBOARD_FAB2_LIB.BASEBOARD_FAB2(SCH_1):PAGE220
     2    GND @BASEBOARD_FAB2_LIB.BASEBOARD_FAB2(SCH_1):GND   I195 @BASEBOARD_FAB2_LIB.BASEBOARD_FAB2(SCH_1):PAGE220

C5M10 CAP_A_0603V-47UF,4V,20%,X5R,60A
     1 PVDDQ_DEF @BASEBOARD_FAB2_LIB.BASEBOARD_FAB2(SCH_1):PVDDQ_DEF   I198 @BASEBOARD_FAB2_LIB.BASEBOARD_FAB2(SCH_1):PAGE220
     2    GND @BASEBOARD_FAB2_LIB.BASEBOARD_FAB2(SCH_1):GND   I198 @BASEBOARD_FAB2_LIB.BASEBOARD_FAB2(SCH_1):PAGE220

C5M11 CAP_A_0603V-47UF,4V,20%,X5R,60A
     1 PVDDQ_DEF @BASEBOARD_FAB2_LIB.BASEBOARD_FAB2(SCH_1):PVDDQ_DEF   I200 @BASEBOARD_FAB2_LIB.BASEBOARD_FAB2(SCH_1):PAGE220
     2    GND @BASEBOARD_FAB2_LIB.BASEBOARD_FAB2(SCH_1):GND   I200 @BASEBOARD_FAB2_LIB.BASEBOARD_FAB2(SCH_1):PAGE220

C5M12 CAP_0805-100UF,4V,20%,X5R,6024A
     1 PVDDQ_DEF @BASEBOARD_FAB2_LIB.BASEBOARD_FAB2(SCH_1):PVDDQ_DEF    I88 @BASEBOARD_FAB2_LIB.BASEBOARD_FAB2(SCH_1):PAGE220
     2    GND @BASEBOARD_FAB2_LIB.BASEBOARD_FAB2(SCH_1):GND    I88 @BASEBOARD_FAB2_LIB.BASEBOARD_FAB2(SCH_1):PAGE220

C5M13 CAP_A_0603V-47UF,4V,20%,X5R,60A
     1 PVTT_DEF @BASEBOARD_FAB2_LIB.BASEBOARD_FAB2(SCH_1):PVTT_DEF    I48 @BASEBOARD_FAB2_LIB.BASEBOARD_FAB2(SCH_1):PAGE222
     2    GND @BASEBOARD_FAB2_LIB.BASEBOARD_FAB2(SCH_1):GND    I48 @BASEBOARD_FAB2_LIB.BASEBOARD_FAB2(SCH_1):PAGE222

C5P1 CAP_0805LF-22UF,4V,20%,X6S,C95A
     1 PVDDQ_DEF @BASEBOARD_FAB2_LIB.BASEBOARD_FAB2(SCH_1):PVDDQ_DEF   I179 @BASEBOARD_FAB2_LIB.BASEBOARD_FAB2(SCH_1):PAGE220
     2    GND @BASEBOARD_FAB2_LIB.BASEBOARD_FAB2(SCH_1):GND   I179 @BASEBOARD_FAB2_LIB.BASEBOARD_FAB2(SCH_1):PAGE220

C5P2 CAP_0805LF-22UF,4V,20%,X6S,C95A
     1 PVDDQ_DEF @BASEBOARD_FAB2_LIB.BASEBOARD_FAB2(SCH_1):PVDDQ_DEF   I177 @BASEBOARD_FAB2_LIB.BASEBOARD_FAB2(SCH_1):PAGE220
     2    GND @BASEBOARD_FAB2_LIB.BASEBOARD_FAB2(SCH_1):GND   I177 @BASEBOARD_FAB2_LIB.BASEBOARD_FAB2(SCH_1):PAGE220

C5P3 CAP_0805-47UF,4V,20%,X6S,C9533A
     1 PVCCIN_CPU0 @BASEBOARD_FAB2_LIB.BASEBOARD_FAB2(SCH_1):PVCCIN_CPU0   I189 @BASEBOARD_FAB2_LIB.BASEBOARD_FAB2(SCH_1):PAGE42
     2    GND @BASEBOARD_FAB2_LIB.BASEBOARD_FAB2(SCH_1):GND   I189 @BASEBOARD_FAB2_LIB.BASEBOARD_FAB2(SCH_1):PAGE42

C5P4 CAP_0805-47UF,4V,20%,X6S,C9533A
     1 PVCCIN_CPU0 @BASEBOARD_FAB2_LIB.BASEBOARD_FAB2(SCH_1):PVCCIN_CPU0    I27 @BASEBOARD_FAB2_LIB.BASEBOARD_FAB2(SCH_1):PAGE42
     2    GND @BASEBOARD_FAB2_LIB.BASEBOARD_FAB2(SCH_1):GND    I27 @BASEBOARD_FAB2_LIB.BASEBOARD_FAB2(SCH_1):PAGE42

C5P5 CAP_0805-47UF,4V,20%,X6S,C9533A
     1 PVCCIN_CPU0 @BASEBOARD_FAB2_LIB.BASEBOARD_FAB2(SCH_1):PVCCIN_CPU0    I42 @BASEBOARD_FAB2_LIB.BASEBOARD_FAB2(SCH_1):PAGE42
     2    GND @BASEBOARD_FAB2_LIB.BASEBOARD_FAB2(SCH_1):GND    I42 @BASEBOARD_FAB2_LIB.BASEBOARD_FAB2(SCH_1):PAGE42

C5P6 CAP_0805-47UF,4V,20%,X6S,C9533A
     1 PVCCIN_CPU0 @BASEBOARD_FAB2_LIB.BASEBOARD_FAB2(SCH_1):PVCCIN_CPU0    I38 @BASEBOARD_FAB2_LIB.BASEBOARD_FAB2(SCH_1):PAGE42
     2    GND @BASEBOARD_FAB2_LIB.BASEBOARD_FAB2(SCH_1):GND    I38 @BASEBOARD_FAB2_LIB.BASEBOARD_FAB2(SCH_1):PAGE42

C5P7 CAP_0805LF-22UF,4V,20%,X6S,C95A
     1 PVSA_CPU0 @BASEBOARD_FAB2_LIB.BASEBOARD_FAB2(SCH_1):PVSA_CPU0    I25 @BASEBOARD_FAB2_LIB.BASEBOARD_FAB2(SCH_1):PAGE42
     2    GND @BASEBOARD_FAB2_LIB.BASEBOARD_FAB2(SCH_1):GND    I25 @BASEBOARD_FAB2_LIB.BASEBOARD_FAB2(SCH_1):PAGE42

C5P8 CAP_0805LF-22UF,4V,20%,X6S,C95A
     1 PVSA_CPU0 @BASEBOARD_FAB2_LIB.BASEBOARD_FAB2(SCH_1):PVSA_CPU0    I19 @BASEBOARD_FAB2_LIB.BASEBOARD_FAB2(SCH_1):PAGE42
     2    GND @BASEBOARD_FAB2_LIB.BASEBOARD_FAB2(SCH_1):GND    I19 @BASEBOARD_FAB2_LIB.BASEBOARD_FAB2(SCH_1):PAGE42

C5P9 CAP_0805LF-22UF,4V,20%,X6S,C95A
     1 PVSA_CPU0 @BASEBOARD_FAB2_LIB.BASEBOARD_FAB2(SCH_1):PVSA_CPU0    I18 @BASEBOARD_FAB2_LIB.BASEBOARD_FAB2(SCH_1):PAGE42
     2    GND @BASEBOARD_FAB2_LIB.BASEBOARD_FAB2(SCH_1):GND    I18 @BASEBOARD_FAB2_LIB.BASEBOARD_FAB2(SCH_1):PAGE42

C5P10 CAP_0805-47UF,4V,20%,X6S,C9533A
     1 PVCCMCP_CPU0 @BASEBOARD_FAB2_LIB.BASEBOARD_FAB2(SCH_1):PVCCMCP_CPU0     I6 @BASEBOARD_FAB2_LIB.BASEBOARD_FAB2(SCH_1):PAGE42
     2    GND @BASEBOARD_FAB2_LIB.BASEBOARD_FAB2(SCH_1):GND     I6 @BASEBOARD_FAB2_LIB.BASEBOARD_FAB2(SCH_1):PAGE42

C5P11 CAP_0805-47UF,4V,20%,X6S,C9533A
     1 PVCCMCP_CPU0 @BASEBOARD_FAB2_LIB.BASEBOARD_FAB2(SCH_1):PVCCMCP_CPU0     I4 @BASEBOARD_FAB2_LIB.BASEBOARD_FAB2(SCH_1):PAGE42
     2    GND @BASEBOARD_FAB2_LIB.BASEBOARD_FAB2(SCH_1):GND     I4 @BASEBOARD_FAB2_LIB.BASEBOARD_FAB2(SCH_1):PAGE42

C5P12 CAP_0805-47UF,4V,20%,X6S,C9533A
     1 PVCCMCP_CPU0 @BASEBOARD_FAB2_LIB.BASEBOARD_FAB2(SCH_1):PVCCMCP_CPU0   I183 @BASEBOARD_FAB2_LIB.BASEBOARD_FAB2(SCH_1):PAGE42
     2    GND @BASEBOARD_FAB2_LIB.BASEBOARD_FAB2(SCH_1):GND   I183 @BASEBOARD_FAB2_LIB.BASEBOARD_FAB2(SCH_1):PAGE42

C5P13 CAP_0805-47UF,4V,20%,X6S,C9533A
     1 PVCCMCP_CPU0 @BASEBOARD_FAB2_LIB.BASEBOARD_FAB2(SCH_1):PVCCMCP_CPU0   I186 @BASEBOARD_FAB2_LIB.BASEBOARD_FAB2(SCH_1):PAGE42
     2    GND @BASEBOARD_FAB2_LIB.BASEBOARD_FAB2(SCH_1):GND   I186 @BASEBOARD_FAB2_LIB.BASEBOARD_FAB2(SCH_1):PAGE42

C5P14 CAP_0805-47UF,4V,20%,X6S,C9533A
     1 PVCCIN_CPU0 @BASEBOARD_FAB2_LIB.BASEBOARD_FAB2(SCH_1):PVCCIN_CPU0    I41 @BASEBOARD_FAB2_LIB.BASEBOARD_FAB2(SCH_1):PAGE42
     2    GND @BASEBOARD_FAB2_LIB.BASEBOARD_FAB2(SCH_1):GND    I41 @BASEBOARD_FAB2_LIB.BASEBOARD_FAB2(SCH_1):PAGE42

C5P15 CAP_0805-47UF,4V,20%,X6S,C9533A
     1 PVCCIN_CPU0 @BASEBOARD_FAB2_LIB.BASEBOARD_FAB2(SCH_1):PVCCIN_CPU0   I187 @BASEBOARD_FAB2_LIB.BASEBOARD_FAB2(SCH_1):PAGE42
     2    GND @BASEBOARD_FAB2_LIB.BASEBOARD_FAB2(SCH_1):GND   I187 @BASEBOARD_FAB2_LIB.BASEBOARD_FAB2(SCH_1):PAGE42

C5P16 CAP_0805-47UF,4V,20%,X6S,C9533A
     1 PVCCIN_CPU0 @BASEBOARD_FAB2_LIB.BASEBOARD_FAB2(SCH_1):PVCCIN_CPU0   I188 @BASEBOARD_FAB2_LIB.BASEBOARD_FAB2(SCH_1):PAGE42
     2    GND @BASEBOARD_FAB2_LIB.BASEBOARD_FAB2(SCH_1):GND   I188 @BASEBOARD_FAB2_LIB.BASEBOARD_FAB2(SCH_1):PAGE42

C5P17 CAP_0805-47UF,4V,20%,X6S,C9533A
     1 PVCCIN_CPU0 @BASEBOARD_FAB2_LIB.BASEBOARD_FAB2(SCH_1):PVCCIN_CPU0   I190 @BASEBOARD_FAB2_LIB.BASEBOARD_FAB2(SCH_1):PAGE42
     2    GND @BASEBOARD_FAB2_LIB.BASEBOARD_FAB2(SCH_1):GND   I190 @BASEBOARD_FAB2_LIB.BASEBOARD_FAB2(SCH_1):PAGE42

C5P18 CAP_0805-47UF,4V,20%,X6S,C9533A
     1 PVCCMCP_CPU0 @BASEBOARD_FAB2_LIB.BASEBOARD_FAB2(SCH_1):PVCCMCP_CPU0     I2 @BASEBOARD_FAB2_LIB.BASEBOARD_FAB2(SCH_1):PAGE42
     2    GND @BASEBOARD_FAB2_LIB.BASEBOARD_FAB2(SCH_1):GND     I2 @BASEBOARD_FAB2_LIB.BASEBOARD_FAB2(SCH_1):PAGE42

C5P19 CAP_0805-47UF,4V,20%,X6S,C9533A
     1 PVCCMCP_CPU0 @BASEBOARD_FAB2_LIB.BASEBOARD_FAB2(SCH_1):PVCCMCP_CPU0    I13 @BASEBOARD_FAB2_LIB.BASEBOARD_FAB2(SCH_1):PAGE42
     2    GND @BASEBOARD_FAB2_LIB.BASEBOARD_FAB2(SCH_1):GND    I13 @BASEBOARD_FAB2_LIB.BASEBOARD_FAB2(SCH_1):PAGE42

C5P20 CAP_0805-47UF,4V,20%,X6S,C9533A
     1 PVCCMCP_CPU0 @BASEBOARD_FAB2_LIB.BASEBOARD_FAB2(SCH_1):PVCCMCP_CPU0   I185 @BASEBOARD_FAB2_LIB.BASEBOARD_FAB2(SCH_1):PAGE42
     2    GND @BASEBOARD_FAB2_LIB.BASEBOARD_FAB2(SCH_1):GND   I185 @BASEBOARD_FAB2_LIB.BASEBOARD_FAB2(SCH_1):PAGE42

C5P21 CAP_0805-47UF,4V,20%,X6S,C9533A
     1 PVCCMCP_CPU0 @BASEBOARD_FAB2_LIB.BASEBOARD_FAB2(SCH_1):PVCCMCP_CPU0   I184 @BASEBOARD_FAB2_LIB.BASEBOARD_FAB2(SCH_1):PAGE42
     2    GND @BASEBOARD_FAB2_LIB.BASEBOARD_FAB2(SCH_1):GND   I184 @BASEBOARD_FAB2_LIB.BASEBOARD_FAB2(SCH_1):PAGE42

C5P22 CAP_0805-47UF,4V,20%,X6S,C9533A
     1 PVCCIN_CPU0 @BASEBOARD_FAB2_LIB.BASEBOARD_FAB2(SCH_1):PVCCIN_CPU0    I55 @BASEBOARD_FAB2_LIB.BASEBOARD_FAB2(SCH_1):PAGE42
     2    GND @BASEBOARD_FAB2_LIB.BASEBOARD_FAB2(SCH_1):GND    I55 @BASEBOARD_FAB2_LIB.BASEBOARD_FAB2(SCH_1):PAGE42

C5P23 CAP_0805-47UF,4V,20%,X6S,C9533A
     1 PVCCIN_CPU0 @BASEBOARD_FAB2_LIB.BASEBOARD_FAB2(SCH_1):PVCCIN_CPU0    I28 @BASEBOARD_FAB2_LIB.BASEBOARD_FAB2(SCH_1):PAGE42
     2    GND @BASEBOARD_FAB2_LIB.BASEBOARD_FAB2(SCH_1):GND    I28 @BASEBOARD_FAB2_LIB.BASEBOARD_FAB2(SCH_1):PAGE42

C5P24 CAP_0805-47UF,4V,20%,X6S,C9533A
     1 PVCCIN_CPU0 @BASEBOARD_FAB2_LIB.BASEBOARD_FAB2(SCH_1):PVCCIN_CPU0    I33 @BASEBOARD_FAB2_LIB.BASEBOARD_FAB2(SCH_1):PAGE42
     2    GND @BASEBOARD_FAB2_LIB.BASEBOARD_FAB2(SCH_1):GND    I33 @BASEBOARD_FAB2_LIB.BASEBOARD_FAB2(SCH_1):PAGE42

C5P25 CAP_0805-47UF,4V,20%,X6S,C9533A
     1 PVCCIN_CPU0 @BASEBOARD_FAB2_LIB.BASEBOARD_FAB2(SCH_1):PVCCIN_CPU0    I37 @BASEBOARD_FAB2_LIB.BASEBOARD_FAB2(SCH_1):PAGE42
     2    GND @BASEBOARD_FAB2_LIB.BASEBOARD_FAB2(SCH_1):GND    I37 @BASEBOARD_FAB2_LIB.BASEBOARD_FAB2(SCH_1):PAGE42

C5P26 CAP_0805-47UF,4V,20%,X6S,C9533A
     1 PVCCIN_CPU0 @BASEBOARD_FAB2_LIB.BASEBOARD_FAB2(SCH_1):PVCCIN_CPU0    I56 @BASEBOARD_FAB2_LIB.BASEBOARD_FAB2(SCH_1):PAGE42
     2    GND @BASEBOARD_FAB2_LIB.BASEBOARD_FAB2(SCH_1):GND    I56 @BASEBOARD_FAB2_LIB.BASEBOARD_FAB2(SCH_1):PAGE42

C5P27 CAP_0805-47UF,4V,20%,X6S,C9533A
     1 PVCCIN_CPU0 @BASEBOARD_FAB2_LIB.BASEBOARD_FAB2(SCH_1):PVCCIN_CPU0    I44 @BASEBOARD_FAB2_LIB.BASEBOARD_FAB2(SCH_1):PAGE42
     2    GND @BASEBOARD_FAB2_LIB.BASEBOARD_FAB2(SCH_1):GND    I44 @BASEBOARD_FAB2_LIB.BASEBOARD_FAB2(SCH_1):PAGE42

C5P28 CAP_0805-47UF,4V,20%,X6S,C9533A
     1 PVCCMCP_CPU0 @BASEBOARD_FAB2_LIB.BASEBOARD_FAB2(SCH_1):PVCCMCP_CPU0     I3 @BASEBOARD_FAB2_LIB.BASEBOARD_FAB2(SCH_1):PAGE42
     2    GND @BASEBOARD_FAB2_LIB.BASEBOARD_FAB2(SCH_1):GND     I3 @BASEBOARD_FAB2_LIB.BASEBOARD_FAB2(SCH_1):PAGE42

C5P29 CAP_0805-47UF,4V,20%,X6S,C9533A
     1 PVCCMCP_CPU0 @BASEBOARD_FAB2_LIB.BASEBOARD_FAB2(SCH_1):PVCCMCP_CPU0   I149 @BASEBOARD_FAB2_LIB.BASEBOARD_FAB2(SCH_1):PAGE42
     2    GND @BASEBOARD_FAB2_LIB.BASEBOARD_FAB2(SCH_1):GND   I149 @BASEBOARD_FAB2_LIB.BASEBOARD_FAB2(SCH_1):PAGE42

C5P30 CAP_0805-47UF,4V,20%,X6S,C9533A
     1 PVCCMCP_CPU0 @BASEBOARD_FAB2_LIB.BASEBOARD_FAB2(SCH_1):PVCCMCP_CPU0   I148 @BASEBOARD_FAB2_LIB.BASEBOARD_FAB2(SCH_1):PAGE42
     2    GND @BASEBOARD_FAB2_LIB.BASEBOARD_FAB2(SCH_1):GND   I148 @BASEBOARD_FAB2_LIB.BASEBOARD_FAB2(SCH_1):PAGE42

C5P31 CAP_0805-47UF,4V,20%,X6S,C9533A
     1 PVCCMCP_CPU0 @BASEBOARD_FAB2_LIB.BASEBOARD_FAB2(SCH_1):PVCCMCP_CPU0   I162 @BASEBOARD_FAB2_LIB.BASEBOARD_FAB2(SCH_1):PAGE42
     2    GND @BASEBOARD_FAB2_LIB.BASEBOARD_FAB2(SCH_1):GND   I162 @BASEBOARD_FAB2_LIB.BASEBOARD_FAB2(SCH_1):PAGE42

C5P32 CAP_0805-47UF,4V,20%,X6S,C9533A
     1 PVCCIN_CPU0 @BASEBOARD_FAB2_LIB.BASEBOARD_FAB2(SCH_1):PVCCIN_CPU0    I53 @BASEBOARD_FAB2_LIB.BASEBOARD_FAB2(SCH_1):PAGE42
     2    GND @BASEBOARD_FAB2_LIB.BASEBOARD_FAB2(SCH_1):GND    I53 @BASEBOARD_FAB2_LIB.BASEBOARD_FAB2(SCH_1):PAGE42

C5P33 CAP_0805-47UF,4V,20%,X6S,C9533A
     1 PVCCIN_CPU0 @BASEBOARD_FAB2_LIB.BASEBOARD_FAB2(SCH_1):PVCCIN_CPU0    I50 @BASEBOARD_FAB2_LIB.BASEBOARD_FAB2(SCH_1):PAGE42
     2    GND @BASEBOARD_FAB2_LIB.BASEBOARD_FAB2(SCH_1):GND    I50 @BASEBOARD_FAB2_LIB.BASEBOARD_FAB2(SCH_1):PAGE42

C5P34 CAP_0805-47UF,4V,20%,X6S,C9533A
     1 PVCCIN_CPU0 @BASEBOARD_FAB2_LIB.BASEBOARD_FAB2(SCH_1):PVCCIN_CPU0    I54 @BASEBOARD_FAB2_LIB.BASEBOARD_FAB2(SCH_1):PAGE42
     2    GND @BASEBOARD_FAB2_LIB.BASEBOARD_FAB2(SCH_1):GND    I54 @BASEBOARD_FAB2_LIB.BASEBOARD_FAB2(SCH_1):PAGE42

C5P35 CAP_0805-47UF,4V,20%,X6S,C9533A
     1 PVCCIN_CPU0 @BASEBOARD_FAB2_LIB.BASEBOARD_FAB2(SCH_1):PVCCIN_CPU0    I51 @BASEBOARD_FAB2_LIB.BASEBOARD_FAB2(SCH_1):PAGE42
     2    GND @BASEBOARD_FAB2_LIB.BASEBOARD_FAB2(SCH_1):GND    I51 @BASEBOARD_FAB2_LIB.BASEBOARD_FAB2(SCH_1):PAGE42

C5P36 CAP_0805-47UF,4V,20%,X6S,C9533A
     1 PVCCIN_CPU0 @BASEBOARD_FAB2_LIB.BASEBOARD_FAB2(SCH_1):PVCCIN_CPU0    I65 @BASEBOARD_FAB2_LIB.BASEBOARD_FAB2(SCH_1):PAGE42
     2    GND @BASEBOARD_FAB2_LIB.BASEBOARD_FAB2(SCH_1):GND    I65 @BASEBOARD_FAB2_LIB.BASEBOARD_FAB2(SCH_1):PAGE42

C5P37 CAP_0805-47UF,4V,20%,X6S,C9533A
     1 PVCCIN_CPU0 @BASEBOARD_FAB2_LIB.BASEBOARD_FAB2(SCH_1):PVCCIN_CPU0    I63 @BASEBOARD_FAB2_LIB.BASEBOARD_FAB2(SCH_1):PAGE42
     2    GND @BASEBOARD_FAB2_LIB.BASEBOARD_FAB2(SCH_1):GND    I63 @BASEBOARD_FAB2_LIB.BASEBOARD_FAB2(SCH_1):PAGE42

C5P38 CAP_0805LF-22UF,4V,20%,X6S,C95A
     1 PVDDQ_ABC @BASEBOARD_FAB2_LIB.BASEBOARD_FAB2(SCH_1):PVDDQ_ABC   I193 @BASEBOARD_FAB2_LIB.BASEBOARD_FAB2(SCH_1):PAGE217
     2    GND @BASEBOARD_FAB2_LIB.BASEBOARD_FAB2(SCH_1):GND   I193 @BASEBOARD_FAB2_LIB.BASEBOARD_FAB2(SCH_1):PAGE217

C5P39 CAP_0805LF-22UF,4V,20%,X6S,C95A
     1 PVDDQ_ABC @BASEBOARD_FAB2_LIB.BASEBOARD_FAB2(SCH_1):PVDDQ_ABC   I184 @BASEBOARD_FAB2_LIB.BASEBOARD_FAB2(SCH_1):PAGE217
     2    GND @BASEBOARD_FAB2_LIB.BASEBOARD_FAB2(SCH_1):GND   I184 @BASEBOARD_FAB2_LIB.BASEBOARD_FAB2(SCH_1):PAGE217

C5P40 CAP_0805-47UF,4V,20%,X6S,C9533A
     1 PVCCIN_CPU0 @BASEBOARD_FAB2_LIB.BASEBOARD_FAB2(SCH_1):PVCCIN_CPU0    I57 @BASEBOARD_FAB2_LIB.BASEBOARD_FAB2(SCH_1):PAGE42
     2    GND @BASEBOARD_FAB2_LIB.BASEBOARD_FAB2(SCH_1):GND    I57 @BASEBOARD_FAB2_LIB.BASEBOARD_FAB2(SCH_1):PAGE42

C5P41 CAP_0805-47UF,4V,20%,X6S,C9533A
     1 PVCCIN_CPU0 @BASEBOARD_FAB2_LIB.BASEBOARD_FAB2(SCH_1):PVCCIN_CPU0    I40 @BASEBOARD_FAB2_LIB.BASEBOARD_FAB2(SCH_1):PAGE42
     2    GND @BASEBOARD_FAB2_LIB.BASEBOARD_FAB2(SCH_1):GND    I40 @BASEBOARD_FAB2_LIB.BASEBOARD_FAB2(SCH_1):PAGE42

C5P42 CAP_0805-47UF,4V,20%,X6S,C9533A
     1 PVCCIN_CPU0 @BASEBOARD_FAB2_LIB.BASEBOARD_FAB2(SCH_1):PVCCIN_CPU0    I59 @BASEBOARD_FAB2_LIB.BASEBOARD_FAB2(SCH_1):PAGE42
     2    GND @BASEBOARD_FAB2_LIB.BASEBOARD_FAB2(SCH_1):GND    I59 @BASEBOARD_FAB2_LIB.BASEBOARD_FAB2(SCH_1):PAGE42

C5P43 CAP_0805-47UF,4V,20%,X6S,C9533A
     1 PVCCIN_CPU0 @BASEBOARD_FAB2_LIB.BASEBOARD_FAB2(SCH_1):PVCCIN_CPU0    I60 @BASEBOARD_FAB2_LIB.BASEBOARD_FAB2(SCH_1):PAGE42
     2    GND @BASEBOARD_FAB2_LIB.BASEBOARD_FAB2(SCH_1):GND    I60 @BASEBOARD_FAB2_LIB.BASEBOARD_FAB2(SCH_1):PAGE42

C5P44 CAP_0805-47UF,4V,20%,X6S,C9533A
     1 PVCCIN_CPU0 @BASEBOARD_FAB2_LIB.BASEBOARD_FAB2(SCH_1):PVCCIN_CPU0    I61 @BASEBOARD_FAB2_LIB.BASEBOARD_FAB2(SCH_1):PAGE42
     2    GND @BASEBOARD_FAB2_LIB.BASEBOARD_FAB2(SCH_1):GND    I61 @BASEBOARD_FAB2_LIB.BASEBOARD_FAB2(SCH_1):PAGE42

C5T1 CAP_A_0603V-47UF,4V,20%,X5R,60A
     1 PVDDQ_ABC @BASEBOARD_FAB2_LIB.BASEBOARD_FAB2(SCH_1):PVDDQ_ABC   I212 @BASEBOARD_FAB2_LIB.BASEBOARD_FAB2(SCH_1):PAGE217
     2    GND @BASEBOARD_FAB2_LIB.BASEBOARD_FAB2(SCH_1):GND   I212 @BASEBOARD_FAB2_LIB.BASEBOARD_FAB2(SCH_1):PAGE217

C5T2 CAP_A_0603V-47UF,4V,20%,X5R,60A
     1 PVDDQ_ABC @BASEBOARD_FAB2_LIB.BASEBOARD_FAB2(SCH_1):PVDDQ_ABC   I208 @BASEBOARD_FAB2_LIB.BASEBOARD_FAB2(SCH_1):PAGE217
     2    GND @BASEBOARD_FAB2_LIB.BASEBOARD_FAB2(SCH_1):GND   I208 @BASEBOARD_FAB2_LIB.BASEBOARD_FAB2(SCH_1):PAGE217

C5T3 CAP_A_0603V-47UF,4V,20%,X5R,60A
     1 PVTT_ABC @BASEBOARD_FAB2_LIB.BASEBOARD_FAB2(SCH_1):PVTT_ABC    I51 @BASEBOARD_FAB2_LIB.BASEBOARD_FAB2(SCH_1):PAGE221
     2    GND @BASEBOARD_FAB2_LIB.BASEBOARD_FAB2(SCH_1):GND    I51 @BASEBOARD_FAB2_LIB.BASEBOARD_FAB2(SCH_1):PAGE221

C5T4 CAP_A_0603V-47UF,4V,20%,X5R,60A
     1 PVDDQ_ABC @BASEBOARD_FAB2_LIB.BASEBOARD_FAB2(SCH_1):PVDDQ_ABC   I211 @BASEBOARD_FAB2_LIB.BASEBOARD_FAB2(SCH_1):PAGE217
     2    GND @BASEBOARD_FAB2_LIB.BASEBOARD_FAB2(SCH_1):GND   I211 @BASEBOARD_FAB2_LIB.BASEBOARD_FAB2(SCH_1):PAGE217

C5T5 CAP_A_0603V-22.0UF,4V,20%,X6S,A
     1 PVDDQ_ABC @BASEBOARD_FAB2_LIB.BASEBOARD_FAB2(SCH_1):PVDDQ_ABC   I216 @BASEBOARD_FAB2_LIB.BASEBOARD_FAB2(SCH_1):PAGE217
     2    GND @BASEBOARD_FAB2_LIB.BASEBOARD_FAB2(SCH_1):GND   I216 @BASEBOARD_FAB2_LIB.BASEBOARD_FAB2(SCH_1):PAGE217

C5T6 CAP_A_0603V-22.0UF,4V,20%,X6S,A
     1 PVDDQ_ABC @BASEBOARD_FAB2_LIB.BASEBOARD_FAB2(SCH_1):PVDDQ_ABC   I218 @BASEBOARD_FAB2_LIB.BASEBOARD_FAB2(SCH_1):PAGE217
     2    GND @BASEBOARD_FAB2_LIB.BASEBOARD_FAB2(SCH_1):GND   I218 @BASEBOARD_FAB2_LIB.BASEBOARD_FAB2(SCH_1):PAGE217

C5T7 CAP_A_0603V-22.0UF,4V,20%,X6S,A
     1 PVDDQ_ABC @BASEBOARD_FAB2_LIB.BASEBOARD_FAB2(SCH_1):PVDDQ_ABC   I219 @BASEBOARD_FAB2_LIB.BASEBOARD_FAB2(SCH_1):PAGE217
     2    GND @BASEBOARD_FAB2_LIB.BASEBOARD_FAB2(SCH_1):GND   I219 @BASEBOARD_FAB2_LIB.BASEBOARD_FAB2(SCH_1):PAGE217

C5T8 CAP_A_0603V-22.0UF,4V,20%,X6S,A
     1 PVDDQ_ABC @BASEBOARD_FAB2_LIB.BASEBOARD_FAB2(SCH_1):PVDDQ_ABC   I222 @BASEBOARD_FAB2_LIB.BASEBOARD_FAB2(SCH_1):PAGE217
     2    GND @BASEBOARD_FAB2_LIB.BASEBOARD_FAB2(SCH_1):GND   I222 @BASEBOARD_FAB2_LIB.BASEBOARD_FAB2(SCH_1):PAGE217

C5T9 CAP_A_0603V-22.0UF,4V,20%,X6S,A
     1 PVDDQ_ABC @BASEBOARD_FAB2_LIB.BASEBOARD_FAB2(SCH_1):PVDDQ_ABC   I224 @BASEBOARD_FAB2_LIB.BASEBOARD_FAB2(SCH_1):PAGE217
     2    GND @BASEBOARD_FAB2_LIB.BASEBOARD_FAB2(SCH_1):GND   I224 @BASEBOARD_FAB2_LIB.BASEBOARD_FAB2(SCH_1):PAGE217

C5T10 CAP_A_0603V-22.0UF,4V,20%,X6S,A
     1 PVDDQ_ABC @BASEBOARD_FAB2_LIB.BASEBOARD_FAB2(SCH_1):PVDDQ_ABC   I225 @BASEBOARD_FAB2_LIB.BASEBOARD_FAB2(SCH_1):PAGE217
     2    GND @BASEBOARD_FAB2_LIB.BASEBOARD_FAB2(SCH_1):GND   I225 @BASEBOARD_FAB2_LIB.BASEBOARD_FAB2(SCH_1):PAGE217

C5T11 CAP_A_0603V-22.0UF,4V,20%,X6S,A
     1 PVDDQ_ABC @BASEBOARD_FAB2_LIB.BASEBOARD_FAB2(SCH_1):PVDDQ_ABC   I228 @BASEBOARD_FAB2_LIB.BASEBOARD_FAB2(SCH_1):PAGE217
     2    GND @BASEBOARD_FAB2_LIB.BASEBOARD_FAB2(SCH_1):GND   I228 @BASEBOARD_FAB2_LIB.BASEBOARD_FAB2(SCH_1):PAGE217

C5T12 CAP_A_0603V-22.0UF,4V,20%,X6S,A
     1 PVDDQ_ABC @BASEBOARD_FAB2_LIB.BASEBOARD_FAB2(SCH_1):PVDDQ_ABC   I229 @BASEBOARD_FAB2_LIB.BASEBOARD_FAB2(SCH_1):PAGE217
     2    GND @BASEBOARD_FAB2_LIB.BASEBOARD_FAB2(SCH_1):GND   I229 @BASEBOARD_FAB2_LIB.BASEBOARD_FAB2(SCH_1):PAGE217

C5T13 CAP_A_0603V-47UF,4V,20%,X5R,60A
     1 PVDDQ_ABC @BASEBOARD_FAB2_LIB.BASEBOARD_FAB2(SCH_1):PVDDQ_ABC   I210 @BASEBOARD_FAB2_LIB.BASEBOARD_FAB2(SCH_1):PAGE217
     2    GND @BASEBOARD_FAB2_LIB.BASEBOARD_FAB2(SCH_1):GND   I210 @BASEBOARD_FAB2_LIB.BASEBOARD_FAB2(SCH_1):PAGE217

C5U1 CAP_0805-100UF,4V,20%,X5R,6024A
     1 PVDDQ_ABC @BASEBOARD_FAB2_LIB.BASEBOARD_FAB2(SCH_1):PVDDQ_ABC    I88 @BASEBOARD_FAB2_LIB.BASEBOARD_FAB2(SCH_1):PAGE217
     2    GND @BASEBOARD_FAB2_LIB.BASEBOARD_FAB2(SCH_1):GND    I88 @BASEBOARD_FAB2_LIB.BASEBOARD_FAB2(SCH_1):PAGE217

C5U2 CAP_A_0603V-22.0UF,4V,20%,X6S,A
     1 PVDDQ_ABC @BASEBOARD_FAB2_LIB.BASEBOARD_FAB2(SCH_1):PVDDQ_ABC   I247 @BASEBOARD_FAB2_LIB.BASEBOARD_FAB2(SCH_1):PAGE217
     2    GND @BASEBOARD_FAB2_LIB.BASEBOARD_FAB2(SCH_1):GND   I247 @BASEBOARD_FAB2_LIB.BASEBOARD_FAB2(SCH_1):PAGE217

C5U3 CAP_A_0603V-22.0UF,4V,20%,X6S,A
     1 PVDDQ_ABC @BASEBOARD_FAB2_LIB.BASEBOARD_FAB2(SCH_1):PVDDQ_ABC   I244 @BASEBOARD_FAB2_LIB.BASEBOARD_FAB2(SCH_1):PAGE217
     2    GND @BASEBOARD_FAB2_LIB.BASEBOARD_FAB2(SCH_1):GND   I244 @BASEBOARD_FAB2_LIB.BASEBOARD_FAB2(SCH_1):PAGE217

C5U4 CAP_A_0603V-22.0UF,4V,20%,X6S,A
     1 PVDDQ_ABC @BASEBOARD_FAB2_LIB.BASEBOARD_FAB2(SCH_1):PVDDQ_ABC   I243 @BASEBOARD_FAB2_LIB.BASEBOARD_FAB2(SCH_1):PAGE217
     2    GND @BASEBOARD_FAB2_LIB.BASEBOARD_FAB2(SCH_1):GND   I243 @BASEBOARD_FAB2_LIB.BASEBOARD_FAB2(SCH_1):PAGE217

C5U5 CAP_A_0603V-22.0UF,4V,20%,X6S,A
     1 PVDDQ_ABC @BASEBOARD_FAB2_LIB.BASEBOARD_FAB2(SCH_1):PVDDQ_ABC   I239 @BASEBOARD_FAB2_LIB.BASEBOARD_FAB2(SCH_1):PAGE217
     2    GND @BASEBOARD_FAB2_LIB.BASEBOARD_FAB2(SCH_1):GND   I239 @BASEBOARD_FAB2_LIB.BASEBOARD_FAB2(SCH_1):PAGE217

C5U6 CAP_A_0603V-22.0UF,4V,20%,X6S,A
     1 PVDDQ_ABC @BASEBOARD_FAB2_LIB.BASEBOARD_FAB2(SCH_1):PVDDQ_ABC   I238 @BASEBOARD_FAB2_LIB.BASEBOARD_FAB2(SCH_1):PAGE217
     2    GND @BASEBOARD_FAB2_LIB.BASEBOARD_FAB2(SCH_1):GND   I238 @BASEBOARD_FAB2_LIB.BASEBOARD_FAB2(SCH_1):PAGE217

C5U7 CAP_A_0603V-22.0UF,4V,20%,X6S,A
     1 PVDDQ_ABC @BASEBOARD_FAB2_LIB.BASEBOARD_FAB2(SCH_1):PVDDQ_ABC   I236 @BASEBOARD_FAB2_LIB.BASEBOARD_FAB2(SCH_1):PAGE217
     2    GND @BASEBOARD_FAB2_LIB.BASEBOARD_FAB2(SCH_1):GND   I236 @BASEBOARD_FAB2_LIB.BASEBOARD_FAB2(SCH_1):PAGE217

C5U8 CAP_A_0603V-22.0UF,4V,20%,X6S,A
     1 PVDDQ_ABC @BASEBOARD_FAB2_LIB.BASEBOARD_FAB2(SCH_1):PVDDQ_ABC   I233 @BASEBOARD_FAB2_LIB.BASEBOARD_FAB2(SCH_1):PAGE217
     2    GND @BASEBOARD_FAB2_LIB.BASEBOARD_FAB2(SCH_1):GND   I233 @BASEBOARD_FAB2_LIB.BASEBOARD_FAB2(SCH_1):PAGE217

C5U9 CAP_A_0603V-22.0UF,4V,20%,X6S,A
     1 PVDDQ_ABC @BASEBOARD_FAB2_LIB.BASEBOARD_FAB2(SCH_1):PVDDQ_ABC   I232 @BASEBOARD_FAB2_LIB.BASEBOARD_FAB2(SCH_1):PAGE217
     2    GND @BASEBOARD_FAB2_LIB.BASEBOARD_FAB2(SCH_1):GND   I232 @BASEBOARD_FAB2_LIB.BASEBOARD_FAB2(SCH_1):PAGE217

C5U10 CAP_0805-100UF,4V,20%,X5R,6024A
     1 PVDDQ_ABC @BASEBOARD_FAB2_LIB.BASEBOARD_FAB2(SCH_1):PVDDQ_ABC    I83 @BASEBOARD_FAB2_LIB.BASEBOARD_FAB2(SCH_1):PAGE217
     2    GND @BASEBOARD_FAB2_LIB.BASEBOARD_FAB2(SCH_1):GND    I83 @BASEBOARD_FAB2_LIB.BASEBOARD_FAB2(SCH_1):PAGE217

C5U11 CAP_A_0603V-47UF,4V,20%,X5R,60A
     1 PVDDQ_ABC @BASEBOARD_FAB2_LIB.BASEBOARD_FAB2(SCH_1):PVDDQ_ABC   I209 @BASEBOARD_FAB2_LIB.BASEBOARD_FAB2(SCH_1):PAGE217
     2    GND @BASEBOARD_FAB2_LIB.BASEBOARD_FAB2(SCH_1):GND   I209 @BASEBOARD_FAB2_LIB.BASEBOARD_FAB2(SCH_1):PAGE217

C5U12 CAP_A_0603V-47UF,4V,20%,X5R,60A
     1 PVTT_ABC @BASEBOARD_FAB2_LIB.BASEBOARD_FAB2(SCH_1):PVTT_ABC    I50 @BASEBOARD_FAB2_LIB.BASEBOARD_FAB2(SCH_1):PAGE221
     2    GND @BASEBOARD_FAB2_LIB.BASEBOARD_FAB2(SCH_1):GND    I50 @BASEBOARD_FAB2_LIB.BASEBOARD_FAB2(SCH_1):PAGE221

C5U13 CAP_0805-100UF,4V,20%,X5R,6024A
     1 PVDDQ_ABC @BASEBOARD_FAB2_LIB.BASEBOARD_FAB2(SCH_1):PVDDQ_ABC    I82 @BASEBOARD_FAB2_LIB.BASEBOARD_FAB2(SCH_1):PAGE217
     2    GND @BASEBOARD_FAB2_LIB.BASEBOARD_FAB2(SCH_1):GND    I82 @BASEBOARD_FAB2_LIB.BASEBOARD_FAB2(SCH_1):PAGE217

C5U14 CAP_0805-100UF,4V,20%,X5R,6024A
     1 PVDDQ_ABC @BASEBOARD_FAB2_LIB.BASEBOARD_FAB2(SCH_1):PVDDQ_ABC    I89 @BASEBOARD_FAB2_LIB.BASEBOARD_FAB2(SCH_1):PAGE217
     2    GND @BASEBOARD_FAB2_LIB.BASEBOARD_FAB2(SCH_1):GND    I89 @BASEBOARD_FAB2_LIB.BASEBOARD_FAB2(SCH_1):PAGE217

C5U15 CAP_0805-100UF,4V,20%,X5R,6024A
     1 PVDDQ_ABC @BASEBOARD_FAB2_LIB.BASEBOARD_FAB2(SCH_1):PVDDQ_ABC    I90 @BASEBOARD_FAB2_LIB.BASEBOARD_FAB2(SCH_1):PAGE217
     2    GND @BASEBOARD_FAB2_LIB.BASEBOARD_FAB2(SCH_1):GND    I90 @BASEBOARD_FAB2_LIB.BASEBOARD_FAB2(SCH_1):PAGE217

C5U16 CAP_A_0603V-47UF,4V,20%,X5R,60A
     1 PVTT_ABC @BASEBOARD_FAB2_LIB.BASEBOARD_FAB2(SCH_1):PVTT_ABC    I52 @BASEBOARD_FAB2_LIB.BASEBOARD_FAB2(SCH_1):PAGE221
     2    GND @BASEBOARD_FAB2_LIB.BASEBOARD_FAB2(SCH_1):GND    I52 @BASEBOARD_FAB2_LIB.BASEBOARD_FAB2(SCH_1):PAGE221

C6A1 CAP_0805LF-22UF,4V,20%,X6S,C95A
     1 PVDDQ_DEF @BASEBOARD_FAB2_LIB.BASEBOARD_FAB2(SCH_1):PVDDQ_DEF    I87 @BASEBOARD_FAB2_LIB.BASEBOARD_FAB2(SCH_1):PAGE219
     2    GND @BASEBOARD_FAB2_LIB.BASEBOARD_FAB2(SCH_1):GND    I87 @BASEBOARD_FAB2_LIB.BASEBOARD_FAB2(SCH_1):PAGE219

C6A2 CAP_0603LF-10UF,4V,20%,X6S,E15A
     1 PVPP_DEF @BASEBOARD_FAB2_LIB.BASEBOARD_FAB2(SCH_1):PVPP_DEF   I105 @BASEBOARD_FAB2_LIB.BASEBOARD_FAB2(SCH_1):PAGE232
     2    GND @BASEBOARD_FAB2_LIB.BASEBOARD_FAB2(SCH_1):GND   I105 @BASEBOARD_FAB2_LIB.BASEBOARD_FAB2(SCH_1):PAGE232

C6A3 CAP_0603LF-10UF,4V,20%,X6S,E15A
     1 PVPP_DEF @BASEBOARD_FAB2_LIB.BASEBOARD_FAB2(SCH_1):PVPP_DEF   I104 @BASEBOARD_FAB2_LIB.BASEBOARD_FAB2(SCH_1):PAGE232
     2    GND @BASEBOARD_FAB2_LIB.BASEBOARD_FAB2(SCH_1):GND   I104 @BASEBOARD_FAB2_LIB.BASEBOARD_FAB2(SCH_1):PAGE232

C6A4 CAP_0805LF-22UF,4V,20%,X6S,C95A
     1 PVDDQ_DEF @BASEBOARD_FAB2_LIB.BASEBOARD_FAB2(SCH_1):PVDDQ_DEF    I68 @BASEBOARD_FAB2_LIB.BASEBOARD_FAB2(SCH_1):PAGE219
     2    GND @BASEBOARD_FAB2_LIB.BASEBOARD_FAB2(SCH_1):GND    I68 @BASEBOARD_FAB2_LIB.BASEBOARD_FAB2(SCH_1):PAGE219

C6A5 CAPP_3018-470UF,2.5V,20%,ALUM,A
     1 PVDDQ_DEF @BASEBOARD_FAB2_LIB.BASEBOARD_FAB2(SCH_1):PVDDQ_DEF    I77 @BASEBOARD_FAB2_LIB.BASEBOARD_FAB2(SCH_1):PAGE220
     2    GND @BASEBOARD_FAB2_LIB.BASEBOARD_FAB2(SCH_1):GND    I77 @BASEBOARD_FAB2_LIB.BASEBOARD_FAB2(SCH_1):PAGE220

C6A6 CAP_0603LF-10UF,4V,20%,X6S,E15A
     1 PVPP_DEF @BASEBOARD_FAB2_LIB.BASEBOARD_FAB2(SCH_1):PVPP_DEF   I110 @BASEBOARD_FAB2_LIB.BASEBOARD_FAB2(SCH_1):PAGE232
     2    GND @BASEBOARD_FAB2_LIB.BASEBOARD_FAB2(SCH_1):GND   I110 @BASEBOARD_FAB2_LIB.BASEBOARD_FAB2(SCH_1):PAGE232

C6A7 CAP_0603LF-10UF,4V,20%,X6S,E15A
     1 PVPP_DEF @BASEBOARD_FAB2_LIB.BASEBOARD_FAB2(SCH_1):PVPP_DEF   I109 @BASEBOARD_FAB2_LIB.BASEBOARD_FAB2(SCH_1):PAGE232
     2    GND @BASEBOARD_FAB2_LIB.BASEBOARD_FAB2(SCH_1):GND   I109 @BASEBOARD_FAB2_LIB.BASEBOARD_FAB2(SCH_1):PAGE232

C6B1 CAP_0603LF-10UF,4V,20%,X6S,E15A
     1 PVPP_DEF @BASEBOARD_FAB2_LIB.BASEBOARD_FAB2(SCH_1):PVPP_DEF   I128 @BASEBOARD_FAB2_LIB.BASEBOARD_FAB2(SCH_1):PAGE232
     2    GND @BASEBOARD_FAB2_LIB.BASEBOARD_FAB2(SCH_1):GND   I128 @BASEBOARD_FAB2_LIB.BASEBOARD_FAB2(SCH_1):PAGE232

C6B2 CAP_0603LF-10UF,4V,20%,X6S,E15A
     1 PVPP_DEF @BASEBOARD_FAB2_LIB.BASEBOARD_FAB2(SCH_1):PVPP_DEF   I126 @BASEBOARD_FAB2_LIB.BASEBOARD_FAB2(SCH_1):PAGE232
     2    GND @BASEBOARD_FAB2_LIB.BASEBOARD_FAB2(SCH_1):GND   I126 @BASEBOARD_FAB2_LIB.BASEBOARD_FAB2(SCH_1):PAGE232

C6B3 CAP_0805-47UF,4V,20%,X6S,C9533A
     1 PVPP_DEF @BASEBOARD_FAB2_LIB.BASEBOARD_FAB2(SCH_1):PVPP_DEF   I236 @BASEBOARD_FAB2_LIB.BASEBOARD_FAB2(SCH_1):PAGE232
     2    GND @BASEBOARD_FAB2_LIB.BASEBOARD_FAB2(SCH_1):GND   I236 @BASEBOARD_FAB2_LIB.BASEBOARD_FAB2(SCH_1):PAGE232

C6B4 CAP_0402-0.22UF,16V,10%,X7R,A3A
     1 P3E_CPU0_PE1_PCH_TXN<15> @BASEBOARD_FAB2_LIB.BASEBOARD_FAB2(SCH_1):P3E_CPU0_PE1_PCH_TXN(15)   I196 @BASEBOARD_FAB2_LIB.BASEBOARD_FAB2(SCH_1):PAGE105
     2 P3E_CPU0_PE1_PCH_C_TXN<15> @BASEBOARD_FAB2_LIB.BASEBOARD_FAB2(SCH_1):P3E_CPU0_PE1_PCH_C_TXN(15)   I196 @BASEBOARD_FAB2_LIB.BASEBOARD_FAB2(SCH_1):PAGE105

C6B5 CAP_0402-0.22UF,16V,10%,X7R,A3A
     1 P3E_CPU0_PE1_PCH_TXP<15> @BASEBOARD_FAB2_LIB.BASEBOARD_FAB2(SCH_1):P3E_CPU0_PE1_PCH_TXP(15)   I201 @BASEBOARD_FAB2_LIB.BASEBOARD_FAB2(SCH_1):PAGE105
     2 P3E_CPU0_PE1_PCH_C_TXP<15> @BASEBOARD_FAB2_LIB.BASEBOARD_FAB2(SCH_1):P3E_CPU0_PE1_PCH_C_TXP(15)   I201 @BASEBOARD_FAB2_LIB.BASEBOARD_FAB2(SCH_1):PAGE105

C6B6 CAP_0402-0.22UF,16V,10%,X7R,A3A
     1 P3E_CPU0_PE1_PCH_TXN<14> @BASEBOARD_FAB2_LIB.BASEBOARD_FAB2(SCH_1):P3E_CPU0_PE1_PCH_TXN(14)   I169 @BASEBOARD_FAB2_LIB.BASEBOARD_FAB2(SCH_1):PAGE105
     2 P3E_CPU0_PE1_PCH_C_TXN<14> @BASEBOARD_FAB2_LIB.BASEBOARD_FAB2(SCH_1):P3E_CPU0_PE1_PCH_C_TXN(14)   I169 @BASEBOARD_FAB2_LIB.BASEBOARD_FAB2(SCH_1):PAGE105

C6B7 CAPP_7343LF-330UF,6.3V,20%,POSA
     1 PVPP_DEF @BASEBOARD_FAB2_LIB.BASEBOARD_FAB2(SCH_1):PVPP_DEF   I229 @BASEBOARD_FAB2_LIB.BASEBOARD_FAB2(SCH_1):PAGE232
     2    GND @BASEBOARD_FAB2_LIB.BASEBOARD_FAB2(SCH_1):GND   I229 @BASEBOARD_FAB2_LIB.BASEBOARD_FAB2(SCH_1):PAGE232

C6B8 CAP_0402-0.22UF,16V,10%,X7R,A3A
     1 P3E_CPU0_PE1_PCH_TXP<14> @BASEBOARD_FAB2_LIB.BASEBOARD_FAB2(SCH_1):P3E_CPU0_PE1_PCH_TXP(14)   I198 @BASEBOARD_FAB2_LIB.BASEBOARD_FAB2(SCH_1):PAGE105
     2 P3E_CPU0_PE1_PCH_C_TXP<14> @BASEBOARD_FAB2_LIB.BASEBOARD_FAB2(SCH_1):P3E_CPU0_PE1_PCH_C_TXP(14)   I198 @BASEBOARD_FAB2_LIB.BASEBOARD_FAB2(SCH_1):PAGE105

C6B9 CAP_0402-0.22UF,16V,10%,X7R,A3A
     1 P3E_CPU0_PE1_PCH_TXN<13> @BASEBOARD_FAB2_LIB.BASEBOARD_FAB2(SCH_1):P3E_CPU0_PE1_PCH_TXN(13)   I185 @BASEBOARD_FAB2_LIB.BASEBOARD_FAB2(SCH_1):PAGE105
     2 P3E_CPU0_PE1_PCH_C_TXN<13> @BASEBOARD_FAB2_LIB.BASEBOARD_FAB2(SCH_1):P3E_CPU0_PE1_PCH_C_TXN(13)   I185 @BASEBOARD_FAB2_LIB.BASEBOARD_FAB2(SCH_1):PAGE105

C6B10 CAP_0402-0.22UF,16V,10%,X7R,A3A
     1 P3E_CPU0_PE1_PCH_TXP<13> @BASEBOARD_FAB2_LIB.BASEBOARD_FAB2(SCH_1):P3E_CPU0_PE1_PCH_TXP(13)   I193 @BASEBOARD_FAB2_LIB.BASEBOARD_FAB2(SCH_1):PAGE105
     2 P3E_CPU0_PE1_PCH_C_TXP<13> @BASEBOARD_FAB2_LIB.BASEBOARD_FAB2(SCH_1):P3E_CPU0_PE1_PCH_C_TXP(13)   I193 @BASEBOARD_FAB2_LIB.BASEBOARD_FAB2(SCH_1):PAGE105

C6B11 CAP_0402-0.22UF,16V,10%,X7R,A3A
     1 P3E_CPU0_PE1_PCH_TXN<12> @BASEBOARD_FAB2_LIB.BASEBOARD_FAB2(SCH_1):P3E_CPU0_PE1_PCH_TXN(12)   I166 @BASEBOARD_FAB2_LIB.BASEBOARD_FAB2(SCH_1):PAGE105
     2 P3E_CPU0_PE1_PCH_C_TXN<12> @BASEBOARD_FAB2_LIB.BASEBOARD_FAB2(SCH_1):P3E_CPU0_PE1_PCH_C_TXN(12)   I166 @BASEBOARD_FAB2_LIB.BASEBOARD_FAB2(SCH_1):PAGE105

C6B12 CAP_0402-0.22UF,16V,10%,X7R,A3A
     1 P3E_CPU0_PE1_PCH_TXP<12> @BASEBOARD_FAB2_LIB.BASEBOARD_FAB2(SCH_1):P3E_CPU0_PE1_PCH_TXP(12)   I187 @BASEBOARD_FAB2_LIB.BASEBOARD_FAB2(SCH_1):PAGE105
     2 P3E_CPU0_PE1_PCH_C_TXP<12> @BASEBOARD_FAB2_LIB.BASEBOARD_FAB2(SCH_1):P3E_CPU0_PE1_PCH_C_TXP(12)   I187 @BASEBOARD_FAB2_LIB.BASEBOARD_FAB2(SCH_1):PAGE105

C6B13 CAP_0402-0.22UF,16V,10%,X7R,A3A
     1 P3E_CPU0_PE1_PCH_TXP<11> @BASEBOARD_FAB2_LIB.BASEBOARD_FAB2(SCH_1):P3E_CPU0_PE1_PCH_TXP(11)   I189 @BASEBOARD_FAB2_LIB.BASEBOARD_FAB2(SCH_1):PAGE105
     2 P3E_CPU0_PE1_PCH_C_TXP<11> @BASEBOARD_FAB2_LIB.BASEBOARD_FAB2(SCH_1):P3E_CPU0_PE1_PCH_C_TXP(11)   I189 @BASEBOARD_FAB2_LIB.BASEBOARD_FAB2(SCH_1):PAGE105

C6B14 CAP_0402-0.22UF,16V,10%,X7R,A3A
     1 P3E_CPU0_PE1_PCH_TXN<11> @BASEBOARD_FAB2_LIB.BASEBOARD_FAB2(SCH_1):P3E_CPU0_PE1_PCH_TXN(11)   I181 @BASEBOARD_FAB2_LIB.BASEBOARD_FAB2(SCH_1):PAGE105
     2 P3E_CPU0_PE1_PCH_C_TXN<11> @BASEBOARD_FAB2_LIB.BASEBOARD_FAB2(SCH_1):P3E_CPU0_PE1_PCH_C_TXN(11)   I181 @BASEBOARD_FAB2_LIB.BASEBOARD_FAB2(SCH_1):PAGE105

C6B15 CAP_0402-0.22UF,16V,10%,X7R,A3A
     1 P3E_CPU0_PE1_PCH_TXN<10> @BASEBOARD_FAB2_LIB.BASEBOARD_FAB2(SCH_1):P3E_CPU0_PE1_PCH_TXN(10)   I163 @BASEBOARD_FAB2_LIB.BASEBOARD_FAB2(SCH_1):PAGE105
     2 P3E_CPU0_PE1_PCH_C_TXN<10> @BASEBOARD_FAB2_LIB.BASEBOARD_FAB2(SCH_1):P3E_CPU0_PE1_PCH_C_TXN(10)   I163 @BASEBOARD_FAB2_LIB.BASEBOARD_FAB2(SCH_1):PAGE105

C6B16 CAP_0402-0.22UF,16V,10%,X7R,A3A
     1 P3E_CPU0_PE1_PCH_TXP<10> @BASEBOARD_FAB2_LIB.BASEBOARD_FAB2(SCH_1):P3E_CPU0_PE1_PCH_TXP(10)   I180 @BASEBOARD_FAB2_LIB.BASEBOARD_FAB2(SCH_1):PAGE105
     2 P3E_CPU0_PE1_PCH_C_TXP<10> @BASEBOARD_FAB2_LIB.BASEBOARD_FAB2(SCH_1):P3E_CPU0_PE1_PCH_C_TXP(10)   I180 @BASEBOARD_FAB2_LIB.BASEBOARD_FAB2(SCH_1):PAGE105

C6B17 CAP_0402-0.22UF,16V,10%,X7R,A3A
     1 P3E_CPU0_PE1_PCH_TXN<9> @BASEBOARD_FAB2_LIB.BASEBOARD_FAB2(SCH_1):P3E_CPU0_PE1_PCH_TXN(9)   I175 @BASEBOARD_FAB2_LIB.BASEBOARD_FAB2(SCH_1):PAGE105
     2 P3E_CPU0_PE1_PCH_C_TXN<9> @BASEBOARD_FAB2_LIB.BASEBOARD_FAB2(SCH_1):P3E_CPU0_PE1_PCH_C_TXN(9)   I175 @BASEBOARD_FAB2_LIB.BASEBOARD_FAB2(SCH_1):PAGE105

C6B18 CAP_0402-0.22UF,16V,10%,X7R,A3A
     1 P3E_CPU0_PE1_PCH_TXP<9> @BASEBOARD_FAB2_LIB.BASEBOARD_FAB2(SCH_1):P3E_CPU0_PE1_PCH_TXP(9)   I153 @BASEBOARD_FAB2_LIB.BASEBOARD_FAB2(SCH_1):PAGE105
     2 P3E_CPU0_PE1_PCH_C_TXP<9> @BASEBOARD_FAB2_LIB.BASEBOARD_FAB2(SCH_1):P3E_CPU0_PE1_PCH_C_TXP(9)   I153 @BASEBOARD_FAB2_LIB.BASEBOARD_FAB2(SCH_1):PAGE105

C6B19 CAP_0402-0.22UF,16V,10%,X7R,A3A
     1 P3E_CPU0_PE1_PCH_TXN<8> @BASEBOARD_FAB2_LIB.BASEBOARD_FAB2(SCH_1):P3E_CPU0_PE1_PCH_TXN(8)   I160 @BASEBOARD_FAB2_LIB.BASEBOARD_FAB2(SCH_1):PAGE105
     2 P3E_CPU0_PE1_PCH_C_TXN<8> @BASEBOARD_FAB2_LIB.BASEBOARD_FAB2(SCH_1):P3E_CPU0_PE1_PCH_C_TXN(8)   I160 @BASEBOARD_FAB2_LIB.BASEBOARD_FAB2(SCH_1):PAGE105

C6B20 CAP_0402-0.22UF,16V,10%,X7R,A3A
     1 P3E_CPU0_PE1_PCH_TXP<8> @BASEBOARD_FAB2_LIB.BASEBOARD_FAB2(SCH_1):P3E_CPU0_PE1_PCH_TXP(8)   I173 @BASEBOARD_FAB2_LIB.BASEBOARD_FAB2(SCH_1):PAGE105
     2 P3E_CPU0_PE1_PCH_C_TXP<8> @BASEBOARD_FAB2_LIB.BASEBOARD_FAB2(SCH_1):P3E_CPU0_PE1_PCH_C_TXP(8)   I173 @BASEBOARD_FAB2_LIB.BASEBOARD_FAB2(SCH_1):PAGE105

C6D1 CAP_0603LF-10UF,4V,20%,X6S,E15A
     1 P1V8_MCP_CPU0 @BASEBOARD_FAB2_LIB.BASEBOARD_FAB2(SCH_1):P1V8_MCP_CPU0    I19 @BASEBOARD_FAB2_LIB.BASEBOARD_FAB2(SCH_1):PAGE38
     2    GND @BASEBOARD_FAB2_LIB.BASEBOARD_FAB2(SCH_1):GND    I19 @BASEBOARD_FAB2_LIB.BASEBOARD_FAB2(SCH_1):PAGE38

C6D2 CAP_A_0603V-22.0UF,4V,20%,X6S,A
     1 PVCCMCP_CPU0 @BASEBOARD_FAB2_LIB.BASEBOARD_FAB2(SCH_1):PVCCMCP_CPU0    I77 @BASEBOARD_FAB2_LIB.BASEBOARD_FAB2(SCH_1):PAGE42
     2    GND @BASEBOARD_FAB2_LIB.BASEBOARD_FAB2(SCH_1):GND    I77 @BASEBOARD_FAB2_LIB.BASEBOARD_FAB2(SCH_1):PAGE42

C6D3 CAP_A_0603V-22.0UF,4V,20%,X6S,A
     1 PVCCIO_CPU0 @BASEBOARD_FAB2_LIB.BASEBOARD_FAB2(SCH_1):PVCCIO_CPU0    I80 @BASEBOARD_FAB2_LIB.BASEBOARD_FAB2(SCH_1):PAGE42
     2    GND @BASEBOARD_FAB2_LIB.BASEBOARD_FAB2(SCH_1):GND    I80 @BASEBOARD_FAB2_LIB.BASEBOARD_FAB2(SCH_1):PAGE42

C6D4 CAP_A_0603V-22.0UF,4V,20%,X6S,A
     1 PVCCIO_CPU0 @BASEBOARD_FAB2_LIB.BASEBOARD_FAB2(SCH_1):PVCCIO_CPU0    I74 @BASEBOARD_FAB2_LIB.BASEBOARD_FAB2(SCH_1):PAGE42
     2    GND @BASEBOARD_FAB2_LIB.BASEBOARD_FAB2(SCH_1):GND    I74 @BASEBOARD_FAB2_LIB.BASEBOARD_FAB2(SCH_1):PAGE42

C6D5 CAP_A_0603V-22.0UF,4V,20%,X6S,A
     1 PVCCMCP_CPU0 @BASEBOARD_FAB2_LIB.BASEBOARD_FAB2(SCH_1):PVCCMCP_CPU0    I75 @BASEBOARD_FAB2_LIB.BASEBOARD_FAB2(SCH_1):PAGE42
     2    GND @BASEBOARD_FAB2_LIB.BASEBOARD_FAB2(SCH_1):GND    I75 @BASEBOARD_FAB2_LIB.BASEBOARD_FAB2(SCH_1):PAGE42

C6D6 CAP_A_0603V-22.0UF,4V,20%,X6S,A
     1 PVCCIO_CPU0 @BASEBOARD_FAB2_LIB.BASEBOARD_FAB2(SCH_1):PVCCIO_CPU0    I81 @BASEBOARD_FAB2_LIB.BASEBOARD_FAB2(SCH_1):PAGE42
     2    GND @BASEBOARD_FAB2_LIB.BASEBOARD_FAB2(SCH_1):GND    I81 @BASEBOARD_FAB2_LIB.BASEBOARD_FAB2(SCH_1):PAGE42

C6D7 CAP_A_0603V-22.0UF,4V,20%,X6S,A
     1 PVCCIO_CPU0 @BASEBOARD_FAB2_LIB.BASEBOARD_FAB2(SCH_1):PVCCIO_CPU0    I72 @BASEBOARD_FAB2_LIB.BASEBOARD_FAB2(SCH_1):PAGE42
     2    GND @BASEBOARD_FAB2_LIB.BASEBOARD_FAB2(SCH_1):GND    I72 @BASEBOARD_FAB2_LIB.BASEBOARD_FAB2(SCH_1):PAGE42

C6D8 CAP_A_0603V-22.0UF,4V,20%,X6S,A
     1 PVCCMCP_CPU0 @BASEBOARD_FAB2_LIB.BASEBOARD_FAB2(SCH_1):PVCCMCP_CPU0    I68 @BASEBOARD_FAB2_LIB.BASEBOARD_FAB2(SCH_1):PAGE42
     2    GND @BASEBOARD_FAB2_LIB.BASEBOARD_FAB2(SCH_1):GND    I68 @BASEBOARD_FAB2_LIB.BASEBOARD_FAB2(SCH_1):PAGE42

C6D9 CAP_A_0603V-22.0UF,4V,20%,X6S,A
     1 PVCCIO_CPU0 @BASEBOARD_FAB2_LIB.BASEBOARD_FAB2(SCH_1):PVCCIO_CPU0   I145 @BASEBOARD_FAB2_LIB.BASEBOARD_FAB2(SCH_1):PAGE42
     2    GND @BASEBOARD_FAB2_LIB.BASEBOARD_FAB2(SCH_1):GND   I145 @BASEBOARD_FAB2_LIB.BASEBOARD_FAB2(SCH_1):PAGE42

C6D10 CAP_A_0603V-22.0UF,4V,20%,X6S,A
     1 PVCCIO_CPU0 @BASEBOARD_FAB2_LIB.BASEBOARD_FAB2(SCH_1):PVCCIO_CPU0   I147 @BASEBOARD_FAB2_LIB.BASEBOARD_FAB2(SCH_1):PAGE42
     2    GND @BASEBOARD_FAB2_LIB.BASEBOARD_FAB2(SCH_1):GND   I147 @BASEBOARD_FAB2_LIB.BASEBOARD_FAB2(SCH_1):PAGE42

C6F1 CAP_A_0402V-0.1UF,16V,10%,X7R,A
     1   P3V3 @BASEBOARD_FAB2_LIB.BASEBOARD_FAB2(SCH_1):P3V3    I25 @BASEBOARD_FAB2_LIB.BASEBOARD_FAB2(SCH_1):PAGE104
     2    GND @BASEBOARD_FAB2_LIB.BASEBOARD_FAB2(SCH_1):GND    I25 @BASEBOARD_FAB2_LIB.BASEBOARD_FAB2(SCH_1):PAGE104

C6F2 CAP_A_0402V-0.1UF,16V,10%,X7R,A
     1 PVCCIO_CPU0 @BASEBOARD_FAB2_LIB.BASEBOARD_FAB2(SCH_1):PVCCIO_CPU0     I2 @BASEBOARD_FAB2_LIB.BASEBOARD_FAB2(SCH_1):PAGE99
     2    GND @BASEBOARD_FAB2_LIB.BASEBOARD_FAB2(SCH_1):GND     I2 @BASEBOARD_FAB2_LIB.BASEBOARD_FAB2(SCH_1):PAGE99

C6F3 CAP_A_0402V-0.1UF,16V,10%,X7R,A
     1 PVPP_ABC @BASEBOARD_FAB2_LIB.BASEBOARD_FAB2(SCH_1):PVPP_ABC     I7 @BASEBOARD_FAB2_LIB.BASEBOARD_FAB2(SCH_1):PAGE99
     2    GND @BASEBOARD_FAB2_LIB.BASEBOARD_FAB2(SCH_1):GND     I7 @BASEBOARD_FAB2_LIB.BASEBOARD_FAB2(SCH_1):PAGE99

C6F4 CAPP_7343LF-330UF,6.3V,20%,POSA
     1 PVPP_ABC @BASEBOARD_FAB2_LIB.BASEBOARD_FAB2(SCH_1):PVPP_ABC   I180 @BASEBOARD_FAB2_LIB.BASEBOARD_FAB2(SCH_1):PAGE231
     2    GND @BASEBOARD_FAB2_LIB.BASEBOARD_FAB2(SCH_1):GND   I180 @BASEBOARD_FAB2_LIB.BASEBOARD_FAB2(SCH_1):PAGE231

C6F5 CAP_0603LF-10UF,4V,20%,X6S,E15A
     1 PVPP_ABC @BASEBOARD_FAB2_LIB.BASEBOARD_FAB2(SCH_1):PVPP_ABC   I149 @BASEBOARD_FAB2_LIB.BASEBOARD_FAB2(SCH_1):PAGE231
     2    GND @BASEBOARD_FAB2_LIB.BASEBOARD_FAB2(SCH_1):GND   I149 @BASEBOARD_FAB2_LIB.BASEBOARD_FAB2(SCH_1):PAGE231

C6F6 CAP_0603LF-10UF,4V,20%,X6S,E15A
     1 PVPP_ABC @BASEBOARD_FAB2_LIB.BASEBOARD_FAB2(SCH_1):PVPP_ABC   I122 @BASEBOARD_FAB2_LIB.BASEBOARD_FAB2(SCH_1):PAGE231
     2    GND @BASEBOARD_FAB2_LIB.BASEBOARD_FAB2(SCH_1):GND   I122 @BASEBOARD_FAB2_LIB.BASEBOARD_FAB2(SCH_1):PAGE231

C6G1 CAP_0603LF-10UF,4V,20%,X6S,E15A
     1 PVPP_ABC @BASEBOARD_FAB2_LIB.BASEBOARD_FAB2(SCH_1):PVPP_ABC   I126 @BASEBOARD_FAB2_LIB.BASEBOARD_FAB2(SCH_1):PAGE231
     2    GND @BASEBOARD_FAB2_LIB.BASEBOARD_FAB2(SCH_1):GND   I126 @BASEBOARD_FAB2_LIB.BASEBOARD_FAB2(SCH_1):PAGE231

C6G2 CAP_0603LF-10UF,4V,20%,X6S,E15A
     1 PVPP_ABC @BASEBOARD_FAB2_LIB.BASEBOARD_FAB2(SCH_1):PVPP_ABC   I128 @BASEBOARD_FAB2_LIB.BASEBOARD_FAB2(SCH_1):PAGE231
     2    GND @BASEBOARD_FAB2_LIB.BASEBOARD_FAB2(SCH_1):GND   I128 @BASEBOARD_FAB2_LIB.BASEBOARD_FAB2(SCH_1):PAGE231

C6G3 CAP_0805LF-22UF,4V,20%,X6S,C95A
     1 PVDDQ_ABC @BASEBOARD_FAB2_LIB.BASEBOARD_FAB2(SCH_1):PVDDQ_ABC     I6 @BASEBOARD_FAB2_LIB.BASEBOARD_FAB2(SCH_1):PAGE216
     2    GND @BASEBOARD_FAB2_LIB.BASEBOARD_FAB2(SCH_1):GND     I6 @BASEBOARD_FAB2_LIB.BASEBOARD_FAB2(SCH_1):PAGE216

C6G4 CAP_0603LF-10UF,4V,20%,X6S,E15A
     1 PVPP_ABC @BASEBOARD_FAB2_LIB.BASEBOARD_FAB2(SCH_1):PVPP_ABC   I131 @BASEBOARD_FAB2_LIB.BASEBOARD_FAB2(SCH_1):PAGE231
     2    GND @BASEBOARD_FAB2_LIB.BASEBOARD_FAB2(SCH_1):GND   I131 @BASEBOARD_FAB2_LIB.BASEBOARD_FAB2(SCH_1):PAGE231

C6G5 CAP_0603LF-10UF,4V,20%,X6S,E15A
     1 PVPP_ABC @BASEBOARD_FAB2_LIB.BASEBOARD_FAB2(SCH_1):PVPP_ABC   I145 @BASEBOARD_FAB2_LIB.BASEBOARD_FAB2(SCH_1):PAGE231
     2    GND @BASEBOARD_FAB2_LIB.BASEBOARD_FAB2(SCH_1):GND   I145 @BASEBOARD_FAB2_LIB.BASEBOARD_FAB2(SCH_1):PAGE231

C6L1 CAP_A_0402V-0.01UF,25V,10%,X7RA
     1 M_F_VREF @BASEBOARD_FAB2_LIB.BASEBOARD_FAB2(SCH_1):M_F_VREF   I178 @BASEBOARD_FAB2_LIB.BASEBOARD_FAB2(SCH_1):PAGE53
     2    GND @BASEBOARD_FAB2_LIB.BASEBOARD_FAB2(SCH_1):GND   I178 @BASEBOARD_FAB2_LIB.BASEBOARD_FAB2(SCH_1):PAGE53

C6L2 CAP_A_0402V-0.01UF,25V,10%,X7RA
     1 M_F_CPU_VREF @BASEBOARD_FAB2_LIB.BASEBOARD_FAB2(SCH_1):M_F_CPU_VREF    I67 @BASEBOARD_FAB2_LIB.BASEBOARD_FAB2(SCH_1):PAGE98
     2    GND @BASEBOARD_FAB2_LIB.BASEBOARD_FAB2(SCH_1):GND    I67 @BASEBOARD_FAB2_LIB.BASEBOARD_FAB2(SCH_1):PAGE98

C6L3 CAP_0603LF-10UF,4V,20%,X6S,E15A
     1 PVDDQ_DEF @BASEBOARD_FAB2_LIB.BASEBOARD_FAB2(SCH_1):PVDDQ_DEF    I24 @BASEBOARD_FAB2_LIB.BASEBOARD_FAB2(SCH_1):PAGE222
     2    GND @BASEBOARD_FAB2_LIB.BASEBOARD_FAB2(SCH_1):GND    I24 @BASEBOARD_FAB2_LIB.BASEBOARD_FAB2(SCH_1):PAGE222

C6L4 CAP_0603LF-10UF,4V,20%,X6S,E15A
     1 PVDDQ_DEF @BASEBOARD_FAB2_LIB.BASEBOARD_FAB2(SCH_1):PVDDQ_DEF    I26 @BASEBOARD_FAB2_LIB.BASEBOARD_FAB2(SCH_1):PAGE222
     2    GND @BASEBOARD_FAB2_LIB.BASEBOARD_FAB2(SCH_1):GND    I26 @BASEBOARD_FAB2_LIB.BASEBOARD_FAB2(SCH_1):PAGE222

C6L5 CAP_0603LF-10UF,4V,20%,X6S,E15A
     1 PVDDQ_KLM @BASEBOARD_FAB2_LIB.BASEBOARD_FAB2(SCH_1):PVDDQ_KLM    I26 @BASEBOARD_FAB2_LIB.BASEBOARD_FAB2(SCH_1):PAGE230
     2    GND @BASEBOARD_FAB2_LIB.BASEBOARD_FAB2(SCH_1):GND    I26 @BASEBOARD_FAB2_LIB.BASEBOARD_FAB2(SCH_1):PAGE230

C6L6 CAP_A_0402V-0.01UF,25V,10%,X7RA
     1 M_E_VREF @BASEBOARD_FAB2_LIB.BASEBOARD_FAB2(SCH_1):M_E_VREF   I175 @BASEBOARD_FAB2_LIB.BASEBOARD_FAB2(SCH_1):PAGE51
     2    GND @BASEBOARD_FAB2_LIB.BASEBOARD_FAB2(SCH_1):GND   I175 @BASEBOARD_FAB2_LIB.BASEBOARD_FAB2(SCH_1):PAGE51

C6L7 CAP_A_0402V-0.01UF,25V,10%,X7RA
     1 M_E_CPU_VREF @BASEBOARD_FAB2_LIB.BASEBOARD_FAB2(SCH_1):M_E_CPU_VREF    I59 @BASEBOARD_FAB2_LIB.BASEBOARD_FAB2(SCH_1):PAGE98
     2    GND @BASEBOARD_FAB2_LIB.BASEBOARD_FAB2(SCH_1):GND    I59 @BASEBOARD_FAB2_LIB.BASEBOARD_FAB2(SCH_1):PAGE98

C6L8 CAPP_7343-220UF,4V,20%,POSCAP,A
     1 PVPP_KLM @BASEBOARD_FAB2_LIB.BASEBOARD_FAB2(SCH_1):PVPP_KLM   I210 @BASEBOARD_FAB2_LIB.BASEBOARD_FAB2(SCH_1):PAGE234
     2    GND @BASEBOARD_FAB2_LIB.BASEBOARD_FAB2(SCH_1):GND   I210 @BASEBOARD_FAB2_LIB.BASEBOARD_FAB2(SCH_1):PAGE234

C6L10 CAP_0805-10UF,16V,10%,X6S,C953A
     1 VR_FET_SW_P12V_STBY_PVPP_KLM @BASEBOARD_FAB2_LIB.BASEBOARD_FAB2(SCH_1):VR_FET_SW_P12V_STBY_PVPP_KLM   I202 @BASEBOARD_FAB2_LIB.BASEBOARD_FAB2(SCH_1):PAGE234
     2    GND @BASEBOARD_FAB2_LIB.BASEBOARD_FAB2(SCH_1):GND   I202 @BASEBOARD_FAB2_LIB.BASEBOARD_FAB2(SCH_1):PAGE234

C6L11 CAP_0402-1.0UF,16V,10%,X6S,D97A
     1 VR_FET_SW_P12V_STBY_PVPP_KLM @BASEBOARD_FAB2_LIB.BASEBOARD_FAB2(SCH_1):VR_FET_SW_P12V_STBY_PVPP_KLM   I152 @BASEBOARD_FAB2_LIB.BASEBOARD_FAB2(SCH_1):PAGE234
     2    GND @BASEBOARD_FAB2_LIB.BASEBOARD_FAB2(SCH_1):GND   I152 @BASEBOARD_FAB2_LIB.BASEBOARD_FAB2(SCH_1):PAGE234

C6L12 CAP_0603-4.7UF,6.3V,10%,X6S,E1A
     1 VR_VB_PVPP_KLM @BASEBOARD_FAB2_LIB.BASEBOARD_FAB2(SCH_1):VR_VB_PVPP_KLM   I144 @BASEBOARD_FAB2_LIB.BASEBOARD_FAB2(SCH_1):PAGE234
     2 AGND_PVPP_KLM @BASEBOARD_FAB2_LIB.BASEBOARD_FAB2(SCH_1):AGND_PVPP_KLM   I144 @BASEBOARD_FAB2_LIB.BASEBOARD_FAB2(SCH_1):PAGE234

C6M1 CAP_A_0402V-0.01UF,25V,10%,X7RA
     1 M_D_VREF @BASEBOARD_FAB2_LIB.BASEBOARD_FAB2(SCH_1):M_D_VREF   I177 @BASEBOARD_FAB2_LIB.BASEBOARD_FAB2(SCH_1):PAGE50
     2    GND @BASEBOARD_FAB2_LIB.BASEBOARD_FAB2(SCH_1):GND   I177 @BASEBOARD_FAB2_LIB.BASEBOARD_FAB2(SCH_1):PAGE50

C6M2 CAP_A_0402V-0.01UF,25V,10%,X7RA
     1 M_D_CPU_VREF @BASEBOARD_FAB2_LIB.BASEBOARD_FAB2(SCH_1):M_D_CPU_VREF    I33 @BASEBOARD_FAB2_LIB.BASEBOARD_FAB2(SCH_1):PAGE98
     2    GND @BASEBOARD_FAB2_LIB.BASEBOARD_FAB2(SCH_1):GND    I33 @BASEBOARD_FAB2_LIB.BASEBOARD_FAB2(SCH_1):PAGE98

C6M3 CAP_0805-10UF,16V,10%,X6S,C953A
     1 VR_FET_SW_P12V_STBY_PVPP_KLM @BASEBOARD_FAB2_LIB.BASEBOARD_FAB2(SCH_1):VR_FET_SW_P12V_STBY_PVPP_KLM   I203 @BASEBOARD_FAB2_LIB.BASEBOARD_FAB2(SCH_1):PAGE234
     2    GND @BASEBOARD_FAB2_LIB.BASEBOARD_FAB2(SCH_1):GND   I203 @BASEBOARD_FAB2_LIB.BASEBOARD_FAB2(SCH_1):PAGE234

C6M5 CAP_0805-10UF,16V,10%,X6S,C953A
     1 VR_FET_SW_P12V_STBY_PVPP_KLM @BASEBOARD_FAB2_LIB.BASEBOARD_FAB2(SCH_1):VR_FET_SW_P12V_STBY_PVPP_KLM   I204 @BASEBOARD_FAB2_LIB.BASEBOARD_FAB2(SCH_1):PAGE234
     2    GND @BASEBOARD_FAB2_LIB.BASEBOARD_FAB2(SCH_1):GND   I204 @BASEBOARD_FAB2_LIB.BASEBOARD_FAB2(SCH_1):PAGE234

C6M6 CAP_A_0402V-0.1UF,16V,10%,X7R,A
     1 JTAG_MCP_CPU1_TDI_R @BASEBOARD_FAB2_LIB.BASEBOARD_FAB2(SCH_1):JTAG_MCP_CPU1_TDI_R   I250 @BASEBOARD_FAB2_LIB.BASEBOARD_FAB2(SCH_1):PAGE113
     2    GND @BASEBOARD_FAB2_LIB.BASEBOARD_FAB2(SCH_1):GND   I250 @BASEBOARD_FAB2_LIB.BASEBOARD_FAB2(SCH_1):PAGE113

C6N1 CAPP_3018-470UF,2.5V,20%,ALUM,A
     1 PVSA_CPU0 @BASEBOARD_FAB2_LIB.BASEBOARD_FAB2(SCH_1):PVSA_CPU0    I12 @BASEBOARD_FAB2_LIB.BASEBOARD_FAB2(SCH_1):PAGE205
     2    GND @BASEBOARD_FAB2_LIB.BASEBOARD_FAB2(SCH_1):GND    I12 @BASEBOARD_FAB2_LIB.BASEBOARD_FAB2(SCH_1):PAGE205

C6N2 CAP_0805-10UF,16V,10%,X6S,C953A
     1 VR_FET_SW_P12V_STBY_PVCCIN_CPU0 @BASEBOARD_FAB2_LIB.BASEBOARD_FAB2(SCH_1):VR_FET_SW_P12V_STBY_PVCCIN_CPU0    I33 @BASEBOARD_FAB2_LIB.BASEBOARD_FAB2(SCH_1):PAGE205
     2    GND @BASEBOARD_FAB2_LIB.BASEBOARD_FAB2(SCH_1):GND    I33 @BASEBOARD_FAB2_LIB.BASEBOARD_FAB2(SCH_1):PAGE205

C6N3 CAP_0805-10UF,16V,10%,X6S,C953A
     1 VR_FET_SW_P12V_STBY_PVCCIN_CPU0 @BASEBOARD_FAB2_LIB.BASEBOARD_FAB2(SCH_1):VR_FET_SW_P12V_STBY_PVCCIN_CPU0    I34 @BASEBOARD_FAB2_LIB.BASEBOARD_FAB2(SCH_1):PAGE205
     2    GND @BASEBOARD_FAB2_LIB.BASEBOARD_FAB2(SCH_1):GND    I34 @BASEBOARD_FAB2_LIB.BASEBOARD_FAB2(SCH_1):PAGE205

C6N4 CAPP_3018-470UF,2.5V,20%,ALUM,A
     1 PVSA_CPU0 @BASEBOARD_FAB2_LIB.BASEBOARD_FAB2(SCH_1):PVSA_CPU0    I14 @BASEBOARD_FAB2_LIB.BASEBOARD_FAB2(SCH_1):PAGE205
     2    GND @BASEBOARD_FAB2_LIB.BASEBOARD_FAB2(SCH_1):GND    I14 @BASEBOARD_FAB2_LIB.BASEBOARD_FAB2(SCH_1):PAGE205

C6N5 CAPP_3018-68UF,16V,20%,TANT,72A
     1 P12V_STBY @BASEBOARD_FAB2_LIB.BASEBOARD_FAB2(SCH_1):P12V_STBY   I109 @BASEBOARD_FAB2_LIB.BASEBOARD_FAB2(SCH_1):PAGE195
     2    GND @BASEBOARD_FAB2_LIB.BASEBOARD_FAB2(SCH_1):GND   I109 @BASEBOARD_FAB2_LIB.BASEBOARD_FAB2(SCH_1):PAGE195

C6N6 CAP_0805-10UF,16V,10%,X6S,C953A
     1 VR_FET_SW_P12V_STBY_PVCCIN_CPU0 @BASEBOARD_FAB2_LIB.BASEBOARD_FAB2(SCH_1):VR_FET_SW_P12V_STBY_PVCCIN_CPU0    I35 @BASEBOARD_FAB2_LIB.BASEBOARD_FAB2(SCH_1):PAGE205
     2    GND @BASEBOARD_FAB2_LIB.BASEBOARD_FAB2(SCH_1):GND    I35 @BASEBOARD_FAB2_LIB.BASEBOARD_FAB2(SCH_1):PAGE205

C6N7 CAP_A_0603V-22.0UF,4V,20%,X6S,A
     1 PVSA_CPU0 @BASEBOARD_FAB2_LIB.BASEBOARD_FAB2(SCH_1):PVSA_CPU0     I5 @BASEBOARD_FAB2_LIB.BASEBOARD_FAB2(SCH_1):PAGE205
     2    GND @BASEBOARD_FAB2_LIB.BASEBOARD_FAB2(SCH_1):GND     I5 @BASEBOARD_FAB2_LIB.BASEBOARD_FAB2(SCH_1):PAGE205

C6N8 CAP_0805-10UF,16V,10%,X6S,C953A
     1 VR_FET_SW_P12V_STBY_PVCCIN_CPU0 @BASEBOARD_FAB2_LIB.BASEBOARD_FAB2(SCH_1):VR_FET_SW_P12V_STBY_PVCCIN_CPU0    I51 @BASEBOARD_FAB2_LIB.BASEBOARD_FAB2(SCH_1):PAGE202
     2    GND @BASEBOARD_FAB2_LIB.BASEBOARD_FAB2(SCH_1):GND    I51 @BASEBOARD_FAB2_LIB.BASEBOARD_FAB2(SCH_1):PAGE202

C6N9 CAPP_3018-470UF,2.5V,20%,ALUM,A
     1 PVCCIN_CPU0 @BASEBOARD_FAB2_LIB.BASEBOARD_FAB2(SCH_1):PVCCIN_CPU0    I34 @BASEBOARD_FAB2_LIB.BASEBOARD_FAB2(SCH_1):PAGE203
     2    GND @BASEBOARD_FAB2_LIB.BASEBOARD_FAB2(SCH_1):GND    I34 @BASEBOARD_FAB2_LIB.BASEBOARD_FAB2(SCH_1):PAGE203

C6N10 CAP_0805-10UF,16V,10%,X6S,C953A
     1 VR_FET_SW_P12V_STBY_PVCCIN_CPU0 @BASEBOARD_FAB2_LIB.BASEBOARD_FAB2(SCH_1):VR_FET_SW_P12V_STBY_PVCCIN_CPU0    I37 @BASEBOARD_FAB2_LIB.BASEBOARD_FAB2(SCH_1):PAGE204
     2    GND @BASEBOARD_FAB2_LIB.BASEBOARD_FAB2(SCH_1):GND    I37 @BASEBOARD_FAB2_LIB.BASEBOARD_FAB2(SCH_1):PAGE204

C6N11 CAP_0805-10UF,16V,10%,X6S,C953A
     1 VR_FET_SW_P12V_STBY_PVCCIN_CPU0 @BASEBOARD_FAB2_LIB.BASEBOARD_FAB2(SCH_1):VR_FET_SW_P12V_STBY_PVCCIN_CPU0    I42 @BASEBOARD_FAB2_LIB.BASEBOARD_FAB2(SCH_1):PAGE204
     2    GND @BASEBOARD_FAB2_LIB.BASEBOARD_FAB2(SCH_1):GND    I42 @BASEBOARD_FAB2_LIB.BASEBOARD_FAB2(SCH_1):PAGE204

C6P3 CAP_A_0603V-22.0UF,4V,20%,X6S,A
     1 PVCCIN_CPU0 @BASEBOARD_FAB2_LIB.BASEBOARD_FAB2(SCH_1):PVCCIN_CPU0    I25 @BASEBOARD_FAB2_LIB.BASEBOARD_FAB2(SCH_1):PAGE203
     2    GND @BASEBOARD_FAB2_LIB.BASEBOARD_FAB2(SCH_1):GND    I25 @BASEBOARD_FAB2_LIB.BASEBOARD_FAB2(SCH_1):PAGE203

C6P4 CAP_A_0402V-0.1UF,16V,10%,X7R,A
     1 P3V3_DB1200 @BASEBOARD_FAB2_LIB.BASEBOARD_FAB2(SCH_1):P3V3_DB1200    I11 @BASEBOARD_FAB2_LIB.BASEBOARD_FAB2(SCH_1):PAGE102
     2    GND @BASEBOARD_FAB2_LIB.BASEBOARD_FAB2(SCH_1):GND    I11 @BASEBOARD_FAB2_LIB.BASEBOARD_FAB2(SCH_1):PAGE102

C6P5 CAP_A_0402V-0.1UF,16V,10%,X7R,A
     1 P3V3_DB1200 @BASEBOARD_FAB2_LIB.BASEBOARD_FAB2(SCH_1):P3V3_DB1200    I14 @BASEBOARD_FAB2_LIB.BASEBOARD_FAB2(SCH_1):PAGE102
     2    GND @BASEBOARD_FAB2_LIB.BASEBOARD_FAB2(SCH_1):GND    I14 @BASEBOARD_FAB2_LIB.BASEBOARD_FAB2(SCH_1):PAGE102

C6P6 CAP_A_0402V-0.1UF,16V,10%,X7R,A
     1 P3V3_DB1200 @BASEBOARD_FAB2_LIB.BASEBOARD_FAB2(SCH_1):P3V3_DB1200    I12 @BASEBOARD_FAB2_LIB.BASEBOARD_FAB2(SCH_1):PAGE102
     2    GND @BASEBOARD_FAB2_LIB.BASEBOARD_FAB2(SCH_1):GND    I12 @BASEBOARD_FAB2_LIB.BASEBOARD_FAB2(SCH_1):PAGE102

C6P7 CAP_0805-10UF,16V,10%,X6S,C953A
     1 VR_FET_SW_P12V_STBY_PVCCIN_CPU0 @BASEBOARD_FAB2_LIB.BASEBOARD_FAB2(SCH_1):VR_FET_SW_P12V_STBY_PVCCIN_CPU0    I59 @BASEBOARD_FAB2_LIB.BASEBOARD_FAB2(SCH_1):PAGE203
     2    GND @BASEBOARD_FAB2_LIB.BASEBOARD_FAB2(SCH_1):GND    I59 @BASEBOARD_FAB2_LIB.BASEBOARD_FAB2(SCH_1):PAGE203

C6P8 CAPP_3018-470UF,2.5V,20%,ALUM,A
     1 PVCCIN_CPU0 @BASEBOARD_FAB2_LIB.BASEBOARD_FAB2(SCH_1):PVCCIN_CPU0    I32 @BASEBOARD_FAB2_LIB.BASEBOARD_FAB2(SCH_1):PAGE203
     2    GND @BASEBOARD_FAB2_LIB.BASEBOARD_FAB2(SCH_1):GND    I32 @BASEBOARD_FAB2_LIB.BASEBOARD_FAB2(SCH_1):PAGE203

C6P9 CAP_A_0402V-0.1UF,16V,10%,X7R,A
     1 P3V3_DB1200 @BASEBOARD_FAB2_LIB.BASEBOARD_FAB2(SCH_1):P3V3_DB1200    I79 @BASEBOARD_FAB2_LIB.BASEBOARD_FAB2(SCH_1):PAGE102
     2    GND @BASEBOARD_FAB2_LIB.BASEBOARD_FAB2(SCH_1):GND    I79 @BASEBOARD_FAB2_LIB.BASEBOARD_FAB2(SCH_1):PAGE102

C6P10 CAP_A_0402V-0.1UF,16V,10%,X7R,A
     1 P3V3_DB1200 @BASEBOARD_FAB2_LIB.BASEBOARD_FAB2(SCH_1):P3V3_DB1200    I13 @BASEBOARD_FAB2_LIB.BASEBOARD_FAB2(SCH_1):PAGE102
     2    GND @BASEBOARD_FAB2_LIB.BASEBOARD_FAB2(SCH_1):GND    I13 @BASEBOARD_FAB2_LIB.BASEBOARD_FAB2(SCH_1):PAGE102

C6P11 CAP_A_0402V-0.1UF,16V,10%,X7R,A
     1 P3V3_DB1200 @BASEBOARD_FAB2_LIB.BASEBOARD_FAB2(SCH_1):P3V3_DB1200    I16 @BASEBOARD_FAB2_LIB.BASEBOARD_FAB2(SCH_1):PAGE102
     2    GND @BASEBOARD_FAB2_LIB.BASEBOARD_FAB2(SCH_1):GND    I16 @BASEBOARD_FAB2_LIB.BASEBOARD_FAB2(SCH_1):PAGE102

C6P12 CAP_A_0402V-0.1UF,16V,10%,X7R,A
     1 P3V3_DB1200 @BASEBOARD_FAB2_LIB.BASEBOARD_FAB2(SCH_1):P3V3_DB1200    I15 @BASEBOARD_FAB2_LIB.BASEBOARD_FAB2(SCH_1):PAGE102
     2    GND @BASEBOARD_FAB2_LIB.BASEBOARD_FAB2(SCH_1):GND    I15 @BASEBOARD_FAB2_LIB.BASEBOARD_FAB2(SCH_1):PAGE102

C6P13 CAP_0805-10UF,16V,10%,X6S,C953A
     1 VR_FET_SW_P12V_STBY_PVCCIN_CPU0 @BASEBOARD_FAB2_LIB.BASEBOARD_FAB2(SCH_1):VR_FET_SW_P12V_STBY_PVCCIN_CPU0    I38 @BASEBOARD_FAB2_LIB.BASEBOARD_FAB2(SCH_1):PAGE202
     2    GND @BASEBOARD_FAB2_LIB.BASEBOARD_FAB2(SCH_1):GND    I38 @BASEBOARD_FAB2_LIB.BASEBOARD_FAB2(SCH_1):PAGE202

C6P14 CAPP_3018-470UF,2.5V,20%,ALUM,A
     1 PVCCIN_CPU0 @BASEBOARD_FAB2_LIB.BASEBOARD_FAB2(SCH_1):PVCCIN_CPU0    I29 @BASEBOARD_FAB2_LIB.BASEBOARD_FAB2(SCH_1):PAGE203
     2    GND @BASEBOARD_FAB2_LIB.BASEBOARD_FAB2(SCH_1):GND    I29 @BASEBOARD_FAB2_LIB.BASEBOARD_FAB2(SCH_1):PAGE203

C6P15 CAP_0805-10UF,16V,10%,X6S,C953A
     1 VR_FET_SW_P12V_STBY_PVCCIN_CPU0 @BASEBOARD_FAB2_LIB.BASEBOARD_FAB2(SCH_1):VR_FET_SW_P12V_STBY_PVCCIN_CPU0    I58 @BASEBOARD_FAB2_LIB.BASEBOARD_FAB2(SCH_1):PAGE203
     2    GND @BASEBOARD_FAB2_LIB.BASEBOARD_FAB2(SCH_1):GND    I58 @BASEBOARD_FAB2_LIB.BASEBOARD_FAB2(SCH_1):PAGE203

C6P16 CAP_A_0603V-22.0UF,4V,20%,X6S,A
     1 PVCCIN_CPU0 @BASEBOARD_FAB2_LIB.BASEBOARD_FAB2(SCH_1):PVCCIN_CPU0    I62 @BASEBOARD_FAB2_LIB.BASEBOARD_FAB2(SCH_1):PAGE202
     2    GND @BASEBOARD_FAB2_LIB.BASEBOARD_FAB2(SCH_1):GND    I62 @BASEBOARD_FAB2_LIB.BASEBOARD_FAB2(SCH_1):PAGE202

C6P17 CAP_0805-10UF,16V,10%,X6S,C953A
     1 VR_FET_SW_P12V_STBY_PVCCIN_CPU0 @BASEBOARD_FAB2_LIB.BASEBOARD_FAB2(SCH_1):VR_FET_SW_P12V_STBY_PVCCIN_CPU0    I38 @BASEBOARD_FAB2_LIB.BASEBOARD_FAB2(SCH_1):PAGE204
     2    GND @BASEBOARD_FAB2_LIB.BASEBOARD_FAB2(SCH_1):GND    I38 @BASEBOARD_FAB2_LIB.BASEBOARD_FAB2(SCH_1):PAGE204

C6P18 CAPP_3018-470UF,2.5V,20%,ALUM,A
     1 PVCCIN_CPU0 @BASEBOARD_FAB2_LIB.BASEBOARD_FAB2(SCH_1):PVCCIN_CPU0    I30 @BASEBOARD_FAB2_LIB.BASEBOARD_FAB2(SCH_1):PAGE203
     2    GND @BASEBOARD_FAB2_LIB.BASEBOARD_FAB2(SCH_1):GND    I30 @BASEBOARD_FAB2_LIB.BASEBOARD_FAB2(SCH_1):PAGE203

C6P19 CAP_0805-10UF,16V,10%,X6S,C953A
     1 VR_FET_SW_P12V_STBY_PVCCIN_CPU0 @BASEBOARD_FAB2_LIB.BASEBOARD_FAB2(SCH_1):VR_FET_SW_P12V_STBY_PVCCIN_CPU0    I54 @BASEBOARD_FAB2_LIB.BASEBOARD_FAB2(SCH_1):PAGE203
     2    GND @BASEBOARD_FAB2_LIB.BASEBOARD_FAB2(SCH_1):GND    I54 @BASEBOARD_FAB2_LIB.BASEBOARD_FAB2(SCH_1):PAGE203

C6P20 CAP_0805-10UF,16V,10%,X6S,C953A
     1 VR_FET_SW_P12V_STBY_PVCCIN_CPU0 @BASEBOARD_FAB2_LIB.BASEBOARD_FAB2(SCH_1):VR_FET_SW_P12V_STBY_PVCCIN_CPU0    I57 @BASEBOARD_FAB2_LIB.BASEBOARD_FAB2(SCH_1):PAGE203
     2    GND @BASEBOARD_FAB2_LIB.BASEBOARD_FAB2(SCH_1):GND    I57 @BASEBOARD_FAB2_LIB.BASEBOARD_FAB2(SCH_1):PAGE203

C6P21 CAP_A_0603V-22.0UF,4V,20%,X6S,A
     1 PVCCIN_CPU0 @BASEBOARD_FAB2_LIB.BASEBOARD_FAB2(SCH_1):PVCCIN_CPU0    I66 @BASEBOARD_FAB2_LIB.BASEBOARD_FAB2(SCH_1):PAGE203
     2    GND @BASEBOARD_FAB2_LIB.BASEBOARD_FAB2(SCH_1):GND    I66 @BASEBOARD_FAB2_LIB.BASEBOARD_FAB2(SCH_1):PAGE203

C6P22 CAP_0805-10UF,16V,10%,X6S,C953A
     1 VR_FET_SW_P12V_STBY_PVCCIN_CPU0 @BASEBOARD_FAB2_LIB.BASEBOARD_FAB2(SCH_1):VR_FET_SW_P12V_STBY_PVCCIN_CPU0    I49 @BASEBOARD_FAB2_LIB.BASEBOARD_FAB2(SCH_1):PAGE202
     2    GND @BASEBOARD_FAB2_LIB.BASEBOARD_FAB2(SCH_1):GND    I49 @BASEBOARD_FAB2_LIB.BASEBOARD_FAB2(SCH_1):PAGE202

C6P23 CAPP_3018-470UF,2.5V,20%,ALUM,A
     1 PVCCIN_CPU0 @BASEBOARD_FAB2_LIB.BASEBOARD_FAB2(SCH_1):PVCCIN_CPU0    I28 @BASEBOARD_FAB2_LIB.BASEBOARD_FAB2(SCH_1):PAGE203
     2    GND @BASEBOARD_FAB2_LIB.BASEBOARD_FAB2(SCH_1):GND    I28 @BASEBOARD_FAB2_LIB.BASEBOARD_FAB2(SCH_1):PAGE203

C6P24 CAP_0805-10UF,16V,10%,X6S,C953A
     1 VR_FET_SW_P12V_STBY_PVCCIN_CPU0 @BASEBOARD_FAB2_LIB.BASEBOARD_FAB2(SCH_1):VR_FET_SW_P12V_STBY_PVCCIN_CPU0     I1 @BASEBOARD_FAB2_LIB.BASEBOARD_FAB2(SCH_1):PAGE203
     2    GND @BASEBOARD_FAB2_LIB.BASEBOARD_FAB2(SCH_1):GND     I1 @BASEBOARD_FAB2_LIB.BASEBOARD_FAB2(SCH_1):PAGE203

C6R2 CAP_A_0603V-22.0UF,4V,20%,X6S,A
     1 PVCCIN_CPU0 @BASEBOARD_FAB2_LIB.BASEBOARD_FAB2(SCH_1):PVCCIN_CPU0    I70 @BASEBOARD_FAB2_LIB.BASEBOARD_FAB2(SCH_1):PAGE204
     2    GND @BASEBOARD_FAB2_LIB.BASEBOARD_FAB2(SCH_1):GND    I70 @BASEBOARD_FAB2_LIB.BASEBOARD_FAB2(SCH_1):PAGE204

C6R3 CAPP_3018-470UF,2.5V,20%,ALUM,A
     1 PVCCIN_CPU0 @BASEBOARD_FAB2_LIB.BASEBOARD_FAB2(SCH_1):PVCCIN_CPU0    I16 @BASEBOARD_FAB2_LIB.BASEBOARD_FAB2(SCH_1):PAGE203
     2    GND @BASEBOARD_FAB2_LIB.BASEBOARD_FAB2(SCH_1):GND    I16 @BASEBOARD_FAB2_LIB.BASEBOARD_FAB2(SCH_1):PAGE203

C6R4 CAP_0805-10UF,16V,10%,X6S,C953A
     1 VR_FET_SW_P12V_STBY_PVCCIN_CPU0 @BASEBOARD_FAB2_LIB.BASEBOARD_FAB2(SCH_1):VR_FET_SW_P12V_STBY_PVCCIN_CPU0    I48 @BASEBOARD_FAB2_LIB.BASEBOARD_FAB2(SCH_1):PAGE202
     2    GND @BASEBOARD_FAB2_LIB.BASEBOARD_FAB2(SCH_1):GND    I48 @BASEBOARD_FAB2_LIB.BASEBOARD_FAB2(SCH_1):PAGE202

C6R5 CAPP_3018-470UF,2.5V,20%,ALUM,A
     1 PVCCIO_CPU1 @BASEBOARD_FAB2_LIB.BASEBOARD_FAB2(SCH_1):PVCCIO_CPU1    I24 @BASEBOARD_FAB2_LIB.BASEBOARD_FAB2(SCH_1):PAGE214
     2    GND @BASEBOARD_FAB2_LIB.BASEBOARD_FAB2(SCH_1):GND    I24 @BASEBOARD_FAB2_LIB.BASEBOARD_FAB2(SCH_1):PAGE214

C6R6 CAP_0805-10UF,16V,10%,X6S,C953A
     1 VR_FET_SW_P12V_STBY_PVCCIN_CPU0 @BASEBOARD_FAB2_LIB.BASEBOARD_FAB2(SCH_1):VR_FET_SW_P12V_STBY_PVCCIN_CPU0     I2 @BASEBOARD_FAB2_LIB.BASEBOARD_FAB2(SCH_1):PAGE203
     2    GND @BASEBOARD_FAB2_LIB.BASEBOARD_FAB2(SCH_1):GND     I2 @BASEBOARD_FAB2_LIB.BASEBOARD_FAB2(SCH_1):PAGE203

C6R7 CAP_A_0603V-22.0UF,4V,20%,X6S,A
     1 PVCCIN_CPU0 @BASEBOARD_FAB2_LIB.BASEBOARD_FAB2(SCH_1):PVCCIN_CPU0     I9 @BASEBOARD_FAB2_LIB.BASEBOARD_FAB2(SCH_1):PAGE202
     2    GND @BASEBOARD_FAB2_LIB.BASEBOARD_FAB2(SCH_1):GND     I9 @BASEBOARD_FAB2_LIB.BASEBOARD_FAB2(SCH_1):PAGE202

C6R8 CAP_0805-10UF,16V,10%,X6S,C953A
     1 VR_FET_SW_P12V_STBY_PVCCIN_CPU0 @BASEBOARD_FAB2_LIB.BASEBOARD_FAB2(SCH_1):VR_FET_SW_P12V_STBY_PVCCIN_CPU0    I83 @BASEBOARD_FAB2_LIB.BASEBOARD_FAB2(SCH_1):PAGE214
     2    GND @BASEBOARD_FAB2_LIB.BASEBOARD_FAB2(SCH_1):GND    I83 @BASEBOARD_FAB2_LIB.BASEBOARD_FAB2(SCH_1):PAGE214

C6R9 CAPP_3018-470UF,2.5V,20%,ALUM,A
     1 PVCCIN_CPU0 @BASEBOARD_FAB2_LIB.BASEBOARD_FAB2(SCH_1):PVCCIN_CPU0    I18 @BASEBOARD_FAB2_LIB.BASEBOARD_FAB2(SCH_1):PAGE203
     2    GND @BASEBOARD_FAB2_LIB.BASEBOARD_FAB2(SCH_1):GND    I18 @BASEBOARD_FAB2_LIB.BASEBOARD_FAB2(SCH_1):PAGE203

C6R10 CAP_0805-10UF,16V,10%,X6S,C953A
     1 VR_FET_SW_P12V_STBY_PVCCIN_CPU0 @BASEBOARD_FAB2_LIB.BASEBOARD_FAB2(SCH_1):VR_FET_SW_P12V_STBY_PVCCIN_CPU0    I81 @BASEBOARD_FAB2_LIB.BASEBOARD_FAB2(SCH_1):PAGE214
     2    GND @BASEBOARD_FAB2_LIB.BASEBOARD_FAB2(SCH_1):GND    I81 @BASEBOARD_FAB2_LIB.BASEBOARD_FAB2(SCH_1):PAGE214

C6R11 CAP_0805-10UF,16V,10%,X6S,C953A
     1 VR_FET_SW_P12V_STBY_PVCCIN_CPU0 @BASEBOARD_FAB2_LIB.BASEBOARD_FAB2(SCH_1):VR_FET_SW_P12V_STBY_PVCCIN_CPU0    I37 @BASEBOARD_FAB2_LIB.BASEBOARD_FAB2(SCH_1):PAGE202
     2    GND @BASEBOARD_FAB2_LIB.BASEBOARD_FAB2(SCH_1):GND    I37 @BASEBOARD_FAB2_LIB.BASEBOARD_FAB2(SCH_1):PAGE202

C6R12 CAPP_3018-470UF,2.5V,20%,ALUM,A
     1 PVCCIO_CPU1 @BASEBOARD_FAB2_LIB.BASEBOARD_FAB2(SCH_1):PVCCIO_CPU1    I21 @BASEBOARD_FAB2_LIB.BASEBOARD_FAB2(SCH_1):PAGE214
     2    GND @BASEBOARD_FAB2_LIB.BASEBOARD_FAB2(SCH_1):GND    I21 @BASEBOARD_FAB2_LIB.BASEBOARD_FAB2(SCH_1):PAGE214

C6R13 CAP_0805-10UF,16V,10%,X6S,C953A
     1 VR_FET_SW_P12V_STBY_PVCCIN_CPU0 @BASEBOARD_FAB2_LIB.BASEBOARD_FAB2(SCH_1):VR_FET_SW_P12V_STBY_PVCCIN_CPU0    I42 @BASEBOARD_FAB2_LIB.BASEBOARD_FAB2(SCH_1):PAGE202
     2    GND @BASEBOARD_FAB2_LIB.BASEBOARD_FAB2(SCH_1):GND    I42 @BASEBOARD_FAB2_LIB.BASEBOARD_FAB2(SCH_1):PAGE202

C6R14 CAP_0805-10UF,16V,10%,X6S,C953A
     1 VR_FET_SW_P12V_STBY_PVCCIN_CPU0 @BASEBOARD_FAB2_LIB.BASEBOARD_FAB2(SCH_1):VR_FET_SW_P12V_STBY_PVCCIN_CPU0    I80 @BASEBOARD_FAB2_LIB.BASEBOARD_FAB2(SCH_1):PAGE214
     2    GND @BASEBOARD_FAB2_LIB.BASEBOARD_FAB2(SCH_1):GND    I80 @BASEBOARD_FAB2_LIB.BASEBOARD_FAB2(SCH_1):PAGE214

C6R16 CAPP_3018-470UF,2.5V,20%,ALUM,A
     1 PVCCMCP_CPU1 @BASEBOARD_FAB2_LIB.BASEBOARD_FAB2(SCH_1):PVCCMCP_CPU1    I62 @BASEBOARD_FAB2_LIB.BASEBOARD_FAB2(SCH_1):PAGE193
     2    GND @BASEBOARD_FAB2_LIB.BASEBOARD_FAB2(SCH_1):GND    I62 @BASEBOARD_FAB2_LIB.BASEBOARD_FAB2(SCH_1):PAGE193

C6T1 CAP_A_0402V-0.01UF,25V,10%,X7RA
     1 M_A_VREF @BASEBOARD_FAB2_LIB.BASEBOARD_FAB2(SCH_1):M_A_VREF     I2 @BASEBOARD_FAB2_LIB.BASEBOARD_FAB2(SCH_1):PAGE44
     2    GND @BASEBOARD_FAB2_LIB.BASEBOARD_FAB2(SCH_1):GND     I2 @BASEBOARD_FAB2_LIB.BASEBOARD_FAB2(SCH_1):PAGE44

C6T2 CAP_0805-10UF,16V,10%,X7R,G106A
     1 P12V_NVDIMM_ABC @BASEBOARD_FAB2_LIB.BASEBOARD_FAB2(SCH_1):P12V_NVDIMM_ABC    I54 @BASEBOARD_FAB2_LIB.BASEBOARD_FAB2(SCH_1):PAGE197
     2    GND @BASEBOARD_FAB2_LIB.BASEBOARD_FAB2(SCH_1):GND    I54 @BASEBOARD_FAB2_LIB.BASEBOARD_FAB2(SCH_1):PAGE197

C6U2 CAP_0805-47UF,4V,20%,X6S,C9533A
     1 PVPP_GHJ @BASEBOARD_FAB2_LIB.BASEBOARD_FAB2(SCH_1):PVPP_GHJ   I223 @BASEBOARD_FAB2_LIB.BASEBOARD_FAB2(SCH_1):PAGE233
     2    GND @BASEBOARD_FAB2_LIB.BASEBOARD_FAB2(SCH_1):GND   I223 @BASEBOARD_FAB2_LIB.BASEBOARD_FAB2(SCH_1):PAGE233

C6U3 CAP_0805-47UF,4V,20%,X6S,C9533A
     1 PVPP_GHJ @BASEBOARD_FAB2_LIB.BASEBOARD_FAB2(SCH_1):PVPP_GHJ   I221 @BASEBOARD_FAB2_LIB.BASEBOARD_FAB2(SCH_1):PAGE233
     2    GND @BASEBOARD_FAB2_LIB.BASEBOARD_FAB2(SCH_1):GND   I221 @BASEBOARD_FAB2_LIB.BASEBOARD_FAB2(SCH_1):PAGE233

C6U4 CAP_0805-10UF,16V,10%,X6S,C953A
     1 VR_FET_SW_P12V_STBY_PVPP_GHJ @BASEBOARD_FAB2_LIB.BASEBOARD_FAB2(SCH_1):VR_FET_SW_P12V_STBY_PVPP_GHJ   I248 @BASEBOARD_FAB2_LIB.BASEBOARD_FAB2(SCH_1):PAGE233
     2    GND @BASEBOARD_FAB2_LIB.BASEBOARD_FAB2(SCH_1):GND   I248 @BASEBOARD_FAB2_LIB.BASEBOARD_FAB2(SCH_1):PAGE233

C6U5 CAP_A_0402V-0.1UF,16V,10%,X7R,A
     1 VR_FET_SW_P12V_STBY_PVPP_GHJ @BASEBOARD_FAB2_LIB.BASEBOARD_FAB2(SCH_1):VR_FET_SW_P12V_STBY_PVPP_GHJ   I242 @BASEBOARD_FAB2_LIB.BASEBOARD_FAB2(SCH_1):PAGE233
     2    GND @BASEBOARD_FAB2_LIB.BASEBOARD_FAB2(SCH_1):GND   I242 @BASEBOARD_FAB2_LIB.BASEBOARD_FAB2(SCH_1):PAGE233

C6U6 CAP_0603-4.7UF,6.3V,10%,X6S,E1A
     1 VR_VB_PVPP_GHJ @BASEBOARD_FAB2_LIB.BASEBOARD_FAB2(SCH_1):VR_VB_PVPP_GHJ   I187 @BASEBOARD_FAB2_LIB.BASEBOARD_FAB2(SCH_1):PAGE233
     2 AGND_PVPP_GHJ @BASEBOARD_FAB2_LIB.BASEBOARD_FAB2(SCH_1):AGND_PVPP_GHJ   I187 @BASEBOARD_FAB2_LIB.BASEBOARD_FAB2(SCH_1):PAGE233

C6U7 CAP_0805-10UF,16V,10%,X6S,C953A
     1 VR_FET_SW_P12V_STBY_PVPP_GHJ @BASEBOARD_FAB2_LIB.BASEBOARD_FAB2(SCH_1):VR_FET_SW_P12V_STBY_PVPP_GHJ   I254 @BASEBOARD_FAB2_LIB.BASEBOARD_FAB2(SCH_1):PAGE233
     2    GND @BASEBOARD_FAB2_LIB.BASEBOARD_FAB2(SCH_1):GND   I254 @BASEBOARD_FAB2_LIB.BASEBOARD_FAB2(SCH_1):PAGE233

C6U8 CAP_0805-10UF,16V,10%,X6S,C953A
     1 VR_FET_SW_P12V_STBY_PVPP_GHJ @BASEBOARD_FAB2_LIB.BASEBOARD_FAB2(SCH_1):VR_FET_SW_P12V_STBY_PVPP_GHJ   I255 @BASEBOARD_FAB2_LIB.BASEBOARD_FAB2(SCH_1):PAGE233
     2    GND @BASEBOARD_FAB2_LIB.BASEBOARD_FAB2(SCH_1):GND   I255 @BASEBOARD_FAB2_LIB.BASEBOARD_FAB2(SCH_1):PAGE233

C6U9 CAP_A_0402V-0.01UF,25V,10%,X7RA
     1 M_B_VREF @BASEBOARD_FAB2_LIB.BASEBOARD_FAB2(SCH_1):M_B_VREF     I5 @BASEBOARD_FAB2_LIB.BASEBOARD_FAB2(SCH_1):PAGE46
     2    GND @BASEBOARD_FAB2_LIB.BASEBOARD_FAB2(SCH_1):GND     I5 @BASEBOARD_FAB2_LIB.BASEBOARD_FAB2(SCH_1):PAGE46

C6U10 CAP_0805-10UF,16V,10%,X7R,G106A
     1 P12V_NVDIMM_ABC @BASEBOARD_FAB2_LIB.BASEBOARD_FAB2(SCH_1):P12V_NVDIMM_ABC    I65 @BASEBOARD_FAB2_LIB.BASEBOARD_FAB2(SCH_1):PAGE197
     2    GND @BASEBOARD_FAB2_LIB.BASEBOARD_FAB2(SCH_1):GND    I65 @BASEBOARD_FAB2_LIB.BASEBOARD_FAB2(SCH_1):PAGE197

C6U11 CAP_0603-4.7UF,6.3V,10%,X6S,E1A
     1 VSENSE_PVDDQ_GHJ_VTT @BASEBOARD_FAB2_LIB.BASEBOARD_FAB2(SCH_1):VSENSE_PVDDQ_GHJ_VTT    I46 @BASEBOARD_FAB2_LIB.BASEBOARD_FAB2(SCH_1):PAGE229
     2    GND @BASEBOARD_FAB2_LIB.BASEBOARD_FAB2(SCH_1):GND    I46 @BASEBOARD_FAB2_LIB.BASEBOARD_FAB2(SCH_1):PAGE229

C6U12 CAP_0603-4.7UF,6.3V,10%,X6S,E1A
     1 VSENSE_PVDDQ_ABC_VTT @BASEBOARD_FAB2_LIB.BASEBOARD_FAB2(SCH_1):VSENSE_PVDDQ_ABC_VTT    I49 @BASEBOARD_FAB2_LIB.BASEBOARD_FAB2(SCH_1):PAGE221
     2    GND @BASEBOARD_FAB2_LIB.BASEBOARD_FAB2(SCH_1):GND    I49 @BASEBOARD_FAB2_LIB.BASEBOARD_FAB2(SCH_1):PAGE221

C6U13 CAP_0603LF-10UF,4V,20%,X6S,E15A
     1 PVDDQ_GHJ @BASEBOARD_FAB2_LIB.BASEBOARD_FAB2(SCH_1):PVDDQ_GHJ    I29 @BASEBOARD_FAB2_LIB.BASEBOARD_FAB2(SCH_1):PAGE229
     2    GND @BASEBOARD_FAB2_LIB.BASEBOARD_FAB2(SCH_1):GND    I29 @BASEBOARD_FAB2_LIB.BASEBOARD_FAB2(SCH_1):PAGE229

C6U14 CAP_0603LF-10UF,4V,20%,X6S,E15A
     1 PVDDQ_GHJ @BASEBOARD_FAB2_LIB.BASEBOARD_FAB2(SCH_1):PVDDQ_GHJ    I25 @BASEBOARD_FAB2_LIB.BASEBOARD_FAB2(SCH_1):PAGE229
     2    GND @BASEBOARD_FAB2_LIB.BASEBOARD_FAB2(SCH_1):GND    I25 @BASEBOARD_FAB2_LIB.BASEBOARD_FAB2(SCH_1):PAGE229

C6U15 CAP_0603LF-10UF,4V,20%,X6S,E15A
     1 PVDDQ_ABC @BASEBOARD_FAB2_LIB.BASEBOARD_FAB2(SCH_1):PVDDQ_ABC    I26 @BASEBOARD_FAB2_LIB.BASEBOARD_FAB2(SCH_1):PAGE221
     2    GND @BASEBOARD_FAB2_LIB.BASEBOARD_FAB2(SCH_1):GND    I26 @BASEBOARD_FAB2_LIB.BASEBOARD_FAB2(SCH_1):PAGE221

C6U16 CAP_0603LF-10UF,4V,20%,X6S,E15A
     1 PVDDQ_ABC @BASEBOARD_FAB2_LIB.BASEBOARD_FAB2(SCH_1):PVDDQ_ABC    I22 @BASEBOARD_FAB2_LIB.BASEBOARD_FAB2(SCH_1):PAGE221
     2    GND @BASEBOARD_FAB2_LIB.BASEBOARD_FAB2(SCH_1):GND    I22 @BASEBOARD_FAB2_LIB.BASEBOARD_FAB2(SCH_1):PAGE221

C6U17 CAP_A_0402V-0.01UF,25V,10%,X7RA
     1 M_C_VREF @BASEBOARD_FAB2_LIB.BASEBOARD_FAB2(SCH_1):M_C_VREF   I176 @BASEBOARD_FAB2_LIB.BASEBOARD_FAB2(SCH_1):PAGE48
     2    GND @BASEBOARD_FAB2_LIB.BASEBOARD_FAB2(SCH_1):GND   I176 @BASEBOARD_FAB2_LIB.BASEBOARD_FAB2(SCH_1):PAGE48

C6U18 CAP_0805-10UF,16V,10%,X7R,G106A
     1 P12V_NVDIMM_ABC @BASEBOARD_FAB2_LIB.BASEBOARD_FAB2(SCH_1):P12V_NVDIMM_ABC    I52 @BASEBOARD_FAB2_LIB.BASEBOARD_FAB2(SCH_1):PAGE197
     2    GND @BASEBOARD_FAB2_LIB.BASEBOARD_FAB2(SCH_1):GND    I52 @BASEBOARD_FAB2_LIB.BASEBOARD_FAB2(SCH_1):PAGE197

C6W1 CAP_0402LF-0.1UF,16V,10%,X7R,AA
     1 P3V3_STBY @BASEBOARD_FAB2_LIB.BASEBOARD_FAB2(SCH_1):P3V3_STBY    I18 @BASEBOARD_FAB2_LIB.BASEBOARD_FAB2(SCH_1):PAGE247
     2    GND @BASEBOARD_FAB2_LIB.BASEBOARD_FAB2(SCH_1):GND    I18 @BASEBOARD_FAB2_LIB.BASEBOARD_FAB2(SCH_1):PAGE247

C6W2 CAP_0402LF-0.1UF,16V,10%,X7R,AA
     1 P3V3_STBY @BASEBOARD_FAB2_LIB.BASEBOARD_FAB2(SCH_1):P3V3_STBY    I81 @BASEBOARD_FAB2_LIB.BASEBOARD_FAB2(SCH_1):PAGE247
     2    GND @BASEBOARD_FAB2_LIB.BASEBOARD_FAB2(SCH_1):GND    I81 @BASEBOARD_FAB2_LIB.BASEBOARD_FAB2(SCH_1):PAGE247

C6W3 CAP_A_0402V-0.1UF,16V,10%,X7R,A
     1 P3V3_STBY @BASEBOARD_FAB2_LIB.BASEBOARD_FAB2(SCH_1):P3V3_STBY    I85 @BASEBOARD_FAB2_LIB.BASEBOARD_FAB2(SCH_1):PAGE247
     2    GND @BASEBOARD_FAB2_LIB.BASEBOARD_FAB2(SCH_1):GND    I85 @BASEBOARD_FAB2_LIB.BASEBOARD_FAB2(SCH_1):PAGE247

C6W10 CAP_0402LF-0.1UF,16V,10%,X7R,AA
     1 P3V3_STBY @BASEBOARD_FAB2_LIB.BASEBOARD_FAB2(SCH_1):P3V3_STBY   I124 @BASEBOARD_FAB2_LIB.BASEBOARD_FAB2(SCH_1):PAGE176
     2    GND @BASEBOARD_FAB2_LIB.BASEBOARD_FAB2(SCH_1):GND   I124 @BASEBOARD_FAB2_LIB.BASEBOARD_FAB2(SCH_1):PAGE176

C7A5 CAP_A_0402V-0.1UF,16V,10%,X7R,A
     1 VR_FET_SW_P12V_STBY_PVDDQ_DEF @BASEBOARD_FAB2_LIB.BASEBOARD_FAB2(SCH_1):VR_FET_SW_P12V_STBY_PVDDQ_DEF    I51 @BASEBOARD_FAB2_LIB.BASEBOARD_FAB2(SCH_1):PAGE219
     2    GND @BASEBOARD_FAB2_LIB.BASEBOARD_FAB2(SCH_1):GND    I51 @BASEBOARD_FAB2_LIB.BASEBOARD_FAB2(SCH_1):PAGE219

C7A6 CAP_0402-1.0UF,16V,10%,X6S,D97A
     1 VR_PVNN_PCH_PH1_VCIN @BASEBOARD_FAB2_LIB.BASEBOARD_FAB2(SCH_1):VR_PVNN_PCH_PH1_VCIN    I19 @BASEBOARD_FAB2_LIB.BASEBOARD_FAB2(SCH_1):PAGE236
     2    GND @BASEBOARD_FAB2_LIB.BASEBOARD_FAB2(SCH_1):GND    I19 @BASEBOARD_FAB2_LIB.BASEBOARD_FAB2(SCH_1):PAGE236

C7A7 CAP_0402-1.0UF,16V,10%,X6S,D97A
     1 VR_FET_SW_P12V_STBY_PVDDQ_DEF @BASEBOARD_FAB2_LIB.BASEBOARD_FAB2(SCH_1):VR_FET_SW_P12V_STBY_PVDDQ_DEF    I22 @BASEBOARD_FAB2_LIB.BASEBOARD_FAB2(SCH_1):PAGE236
     2    GND @BASEBOARD_FAB2_LIB.BASEBOARD_FAB2(SCH_1):GND    I22 @BASEBOARD_FAB2_LIB.BASEBOARD_FAB2(SCH_1):PAGE236

C7A8 CAP_0402-0.22UF,16V,10%,X7R,A3A
     1 P5V_STBY @BASEBOARD_FAB2_LIB.BASEBOARD_FAB2(SCH_1):P5V_STBY    I16 @BASEBOARD_FAB2_LIB.BASEBOARD_FAB2(SCH_1):PAGE236
     2    GND @BASEBOARD_FAB2_LIB.BASEBOARD_FAB2(SCH_1):GND    I16 @BASEBOARD_FAB2_LIB.BASEBOARD_FAB2(SCH_1):PAGE236

C7A9 CAP_0402-1.0UF,16V,10%,X6S,D97A
     1 VR_FET_SW_P12V_STBY_PVDDQ_DEF @BASEBOARD_FAB2_LIB.BASEBOARD_FAB2(SCH_1):VR_FET_SW_P12V_STBY_PVDDQ_DEF    I33 @BASEBOARD_FAB2_LIB.BASEBOARD_FAB2(SCH_1):PAGE236
     2    GND @BASEBOARD_FAB2_LIB.BASEBOARD_FAB2(SCH_1):GND    I33 @BASEBOARD_FAB2_LIB.BASEBOARD_FAB2(SCH_1):PAGE236

C7A10 CAP_0402-1.0UF,16V,10%,X6S,D97A
     1 VR_P1V05_PCH_STBY_PH1_VCIN @BASEBOARD_FAB2_LIB.BASEBOARD_FAB2(SCH_1):VR_P1V05_PCH_STBY_PH1_VCIN    I36 @BASEBOARD_FAB2_LIB.BASEBOARD_FAB2(SCH_1):PAGE236
     2    GND @BASEBOARD_FAB2_LIB.BASEBOARD_FAB2(SCH_1):GND    I36 @BASEBOARD_FAB2_LIB.BASEBOARD_FAB2(SCH_1):PAGE236

C7A11 CAP_0402-1.0UF,16V,10%,X6S,D97A
     1 VR_FET_SW_P12V_STBY_PVDDQ_DEF @BASEBOARD_FAB2_LIB.BASEBOARD_FAB2(SCH_1):VR_FET_SW_P12V_STBY_PVDDQ_DEF    I48 @BASEBOARD_FAB2_LIB.BASEBOARD_FAB2(SCH_1):PAGE219
     2    GND @BASEBOARD_FAB2_LIB.BASEBOARD_FAB2(SCH_1):GND    I48 @BASEBOARD_FAB2_LIB.BASEBOARD_FAB2(SCH_1):PAGE219

C7A12 CAP_0402-0.220UF,16V,10%,X7R,AA
     1 VR_PVDDQ_DEF_PH1_BOOT @BASEBOARD_FAB2_LIB.BASEBOARD_FAB2(SCH_1):VR_PVDDQ_DEF_PH1_BOOT    I44 @BASEBOARD_FAB2_LIB.BASEBOARD_FAB2(SCH_1):PAGE219
     2 VR_PVDDQ_DEF_PH1_PHASE @BASEBOARD_FAB2_LIB.BASEBOARD_FAB2(SCH_1):VR_PVDDQ_DEF_PH1_PHASE    I44 @BASEBOARD_FAB2_LIB.BASEBOARD_FAB2(SCH_1):PAGE219

C7A13 CAP_1210-100UF,16V,20%,X5R,644A
     1 VR_FET_SW_P12V_STBY_PVDDQ_DEF @BASEBOARD_FAB2_LIB.BASEBOARD_FAB2(SCH_1):VR_FET_SW_P12V_STBY_PVDDQ_DEF    I63 @BASEBOARD_FAB2_LIB.BASEBOARD_FAB2(SCH_1):PAGE236
     2    GND @BASEBOARD_FAB2_LIB.BASEBOARD_FAB2(SCH_1):GND    I63 @BASEBOARD_FAB2_LIB.BASEBOARD_FAB2(SCH_1):PAGE236

C7A14 CAP_1210-100UF,16V,20%,X5R,644A
     1 VR_FET_SW_P12V_STBY_PVDDQ_DEF @BASEBOARD_FAB2_LIB.BASEBOARD_FAB2(SCH_1):VR_FET_SW_P12V_STBY_PVDDQ_DEF    I65 @BASEBOARD_FAB2_LIB.BASEBOARD_FAB2(SCH_1):PAGE236
     2    GND @BASEBOARD_FAB2_LIB.BASEBOARD_FAB2(SCH_1):GND    I65 @BASEBOARD_FAB2_LIB.BASEBOARD_FAB2(SCH_1):PAGE236

C7A16 CAP_0402-1.0UF,16V,10%,X6S,D97A
     1 VR_PVDDQ_DEF_PH1_VCIN @BASEBOARD_FAB2_LIB.BASEBOARD_FAB2(SCH_1):VR_PVDDQ_DEF_PH1_VCIN    I50 @BASEBOARD_FAB2_LIB.BASEBOARD_FAB2(SCH_1):PAGE219
     2    GND @BASEBOARD_FAB2_LIB.BASEBOARD_FAB2(SCH_1):GND    I50 @BASEBOARD_FAB2_LIB.BASEBOARD_FAB2(SCH_1):PAGE219

C7A17 CAP_0402-0.22UF,16V,10%,X7R,A3A
     1 P5V_STBY @BASEBOARD_FAB2_LIB.BASEBOARD_FAB2(SCH_1):P5V_STBY    I54 @BASEBOARD_FAB2_LIB.BASEBOARD_FAB2(SCH_1):PAGE219
     2    GND @BASEBOARD_FAB2_LIB.BASEBOARD_FAB2(SCH_1):GND    I54 @BASEBOARD_FAB2_LIB.BASEBOARD_FAB2(SCH_1):PAGE219

C7A18 CAP_A_0402V-1.0UF,6.3V,10%,X6SA
     1 P5V_STBY @BASEBOARD_FAB2_LIB.BASEBOARD_FAB2(SCH_1):P5V_STBY    I53 @BASEBOARD_FAB2_LIB.BASEBOARD_FAB2(SCH_1):PAGE219
     2    GND @BASEBOARD_FAB2_LIB.BASEBOARD_FAB2(SCH_1):GND    I53 @BASEBOARD_FAB2_LIB.BASEBOARD_FAB2(SCH_1):PAGE219

C7A19 CAPP_2626-270UF,16V,20%,OSCON,A
     1 VR_FET_SW_P12V_STBY_PVDDQ_DEF @BASEBOARD_FAB2_LIB.BASEBOARD_FAB2(SCH_1):VR_FET_SW_P12V_STBY_PVDDQ_DEF   I175 @BASEBOARD_FAB2_LIB.BASEBOARD_FAB2(SCH_1):PAGE220
     2    GND @BASEBOARD_FAB2_LIB.BASEBOARD_FAB2(SCH_1):GND   I175 @BASEBOARD_FAB2_LIB.BASEBOARD_FAB2(SCH_1):PAGE220

C7A20 CAP_A_0402V-0.1UF,16V,10%,X7R,A
     1 VR_FET_SW_P12V_STBY_PVDDQ_DEF @BASEBOARD_FAB2_LIB.BASEBOARD_FAB2(SCH_1):VR_FET_SW_P12V_STBY_PVDDQ_DEF    I78 @BASEBOARD_FAB2_LIB.BASEBOARD_FAB2(SCH_1):PAGE219
     2    GND @BASEBOARD_FAB2_LIB.BASEBOARD_FAB2(SCH_1):GND    I78 @BASEBOARD_FAB2_LIB.BASEBOARD_FAB2(SCH_1):PAGE219

C7A21 CAP_0402-1.0UF,16V,10%,X6S,D97A
     1 VR_FET_SW_P12V_STBY_PVDDQ_DEF @BASEBOARD_FAB2_LIB.BASEBOARD_FAB2(SCH_1):VR_FET_SW_P12V_STBY_PVDDQ_DEF    I79 @BASEBOARD_FAB2_LIB.BASEBOARD_FAB2(SCH_1):PAGE219
     2    GND @BASEBOARD_FAB2_LIB.BASEBOARD_FAB2(SCH_1):GND    I79 @BASEBOARD_FAB2_LIB.BASEBOARD_FAB2(SCH_1):PAGE219

C7A22 CAP_0402-0.220UF,16V,10%,X7R,AA
     1 VR_PVDDQ_DEF_PH2_BOOT @BASEBOARD_FAB2_LIB.BASEBOARD_FAB2(SCH_1):VR_PVDDQ_DEF_PH2_BOOT    I75 @BASEBOARD_FAB2_LIB.BASEBOARD_FAB2(SCH_1):PAGE219
     2 VR_PVDDQ_DEF_PH2_PHASE @BASEBOARD_FAB2_LIB.BASEBOARD_FAB2(SCH_1):VR_PVDDQ_DEF_PH2_PHASE    I75 @BASEBOARD_FAB2_LIB.BASEBOARD_FAB2(SCH_1):PAGE219

C7A24 CAP_0402-1.0UF,16V,10%,X6S,D97A
     1 VR_PVDDQ_DEF_PH2_VCIN @BASEBOARD_FAB2_LIB.BASEBOARD_FAB2(SCH_1):VR_PVDDQ_DEF_PH2_VCIN    I77 @BASEBOARD_FAB2_LIB.BASEBOARD_FAB2(SCH_1):PAGE219
     2    GND @BASEBOARD_FAB2_LIB.BASEBOARD_FAB2(SCH_1):GND    I77 @BASEBOARD_FAB2_LIB.BASEBOARD_FAB2(SCH_1):PAGE219

C7A25 CAP_0402-0.22UF,16V,10%,X7R,A3A
     1 P5V_STBY @BASEBOARD_FAB2_LIB.BASEBOARD_FAB2(SCH_1):P5V_STBY    I72 @BASEBOARD_FAB2_LIB.BASEBOARD_FAB2(SCH_1):PAGE219
     2    GND @BASEBOARD_FAB2_LIB.BASEBOARD_FAB2(SCH_1):GND    I72 @BASEBOARD_FAB2_LIB.BASEBOARD_FAB2(SCH_1):PAGE219

C7A26 CAP_A_0402V-1.0UF,6.3V,10%,X6SA
     1 P5V_STBY @BASEBOARD_FAB2_LIB.BASEBOARD_FAB2(SCH_1):P5V_STBY    I73 @BASEBOARD_FAB2_LIB.BASEBOARD_FAB2(SCH_1):PAGE219
     2    GND @BASEBOARD_FAB2_LIB.BASEBOARD_FAB2(SCH_1):GND    I73 @BASEBOARD_FAB2_LIB.BASEBOARD_FAB2(SCH_1):PAGE219

C7A27 CAPP_SM-470UF,2V,20%,ALUM,6990A
     1 PVNN_PCH_STBY @BASEBOARD_FAB2_LIB.BASEBOARD_FAB2(SCH_1):PVNN_PCH_STBY    I75 @BASEBOARD_FAB2_LIB.BASEBOARD_FAB2(SCH_1):PAGE236
     2    GND @BASEBOARD_FAB2_LIB.BASEBOARD_FAB2(SCH_1):GND    I75 @BASEBOARD_FAB2_LIB.BASEBOARD_FAB2(SCH_1):PAGE236

C7A28 CAP_0402LF-220PF,50V,10%,X7R,AA
     1 VR_PVDDQ_DEF_AVSP @BASEBOARD_FAB2_LIB.BASEBOARD_FAB2(SCH_1):VR_PVDDQ_DEF_AVSP    I61 @BASEBOARD_FAB2_LIB.BASEBOARD_FAB2(SCH_1):PAGE218
     2 VSENSE_PVDDQ_DEF_N @BASEBOARD_FAB2_LIB.BASEBOARD_FAB2(SCH_1):VSENSE_PVDDQ_DEF_N    I61 @BASEBOARD_FAB2_LIB.BASEBOARD_FAB2(SCH_1):PAGE218

C7A29 CAP_0402LF-220PF,50V,10%,X7R,AA
     1 A_TSENSE_PVDDQ_DEF @BASEBOARD_FAB2_LIB.BASEBOARD_FAB2(SCH_1):A_TSENSE_PVDDQ_DEF    I39 @BASEBOARD_FAB2_LIB.BASEBOARD_FAB2(SCH_1):PAGE218
     2    GND @BASEBOARD_FAB2_LIB.BASEBOARD_FAB2(SCH_1):GND    I39 @BASEBOARD_FAB2_LIB.BASEBOARD_FAB2(SCH_1):PAGE218

C7A30 CAP_0805LF-22UF,4V,20%,X6S,C95A
     1 PVNN_PCH_STBY @BASEBOARD_FAB2_LIB.BASEBOARD_FAB2(SCH_1):PVNN_PCH_STBY     I9 @BASEBOARD_FAB2_LIB.BASEBOARD_FAB2(SCH_1):PAGE236
     2    GND @BASEBOARD_FAB2_LIB.BASEBOARD_FAB2(SCH_1):GND     I9 @BASEBOARD_FAB2_LIB.BASEBOARD_FAB2(SCH_1):PAGE236

C7A31 CAP_0805-47UF,4V,20%,X6S,C9533A
     1 PVNN_PCH_STBY @BASEBOARD_FAB2_LIB.BASEBOARD_FAB2(SCH_1):PVNN_PCH_STBY    I40 @BASEBOARD_FAB2_LIB.BASEBOARD_FAB2(SCH_1):PAGE132
     2    GND @BASEBOARD_FAB2_LIB.BASEBOARD_FAB2(SCH_1):GND    I40 @BASEBOARD_FAB2_LIB.BASEBOARD_FAB2(SCH_1):PAGE132

C7A32 CAP_0805-47UF,4V,20%,X6S,C9533A
     1 PVNN_PCH_STBY @BASEBOARD_FAB2_LIB.BASEBOARD_FAB2(SCH_1):PVNN_PCH_STBY    I38 @BASEBOARD_FAB2_LIB.BASEBOARD_FAB2(SCH_1):PAGE132
     2    GND @BASEBOARD_FAB2_LIB.BASEBOARD_FAB2(SCH_1):GND    I38 @BASEBOARD_FAB2_LIB.BASEBOARD_FAB2(SCH_1):PAGE132

C7A33 CAP_0805-47UF,4V,20%,X6S,C9533A
     1 PVNN_PCH_STBY @BASEBOARD_FAB2_LIB.BASEBOARD_FAB2(SCH_1):PVNN_PCH_STBY    I23 @BASEBOARD_FAB2_LIB.BASEBOARD_FAB2(SCH_1):PAGE132
     2    GND @BASEBOARD_FAB2_LIB.BASEBOARD_FAB2(SCH_1):GND    I23 @BASEBOARD_FAB2_LIB.BASEBOARD_FAB2(SCH_1):PAGE132

C7A34 CAP_0402LF-3300PF,50V,10%,EMPTA
     1 VR_PVPP_DEF_PHASE @BASEBOARD_FAB2_LIB.BASEBOARD_FAB2(SCH_1):VR_PVPP_DEF_PHASE   I220 @BASEBOARD_FAB2_LIB.BASEBOARD_FAB2(SCH_1):PAGE232
     2 VR_PVPP_DEF_SNUB @BASEBOARD_FAB2_LIB.BASEBOARD_FAB2(SCH_1):VR_PVPP_DEF_SNUB   I220 @BASEBOARD_FAB2_LIB.BASEBOARD_FAB2(SCH_1):PAGE232

C7A35 CAP_0402LF-1000PF,50V,10%,X7R,A
     1 VR_PVDDQ_DEF_VINSEN @BASEBOARD_FAB2_LIB.BASEBOARD_FAB2(SCH_1):VR_PVDDQ_DEF_VINSEN    I55 @BASEBOARD_FAB2_LIB.BASEBOARD_FAB2(SCH_1):PAGE218
     2    GND @BASEBOARD_FAB2_LIB.BASEBOARD_FAB2(SCH_1):GND    I55 @BASEBOARD_FAB2_LIB.BASEBOARD_FAB2(SCH_1):PAGE218

C7A36 CAP_A_0603V-22.0UF,4V,20%,X6S,A
     1 PVNN_PCH_STBY @BASEBOARD_FAB2_LIB.BASEBOARD_FAB2(SCH_1):PVNN_PCH_STBY    I11 @BASEBOARD_FAB2_LIB.BASEBOARD_FAB2(SCH_1):PAGE132
     2    GND @BASEBOARD_FAB2_LIB.BASEBOARD_FAB2(SCH_1):GND    I11 @BASEBOARD_FAB2_LIB.BASEBOARD_FAB2(SCH_1):PAGE132

C7A37 CAP_A_0402V-1.0UF,6.3V,10%,X6SA
     1 VR_PVDDQ_DEF_VDD @BASEBOARD_FAB2_LIB.BASEBOARD_FAB2(SCH_1):VR_PVDDQ_DEF_VDD    I29 @BASEBOARD_FAB2_LIB.BASEBOARD_FAB2(SCH_1):PAGE218
     2    GND @BASEBOARD_FAB2_LIB.BASEBOARD_FAB2(SCH_1):GND    I29 @BASEBOARD_FAB2_LIB.BASEBOARD_FAB2(SCH_1):PAGE218

C7A38 CAP_A_0402V-0.1UF,16V,10%,X7R,A
     1 VR_PVDDQ_DEF_VDD @BASEBOARD_FAB2_LIB.BASEBOARD_FAB2(SCH_1):VR_PVDDQ_DEF_VDD    I31 @BASEBOARD_FAB2_LIB.BASEBOARD_FAB2(SCH_1):PAGE218
     2    GND @BASEBOARD_FAB2_LIB.BASEBOARD_FAB2(SCH_1):GND    I31 @BASEBOARD_FAB2_LIB.BASEBOARD_FAB2(SCH_1):PAGE218

C7A39 CAP_A_0402V-0.1UF,16V,10%,X7R,A
     1 VR_FET_SW_P12V_STBY_PVDDQ_DEF @BASEBOARD_FAB2_LIB.BASEBOARD_FAB2(SCH_1):VR_FET_SW_P12V_STBY_PVDDQ_DEF    I20 @BASEBOARD_FAB2_LIB.BASEBOARD_FAB2(SCH_1):PAGE236
     2    GND @BASEBOARD_FAB2_LIB.BASEBOARD_FAB2(SCH_1):GND    I20 @BASEBOARD_FAB2_LIB.BASEBOARD_FAB2(SCH_1):PAGE236

C7A40 CAP_A_0402V-0.1UF,16V,10%,X7R,A
     1 VR_FET_SW_P12V_STBY_PVDDQ_DEF @BASEBOARD_FAB2_LIB.BASEBOARD_FAB2(SCH_1):VR_FET_SW_P12V_STBY_PVDDQ_DEF    I35 @BASEBOARD_FAB2_LIB.BASEBOARD_FAB2(SCH_1):PAGE236
     2    GND @BASEBOARD_FAB2_LIB.BASEBOARD_FAB2(SCH_1):GND    I35 @BASEBOARD_FAB2_LIB.BASEBOARD_FAB2(SCH_1):PAGE236

C7A41 CAP_0402-0.22UF,16V,10%,X7R,A3A
     1 P5V_STBY @BASEBOARD_FAB2_LIB.BASEBOARD_FAB2(SCH_1):P5V_STBY    I39 @BASEBOARD_FAB2_LIB.BASEBOARD_FAB2(SCH_1):PAGE236
     2    GND @BASEBOARD_FAB2_LIB.BASEBOARD_FAB2(SCH_1):GND    I39 @BASEBOARD_FAB2_LIB.BASEBOARD_FAB2(SCH_1):PAGE236

C7A42 CAP_0805LF-22UF,4V,20%,X6S,C95A
     1 P1V05_PCH_STBY @BASEBOARD_FAB2_LIB.BASEBOARD_FAB2(SCH_1):P1V05_PCH_STBY    I46 @BASEBOARD_FAB2_LIB.BASEBOARD_FAB2(SCH_1):PAGE236
     2    GND @BASEBOARD_FAB2_LIB.BASEBOARD_FAB2(SCH_1):GND    I46 @BASEBOARD_FAB2_LIB.BASEBOARD_FAB2(SCH_1):PAGE236

C7A43 CAP_0402-0.220UF,16V,10%,X7R,AA
     1 VR_PVNN_PCH_PH1_BOOT @BASEBOARD_FAB2_LIB.BASEBOARD_FAB2(SCH_1):VR_PVNN_PCH_PH1_BOOT    I21 @BASEBOARD_FAB2_LIB.BASEBOARD_FAB2(SCH_1):PAGE236
     2 VR_PVNN_PCH_PH1_PHASE @BASEBOARD_FAB2_LIB.BASEBOARD_FAB2(SCH_1):VR_PVNN_PCH_PH1_PHASE    I21 @BASEBOARD_FAB2_LIB.BASEBOARD_FAB2(SCH_1):PAGE236

C7A44 CAP_0402-0.220UF,16V,10%,X7R,AA
     1 VR_P1V05_PCH_STBY_PH1_BOOT @BASEBOARD_FAB2_LIB.BASEBOARD_FAB2(SCH_1):VR_P1V05_PCH_STBY_PH1_BOOT    I34 @BASEBOARD_FAB2_LIB.BASEBOARD_FAB2(SCH_1):PAGE236
     2 VR_P1V05_PCH_STBY_PH1_PHASE @BASEBOARD_FAB2_LIB.BASEBOARD_FAB2(SCH_1):VR_P1V05_PCH_STBY_PH1_PHASE    I34 @BASEBOARD_FAB2_LIB.BASEBOARD_FAB2(SCH_1):PAGE236

C7B1 CAP_A_0402V-1.0UF,6.3V,10%,X6SA
     1 VR_PVDDQ_DEF_VD12 @BASEBOARD_FAB2_LIB.BASEBOARD_FAB2(SCH_1):VR_PVDDQ_DEF_VD12    I22 @BASEBOARD_FAB2_LIB.BASEBOARD_FAB2(SCH_1):PAGE218
     2    GND @BASEBOARD_FAB2_LIB.BASEBOARD_FAB2(SCH_1):GND    I22 @BASEBOARD_FAB2_LIB.BASEBOARD_FAB2(SCH_1):PAGE218

C7B2 CAP_A_0402V-0.1UF,16V,10%,X7R,A
     1 VR_PVDDQ_DEF_VD12 @BASEBOARD_FAB2_LIB.BASEBOARD_FAB2(SCH_1):VR_PVDDQ_DEF_VD12    I23 @BASEBOARD_FAB2_LIB.BASEBOARD_FAB2(SCH_1):PAGE218
     2    GND @BASEBOARD_FAB2_LIB.BASEBOARD_FAB2(SCH_1):GND    I23 @BASEBOARD_FAB2_LIB.BASEBOARD_FAB2(SCH_1):PAGE218

C7B3 CAP_0402LF-1000PF,50V,10%,X7R,A
     1 PWRGD_PVDDQ_DEF_R @BASEBOARD_FAB2_LIB.BASEBOARD_FAB2(SCH_1):PWRGD_PVDDQ_DEF_R    I26 @BASEBOARD_FAB2_LIB.BASEBOARD_FAB2(SCH_1):PAGE218
     2    GND @BASEBOARD_FAB2_LIB.BASEBOARD_FAB2(SCH_1):GND    I26 @BASEBOARD_FAB2_LIB.BASEBOARD_FAB2(SCH_1):PAGE218

C7B4 CAP_0805-47UF,4V,20%,X6S,C9533A
     1 PVNN_PCH_STBY @BASEBOARD_FAB2_LIB.BASEBOARD_FAB2(SCH_1):PVNN_PCH_STBY    I24 @BASEBOARD_FAB2_LIB.BASEBOARD_FAB2(SCH_1):PAGE132
     2    GND @BASEBOARD_FAB2_LIB.BASEBOARD_FAB2(SCH_1):GND    I24 @BASEBOARD_FAB2_LIB.BASEBOARD_FAB2(SCH_1):PAGE132

C7B5 CAP_0805-10UF,16V,10%,X6S,C953A
     1 VR_FET_SW_P12V_STBY_PVPP_DEF @BASEBOARD_FAB2_LIB.BASEBOARD_FAB2(SCH_1):VR_FET_SW_P12V_STBY_PVPP_DEF   I262 @BASEBOARD_FAB2_LIB.BASEBOARD_FAB2(SCH_1):PAGE232
     2    GND @BASEBOARD_FAB2_LIB.BASEBOARD_FAB2(SCH_1):GND   I262 @BASEBOARD_FAB2_LIB.BASEBOARD_FAB2(SCH_1):PAGE232

C7B6 CAP_A_0402V-0.1UF,16V,10%,X7R,A
     1 VR_FET_SW_P12V_STBY_PVPP_DEF @BASEBOARD_FAB2_LIB.BASEBOARD_FAB2(SCH_1):VR_FET_SW_P12V_STBY_PVPP_DEF   I252 @BASEBOARD_FAB2_LIB.BASEBOARD_FAB2(SCH_1):PAGE232
     2    GND @BASEBOARD_FAB2_LIB.BASEBOARD_FAB2(SCH_1):GND   I252 @BASEBOARD_FAB2_LIB.BASEBOARD_FAB2(SCH_1):PAGE232

C7B7 CAP_0805-47UF,4V,20%,X6S,C9533A
     1 PVPP_DEF @BASEBOARD_FAB2_LIB.BASEBOARD_FAB2(SCH_1):PVPP_DEF   I238 @BASEBOARD_FAB2_LIB.BASEBOARD_FAB2(SCH_1):PAGE232
     2    GND @BASEBOARD_FAB2_LIB.BASEBOARD_FAB2(SCH_1):GND   I238 @BASEBOARD_FAB2_LIB.BASEBOARD_FAB2(SCH_1):PAGE232

C7B8 CAP_1210-47UF,16V,20%,X6S,D384A
     1 VR_FET_SW_P12V_STBY_PVPP_DEF @BASEBOARD_FAB2_LIB.BASEBOARD_FAB2(SCH_1):VR_FET_SW_P12V_STBY_PVPP_DEF   I202 @BASEBOARD_FAB2_LIB.BASEBOARD_FAB2(SCH_1):PAGE232
     2    GND @BASEBOARD_FAB2_LIB.BASEBOARD_FAB2(SCH_1):GND   I202 @BASEBOARD_FAB2_LIB.BASEBOARD_FAB2(SCH_1):PAGE232

C7B9 CAP_0402LF-1000PF,50V,10%,EMPTA
     1 FM_PVPP_CPU0_EN @BASEBOARD_FAB2_LIB.BASEBOARD_FAB2(SCH_1):FM_PVPP_CPU0_EN   I185 @BASEBOARD_FAB2_LIB.BASEBOARD_FAB2(SCH_1):PAGE232
     2 AGND_PVPP_DEF @BASEBOARD_FAB2_LIB.BASEBOARD_FAB2(SCH_1):AGND_PVPP_DEF   I185 @BASEBOARD_FAB2_LIB.BASEBOARD_FAB2(SCH_1):PAGE232

C7B10 CAP_0402LF-100.0PF,50V,5%,COG,A
     1 VR_FB_PVPP_DEF @BASEBOARD_FAB2_LIB.BASEBOARD_FAB2(SCH_1):VR_FB_PVPP_DEF   I301 @BASEBOARD_FAB2_LIB.BASEBOARD_FAB2(SCH_1):PAGE232
     2 VR_COMP_PVPP_DEF_3 @BASEBOARD_FAB2_LIB.BASEBOARD_FAB2(SCH_1):VR_COMP_PVPP_DEF_3   I301 @BASEBOARD_FAB2_LIB.BASEBOARD_FAB2(SCH_1):PAGE232

C7B11 CAP_0402-0.027UF,16V,10%,X7R,AA
     1 VR_PVPP_DEF_SS @BASEBOARD_FAB2_LIB.BASEBOARD_FAB2(SCH_1):VR_PVPP_DEF_SS   I197 @BASEBOARD_FAB2_LIB.BASEBOARD_FAB2(SCH_1):PAGE232
     2 AGND_PVPP_DEF @BASEBOARD_FAB2_LIB.BASEBOARD_FAB2(SCH_1):AGND_PVPP_DEF   I197 @BASEBOARD_FAB2_LIB.BASEBOARD_FAB2(SCH_1):PAGE232

C7B12 CAP_0402LF-1000PF,50V,10%,X7R,A
     1 PWRGD_PVPP_DEF_R @BASEBOARD_FAB2_LIB.BASEBOARD_FAB2(SCH_1):PWRGD_PVPP_DEF_R   I209 @BASEBOARD_FAB2_LIB.BASEBOARD_FAB2(SCH_1):PAGE232
     2    GND @BASEBOARD_FAB2_LIB.BASEBOARD_FAB2(SCH_1):GND   I209 @BASEBOARD_FAB2_LIB.BASEBOARD_FAB2(SCH_1):PAGE232

C7B13 CAP_0402LF-2200PF,50V,10%,X7R,A
     1 VR_COMP_PVPP_DEF @BASEBOARD_FAB2_LIB.BASEBOARD_FAB2(SCH_1):VR_COMP_PVPP_DEF   I302 @BASEBOARD_FAB2_LIB.BASEBOARD_FAB2(SCH_1):PAGE232
     2 VR_FB_PVPP_DEF @BASEBOARD_FAB2_LIB.BASEBOARD_FAB2(SCH_1):VR_FB_PVPP_DEF   I302 @BASEBOARD_FAB2_LIB.BASEBOARD_FAB2(SCH_1):PAGE232

C7B14 CAP_0402LF-2200PF,50V,10%,X7R,A
     1 VR_COMP_RC_PVPP_DEF @BASEBOARD_FAB2_LIB.BASEBOARD_FAB2(SCH_1):VR_COMP_RC_PVPP_DEF   I306 @BASEBOARD_FAB2_LIB.BASEBOARD_FAB2(SCH_1):PAGE232
     2 VR_COMP_PVPP_DEF_3 @BASEBOARD_FAB2_LIB.BASEBOARD_FAB2(SCH_1):VR_COMP_PVPP_DEF_3   I306 @BASEBOARD_FAB2_LIB.BASEBOARD_FAB2(SCH_1):PAGE232

C7B15 CAP_A_0603V-22.0UF,4V,20%,X6S,A
     1 P1V05_PCH_STBY @BASEBOARD_FAB2_LIB.BASEBOARD_FAB2(SCH_1):P1V05_PCH_STBY     I1 @BASEBOARD_FAB2_LIB.BASEBOARD_FAB2(SCH_1):PAGE131
     2    GND @BASEBOARD_FAB2_LIB.BASEBOARD_FAB2(SCH_1):GND     I1 @BASEBOARD_FAB2_LIB.BASEBOARD_FAB2(SCH_1):PAGE131

C7B16 CAP_A_0603V-22.0UF,4V,20%,X6S,A
     1 P1V05_PCH_STBY @BASEBOARD_FAB2_LIB.BASEBOARD_FAB2(SCH_1):P1V05_PCH_STBY     I3 @BASEBOARD_FAB2_LIB.BASEBOARD_FAB2(SCH_1):PAGE131
     2    GND @BASEBOARD_FAB2_LIB.BASEBOARD_FAB2(SCH_1):GND     I3 @BASEBOARD_FAB2_LIB.BASEBOARD_FAB2(SCH_1):PAGE131

C7B17 CAP_A_0603V-22.0UF,4V,20%,X6S,A
     1 P1V05_PCH_STBY @BASEBOARD_FAB2_LIB.BASEBOARD_FAB2(SCH_1):P1V05_PCH_STBY    I18 @BASEBOARD_FAB2_LIB.BASEBOARD_FAB2(SCH_1):PAGE131
     2    GND @BASEBOARD_FAB2_LIB.BASEBOARD_FAB2(SCH_1):GND    I18 @BASEBOARD_FAB2_LIB.BASEBOARD_FAB2(SCH_1):PAGE131

C7B18 CAP_A_0603V-22.0UF,4V,20%,X6S,A
     1 P1V05_PCH_STBY @BASEBOARD_FAB2_LIB.BASEBOARD_FAB2(SCH_1):P1V05_PCH_STBY    I12 @BASEBOARD_FAB2_LIB.BASEBOARD_FAB2(SCH_1):PAGE131
     2    GND @BASEBOARD_FAB2_LIB.BASEBOARD_FAB2(SCH_1):GND    I12 @BASEBOARD_FAB2_LIB.BASEBOARD_FAB2(SCH_1):PAGE131

C7B19 CAP_A_0603V-22.0UF,4V,20%,X6S,A
     1 P1V05_PCH_STBY @BASEBOARD_FAB2_LIB.BASEBOARD_FAB2(SCH_1):P1V05_PCH_STBY     I2 @BASEBOARD_FAB2_LIB.BASEBOARD_FAB2(SCH_1):PAGE131
     2    GND @BASEBOARD_FAB2_LIB.BASEBOARD_FAB2(SCH_1):GND     I2 @BASEBOARD_FAB2_LIB.BASEBOARD_FAB2(SCH_1):PAGE131

C7B20 CAP_A_0603V-22.0UF,4V,20%,X6S,A
     1 P1V05_PCH_STBY @BASEBOARD_FAB2_LIB.BASEBOARD_FAB2(SCH_1):P1V05_PCH_STBY     I6 @BASEBOARD_FAB2_LIB.BASEBOARD_FAB2(SCH_1):PAGE131
     2    GND @BASEBOARD_FAB2_LIB.BASEBOARD_FAB2(SCH_1):GND     I6 @BASEBOARD_FAB2_LIB.BASEBOARD_FAB2(SCH_1):PAGE131

C7B21 CAP_A_0603V-22.0UF,4V,20%,X6S,A
     1 P1V05_PCH_STBY @BASEBOARD_FAB2_LIB.BASEBOARD_FAB2(SCH_1):P1V05_PCH_STBY     I4 @BASEBOARD_FAB2_LIB.BASEBOARD_FAB2(SCH_1):PAGE131
     2    GND @BASEBOARD_FAB2_LIB.BASEBOARD_FAB2(SCH_1):GND     I4 @BASEBOARD_FAB2_LIB.BASEBOARD_FAB2(SCH_1):PAGE131

C7B22 CAP_A_0603V-22.0UF,4V,20%,X6S,A
     1 P1V05_PCH_STBY @BASEBOARD_FAB2_LIB.BASEBOARD_FAB2(SCH_1):P1V05_PCH_STBY    I10 @BASEBOARD_FAB2_LIB.BASEBOARD_FAB2(SCH_1):PAGE131
     2    GND @BASEBOARD_FAB2_LIB.BASEBOARD_FAB2(SCH_1):GND    I10 @BASEBOARD_FAB2_LIB.BASEBOARD_FAB2(SCH_1):PAGE131

C7B23 CAP_A_0603V-22.0UF,4V,20%,X6S,A
     1 P1V05_PCH_STBY @BASEBOARD_FAB2_LIB.BASEBOARD_FAB2(SCH_1):P1V05_PCH_STBY     I7 @BASEBOARD_FAB2_LIB.BASEBOARD_FAB2(SCH_1):PAGE131
     2    GND @BASEBOARD_FAB2_LIB.BASEBOARD_FAB2(SCH_1):GND     I7 @BASEBOARD_FAB2_LIB.BASEBOARD_FAB2(SCH_1):PAGE131

C7B24 CAP_A_0603V-22.0UF,4V,20%,X6S,A
     1 P1V05_PCH_STBY @BASEBOARD_FAB2_LIB.BASEBOARD_FAB2(SCH_1):P1V05_PCH_STBY    I11 @BASEBOARD_FAB2_LIB.BASEBOARD_FAB2(SCH_1):PAGE131
     2    GND @BASEBOARD_FAB2_LIB.BASEBOARD_FAB2(SCH_1):GND    I11 @BASEBOARD_FAB2_LIB.BASEBOARD_FAB2(SCH_1):PAGE131

C7B25 CAP_0402-0.22UF,16V,10%,X7R,A3A
     1 DMI_CPU0_PCH_TX_DP<3> @BASEBOARD_FAB2_LIB.BASEBOARD_FAB2(SCH_1):DMI_CPU0_PCH_TX_DP(3)    I35 @BASEBOARD_FAB2_LIB.BASEBOARD_FAB2(SCH_1):PAGE129
     2 DMI_CPU0_PCH_TX_C_DP<3> @BASEBOARD_FAB2_LIB.BASEBOARD_FAB2(SCH_1):DMI_CPU0_PCH_TX_C_DP(3)    I35 @BASEBOARD_FAB2_LIB.BASEBOARD_FAB2(SCH_1):PAGE129

C7B26 CAP_0402-0.22UF,16V,10%,X7R,A3A
     1 DMI_CPU0_PCH_TX_DN<3> @BASEBOARD_FAB2_LIB.BASEBOARD_FAB2(SCH_1):DMI_CPU0_PCH_TX_DN(3)    I79 @BASEBOARD_FAB2_LIB.BASEBOARD_FAB2(SCH_1):PAGE129
     2 DMI_CPU0_PCH_TX_C_DN<3> @BASEBOARD_FAB2_LIB.BASEBOARD_FAB2(SCH_1):DMI_CPU0_PCH_TX_C_DN(3)    I79 @BASEBOARD_FAB2_LIB.BASEBOARD_FAB2(SCH_1):PAGE129

C7B27 CAP_0402-0.22UF,16V,10%,X7R,A3A
     1 DMI_CPU0_PCH_TX_DP<2> @BASEBOARD_FAB2_LIB.BASEBOARD_FAB2(SCH_1):DMI_CPU0_PCH_TX_DP(2)    I69 @BASEBOARD_FAB2_LIB.BASEBOARD_FAB2(SCH_1):PAGE129
     2 DMI_CPU0_PCH_TX_C_DP<2> @BASEBOARD_FAB2_LIB.BASEBOARD_FAB2(SCH_1):DMI_CPU0_PCH_TX_C_DP(2)    I69 @BASEBOARD_FAB2_LIB.BASEBOARD_FAB2(SCH_1):PAGE129

C7B28 CAP_0402-0.22UF,16V,10%,X7R,A3A
     1 DMI_CPU0_PCH_TX_DP<1> @BASEBOARD_FAB2_LIB.BASEBOARD_FAB2(SCH_1):DMI_CPU0_PCH_TX_DP(1)    I70 @BASEBOARD_FAB2_LIB.BASEBOARD_FAB2(SCH_1):PAGE129
     2 DMI_CPU0_PCH_TX_C_DP<1> @BASEBOARD_FAB2_LIB.BASEBOARD_FAB2(SCH_1):DMI_CPU0_PCH_TX_C_DP(1)    I70 @BASEBOARD_FAB2_LIB.BASEBOARD_FAB2(SCH_1):PAGE129

C7B29 CAP_0402-0.22UF,16V,10%,X7R,A3A
     1 DMI_CPU0_PCH_TX_DN<2> @BASEBOARD_FAB2_LIB.BASEBOARD_FAB2(SCH_1):DMI_CPU0_PCH_TX_DN(2)    I78 @BASEBOARD_FAB2_LIB.BASEBOARD_FAB2(SCH_1):PAGE129
     2 DMI_CPU0_PCH_TX_C_DN<2> @BASEBOARD_FAB2_LIB.BASEBOARD_FAB2(SCH_1):DMI_CPU0_PCH_TX_C_DN(2)    I78 @BASEBOARD_FAB2_LIB.BASEBOARD_FAB2(SCH_1):PAGE129

C7B30 CAP_0603LF-0.1UF,25V,10%,X7R,6A
     1 VR_PVPP_DEF_PHASE @BASEBOARD_FAB2_LIB.BASEBOARD_FAB2(SCH_1):VR_PVPP_DEF_PHASE   I241 @BASEBOARD_FAB2_LIB.BASEBOARD_FAB2(SCH_1):PAGE232
     2 VR_PVPP_DEF_BOOT_R @BASEBOARD_FAB2_LIB.BASEBOARD_FAB2(SCH_1):VR_PVPP_DEF_BOOT_R   I241 @BASEBOARD_FAB2_LIB.BASEBOARD_FAB2(SCH_1):PAGE232

C7C1 CAP_0402-0.22UF,16V,10%,X7R,A3A
     1 DMI_CPU0_PCH_TX_DN<1> @BASEBOARD_FAB2_LIB.BASEBOARD_FAB2(SCH_1):DMI_CPU0_PCH_TX_DN(1)    I77 @BASEBOARD_FAB2_LIB.BASEBOARD_FAB2(SCH_1):PAGE129
     2 DMI_CPU0_PCH_TX_C_DN<1> @BASEBOARD_FAB2_LIB.BASEBOARD_FAB2(SCH_1):DMI_CPU0_PCH_TX_C_DN(1)    I77 @BASEBOARD_FAB2_LIB.BASEBOARD_FAB2(SCH_1):PAGE129

C7C2 CAP_0402-0.22UF,16V,10%,X7R,A3A
     1 DMI_CPU0_PCH_TX_DP<0> @BASEBOARD_FAB2_LIB.BASEBOARD_FAB2(SCH_1):DMI_CPU0_PCH_TX_DP(0)    I71 @BASEBOARD_FAB2_LIB.BASEBOARD_FAB2(SCH_1):PAGE129
     2 DMI_CPU0_PCH_TX_C_DP<0> @BASEBOARD_FAB2_LIB.BASEBOARD_FAB2(SCH_1):DMI_CPU0_PCH_TX_C_DP(0)    I71 @BASEBOARD_FAB2_LIB.BASEBOARD_FAB2(SCH_1):PAGE129

C7C3 CAP_0402-0.22UF,16V,10%,X7R,A3A
     1 DMI_CPU0_PCH_TX_DN<0> @BASEBOARD_FAB2_LIB.BASEBOARD_FAB2(SCH_1):DMI_CPU0_PCH_TX_DN(0)    I76 @BASEBOARD_FAB2_LIB.BASEBOARD_FAB2(SCH_1):PAGE129
     2 DMI_CPU0_PCH_TX_C_DN<0> @BASEBOARD_FAB2_LIB.BASEBOARD_FAB2(SCH_1):DMI_CPU0_PCH_TX_C_DN(0)    I76 @BASEBOARD_FAB2_LIB.BASEBOARD_FAB2(SCH_1):PAGE129

C7C4 CAP_0402LF-15.0PF,50V,5%,COG,AA
     1 XTAL_PCH_48M_IN @BASEBOARD_FAB2_LIB.BASEBOARD_FAB2(SCH_1):XTAL_PCH_48M_IN    I50 @BASEBOARD_FAB2_LIB.BASEBOARD_FAB2(SCH_1):PAGE114
     2    GND @BASEBOARD_FAB2_LIB.BASEBOARD_FAB2(SCH_1):GND    I50 @BASEBOARD_FAB2_LIB.BASEBOARD_FAB2(SCH_1):PAGE114

C7C5 CAP_0402LF-15.0PF,50V,5%,COG,AA
     1 XTAL_PCH_48M_OUT @BASEBOARD_FAB2_LIB.BASEBOARD_FAB2(SCH_1):XTAL_PCH_48M_OUT    I47 @BASEBOARD_FAB2_LIB.BASEBOARD_FAB2(SCH_1):PAGE114
     2    GND @BASEBOARD_FAB2_LIB.BASEBOARD_FAB2(SCH_1):GND    I47 @BASEBOARD_FAB2_LIB.BASEBOARD_FAB2(SCH_1):PAGE114

C7C6 CAP_A_0603V-22.0UF,4V,20%,X6S,A
     1 PVCCIO_CPU0 @BASEBOARD_FAB2_LIB.BASEBOARD_FAB2(SCH_1):PVCCIO_CPU0    I23 @BASEBOARD_FAB2_LIB.BASEBOARD_FAB2(SCH_1):PAGE212
     2    GND @BASEBOARD_FAB2_LIB.BASEBOARD_FAB2(SCH_1):GND    I23 @BASEBOARD_FAB2_LIB.BASEBOARD_FAB2(SCH_1):PAGE212

C7C7 CAP_1210-100UF,16V,20%,X5R,644A
     1 VR_FET_SW_P12V_STBY_PVCCIO_CPU0 @BASEBOARD_FAB2_LIB.BASEBOARD_FAB2(SCH_1):VR_FET_SW_P12V_STBY_PVCCIO_CPU0    I54 @BASEBOARD_FAB2_LIB.BASEBOARD_FAB2(SCH_1):PAGE212
     2    GND @BASEBOARD_FAB2_LIB.BASEBOARD_FAB2(SCH_1):GND    I54 @BASEBOARD_FAB2_LIB.BASEBOARD_FAB2(SCH_1):PAGE212

C7C8 CAP_1210-100UF,16V,20%,X5R,644A
     1 VR_FET_SW_P12V_STBY_PVCCIO_CPU0 @BASEBOARD_FAB2_LIB.BASEBOARD_FAB2(SCH_1):VR_FET_SW_P12V_STBY_PVCCIO_CPU0    I51 @BASEBOARD_FAB2_LIB.BASEBOARD_FAB2(SCH_1):PAGE212
     2    GND @BASEBOARD_FAB2_LIB.BASEBOARD_FAB2(SCH_1):GND    I51 @BASEBOARD_FAB2_LIB.BASEBOARD_FAB2(SCH_1):PAGE212

C7C9 CAP_A_0603V-22.0UF,4V,20%,X6S,A
     1 PVNN_PCH_STBY @BASEBOARD_FAB2_LIB.BASEBOARD_FAB2(SCH_1):PVNN_PCH_STBY     I7 @BASEBOARD_FAB2_LIB.BASEBOARD_FAB2(SCH_1):PAGE132
     2    GND @BASEBOARD_FAB2_LIB.BASEBOARD_FAB2(SCH_1):GND     I7 @BASEBOARD_FAB2_LIB.BASEBOARD_FAB2(SCH_1):PAGE132

C7C10 CAP_A_0603V-22.0UF,4V,20%,X6S,A
     1 PVCCIO_CPU0 @BASEBOARD_FAB2_LIB.BASEBOARD_FAB2(SCH_1):PVCCIO_CPU0    I77 @BASEBOARD_FAB2_LIB.BASEBOARD_FAB2(SCH_1):PAGE212
     2    GND @BASEBOARD_FAB2_LIB.BASEBOARD_FAB2(SCH_1):GND    I77 @BASEBOARD_FAB2_LIB.BASEBOARD_FAB2(SCH_1):PAGE212

C7C11 CAP_A_0402V-0.1UF,16V,10%,X7R,A
     1 VR_FET_SW_P12V_STBY_PVCCIO_CPU0 @BASEBOARD_FAB2_LIB.BASEBOARD_FAB2(SCH_1):VR_FET_SW_P12V_STBY_PVCCIO_CPU0    I38 @BASEBOARD_FAB2_LIB.BASEBOARD_FAB2(SCH_1):PAGE212
     2    GND @BASEBOARD_FAB2_LIB.BASEBOARD_FAB2(SCH_1):GND    I38 @BASEBOARD_FAB2_LIB.BASEBOARD_FAB2(SCH_1):PAGE212

C7C12 CAP_0402-1.0UF,16V,10%,X6S,D97A
     1 VR_FET_SW_P12V_STBY_PVCCIO_CPU0 @BASEBOARD_FAB2_LIB.BASEBOARD_FAB2(SCH_1):VR_FET_SW_P12V_STBY_PVCCIO_CPU0    I39 @BASEBOARD_FAB2_LIB.BASEBOARD_FAB2(SCH_1):PAGE212
     2    GND @BASEBOARD_FAB2_LIB.BASEBOARD_FAB2(SCH_1):GND    I39 @BASEBOARD_FAB2_LIB.BASEBOARD_FAB2(SCH_1):PAGE212

C7C13 CAP_0402LF-18PF,50V,5%,C0G,A36A
     1 XTAL_33K_RTC1 @BASEBOARD_FAB2_LIB.BASEBOARD_FAB2(SCH_1):XTAL_33K_RTC1    I56 @BASEBOARD_FAB2_LIB.BASEBOARD_FAB2(SCH_1):PAGE114
     2    GND @BASEBOARD_FAB2_LIB.BASEBOARD_FAB2(SCH_1):GND    I56 @BASEBOARD_FAB2_LIB.BASEBOARD_FAB2(SCH_1):PAGE114

C7C14 CAP_0402-0.220UF,16V,10%,X7R,AA
     1 VR_PVCCIO_CPU0_PH1_BOOT @BASEBOARD_FAB2_LIB.BASEBOARD_FAB2(SCH_1):VR_PVCCIO_CPU0_PH1_BOOT    I37 @BASEBOARD_FAB2_LIB.BASEBOARD_FAB2(SCH_1):PAGE212
     2 VR_PVCCIO_CPU0_PH1_PHASE @BASEBOARD_FAB2_LIB.BASEBOARD_FAB2(SCH_1):VR_PVCCIO_CPU0_PH1_PHASE    I37 @BASEBOARD_FAB2_LIB.BASEBOARD_FAB2(SCH_1):PAGE212

C7C15 CAP_0402LF-18PF,50V,5%,C0G,A36A
     1 XTAL_33K_RTC2 @BASEBOARD_FAB2_LIB.BASEBOARD_FAB2(SCH_1):XTAL_33K_RTC2    I46 @BASEBOARD_FAB2_LIB.BASEBOARD_FAB2(SCH_1):PAGE114
     2    GND @BASEBOARD_FAB2_LIB.BASEBOARD_FAB2(SCH_1):GND    I46 @BASEBOARD_FAB2_LIB.BASEBOARD_FAB2(SCH_1):PAGE114

C7C17 CAP_0402-1.0UF,16V,10%,X6S,D97A
     1 VR_PVCCIO_CPU0_PH1_VCIN @BASEBOARD_FAB2_LIB.BASEBOARD_FAB2(SCH_1):VR_PVCCIO_CPU0_PH1_VCIN    I36 @BASEBOARD_FAB2_LIB.BASEBOARD_FAB2(SCH_1):PAGE212
     2    GND @BASEBOARD_FAB2_LIB.BASEBOARD_FAB2(SCH_1):GND    I36 @BASEBOARD_FAB2_LIB.BASEBOARD_FAB2(SCH_1):PAGE212

C7C18 CAP_0402-0.22UF,16V,10%,X7R,A3A
     1 P5V_STBY @BASEBOARD_FAB2_LIB.BASEBOARD_FAB2(SCH_1):P5V_STBY    I33 @BASEBOARD_FAB2_LIB.BASEBOARD_FAB2(SCH_1):PAGE212
     2    GND @BASEBOARD_FAB2_LIB.BASEBOARD_FAB2(SCH_1):GND    I33 @BASEBOARD_FAB2_LIB.BASEBOARD_FAB2(SCH_1):PAGE212

C7C19 CAP_A_0402V-1.0UF,6.3V,10%,X6SA
     1 RST_RTCRST_N @BASEBOARD_FAB2_LIB.BASEBOARD_FAB2(SCH_1):RST_RTCRST_N    I14 @BASEBOARD_FAB2_LIB.BASEBOARD_FAB2(SCH_1):PAGE137
     2    GND @BASEBOARD_FAB2_LIB.BASEBOARD_FAB2(SCH_1):GND    I14 @BASEBOARD_FAB2_LIB.BASEBOARD_FAB2(SCH_1):PAGE137

C7C20 CAP_A_0402V-1.0UF,6.3V,10%,X6SA
     1 P5V_STBY @BASEBOARD_FAB2_LIB.BASEBOARD_FAB2(SCH_1):P5V_STBY    I34 @BASEBOARD_FAB2_LIB.BASEBOARD_FAB2(SCH_1):PAGE212
     2    GND @BASEBOARD_FAB2_LIB.BASEBOARD_FAB2(SCH_1):GND    I34 @BASEBOARD_FAB2_LIB.BASEBOARD_FAB2(SCH_1):PAGE212

C7D1 CAP_A_0402V-0.1UF,16V,10%,X7R,A
     1 P3V3_STBY @BASEBOARD_FAB2_LIB.BASEBOARD_FAB2(SCH_1):P3V3_STBY   I136 @BASEBOARD_FAB2_LIB.BASEBOARD_FAB2(SCH_1):PAGE118
     2    GND @BASEBOARD_FAB2_LIB.BASEBOARD_FAB2(SCH_1):GND   I136 @BASEBOARD_FAB2_LIB.BASEBOARD_FAB2(SCH_1):PAGE118

C7D2 CAP_0603-10UF,6.3V,20%,X6S,E15A
     1 P3V3_STBY @BASEBOARD_FAB2_LIB.BASEBOARD_FAB2(SCH_1):P3V3_STBY     I2 @BASEBOARD_FAB2_LIB.BASEBOARD_FAB2(SCH_1):PAGE130
     2    GND @BASEBOARD_FAB2_LIB.BASEBOARD_FAB2(SCH_1):GND     I2 @BASEBOARD_FAB2_LIB.BASEBOARD_FAB2(SCH_1):PAGE130

C7D3 CAP_A_0603V-22.0UF,4V,20%,X6S,A
     1 P1V8_PCH_STBY @BASEBOARD_FAB2_LIB.BASEBOARD_FAB2(SCH_1):P1V8_PCH_STBY    I38 @BASEBOARD_FAB2_LIB.BASEBOARD_FAB2(SCH_1):PAGE130
     2    GND @BASEBOARD_FAB2_LIB.BASEBOARD_FAB2(SCH_1):GND    I38 @BASEBOARD_FAB2_LIB.BASEBOARD_FAB2(SCH_1):PAGE130

C7D4 CAP_0402-1.0UF,16V,10%,X6S,D97A
     1   P3V3 @BASEBOARD_FAB2_LIB.BASEBOARD_FAB2(SCH_1):P3V3    I79 @BASEBOARD_FAB2_LIB.BASEBOARD_FAB2(SCH_1):PAGE92
     2    GND @BASEBOARD_FAB2_LIB.BASEBOARD_FAB2(SCH_1):GND    I79 @BASEBOARD_FAB2_LIB.BASEBOARD_FAB2(SCH_1):PAGE92

C7D5 CAP_A_0402V-0.1UF,16V,10%,X7R,A
     1 P0V7_GTL2104_VREF_0 @BASEBOARD_FAB2_LIB.BASEBOARD_FAB2(SCH_1):P0V7_GTL2104_VREF_0    I52 @BASEBOARD_FAB2_LIB.BASEBOARD_FAB2(SCH_1):PAGE92
     2    GND @BASEBOARD_FAB2_LIB.BASEBOARD_FAB2(SCH_1):GND    I52 @BASEBOARD_FAB2_LIB.BASEBOARD_FAB2(SCH_1):PAGE92

C7E1 CAP_A_0402V-0.1UF,16V,10%,X7R,A
     1 PVCCIO_CPU0 @BASEBOARD_FAB2_LIB.BASEBOARD_FAB2(SCH_1):PVCCIO_CPU0    I23 @BASEBOARD_FAB2_LIB.BASEBOARD_FAB2(SCH_1):PAGE99
     2    GND @BASEBOARD_FAB2_LIB.BASEBOARD_FAB2(SCH_1):GND    I23 @BASEBOARD_FAB2_LIB.BASEBOARD_FAB2(SCH_1):PAGE99

C7E2 CAP_A_0402V-0.1UF,16V,10%,X7R,A
     1 PVPP_DEF @BASEBOARD_FAB2_LIB.BASEBOARD_FAB2(SCH_1):PVPP_DEF    I32 @BASEBOARD_FAB2_LIB.BASEBOARD_FAB2(SCH_1):PAGE99
     2    GND @BASEBOARD_FAB2_LIB.BASEBOARD_FAB2(SCH_1):GND    I32 @BASEBOARD_FAB2_LIB.BASEBOARD_FAB2(SCH_1):PAGE99

C7E3 CAP_A_0402V-0.1UF,16V,10%,X7R,A
     1 P3V3_STBY @BASEBOARD_FAB2_LIB.BASEBOARD_FAB2(SCH_1):P3V3_STBY    I92 @BASEBOARD_FAB2_LIB.BASEBOARD_FAB2(SCH_1):PAGE95
     2    GND @BASEBOARD_FAB2_LIB.BASEBOARD_FAB2(SCH_1):GND    I92 @BASEBOARD_FAB2_LIB.BASEBOARD_FAB2(SCH_1):PAGE95

C7E4 CAP_A_0402V-0.1UF,16V,10%,X7R,A
     1 P3V3_STBY @BASEBOARD_FAB2_LIB.BASEBOARD_FAB2(SCH_1):P3V3_STBY   I115 @BASEBOARD_FAB2_LIB.BASEBOARD_FAB2(SCH_1):PAGE95
     2    GND @BASEBOARD_FAB2_LIB.BASEBOARD_FAB2(SCH_1):GND   I115 @BASEBOARD_FAB2_LIB.BASEBOARD_FAB2(SCH_1):PAGE95

C7E5 CAP_A_0402V-0.1UF,16V,10%,X7R,A
     1 P12V_STBY @BASEBOARD_FAB2_LIB.BASEBOARD_FAB2(SCH_1):P12V_STBY    I52 @BASEBOARD_FAB2_LIB.BASEBOARD_FAB2(SCH_1):PAGE198
     2    GND @BASEBOARD_FAB2_LIB.BASEBOARD_FAB2(SCH_1):GND    I52 @BASEBOARD_FAB2_LIB.BASEBOARD_FAB2(SCH_1):PAGE198

C7E6 CAP_0805-10UF,16V,10%,X6S,C953A
     1 P12V_STBY @BASEBOARD_FAB2_LIB.BASEBOARD_FAB2(SCH_1):P12V_STBY    I53 @BASEBOARD_FAB2_LIB.BASEBOARD_FAB2(SCH_1):PAGE198
     2    GND @BASEBOARD_FAB2_LIB.BASEBOARD_FAB2(SCH_1):GND    I53 @BASEBOARD_FAB2_LIB.BASEBOARD_FAB2(SCH_1):PAGE198

C7E8 CAP_0805-10UF,16V,10%,X6S,C953A
     1   P12V @BASEBOARD_FAB2_LIB.BASEBOARD_FAB2(SCH_1):P12V    I50 @BASEBOARD_FAB2_LIB.BASEBOARD_FAB2(SCH_1):PAGE198
     2    GND @BASEBOARD_FAB2_LIB.BASEBOARD_FAB2(SCH_1):GND    I50 @BASEBOARD_FAB2_LIB.BASEBOARD_FAB2(SCH_1):PAGE198

C7E9 CAP_A_0402V-0.1UF,16V,10%,X7R,A
     1   P12V @BASEBOARD_FAB2_LIB.BASEBOARD_FAB2(SCH_1):P12V    I49 @BASEBOARD_FAB2_LIB.BASEBOARD_FAB2(SCH_1):PAGE198
     2    GND @BASEBOARD_FAB2_LIB.BASEBOARD_FAB2(SCH_1):GND    I49 @BASEBOARD_FAB2_LIB.BASEBOARD_FAB2(SCH_1):PAGE198

C7E10 CAP_0402LF-1000PF,50V,10%,X7R,A
     1 PWRGD_P5V_STBY_R @BASEBOARD_FAB2_LIB.BASEBOARD_FAB2(SCH_1):PWRGD_P5V_STBY_R    I14 @BASEBOARD_FAB2_LIB.BASEBOARD_FAB2(SCH_1):PAGE241
     2    GND @BASEBOARD_FAB2_LIB.BASEBOARD_FAB2(SCH_1):GND    I14 @BASEBOARD_FAB2_LIB.BASEBOARD_FAB2(SCH_1):PAGE241

C7E11 CAP_1206LF-22UF,16V,10%,X6S,D3A
     1 VR_FET_SW_P5V_STBY_PVIN @BASEBOARD_FAB2_LIB.BASEBOARD_FAB2(SCH_1):VR_FET_SW_P5V_STBY_PVIN    I39 @BASEBOARD_FAB2_LIB.BASEBOARD_FAB2(SCH_1):PAGE241
     2    GND @BASEBOARD_FAB2_LIB.BASEBOARD_FAB2(SCH_1):GND    I39 @BASEBOARD_FAB2_LIB.BASEBOARD_FAB2(SCH_1):PAGE241

C7E12 CAP_1210-47UF,16V,20%,X6S,D384A
     1 VR_FET_SW_P5V_STBY_PVIN @BASEBOARD_FAB2_LIB.BASEBOARD_FAB2(SCH_1):VR_FET_SW_P5V_STBY_PVIN    I47 @BASEBOARD_FAB2_LIB.BASEBOARD_FAB2(SCH_1):PAGE241
     2    GND @BASEBOARD_FAB2_LIB.BASEBOARD_FAB2(SCH_1):GND    I47 @BASEBOARD_FAB2_LIB.BASEBOARD_FAB2(SCH_1):PAGE241

C7E13 CAP_1210-47UF,16V,20%,X6S,D384A
     1 VR_FET_SW_P5V_STBY_PVIN @BASEBOARD_FAB2_LIB.BASEBOARD_FAB2(SCH_1):VR_FET_SW_P5V_STBY_PVIN    I45 @BASEBOARD_FAB2_LIB.BASEBOARD_FAB2(SCH_1):PAGE241
     2    GND @BASEBOARD_FAB2_LIB.BASEBOARD_FAB2(SCH_1):GND    I45 @BASEBOARD_FAB2_LIB.BASEBOARD_FAB2(SCH_1):PAGE241

C7E14 CAP_0402-1.0UF,16V,10%,X6S,D97A
     1 VR_P5V_STBY_VIN @BASEBOARD_FAB2_LIB.BASEBOARD_FAB2(SCH_1):VR_P5V_STBY_VIN    I30 @BASEBOARD_FAB2_LIB.BASEBOARD_FAB2(SCH_1):PAGE241
     2    GND @BASEBOARD_FAB2_LIB.BASEBOARD_FAB2(SCH_1):GND    I30 @BASEBOARD_FAB2_LIB.BASEBOARD_FAB2(SCH_1):PAGE241

C7F1 CAP_A_0402V-0.01UF,25V,10%,X7RA
     1 P3V3_STBY @BASEBOARD_FAB2_LIB.BASEBOARD_FAB2(SCH_1):P3V3_STBY   I131 @BASEBOARD_FAB2_LIB.BASEBOARD_FAB2(SCH_1):PAGE153
     2    GND @BASEBOARD_FAB2_LIB.BASEBOARD_FAB2(SCH_1):GND   I131 @BASEBOARD_FAB2_LIB.BASEBOARD_FAB2(SCH_1):PAGE153

C7F2 CAP_A_0402V-1.0UF,6.3V,10%,X6SA
     1 P3V3_STBY @BASEBOARD_FAB2_LIB.BASEBOARD_FAB2(SCH_1):P3V3_STBY   I130 @BASEBOARD_FAB2_LIB.BASEBOARD_FAB2(SCH_1):PAGE153
     2    GND @BASEBOARD_FAB2_LIB.BASEBOARD_FAB2(SCH_1):GND   I130 @BASEBOARD_FAB2_LIB.BASEBOARD_FAB2(SCH_1):PAGE153

C7F3 CAP_0402LF-3300PF,50V,10%,EMPTA
     1 VR_PVPP_ABC_PHASE @BASEBOARD_FAB2_LIB.BASEBOARD_FAB2(SCH_1):VR_PVPP_ABC_PHASE   I175 @BASEBOARD_FAB2_LIB.BASEBOARD_FAB2(SCH_1):PAGE231
     2 VR_PVPP_ABC_SNUB @BASEBOARD_FAB2_LIB.BASEBOARD_FAB2(SCH_1):VR_PVPP_ABC_SNUB   I175 @BASEBOARD_FAB2_LIB.BASEBOARD_FAB2(SCH_1):PAGE231

C7F4 CAP_0603LF-0.1UF,25V,10%,X7R,6A
     1 VR_PVPP_ABC_PHASE @BASEBOARD_FAB2_LIB.BASEBOARD_FAB2(SCH_1):VR_PVPP_ABC_PHASE   I159 @BASEBOARD_FAB2_LIB.BASEBOARD_FAB2(SCH_1):PAGE231
     2 VR_PVPP_ABC_BOOT_R @BASEBOARD_FAB2_LIB.BASEBOARD_FAB2(SCH_1):VR_PVPP_ABC_BOOT_R   I159 @BASEBOARD_FAB2_LIB.BASEBOARD_FAB2(SCH_1):PAGE231

C7F5 CAP_0805-10UF,16V,10%,X6S,C953A
     1 VR_FET_SW_P12V_STBY_PVPP_ABC @BASEBOARD_FAB2_LIB.BASEBOARD_FAB2(SCH_1):VR_FET_SW_P12V_STBY_PVPP_ABC   I209 @BASEBOARD_FAB2_LIB.BASEBOARD_FAB2(SCH_1):PAGE231
     2    GND @BASEBOARD_FAB2_LIB.BASEBOARD_FAB2(SCH_1):GND   I209 @BASEBOARD_FAB2_LIB.BASEBOARD_FAB2(SCH_1):PAGE231

C7F6 CAP_A_0402V-0.1UF,16V,10%,X7R,A
     1 VR_FET_SW_P12V_STBY_PVPP_ABC @BASEBOARD_FAB2_LIB.BASEBOARD_FAB2(SCH_1):VR_FET_SW_P12V_STBY_PVPP_ABC   I205 @BASEBOARD_FAB2_LIB.BASEBOARD_FAB2(SCH_1):PAGE231
     2    GND @BASEBOARD_FAB2_LIB.BASEBOARD_FAB2(SCH_1):GND   I205 @BASEBOARD_FAB2_LIB.BASEBOARD_FAB2(SCH_1):PAGE231

C7F7 CAP_1210-47UF,16V,20%,X6S,D384A
     1 VR_FET_SW_P12V_STBY_PVPP_ABC @BASEBOARD_FAB2_LIB.BASEBOARD_FAB2(SCH_1):VR_FET_SW_P12V_STBY_PVPP_ABC   I151 @BASEBOARD_FAB2_LIB.BASEBOARD_FAB2(SCH_1):PAGE231
     2    GND @BASEBOARD_FAB2_LIB.BASEBOARD_FAB2(SCH_1):GND   I151 @BASEBOARD_FAB2_LIB.BASEBOARD_FAB2(SCH_1):PAGE231

C7F8 CAP_0402LF-1000PF,50V,10%,EMPTA
     1 FM_PVPP_CPU0_EN @BASEBOARD_FAB2_LIB.BASEBOARD_FAB2(SCH_1):FM_PVPP_CPU0_EN   I140 @BASEBOARD_FAB2_LIB.BASEBOARD_FAB2(SCH_1):PAGE231
     2 AGND_PVPP_ABC @BASEBOARD_FAB2_LIB.BASEBOARD_FAB2(SCH_1):AGND_PVPP_ABC   I140 @BASEBOARD_FAB2_LIB.BASEBOARD_FAB2(SCH_1):PAGE231

C7F9 CAP_0402LF-100.0PF,50V,5%,COG,A
     1 VR_FB_PVPP_ABC @BASEBOARD_FAB2_LIB.BASEBOARD_FAB2(SCH_1):VR_FB_PVPP_ABC   I199 @BASEBOARD_FAB2_LIB.BASEBOARD_FAB2(SCH_1):PAGE231
     2 VR_COMP_PVPP_ABC_3 @BASEBOARD_FAB2_LIB.BASEBOARD_FAB2(SCH_1):VR_COMP_PVPP_ABC_3   I199 @BASEBOARD_FAB2_LIB.BASEBOARD_FAB2(SCH_1):PAGE231

C7F10 CAP_0402-0.027UF,16V,10%,X7R,AA
     1 VR_PVPP_ABC_SS @BASEBOARD_FAB2_LIB.BASEBOARD_FAB2(SCH_1):VR_PVPP_ABC_SS   I194 @BASEBOARD_FAB2_LIB.BASEBOARD_FAB2(SCH_1):PAGE231
     2 AGND_PVPP_ABC @BASEBOARD_FAB2_LIB.BASEBOARD_FAB2(SCH_1):AGND_PVPP_ABC   I194 @BASEBOARD_FAB2_LIB.BASEBOARD_FAB2(SCH_1):PAGE231

C7F11 CAP_0402LF-1000PF,50V,10%,X7R,A
     1 PWRGD_PVPP_ABC_R @BASEBOARD_FAB2_LIB.BASEBOARD_FAB2(SCH_1):PWRGD_PVPP_ABC_R   I142 @BASEBOARD_FAB2_LIB.BASEBOARD_FAB2(SCH_1):PAGE231
     2    GND @BASEBOARD_FAB2_LIB.BASEBOARD_FAB2(SCH_1):GND   I142 @BASEBOARD_FAB2_LIB.BASEBOARD_FAB2(SCH_1):PAGE231

C7F12 CAP_0402LF-2200PF,50V,10%,X7R,A
     1 VR_COMP_RC_PVPP_ABC @BASEBOARD_FAB2_LIB.BASEBOARD_FAB2(SCH_1):VR_COMP_RC_PVPP_ABC   I200 @BASEBOARD_FAB2_LIB.BASEBOARD_FAB2(SCH_1):PAGE231
     2 VR_COMP_PVPP_ABC_3 @BASEBOARD_FAB2_LIB.BASEBOARD_FAB2(SCH_1):VR_COMP_PVPP_ABC_3   I200 @BASEBOARD_FAB2_LIB.BASEBOARD_FAB2(SCH_1):PAGE231

C7F13 CAP_0402LF-2200PF,50V,10%,X7R,A
     1 VR_COMP_PVPP_ABC @BASEBOARD_FAB2_LIB.BASEBOARD_FAB2(SCH_1):VR_COMP_PVPP_ABC   I219 @BASEBOARD_FAB2_LIB.BASEBOARD_FAB2(SCH_1):PAGE231
     2 VR_FB_PVPP_ABC @BASEBOARD_FAB2_LIB.BASEBOARD_FAB2(SCH_1):VR_FB_PVPP_ABC   I219 @BASEBOARD_FAB2_LIB.BASEBOARD_FAB2(SCH_1):PAGE231

C7F14 CAP_0402LF-1000PF,50V,10%,X7R,A
     1 PWRGD_PVDDQ_ABC_R @BASEBOARD_FAB2_LIB.BASEBOARD_FAB2(SCH_1):PWRGD_PVDDQ_ABC_R   I305 @BASEBOARD_FAB2_LIB.BASEBOARD_FAB2(SCH_1):PAGE215
     2    GND @BASEBOARD_FAB2_LIB.BASEBOARD_FAB2(SCH_1):GND   I305 @BASEBOARD_FAB2_LIB.BASEBOARD_FAB2(SCH_1):PAGE215

C7F15 CAP_A_0402V-0.1UF,16V,10%,X7R,A
     1 VR_PVDDQ_ABC_VD12 @BASEBOARD_FAB2_LIB.BASEBOARD_FAB2(SCH_1):VR_PVDDQ_ABC_VD12   I327 @BASEBOARD_FAB2_LIB.BASEBOARD_FAB2(SCH_1):PAGE215
     2    GND @BASEBOARD_FAB2_LIB.BASEBOARD_FAB2(SCH_1):GND   I327 @BASEBOARD_FAB2_LIB.BASEBOARD_FAB2(SCH_1):PAGE215

C7F16 CAP_A_0402V-1.0UF,6.3V,10%,X6SA
     1 VR_PVDDQ_ABC_VD12 @BASEBOARD_FAB2_LIB.BASEBOARD_FAB2(SCH_1):VR_PVDDQ_ABC_VD12   I325 @BASEBOARD_FAB2_LIB.BASEBOARD_FAB2(SCH_1):PAGE215
     2    GND @BASEBOARD_FAB2_LIB.BASEBOARD_FAB2(SCH_1):GND   I325 @BASEBOARD_FAB2_LIB.BASEBOARD_FAB2(SCH_1):PAGE215

C7F17 CAP_A_0402V-0.1UF,16V,10%,X7R,A
     1 VR_PVDDQ_ABC_VDD @BASEBOARD_FAB2_LIB.BASEBOARD_FAB2(SCH_1):VR_PVDDQ_ABC_VDD   I311 @BASEBOARD_FAB2_LIB.BASEBOARD_FAB2(SCH_1):PAGE215
     2    GND @BASEBOARD_FAB2_LIB.BASEBOARD_FAB2(SCH_1):GND   I311 @BASEBOARD_FAB2_LIB.BASEBOARD_FAB2(SCH_1):PAGE215

C7F18 CAP_A_0402V-1.0UF,6.3V,10%,X6SA
     1 VR_PVDDQ_ABC_VDD @BASEBOARD_FAB2_LIB.BASEBOARD_FAB2(SCH_1):VR_PVDDQ_ABC_VDD   I309 @BASEBOARD_FAB2_LIB.BASEBOARD_FAB2(SCH_1):PAGE215
     2    GND @BASEBOARD_FAB2_LIB.BASEBOARD_FAB2(SCH_1):GND   I309 @BASEBOARD_FAB2_LIB.BASEBOARD_FAB2(SCH_1):PAGE215

C7G1 CAP_0402LF-1000PF,50V,10%,X7R,A
     1 VR_PVDDQ_ABC_VINSEN @BASEBOARD_FAB2_LIB.BASEBOARD_FAB2(SCH_1):VR_PVDDQ_ABC_VINSEN   I339 @BASEBOARD_FAB2_LIB.BASEBOARD_FAB2(SCH_1):PAGE215
     2    GND @BASEBOARD_FAB2_LIB.BASEBOARD_FAB2(SCH_1):GND   I339 @BASEBOARD_FAB2_LIB.BASEBOARD_FAB2(SCH_1):PAGE215

C7G2 CAPP_2626-270UF,16V,20%,OSCON,A
     1 VR_FET_SW_P12V_STBY_PVDDQ_ABC @BASEBOARD_FAB2_LIB.BASEBOARD_FAB2(SCH_1):VR_FET_SW_P12V_STBY_PVDDQ_ABC   I175 @BASEBOARD_FAB2_LIB.BASEBOARD_FAB2(SCH_1):PAGE217
     2    GND @BASEBOARD_FAB2_LIB.BASEBOARD_FAB2(SCH_1):GND   I175 @BASEBOARD_FAB2_LIB.BASEBOARD_FAB2(SCH_1):PAGE217

C7G3 CAP_0402LF-220PF,50V,10%,X7R,AA
     1 A_TSENSE_PVDDQ_ABC @BASEBOARD_FAB2_LIB.BASEBOARD_FAB2(SCH_1):A_TSENSE_PVDDQ_ABC   I320 @BASEBOARD_FAB2_LIB.BASEBOARD_FAB2(SCH_1):PAGE215
     2    GND @BASEBOARD_FAB2_LIB.BASEBOARD_FAB2(SCH_1):GND   I320 @BASEBOARD_FAB2_LIB.BASEBOARD_FAB2(SCH_1):PAGE215

C7G4 CAP_0402LF-220PF,50V,10%,X7R,AA
     1 VR_PVDDQ_ABC_AVSP @BASEBOARD_FAB2_LIB.BASEBOARD_FAB2(SCH_1):VR_PVDDQ_ABC_AVSP   I342 @BASEBOARD_FAB2_LIB.BASEBOARD_FAB2(SCH_1):PAGE215
     2 VSENSE_PVDDQ_ABC_N @BASEBOARD_FAB2_LIB.BASEBOARD_FAB2(SCH_1):VSENSE_PVDDQ_ABC_N   I342 @BASEBOARD_FAB2_LIB.BASEBOARD_FAB2(SCH_1):PAGE215

C7G5 CAP_0402-0.22UF,16V,10%,X7R,A3A
     1 P3E_CPU0_PE2_SS_TXP<15> @BASEBOARD_FAB2_LIB.BASEBOARD_FAB2(SCH_1):P3E_CPU0_PE2_SS_TXP(15)    I20 @BASEBOARD_FAB2_LIB.BASEBOARD_FAB2(SCH_1):PAGE105
     2 P3E_CPU0_PE2_SS_C_TXP<15> @BASEBOARD_FAB2_LIB.BASEBOARD_FAB2(SCH_1):P3E_CPU0_PE2_SS_C_TXP(15)    I20 @BASEBOARD_FAB2_LIB.BASEBOARD_FAB2(SCH_1):PAGE105

C7G6 CAP_0402-0.22UF,16V,10%,X7R,A3A
     1 P3E_CPU0_PE2_SS_TXN<15> @BASEBOARD_FAB2_LIB.BASEBOARD_FAB2(SCH_1):P3E_CPU0_PE2_SS_TXN(15)     I6 @BASEBOARD_FAB2_LIB.BASEBOARD_FAB2(SCH_1):PAGE105
     2 P3E_CPU0_PE2_SS_C_TXN<15> @BASEBOARD_FAB2_LIB.BASEBOARD_FAB2(SCH_1):P3E_CPU0_PE2_SS_C_TXN(15)     I6 @BASEBOARD_FAB2_LIB.BASEBOARD_FAB2(SCH_1):PAGE105

C7G7 CAP_0402-0.22UF,16V,10%,X7R,A3A
     1 P3E_CPU0_PE2_SS_TXN<14> @BASEBOARD_FAB2_LIB.BASEBOARD_FAB2(SCH_1):P3E_CPU0_PE2_SS_TXN(14)     I7 @BASEBOARD_FAB2_LIB.BASEBOARD_FAB2(SCH_1):PAGE105
     2 P3E_CPU0_PE2_SS_C_TXN<14> @BASEBOARD_FAB2_LIB.BASEBOARD_FAB2(SCH_1):P3E_CPU0_PE2_SS_C_TXN(14)     I7 @BASEBOARD_FAB2_LIB.BASEBOARD_FAB2(SCH_1):PAGE105

C7G8 CAP_0402-0.22UF,16V,10%,X7R,A3A
     1 P3E_CPU0_PE2_SS_TXP<14> @BASEBOARD_FAB2_LIB.BASEBOARD_FAB2(SCH_1):P3E_CPU0_PE2_SS_TXP(14)    I22 @BASEBOARD_FAB2_LIB.BASEBOARD_FAB2(SCH_1):PAGE105
     2 P3E_CPU0_PE2_SS_C_TXP<14> @BASEBOARD_FAB2_LIB.BASEBOARD_FAB2(SCH_1):P3E_CPU0_PE2_SS_C_TXP(14)    I22 @BASEBOARD_FAB2_LIB.BASEBOARD_FAB2(SCH_1):PAGE105

C7G9 CAP_0402-0.22UF,16V,10%,X7R,A3A
     1 P3E_CPU0_PE2_SS_TXP<13> @BASEBOARD_FAB2_LIB.BASEBOARD_FAB2(SCH_1):P3E_CPU0_PE2_SS_TXP(13)    I21 @BASEBOARD_FAB2_LIB.BASEBOARD_FAB2(SCH_1):PAGE105
     2 P3E_CPU0_PE2_SS_C_TXP<13> @BASEBOARD_FAB2_LIB.BASEBOARD_FAB2(SCH_1):P3E_CPU0_PE2_SS_C_TXP(13)    I21 @BASEBOARD_FAB2_LIB.BASEBOARD_FAB2(SCH_1):PAGE105

C7G10 CAP_0402-0.22UF,16V,10%,X7R,A3A
     1 P3E_CPU0_PE2_SS_TXN<13> @BASEBOARD_FAB2_LIB.BASEBOARD_FAB2(SCH_1):P3E_CPU0_PE2_SS_TXN(13)     I8 @BASEBOARD_FAB2_LIB.BASEBOARD_FAB2(SCH_1):PAGE105
     2 P3E_CPU0_PE2_SS_C_TXN<13> @BASEBOARD_FAB2_LIB.BASEBOARD_FAB2(SCH_1):P3E_CPU0_PE2_SS_C_TXN(13)     I8 @BASEBOARD_FAB2_LIB.BASEBOARD_FAB2(SCH_1):PAGE105

C7G11 CAP_0402-0.22UF,16V,10%,X7R,A3A
     1 P3E_CPU0_PE2_SS_TXP<12> @BASEBOARD_FAB2_LIB.BASEBOARD_FAB2(SCH_1):P3E_CPU0_PE2_SS_TXP(12)    I27 @BASEBOARD_FAB2_LIB.BASEBOARD_FAB2(SCH_1):PAGE105
     2 P3E_CPU0_PE2_SS_C_TXP<12> @BASEBOARD_FAB2_LIB.BASEBOARD_FAB2(SCH_1):P3E_CPU0_PE2_SS_C_TXP(12)    I27 @BASEBOARD_FAB2_LIB.BASEBOARD_FAB2(SCH_1):PAGE105

C7G12 CAP_0402-0.22UF,16V,10%,X7R,A3A
     1 P3E_CPU0_PE2_SS_TXN<12> @BASEBOARD_FAB2_LIB.BASEBOARD_FAB2(SCH_1):P3E_CPU0_PE2_SS_TXN(12)    I12 @BASEBOARD_FAB2_LIB.BASEBOARD_FAB2(SCH_1):PAGE105
     2 P3E_CPU0_PE2_SS_C_TXN<12> @BASEBOARD_FAB2_LIB.BASEBOARD_FAB2(SCH_1):P3E_CPU0_PE2_SS_C_TXN(12)    I12 @BASEBOARD_FAB2_LIB.BASEBOARD_FAB2(SCH_1):PAGE105

C7G13 CAP_0402-0.22UF,16V,10%,X7R,A3A
     1 P3E_CPU0_PE2_SS_TXN<11> @BASEBOARD_FAB2_LIB.BASEBOARD_FAB2(SCH_1):P3E_CPU0_PE2_SS_TXN(11)    I13 @BASEBOARD_FAB2_LIB.BASEBOARD_FAB2(SCH_1):PAGE105
     2 P3E_CPU0_PE2_SS_C_TXN<11> @BASEBOARD_FAB2_LIB.BASEBOARD_FAB2(SCH_1):P3E_CPU0_PE2_SS_C_TXN(11)    I13 @BASEBOARD_FAB2_LIB.BASEBOARD_FAB2(SCH_1):PAGE105

C7G14 CAP_0402-0.22UF,16V,10%,X7R,A3A
     1 P3E_CPU0_PE2_SS_TXP<11> @BASEBOARD_FAB2_LIB.BASEBOARD_FAB2(SCH_1):P3E_CPU0_PE2_SS_TXP(11)    I28 @BASEBOARD_FAB2_LIB.BASEBOARD_FAB2(SCH_1):PAGE105
     2 P3E_CPU0_PE2_SS_C_TXP<11> @BASEBOARD_FAB2_LIB.BASEBOARD_FAB2(SCH_1):P3E_CPU0_PE2_SS_C_TXP(11)    I28 @BASEBOARD_FAB2_LIB.BASEBOARD_FAB2(SCH_1):PAGE105

C7G15 CAP_0402-0.22UF,16V,10%,X7R,A3A
     1 P3E_CPU0_PE2_SS_TXP<10> @BASEBOARD_FAB2_LIB.BASEBOARD_FAB2(SCH_1):P3E_CPU0_PE2_SS_TXP(10)    I45 @BASEBOARD_FAB2_LIB.BASEBOARD_FAB2(SCH_1):PAGE105
     2 P3E_CPU0_PE2_SS_C_TXP<10> @BASEBOARD_FAB2_LIB.BASEBOARD_FAB2(SCH_1):P3E_CPU0_PE2_SS_C_TXP(10)    I45 @BASEBOARD_FAB2_LIB.BASEBOARD_FAB2(SCH_1):PAGE105

C7G16 CAP_0402-0.22UF,16V,10%,X7R,A3A
     1 P3E_CPU0_PE2_SS_TXN<10> @BASEBOARD_FAB2_LIB.BASEBOARD_FAB2(SCH_1):P3E_CPU0_PE2_SS_TXN(10)    I31 @BASEBOARD_FAB2_LIB.BASEBOARD_FAB2(SCH_1):PAGE105
     2 P3E_CPU0_PE2_SS_C_TXN<10> @BASEBOARD_FAB2_LIB.BASEBOARD_FAB2(SCH_1):P3E_CPU0_PE2_SS_C_TXN(10)    I31 @BASEBOARD_FAB2_LIB.BASEBOARD_FAB2(SCH_1):PAGE105

C7G17 CAP_0402-0.22UF,16V,10%,X7R,A3A
     1 P3E_CPU0_PE2_SS_TXP<9> @BASEBOARD_FAB2_LIB.BASEBOARD_FAB2(SCH_1):P3E_CPU0_PE2_SS_TXP(9)    I44 @BASEBOARD_FAB2_LIB.BASEBOARD_FAB2(SCH_1):PAGE105
     2 P3E_CPU0_PE2_SS_C_TXP<9> @BASEBOARD_FAB2_LIB.BASEBOARD_FAB2(SCH_1):P3E_CPU0_PE2_SS_C_TXP(9)    I44 @BASEBOARD_FAB2_LIB.BASEBOARD_FAB2(SCH_1):PAGE105

C7G18 CAP_0402-0.22UF,16V,10%,X7R,A3A
     1 P3E_CPU0_PE2_SS_TXN<9> @BASEBOARD_FAB2_LIB.BASEBOARD_FAB2(SCH_1):P3E_CPU0_PE2_SS_TXN(9)    I32 @BASEBOARD_FAB2_LIB.BASEBOARD_FAB2(SCH_1):PAGE105
     2 P3E_CPU0_PE2_SS_C_TXN<9> @BASEBOARD_FAB2_LIB.BASEBOARD_FAB2(SCH_1):P3E_CPU0_PE2_SS_C_TXN(9)    I32 @BASEBOARD_FAB2_LIB.BASEBOARD_FAB2(SCH_1):PAGE105

C7G19 CAP_0402-0.22UF,16V,10%,X7R,A3A
     1 P3E_CPU0_PE2_SS_TXP<8> @BASEBOARD_FAB2_LIB.BASEBOARD_FAB2(SCH_1):P3E_CPU0_PE2_SS_TXP(8)    I46 @BASEBOARD_FAB2_LIB.BASEBOARD_FAB2(SCH_1):PAGE105
     2 P3E_CPU0_PE2_SS_C_TXP<8> @BASEBOARD_FAB2_LIB.BASEBOARD_FAB2(SCH_1):P3E_CPU0_PE2_SS_C_TXP(8)    I46 @BASEBOARD_FAB2_LIB.BASEBOARD_FAB2(SCH_1):PAGE105

C7G20 CAP_0402-0.22UF,16V,10%,X7R,A3A
     1 P3E_CPU0_PE2_SS_TXN<8> @BASEBOARD_FAB2_LIB.BASEBOARD_FAB2(SCH_1):P3E_CPU0_PE2_SS_TXN(8)    I34 @BASEBOARD_FAB2_LIB.BASEBOARD_FAB2(SCH_1):PAGE105
     2 P3E_CPU0_PE2_SS_C_TXN<8> @BASEBOARD_FAB2_LIB.BASEBOARD_FAB2(SCH_1):P3E_CPU0_PE2_SS_C_TXN(8)    I34 @BASEBOARD_FAB2_LIB.BASEBOARD_FAB2(SCH_1):PAGE105

C7G21 CAP_0402-0.22UF,16V,10%,X7R,A3A
     1 P3E_CPU0_PE2_SS_TXP<7> @BASEBOARD_FAB2_LIB.BASEBOARD_FAB2(SCH_1):P3E_CPU0_PE2_SS_TXP(7)    I51 @BASEBOARD_FAB2_LIB.BASEBOARD_FAB2(SCH_1):PAGE105
     2 P3E_CPU0_PE2_SS_C_TXP<7> @BASEBOARD_FAB2_LIB.BASEBOARD_FAB2(SCH_1):P3E_CPU0_PE2_SS_C_TXP(7)    I51 @BASEBOARD_FAB2_LIB.BASEBOARD_FAB2(SCH_1):PAGE105

C7G22 CAP_0402-0.22UF,16V,10%,X7R,A3A
     1 P3E_CPU0_PE2_SS_TXN<7> @BASEBOARD_FAB2_LIB.BASEBOARD_FAB2(SCH_1):P3E_CPU0_PE2_SS_TXN(7)    I37 @BASEBOARD_FAB2_LIB.BASEBOARD_FAB2(SCH_1):PAGE105
     2 P3E_CPU0_PE2_SS_C_TXN<7> @BASEBOARD_FAB2_LIB.BASEBOARD_FAB2(SCH_1):P3E_CPU0_PE2_SS_C_TXN(7)    I37 @BASEBOARD_FAB2_LIB.BASEBOARD_FAB2(SCH_1):PAGE105

C7G23 CAP_0402-0.22UF,16V,10%,X7R,A3A
     1 P3E_CPU0_PE2_SS_TXP<6> @BASEBOARD_FAB2_LIB.BASEBOARD_FAB2(SCH_1):P3E_CPU0_PE2_SS_TXP(6)    I52 @BASEBOARD_FAB2_LIB.BASEBOARD_FAB2(SCH_1):PAGE105
     2 P3E_CPU0_PE2_SS_C_TXP<6> @BASEBOARD_FAB2_LIB.BASEBOARD_FAB2(SCH_1):P3E_CPU0_PE2_SS_C_TXP(6)    I52 @BASEBOARD_FAB2_LIB.BASEBOARD_FAB2(SCH_1):PAGE105

C7G24 CAP_0402-0.22UF,16V,10%,X7R,A3A
     1 P3E_CPU0_PE2_SS_TXN<6> @BASEBOARD_FAB2_LIB.BASEBOARD_FAB2(SCH_1):P3E_CPU0_PE2_SS_TXN(6)     I1 @BASEBOARD_FAB2_LIB.BASEBOARD_FAB2(SCH_1):PAGE105
     2 P3E_CPU0_PE2_SS_C_TXN<6> @BASEBOARD_FAB2_LIB.BASEBOARD_FAB2(SCH_1):P3E_CPU0_PE2_SS_C_TXN(6)     I1 @BASEBOARD_FAB2_LIB.BASEBOARD_FAB2(SCH_1):PAGE105

C7G25 CAP_0402-0.22UF,16V,10%,X7R,A3A
     1 P3E_CPU0_PE2_SS_TXP<5> @BASEBOARD_FAB2_LIB.BASEBOARD_FAB2(SCH_1):P3E_CPU0_PE2_SS_TXP(5)    I69 @BASEBOARD_FAB2_LIB.BASEBOARD_FAB2(SCH_1):PAGE105
     2 P3E_CPU0_PE2_SS_C_TXP<5> @BASEBOARD_FAB2_LIB.BASEBOARD_FAB2(SCH_1):P3E_CPU0_PE2_SS_C_TXP(5)    I69 @BASEBOARD_FAB2_LIB.BASEBOARD_FAB2(SCH_1):PAGE105

C7G26 CAP_0402-0.22UF,16V,10%,X7R,A3A
     1 P3E_CPU0_PE2_SS_TXN<5> @BASEBOARD_FAB2_LIB.BASEBOARD_FAB2(SCH_1):P3E_CPU0_PE2_SS_TXN(5)    I55 @BASEBOARD_FAB2_LIB.BASEBOARD_FAB2(SCH_1):PAGE105
     2 P3E_CPU0_PE2_SS_C_TXN<5> @BASEBOARD_FAB2_LIB.BASEBOARD_FAB2(SCH_1):P3E_CPU0_PE2_SS_C_TXN(5)    I55 @BASEBOARD_FAB2_LIB.BASEBOARD_FAB2(SCH_1):PAGE105

C7G27 CAP_0805LF-22UF,4V,20%,X6S,C95A
     1 PVDDQ_ABC @BASEBOARD_FAB2_LIB.BASEBOARD_FAB2(SCH_1):PVDDQ_ABC    I68 @BASEBOARD_FAB2_LIB.BASEBOARD_FAB2(SCH_1):PAGE216
     2    GND @BASEBOARD_FAB2_LIB.BASEBOARD_FAB2(SCH_1):GND    I68 @BASEBOARD_FAB2_LIB.BASEBOARD_FAB2(SCH_1):PAGE216

C7G28 CAPP_3018-470UF,2.5V,20%,ALUM,A
     1 PVDDQ_ABC @BASEBOARD_FAB2_LIB.BASEBOARD_FAB2(SCH_1):PVDDQ_ABC    I75 @BASEBOARD_FAB2_LIB.BASEBOARD_FAB2(SCH_1):PAGE217
     2    GND @BASEBOARD_FAB2_LIB.BASEBOARD_FAB2(SCH_1):GND    I75 @BASEBOARD_FAB2_LIB.BASEBOARD_FAB2(SCH_1):PAGE217

C7G29 CAP_A_0402V-0.1UF,16V,10%,X7R,A
     1 VR_FET_SW_P12V_STBY_PVDDQ_ABC @BASEBOARD_FAB2_LIB.BASEBOARD_FAB2(SCH_1):VR_FET_SW_P12V_STBY_PVDDQ_ABC    I51 @BASEBOARD_FAB2_LIB.BASEBOARD_FAB2(SCH_1):PAGE216
     2    GND @BASEBOARD_FAB2_LIB.BASEBOARD_FAB2(SCH_1):GND    I51 @BASEBOARD_FAB2_LIB.BASEBOARD_FAB2(SCH_1):PAGE216

C7G30 CAP_0402-1.0UF,16V,10%,X6S,D97A
     1 VR_FET_SW_P12V_STBY_PVDDQ_ABC @BASEBOARD_FAB2_LIB.BASEBOARD_FAB2(SCH_1):VR_FET_SW_P12V_STBY_PVDDQ_ABC    I79 @BASEBOARD_FAB2_LIB.BASEBOARD_FAB2(SCH_1):PAGE216
     2    GND @BASEBOARD_FAB2_LIB.BASEBOARD_FAB2(SCH_1):GND    I79 @BASEBOARD_FAB2_LIB.BASEBOARD_FAB2(SCH_1):PAGE216

C7G31 CAP_0402-0.220UF,16V,10%,X7R,AA
     1 VR_PVDDQ_ABC_PH1_BOOT @BASEBOARD_FAB2_LIB.BASEBOARD_FAB2(SCH_1):VR_PVDDQ_ABC_PH1_BOOT    I44 @BASEBOARD_FAB2_LIB.BASEBOARD_FAB2(SCH_1):PAGE216
     2 VR_PVDDQ_ABC_PH1_PHASE @BASEBOARD_FAB2_LIB.BASEBOARD_FAB2(SCH_1):VR_PVDDQ_ABC_PH1_PHASE    I44 @BASEBOARD_FAB2_LIB.BASEBOARD_FAB2(SCH_1):PAGE216

C7G33 CAP_0402-1.0UF,16V,10%,X6S,D97A
     1 VR_PVDDQ_ABC_PH1_VCIN @BASEBOARD_FAB2_LIB.BASEBOARD_FAB2(SCH_1):VR_PVDDQ_ABC_PH1_VCIN    I50 @BASEBOARD_FAB2_LIB.BASEBOARD_FAB2(SCH_1):PAGE216
     2    GND @BASEBOARD_FAB2_LIB.BASEBOARD_FAB2(SCH_1):GND    I50 @BASEBOARD_FAB2_LIB.BASEBOARD_FAB2(SCH_1):PAGE216

C7G34 CAP_0402-0.22UF,16V,10%,X7R,A3A
     1 P5V_STBY @BASEBOARD_FAB2_LIB.BASEBOARD_FAB2(SCH_1):P5V_STBY    I54 @BASEBOARD_FAB2_LIB.BASEBOARD_FAB2(SCH_1):PAGE216
     2    GND @BASEBOARD_FAB2_LIB.BASEBOARD_FAB2(SCH_1):GND    I54 @BASEBOARD_FAB2_LIB.BASEBOARD_FAB2(SCH_1):PAGE216

C7G35 CAP_A_0402V-1.0UF,6.3V,10%,X6SA
     1 P5V_STBY @BASEBOARD_FAB2_LIB.BASEBOARD_FAB2(SCH_1):P5V_STBY    I53 @BASEBOARD_FAB2_LIB.BASEBOARD_FAB2(SCH_1):PAGE216
     2    GND @BASEBOARD_FAB2_LIB.BASEBOARD_FAB2(SCH_1):GND    I53 @BASEBOARD_FAB2_LIB.BASEBOARD_FAB2(SCH_1):PAGE216

C7G36 CAP_A_0402V-0.1UF,16V,10%,X7R,A
     1 VR_FET_SW_P12V_STBY_PVDDQ_ABC @BASEBOARD_FAB2_LIB.BASEBOARD_FAB2(SCH_1):VR_FET_SW_P12V_STBY_PVDDQ_ABC    I78 @BASEBOARD_FAB2_LIB.BASEBOARD_FAB2(SCH_1):PAGE216
     2    GND @BASEBOARD_FAB2_LIB.BASEBOARD_FAB2(SCH_1):GND    I78 @BASEBOARD_FAB2_LIB.BASEBOARD_FAB2(SCH_1):PAGE216

C7G37 CAP_0402-1.0UF,16V,10%,X6S,D97A
     1 VR_FET_SW_P12V_STBY_PVDDQ_ABC @BASEBOARD_FAB2_LIB.BASEBOARD_FAB2(SCH_1):VR_FET_SW_P12V_STBY_PVDDQ_ABC    I48 @BASEBOARD_FAB2_LIB.BASEBOARD_FAB2(SCH_1):PAGE216
     2    GND @BASEBOARD_FAB2_LIB.BASEBOARD_FAB2(SCH_1):GND    I48 @BASEBOARD_FAB2_LIB.BASEBOARD_FAB2(SCH_1):PAGE216

C7G38 CAP_0402-0.220UF,16V,10%,X7R,AA
     1 VR_PVDDQ_ABC_PH2_BOOT @BASEBOARD_FAB2_LIB.BASEBOARD_FAB2(SCH_1):VR_PVDDQ_ABC_PH2_BOOT   I128 @BASEBOARD_FAB2_LIB.BASEBOARD_FAB2(SCH_1):PAGE216
     2 VR_PVDDQ_ABC_PH2_PHASE @BASEBOARD_FAB2_LIB.BASEBOARD_FAB2(SCH_1):VR_PVDDQ_ABC_PH2_PHASE   I128 @BASEBOARD_FAB2_LIB.BASEBOARD_FAB2(SCH_1):PAGE216

C7G40 CAP_0402-1.0UF,16V,10%,X6S,D97A
     1 VR_PVDDQ_ABC_PH2_VCIN @BASEBOARD_FAB2_LIB.BASEBOARD_FAB2(SCH_1):VR_PVDDQ_ABC_PH2_VCIN    I77 @BASEBOARD_FAB2_LIB.BASEBOARD_FAB2(SCH_1):PAGE216
     2    GND @BASEBOARD_FAB2_LIB.BASEBOARD_FAB2(SCH_1):GND    I77 @BASEBOARD_FAB2_LIB.BASEBOARD_FAB2(SCH_1):PAGE216

C7G41 CAP_0402-0.22UF,16V,10%,X7R,A3A
     1 P5V_STBY @BASEBOARD_FAB2_LIB.BASEBOARD_FAB2(SCH_1):P5V_STBY    I72 @BASEBOARD_FAB2_LIB.BASEBOARD_FAB2(SCH_1):PAGE216
     2    GND @BASEBOARD_FAB2_LIB.BASEBOARD_FAB2(SCH_1):GND    I72 @BASEBOARD_FAB2_LIB.BASEBOARD_FAB2(SCH_1):PAGE216

C7G42 CAP_A_0402V-1.0UF,6.3V,10%,X6SA
     1 P5V_STBY @BASEBOARD_FAB2_LIB.BASEBOARD_FAB2(SCH_1):P5V_STBY    I73 @BASEBOARD_FAB2_LIB.BASEBOARD_FAB2(SCH_1):PAGE216
     2    GND @BASEBOARD_FAB2_LIB.BASEBOARD_FAB2(SCH_1):GND    I73 @BASEBOARD_FAB2_LIB.BASEBOARD_FAB2(SCH_1):PAGE216

C7L1 CAP_0805-100UF,4V,20%,X5R,6024A
     1 PVDDQ_KLM @BASEBOARD_FAB2_LIB.BASEBOARD_FAB2(SCH_1):PVDDQ_KLM    I92 @BASEBOARD_FAB2_LIB.BASEBOARD_FAB2(SCH_1):PAGE228
     2    GND @BASEBOARD_FAB2_LIB.BASEBOARD_FAB2(SCH_1):GND    I92 @BASEBOARD_FAB2_LIB.BASEBOARD_FAB2(SCH_1):PAGE228

C7L2 CAP_0603LF-10UF,4V,20%,X6S,E15A
     1 PVPP_KLM @BASEBOARD_FAB2_LIB.BASEBOARD_FAB2(SCH_1):PVPP_KLM    I88 @BASEBOARD_FAB2_LIB.BASEBOARD_FAB2(SCH_1):PAGE234
     2    GND @BASEBOARD_FAB2_LIB.BASEBOARD_FAB2(SCH_1):GND    I88 @BASEBOARD_FAB2_LIB.BASEBOARD_FAB2(SCH_1):PAGE234

C7L3 CAP_0603LF-10UF,4V,20%,X6S,E15A
     1 PVPP_KLM @BASEBOARD_FAB2_LIB.BASEBOARD_FAB2(SCH_1):PVPP_KLM    I87 @BASEBOARD_FAB2_LIB.BASEBOARD_FAB2(SCH_1):PAGE234
     2    GND @BASEBOARD_FAB2_LIB.BASEBOARD_FAB2(SCH_1):GND    I87 @BASEBOARD_FAB2_LIB.BASEBOARD_FAB2(SCH_1):PAGE234

C7L4 CAP_A_0603V-22.0UF,4V,20%,X6S,A
     1 PVDDQ_KLM @BASEBOARD_FAB2_LIB.BASEBOARD_FAB2(SCH_1):PVDDQ_KLM   I238 @BASEBOARD_FAB2_LIB.BASEBOARD_FAB2(SCH_1):PAGE228
     2    GND @BASEBOARD_FAB2_LIB.BASEBOARD_FAB2(SCH_1):GND   I238 @BASEBOARD_FAB2_LIB.BASEBOARD_FAB2(SCH_1):PAGE228

C7L5 CAP_A_0603V-22.0UF,4V,20%,X6S,A
     1 PVDDQ_KLM @BASEBOARD_FAB2_LIB.BASEBOARD_FAB2(SCH_1):PVDDQ_KLM   I225 @BASEBOARD_FAB2_LIB.BASEBOARD_FAB2(SCH_1):PAGE228
     2    GND @BASEBOARD_FAB2_LIB.BASEBOARD_FAB2(SCH_1):GND   I225 @BASEBOARD_FAB2_LIB.BASEBOARD_FAB2(SCH_1):PAGE228

C7L6 CAP_0603LF-10UF,4V,20%,X6S,E15A
     1 PVPP_KLM @BASEBOARD_FAB2_LIB.BASEBOARD_FAB2(SCH_1):PVPP_KLM    I90 @BASEBOARD_FAB2_LIB.BASEBOARD_FAB2(SCH_1):PAGE234
     2    GND @BASEBOARD_FAB2_LIB.BASEBOARD_FAB2(SCH_1):GND    I90 @BASEBOARD_FAB2_LIB.BASEBOARD_FAB2(SCH_1):PAGE234

C7L7 CAP_0603LF-10UF,4V,20%,X6S,E15A
     1 PVPP_KLM @BASEBOARD_FAB2_LIB.BASEBOARD_FAB2(SCH_1):PVPP_KLM    I89 @BASEBOARD_FAB2_LIB.BASEBOARD_FAB2(SCH_1):PAGE234
     2    GND @BASEBOARD_FAB2_LIB.BASEBOARD_FAB2(SCH_1):GND    I89 @BASEBOARD_FAB2_LIB.BASEBOARD_FAB2(SCH_1):PAGE234

C7M1 CAP_A_0603V-22.0UF,4V,20%,X6S,A
     1 PVDDQ_KLM @BASEBOARD_FAB2_LIB.BASEBOARD_FAB2(SCH_1):PVDDQ_KLM   I231 @BASEBOARD_FAB2_LIB.BASEBOARD_FAB2(SCH_1):PAGE228
     2    GND @BASEBOARD_FAB2_LIB.BASEBOARD_FAB2(SCH_1):GND   I231 @BASEBOARD_FAB2_LIB.BASEBOARD_FAB2(SCH_1):PAGE228

C7M2 CAP_A_0603V-22.0UF,4V,20%,X6S,A
     1 PVDDQ_KLM @BASEBOARD_FAB2_LIB.BASEBOARD_FAB2(SCH_1):PVDDQ_KLM   I232 @BASEBOARD_FAB2_LIB.BASEBOARD_FAB2(SCH_1):PAGE228
     2    GND @BASEBOARD_FAB2_LIB.BASEBOARD_FAB2(SCH_1):GND   I232 @BASEBOARD_FAB2_LIB.BASEBOARD_FAB2(SCH_1):PAGE228

C7M3 CAP_0603LF-10UF,4V,20%,X6S,E15A
     1 PVPP_KLM @BASEBOARD_FAB2_LIB.BASEBOARD_FAB2(SCH_1):PVPP_KLM    I92 @BASEBOARD_FAB2_LIB.BASEBOARD_FAB2(SCH_1):PAGE234
     2    GND @BASEBOARD_FAB2_LIB.BASEBOARD_FAB2(SCH_1):GND    I92 @BASEBOARD_FAB2_LIB.BASEBOARD_FAB2(SCH_1):PAGE234

C7M4 CAP_0603LF-10UF,4V,20%,X6S,E15A
     1 PVPP_KLM @BASEBOARD_FAB2_LIB.BASEBOARD_FAB2(SCH_1):PVPP_KLM    I91 @BASEBOARD_FAB2_LIB.BASEBOARD_FAB2(SCH_1):PAGE234
     2    GND @BASEBOARD_FAB2_LIB.BASEBOARD_FAB2(SCH_1):GND    I91 @BASEBOARD_FAB2_LIB.BASEBOARD_FAB2(SCH_1):PAGE234

C7M5 CAP_A_0603V-47UF,4V,20%,X5R,60A
     1 PVDDQ_KLM @BASEBOARD_FAB2_LIB.BASEBOARD_FAB2(SCH_1):PVDDQ_KLM   I202 @BASEBOARD_FAB2_LIB.BASEBOARD_FAB2(SCH_1):PAGE228
     2    GND @BASEBOARD_FAB2_LIB.BASEBOARD_FAB2(SCH_1):GND   I202 @BASEBOARD_FAB2_LIB.BASEBOARD_FAB2(SCH_1):PAGE228

C7M6 CAPP_3018-68UF,16V,20%,TANT,72A
     1 P12V_STBY @BASEBOARD_FAB2_LIB.BASEBOARD_FAB2(SCH_1):P12V_STBY   I108 @BASEBOARD_FAB2_LIB.BASEBOARD_FAB2(SCH_1):PAGE195
     2    GND @BASEBOARD_FAB2_LIB.BASEBOARD_FAB2(SCH_1):GND   I108 @BASEBOARD_FAB2_LIB.BASEBOARD_FAB2(SCH_1):PAGE195

C7P1 CAP_0805-47UF,4V,20%,X6S,C9533A
     1 PVCCIN_CPU1 @BASEBOARD_FAB2_LIB.BASEBOARD_FAB2(SCH_1):PVCCIN_CPU1   I105 @BASEBOARD_FAB2_LIB.BASEBOARD_FAB2(SCH_1):PAGE76
     2    GND @BASEBOARD_FAB2_LIB.BASEBOARD_FAB2(SCH_1):GND   I105 @BASEBOARD_FAB2_LIB.BASEBOARD_FAB2(SCH_1):PAGE76

C7P2 CAP_0805-47UF,4V,20%,X6S,C9533A
     1 PVCCIN_CPU1 @BASEBOARD_FAB2_LIB.BASEBOARD_FAB2(SCH_1):PVCCIN_CPU1   I100 @BASEBOARD_FAB2_LIB.BASEBOARD_FAB2(SCH_1):PAGE76
     2    GND @BASEBOARD_FAB2_LIB.BASEBOARD_FAB2(SCH_1):GND   I100 @BASEBOARD_FAB2_LIB.BASEBOARD_FAB2(SCH_1):PAGE76

C7P3 CAP_0805-47UF,4V,20%,X6S,C9533A
     1 PVCCIO_CPU1 @BASEBOARD_FAB2_LIB.BASEBOARD_FAB2(SCH_1):PVCCIO_CPU1    I52 @BASEBOARD_FAB2_LIB.BASEBOARD_FAB2(SCH_1):PAGE76
     2    GND @BASEBOARD_FAB2_LIB.BASEBOARD_FAB2(SCH_1):GND    I52 @BASEBOARD_FAB2_LIB.BASEBOARD_FAB2(SCH_1):PAGE76

C7P4 CAP_0805-47UF,4V,20%,X6S,C9533A
     1 PVCCMCP_CPU1 @BASEBOARD_FAB2_LIB.BASEBOARD_FAB2(SCH_1):PVCCMCP_CPU1   I195 @BASEBOARD_FAB2_LIB.BASEBOARD_FAB2(SCH_1):PAGE76
     2    GND @BASEBOARD_FAB2_LIB.BASEBOARD_FAB2(SCH_1):GND   I195 @BASEBOARD_FAB2_LIB.BASEBOARD_FAB2(SCH_1):PAGE76

C7P5 CAP_0805-47UF,4V,20%,X6S,C9533A
     1 PVCCMCP_CPU1 @BASEBOARD_FAB2_LIB.BASEBOARD_FAB2(SCH_1):PVCCMCP_CPU1   I182 @BASEBOARD_FAB2_LIB.BASEBOARD_FAB2(SCH_1):PAGE76
     2    GND @BASEBOARD_FAB2_LIB.BASEBOARD_FAB2(SCH_1):GND   I182 @BASEBOARD_FAB2_LIB.BASEBOARD_FAB2(SCH_1):PAGE76

C7P6 CAP_0805-47UF,4V,20%,X6S,C9533A
     1 PVCCMCP_CPU1 @BASEBOARD_FAB2_LIB.BASEBOARD_FAB2(SCH_1):PVCCMCP_CPU1    I23 @BASEBOARD_FAB2_LIB.BASEBOARD_FAB2(SCH_1):PAGE76
     2    GND @BASEBOARD_FAB2_LIB.BASEBOARD_FAB2(SCH_1):GND    I23 @BASEBOARD_FAB2_LIB.BASEBOARD_FAB2(SCH_1):PAGE76

C7P7 CAP_0805-47UF,4V,20%,X6S,C9533A
     1 PVCCMCP_CPU1 @BASEBOARD_FAB2_LIB.BASEBOARD_FAB2(SCH_1):PVCCMCP_CPU1    I27 @BASEBOARD_FAB2_LIB.BASEBOARD_FAB2(SCH_1):PAGE76
     2    GND @BASEBOARD_FAB2_LIB.BASEBOARD_FAB2(SCH_1):GND    I27 @BASEBOARD_FAB2_LIB.BASEBOARD_FAB2(SCH_1):PAGE76

C7P8 CAP_0805-47UF,4V,20%,X6S,C9533A
     1 PVCCMCP_CPU1 @BASEBOARD_FAB2_LIB.BASEBOARD_FAB2(SCH_1):PVCCMCP_CPU1   I184 @BASEBOARD_FAB2_LIB.BASEBOARD_FAB2(SCH_1):PAGE76
     2    GND @BASEBOARD_FAB2_LIB.BASEBOARD_FAB2(SCH_1):GND   I184 @BASEBOARD_FAB2_LIB.BASEBOARD_FAB2(SCH_1):PAGE76

C7P9 CAP_0805-47UF,4V,20%,X6S,C9533A
     1 PVCCMCP_CPU1 @BASEBOARD_FAB2_LIB.BASEBOARD_FAB2(SCH_1):PVCCMCP_CPU1   I181 @BASEBOARD_FAB2_LIB.BASEBOARD_FAB2(SCH_1):PAGE76
     2    GND @BASEBOARD_FAB2_LIB.BASEBOARD_FAB2(SCH_1):GND   I181 @BASEBOARD_FAB2_LIB.BASEBOARD_FAB2(SCH_1):PAGE76

C7P10 CAP_0805-47UF,4V,20%,X6S,C9533A
     1 PVCCMCP_CPU1 @BASEBOARD_FAB2_LIB.BASEBOARD_FAB2(SCH_1):PVCCMCP_CPU1    I26 @BASEBOARD_FAB2_LIB.BASEBOARD_FAB2(SCH_1):PAGE76
     2    GND @BASEBOARD_FAB2_LIB.BASEBOARD_FAB2(SCH_1):GND    I26 @BASEBOARD_FAB2_LIB.BASEBOARD_FAB2(SCH_1):PAGE76

C7P11 CAP_0805-47UF,4V,20%,X6S,C9533A
     1 PVCCMCP_CPU1 @BASEBOARD_FAB2_LIB.BASEBOARD_FAB2(SCH_1):PVCCMCP_CPU1   I183 @BASEBOARD_FAB2_LIB.BASEBOARD_FAB2(SCH_1):PAGE76
     2    GND @BASEBOARD_FAB2_LIB.BASEBOARD_FAB2(SCH_1):GND   I183 @BASEBOARD_FAB2_LIB.BASEBOARD_FAB2(SCH_1):PAGE76

C7P12 CAP_A_0603V-22.0UF,4V,20%,X6S,A
     1 PVCCIO_CPU1 @BASEBOARD_FAB2_LIB.BASEBOARD_FAB2(SCH_1):PVCCIO_CPU1   I179 @BASEBOARD_FAB2_LIB.BASEBOARD_FAB2(SCH_1):PAGE76
     2    GND @BASEBOARD_FAB2_LIB.BASEBOARD_FAB2(SCH_1):GND   I179 @BASEBOARD_FAB2_LIB.BASEBOARD_FAB2(SCH_1):PAGE76

C7P13 CAP_0805-47UF,4V,20%,X6S,C9533A
     1 PVCCMCP_CPU1 @BASEBOARD_FAB2_LIB.BASEBOARD_FAB2(SCH_1):PVCCMCP_CPU1    I25 @BASEBOARD_FAB2_LIB.BASEBOARD_FAB2(SCH_1):PAGE76
     2    GND @BASEBOARD_FAB2_LIB.BASEBOARD_FAB2(SCH_1):GND    I25 @BASEBOARD_FAB2_LIB.BASEBOARD_FAB2(SCH_1):PAGE76

C7P14 CAP_0805-47UF,4V,20%,X6S,C9533A
     1 PVCCMCP_CPU1 @BASEBOARD_FAB2_LIB.BASEBOARD_FAB2(SCH_1):PVCCMCP_CPU1    I49 @BASEBOARD_FAB2_LIB.BASEBOARD_FAB2(SCH_1):PAGE76
     2    GND @BASEBOARD_FAB2_LIB.BASEBOARD_FAB2(SCH_1):GND    I49 @BASEBOARD_FAB2_LIB.BASEBOARD_FAB2(SCH_1):PAGE76

C7P15 CAP_0805-47UF,4V,20%,X6S,C9533A
     1 PVCCMCP_CPU1 @BASEBOARD_FAB2_LIB.BASEBOARD_FAB2(SCH_1):PVCCMCP_CPU1    I45 @BASEBOARD_FAB2_LIB.BASEBOARD_FAB2(SCH_1):PAGE76
     2    GND @BASEBOARD_FAB2_LIB.BASEBOARD_FAB2(SCH_1):GND    I45 @BASEBOARD_FAB2_LIB.BASEBOARD_FAB2(SCH_1):PAGE76

C7P16 CAP_A_0603V-22.0UF,4V,20%,X6S,A
     1 PVCCIO_CPU1 @BASEBOARD_FAB2_LIB.BASEBOARD_FAB2(SCH_1):PVCCIO_CPU1   I206 @BASEBOARD_FAB2_LIB.BASEBOARD_FAB2(SCH_1):PAGE76
     2    GND @BASEBOARD_FAB2_LIB.BASEBOARD_FAB2(SCH_1):GND   I206 @BASEBOARD_FAB2_LIB.BASEBOARD_FAB2(SCH_1):PAGE76

C7P17 CAP_0805-47UF,4V,20%,X6S,C9533A
     1 PVCCIO_CPU1 @BASEBOARD_FAB2_LIB.BASEBOARD_FAB2(SCH_1):PVCCIO_CPU1    I29 @BASEBOARD_FAB2_LIB.BASEBOARD_FAB2(SCH_1):PAGE76
     2    GND @BASEBOARD_FAB2_LIB.BASEBOARD_FAB2(SCH_1):GND    I29 @BASEBOARD_FAB2_LIB.BASEBOARD_FAB2(SCH_1):PAGE76

C7P18 CAP_0805-47UF,4V,20%,X6S,C9533A
     1 PVCCIO_CPU1 @BASEBOARD_FAB2_LIB.BASEBOARD_FAB2(SCH_1):PVCCIO_CPU1    I51 @BASEBOARD_FAB2_LIB.BASEBOARD_FAB2(SCH_1):PAGE76
     2    GND @BASEBOARD_FAB2_LIB.BASEBOARD_FAB2(SCH_1):GND    I51 @BASEBOARD_FAB2_LIB.BASEBOARD_FAB2(SCH_1):PAGE76

C7P19 CAP_0805-47UF,4V,20%,X6S,C9533A
     1 PVCCIN_CPU1 @BASEBOARD_FAB2_LIB.BASEBOARD_FAB2(SCH_1):PVCCIN_CPU1   I215 @BASEBOARD_FAB2_LIB.BASEBOARD_FAB2(SCH_1):PAGE76
     2    GND @BASEBOARD_FAB2_LIB.BASEBOARD_FAB2(SCH_1):GND   I215 @BASEBOARD_FAB2_LIB.BASEBOARD_FAB2(SCH_1):PAGE76

C7P20 CAP_0805-47UF,4V,20%,X6S,C9533A
     1 PVCCIN_CPU1 @BASEBOARD_FAB2_LIB.BASEBOARD_FAB2(SCH_1):PVCCIN_CPU1   I218 @BASEBOARD_FAB2_LIB.BASEBOARD_FAB2(SCH_1):PAGE76
     2    GND @BASEBOARD_FAB2_LIB.BASEBOARD_FAB2(SCH_1):GND   I218 @BASEBOARD_FAB2_LIB.BASEBOARD_FAB2(SCH_1):PAGE76

C7R1 CAP_A_0603V-22.0UF,4V,20%,X6S,A
     1 PVCCIO_CPU1 @BASEBOARD_FAB2_LIB.BASEBOARD_FAB2(SCH_1):PVCCIO_CPU1    I65 @BASEBOARD_FAB2_LIB.BASEBOARD_FAB2(SCH_1):PAGE214
     2    GND @BASEBOARD_FAB2_LIB.BASEBOARD_FAB2(SCH_1):GND    I65 @BASEBOARD_FAB2_LIB.BASEBOARD_FAB2(SCH_1):PAGE214

C7T1 CAP_0805-100UF,4V,20%,X5R,6024A
     1 PVDDQ_GHJ @BASEBOARD_FAB2_LIB.BASEBOARD_FAB2(SCH_1):PVDDQ_GHJ    I90 @BASEBOARD_FAB2_LIB.BASEBOARD_FAB2(SCH_1):PAGE225
     2    GND @BASEBOARD_FAB2_LIB.BASEBOARD_FAB2(SCH_1):GND    I90 @BASEBOARD_FAB2_LIB.BASEBOARD_FAB2(SCH_1):PAGE225

C7T2 CAP_0603LF-10UF,4V,20%,X6S,E15A
     1 PVPP_GHJ @BASEBOARD_FAB2_LIB.BASEBOARD_FAB2(SCH_1):PVPP_GHJ   I112 @BASEBOARD_FAB2_LIB.BASEBOARD_FAB2(SCH_1):PAGE233
     2    GND @BASEBOARD_FAB2_LIB.BASEBOARD_FAB2(SCH_1):GND   I112 @BASEBOARD_FAB2_LIB.BASEBOARD_FAB2(SCH_1):PAGE233

C7T3 CAP_0603LF-10UF,4V,20%,X6S,E15A
     1 PVPP_GHJ @BASEBOARD_FAB2_LIB.BASEBOARD_FAB2(SCH_1):PVPP_GHJ   I113 @BASEBOARD_FAB2_LIB.BASEBOARD_FAB2(SCH_1):PAGE233
     2    GND @BASEBOARD_FAB2_LIB.BASEBOARD_FAB2(SCH_1):GND   I113 @BASEBOARD_FAB2_LIB.BASEBOARD_FAB2(SCH_1):PAGE233

C7T4 CAP_A_0603V-22.0UF,4V,20%,X6S,A
     1 PVDDQ_GHJ @BASEBOARD_FAB2_LIB.BASEBOARD_FAB2(SCH_1):PVDDQ_GHJ   I235 @BASEBOARD_FAB2_LIB.BASEBOARD_FAB2(SCH_1):PAGE225
     2    GND @BASEBOARD_FAB2_LIB.BASEBOARD_FAB2(SCH_1):GND   I235 @BASEBOARD_FAB2_LIB.BASEBOARD_FAB2(SCH_1):PAGE225

C7T5 CAP_A_0603V-22.0UF,4V,20%,X6S,A
     1 PVDDQ_GHJ @BASEBOARD_FAB2_LIB.BASEBOARD_FAB2(SCH_1):PVDDQ_GHJ   I234 @BASEBOARD_FAB2_LIB.BASEBOARD_FAB2(SCH_1):PAGE225
     2    GND @BASEBOARD_FAB2_LIB.BASEBOARD_FAB2(SCH_1):GND   I234 @BASEBOARD_FAB2_LIB.BASEBOARD_FAB2(SCH_1):PAGE225

C7U1 CAP_A_0603V-22.0UF,4V,20%,X6S,A
     1 PVDDQ_GHJ @BASEBOARD_FAB2_LIB.BASEBOARD_FAB2(SCH_1):PVDDQ_GHJ   I237 @BASEBOARD_FAB2_LIB.BASEBOARD_FAB2(SCH_1):PAGE225
     2    GND @BASEBOARD_FAB2_LIB.BASEBOARD_FAB2(SCH_1):GND   I237 @BASEBOARD_FAB2_LIB.BASEBOARD_FAB2(SCH_1):PAGE225

C7U2 CAP_A_0603V-22.0UF,4V,20%,X6S,A
     1 PVDDQ_GHJ @BASEBOARD_FAB2_LIB.BASEBOARD_FAB2(SCH_1):PVDDQ_GHJ   I238 @BASEBOARD_FAB2_LIB.BASEBOARD_FAB2(SCH_1):PAGE225
     2    GND @BASEBOARD_FAB2_LIB.BASEBOARD_FAB2(SCH_1):GND   I238 @BASEBOARD_FAB2_LIB.BASEBOARD_FAB2(SCH_1):PAGE225

C7U3 CAP_0603LF-10UF,4V,20%,X6S,E15A
     1 PVPP_GHJ @BASEBOARD_FAB2_LIB.BASEBOARD_FAB2(SCH_1):PVPP_GHJ   I136 @BASEBOARD_FAB2_LIB.BASEBOARD_FAB2(SCH_1):PAGE233
     2    GND @BASEBOARD_FAB2_LIB.BASEBOARD_FAB2(SCH_1):GND   I136 @BASEBOARD_FAB2_LIB.BASEBOARD_FAB2(SCH_1):PAGE233

C7U4 CAP_0603LF-10UF,4V,20%,X6S,E15A
     1 PVPP_GHJ @BASEBOARD_FAB2_LIB.BASEBOARD_FAB2(SCH_1):PVPP_GHJ   I109 @BASEBOARD_FAB2_LIB.BASEBOARD_FAB2(SCH_1):PAGE233
     2    GND @BASEBOARD_FAB2_LIB.BASEBOARD_FAB2(SCH_1):GND   I109 @BASEBOARD_FAB2_LIB.BASEBOARD_FAB2(SCH_1):PAGE233

C7U5 CAP_0603LF-10UF,4V,20%,X6S,E15A
     1 PVPP_GHJ @BASEBOARD_FAB2_LIB.BASEBOARD_FAB2(SCH_1):PVPP_GHJ   I111 @BASEBOARD_FAB2_LIB.BASEBOARD_FAB2(SCH_1):PAGE233
     2    GND @BASEBOARD_FAB2_LIB.BASEBOARD_FAB2(SCH_1):GND   I111 @BASEBOARD_FAB2_LIB.BASEBOARD_FAB2(SCH_1):PAGE233

C7U6 CAP_0603LF-10UF,4V,20%,X6S,E15A
     1 PVPP_GHJ @BASEBOARD_FAB2_LIB.BASEBOARD_FAB2(SCH_1):PVPP_GHJ   I115 @BASEBOARD_FAB2_LIB.BASEBOARD_FAB2(SCH_1):PAGE233
     2    GND @BASEBOARD_FAB2_LIB.BASEBOARD_FAB2(SCH_1):GND   I115 @BASEBOARD_FAB2_LIB.BASEBOARD_FAB2(SCH_1):PAGE233

C7U7 CAP_0805-100UF,4V,20%,X5R,6024A
     1 PVDDQ_GHJ @BASEBOARD_FAB2_LIB.BASEBOARD_FAB2(SCH_1):PVDDQ_GHJ    I91 @BASEBOARD_FAB2_LIB.BASEBOARD_FAB2(SCH_1):PAGE225
     2    GND @BASEBOARD_FAB2_LIB.BASEBOARD_FAB2(SCH_1):GND    I91 @BASEBOARD_FAB2_LIB.BASEBOARD_FAB2(SCH_1):PAGE225

C8A2 CAP_0402LF-220PF,50V,10%,X7R,AA
     1 VR_PVNN_PCH_AVSP @BASEBOARD_FAB2_LIB.BASEBOARD_FAB2(SCH_1):VR_PVNN_PCH_AVSP   I209 @BASEBOARD_FAB2_LIB.BASEBOARD_FAB2(SCH_1):PAGE235
     2 VSENSE_PVNN_PCH_STBY_AVSN @BASEBOARD_FAB2_LIB.BASEBOARD_FAB2(SCH_1):VSENSE_PVNN_PCH_STBY_AVSN   I209 @BASEBOARD_FAB2_LIB.BASEBOARD_FAB2(SCH_1):PAGE235

C8A3 CAP_0402LF-1000PF,50V,10%,X7R,A
     1 VR_PVNN_PCH_VINSEN @BASEBOARD_FAB2_LIB.BASEBOARD_FAB2(SCH_1):VR_PVNN_PCH_VINSEN   I167 @BASEBOARD_FAB2_LIB.BASEBOARD_FAB2(SCH_1):PAGE235
     2    GND @BASEBOARD_FAB2_LIB.BASEBOARD_FAB2(SCH_1):GND   I167 @BASEBOARD_FAB2_LIB.BASEBOARD_FAB2(SCH_1):PAGE235

C8A4 CAP_0603LF-0.1UF,25V,10%,X7R,6A
     1 P3V3_STBY @BASEBOARD_FAB2_LIB.BASEBOARD_FAB2(SCH_1):P3V3_STBY    I31 @BASEBOARD_FAB2_LIB.BASEBOARD_FAB2(SCH_1):PAGE237
     2    GND @BASEBOARD_FAB2_LIB.BASEBOARD_FAB2(SCH_1):GND    I31 @BASEBOARD_FAB2_LIB.BASEBOARD_FAB2(SCH_1):PAGE237

C8A6 CAP_0603-10UF,6.3V,20%,X6S,E15A
     1 P3V3_STBY @BASEBOARD_FAB2_LIB.BASEBOARD_FAB2(SCH_1):P3V3_STBY    I29 @BASEBOARD_FAB2_LIB.BASEBOARD_FAB2(SCH_1):PAGE237
     2    GND @BASEBOARD_FAB2_LIB.BASEBOARD_FAB2(SCH_1):GND    I29 @BASEBOARD_FAB2_LIB.BASEBOARD_FAB2(SCH_1):PAGE237

C8A7 CAP_A_0402V-1.0UF,6.3V,10%,X6SA
     1 VR_PVNN_P1V05_PCH_VD12 @BASEBOARD_FAB2_LIB.BASEBOARD_FAB2(SCH_1):VR_PVNN_P1V05_PCH_VD12   I143 @BASEBOARD_FAB2_LIB.BASEBOARD_FAB2(SCH_1):PAGE235
     2    GND @BASEBOARD_FAB2_LIB.BASEBOARD_FAB2(SCH_1):GND   I143 @BASEBOARD_FAB2_LIB.BASEBOARD_FAB2(SCH_1):PAGE235

C8A8 CAP_A_0402V-0.1UF,16V,10%,X7R,A
     1 VR_PVNN_P1V05_PCH_VD12 @BASEBOARD_FAB2_LIB.BASEBOARD_FAB2(SCH_1):VR_PVNN_P1V05_PCH_VD12   I145 @BASEBOARD_FAB2_LIB.BASEBOARD_FAB2(SCH_1):PAGE235
     2    GND @BASEBOARD_FAB2_LIB.BASEBOARD_FAB2(SCH_1):GND   I145 @BASEBOARD_FAB2_LIB.BASEBOARD_FAB2(SCH_1):PAGE235

C8A9 CAP_0402LF-1000PF,50V,10%,X7R,A
     1 PWRGD_PVNN_PCH_R @BASEBOARD_FAB2_LIB.BASEBOARD_FAB2(SCH_1):PWRGD_PVNN_PCH_R   I218 @BASEBOARD_FAB2_LIB.BASEBOARD_FAB2(SCH_1):PAGE235
     2    GND @BASEBOARD_FAB2_LIB.BASEBOARD_FAB2(SCH_1):GND   I218 @BASEBOARD_FAB2_LIB.BASEBOARD_FAB2(SCH_1):PAGE235

C8A10 CAP_0402LF-1000PF,50V,10%,EMPTA
     1 PWRGD_P3V3_STBY @BASEBOARD_FAB2_LIB.BASEBOARD_FAB2(SCH_1):PWRGD_P3V3_STBY    I55 @BASEBOARD_FAB2_LIB.BASEBOARD_FAB2(SCH_1):PAGE237
     2    GND @BASEBOARD_FAB2_LIB.BASEBOARD_FAB2(SCH_1):GND    I55 @BASEBOARD_FAB2_LIB.BASEBOARD_FAB2(SCH_1):PAGE237

C8A11 CAP_0402LF-1000PF,50V,10%,X7R,A
     1 PWRGD_P1V8_PCH_STBY_R @BASEBOARD_FAB2_LIB.BASEBOARD_FAB2(SCH_1):PWRGD_P1V8_PCH_STBY_R     I5 @BASEBOARD_FAB2_LIB.BASEBOARD_FAB2(SCH_1):PAGE237
     2    GND @BASEBOARD_FAB2_LIB.BASEBOARD_FAB2(SCH_1):GND     I5 @BASEBOARD_FAB2_LIB.BASEBOARD_FAB2(SCH_1):PAGE237

C8A12 CAP_0805-47UF,4V,20%,X6S,C9533A
     1 P1V8_PCH_STBY @BASEBOARD_FAB2_LIB.BASEBOARD_FAB2(SCH_1):P1V8_PCH_STBY    I77 @BASEBOARD_FAB2_LIB.BASEBOARD_FAB2(SCH_1):PAGE237
     2    GND @BASEBOARD_FAB2_LIB.BASEBOARD_FAB2(SCH_1):GND    I77 @BASEBOARD_FAB2_LIB.BASEBOARD_FAB2(SCH_1):PAGE237

C8A13 CAP_0805-47UF,4V,20%,X6S,C9533A
     1 P1V05_PCH_STBY @BASEBOARD_FAB2_LIB.BASEBOARD_FAB2(SCH_1):P1V05_PCH_STBY    I37 @BASEBOARD_FAB2_LIB.BASEBOARD_FAB2(SCH_1):PAGE131
     2    GND @BASEBOARD_FAB2_LIB.BASEBOARD_FAB2(SCH_1):GND    I37 @BASEBOARD_FAB2_LIB.BASEBOARD_FAB2(SCH_1):PAGE131

C8A14 CAP_0805-22UF,6.3V,20%,X6S,C95A
     1 P1V8_PCH_STBY @BASEBOARD_FAB2_LIB.BASEBOARD_FAB2(SCH_1):P1V8_PCH_STBY    I13 @BASEBOARD_FAB2_LIB.BASEBOARD_FAB2(SCH_1):PAGE237
     2    GND @BASEBOARD_FAB2_LIB.BASEBOARD_FAB2(SCH_1):GND    I13 @BASEBOARD_FAB2_LIB.BASEBOARD_FAB2(SCH_1):PAGE237

C8A15 CAPP_SM-470UF,2V,20%,ALUM,6990A
     1 P1V05_PCH_STBY @BASEBOARD_FAB2_LIB.BASEBOARD_FAB2(SCH_1):P1V05_PCH_STBY    I78 @BASEBOARD_FAB2_LIB.BASEBOARD_FAB2(SCH_1):PAGE236
     2    GND @BASEBOARD_FAB2_LIB.BASEBOARD_FAB2(SCH_1):GND    I78 @BASEBOARD_FAB2_LIB.BASEBOARD_FAB2(SCH_1):PAGE236

C8B1 CAP_A_0603V-22.0UF,4V,20%,X6S,A
     1 P1V8_PCH_STBY @BASEBOARD_FAB2_LIB.BASEBOARD_FAB2(SCH_1):P1V8_PCH_STBY    I41 @BASEBOARD_FAB2_LIB.BASEBOARD_FAB2(SCH_1):PAGE130
     2    GND @BASEBOARD_FAB2_LIB.BASEBOARD_FAB2(SCH_1):GND    I41 @BASEBOARD_FAB2_LIB.BASEBOARD_FAB2(SCH_1):PAGE130

C8B2 CAP_A_0603V-22.0UF,4V,20%,X6S,A
     1 P1V8_PCH_STBY @BASEBOARD_FAB2_LIB.BASEBOARD_FAB2(SCH_1):P1V8_PCH_STBY    I30 @BASEBOARD_FAB2_LIB.BASEBOARD_FAB2(SCH_1):PAGE130
     2    GND @BASEBOARD_FAB2_LIB.BASEBOARD_FAB2(SCH_1):GND    I30 @BASEBOARD_FAB2_LIB.BASEBOARD_FAB2(SCH_1):PAGE130

C8B3 CAP_A_0603V-22.0UF,4V,20%,X6S,A
     1 P1V8_PCH_STBY @BASEBOARD_FAB2_LIB.BASEBOARD_FAB2(SCH_1):P1V8_PCH_STBY    I32 @BASEBOARD_FAB2_LIB.BASEBOARD_FAB2(SCH_1):PAGE130
     2    GND @BASEBOARD_FAB2_LIB.BASEBOARD_FAB2(SCH_1):GND    I32 @BASEBOARD_FAB2_LIB.BASEBOARD_FAB2(SCH_1):PAGE130

C8B4 CAP_A_0603V-22.0UF,4V,20%,X6S,A
     1 P1V8_PCH_STBY @BASEBOARD_FAB2_LIB.BASEBOARD_FAB2(SCH_1):P1V8_PCH_STBY    I39 @BASEBOARD_FAB2_LIB.BASEBOARD_FAB2(SCH_1):PAGE130
     2    GND @BASEBOARD_FAB2_LIB.BASEBOARD_FAB2(SCH_1):GND    I39 @BASEBOARD_FAB2_LIB.BASEBOARD_FAB2(SCH_1):PAGE130

C8B5 CAP_A_0402V-0.1UF,16V,10%,X7R,A
     1 P5V_STBY @BASEBOARD_FAB2_LIB.BASEBOARD_FAB2(SCH_1):P5V_STBY    I37 @BASEBOARD_FAB2_LIB.BASEBOARD_FAB2(SCH_1):PAGE198
     2    GND @BASEBOARD_FAB2_LIB.BASEBOARD_FAB2(SCH_1):GND    I37 @BASEBOARD_FAB2_LIB.BASEBOARD_FAB2(SCH_1):PAGE198

C8B6 CAP_0805-10UF,16V,10%,X6S,C953A
     1    P5V @BASEBOARD_FAB2_LIB.BASEBOARD_FAB2(SCH_1):P5V    I40 @BASEBOARD_FAB2_LIB.BASEBOARD_FAB2(SCH_1):PAGE198
     2    GND @BASEBOARD_FAB2_LIB.BASEBOARD_FAB2(SCH_1):GND    I40 @BASEBOARD_FAB2_LIB.BASEBOARD_FAB2(SCH_1):PAGE198

C8B7 CAP_A_0402V-0.1UF,16V,10%,X7R,A
     1    P5V @BASEBOARD_FAB2_LIB.BASEBOARD_FAB2(SCH_1):P5V    I41 @BASEBOARD_FAB2_LIB.BASEBOARD_FAB2(SCH_1):PAGE198
     2    GND @BASEBOARD_FAB2_LIB.BASEBOARD_FAB2(SCH_1):GND    I41 @BASEBOARD_FAB2_LIB.BASEBOARD_FAB2(SCH_1):PAGE198

C8B8 CAP_A_0402V-0.1UF,16V,10%,X7R,A
     1 P5V_STBY @BASEBOARD_FAB2_LIB.BASEBOARD_FAB2(SCH_1):P5V_STBY    I26 @BASEBOARD_FAB2_LIB.BASEBOARD_FAB2(SCH_1):PAGE198
     2    GND @BASEBOARD_FAB2_LIB.BASEBOARD_FAB2(SCH_1):GND    I26 @BASEBOARD_FAB2_LIB.BASEBOARD_FAB2(SCH_1):PAGE198

C8B9 CAP_A_0603V-22.0UF,4V,20%,X6S,A
     1 P1V05_PCH_STBY @BASEBOARD_FAB2_LIB.BASEBOARD_FAB2(SCH_1):P1V05_PCH_STBY    I14 @BASEBOARD_FAB2_LIB.BASEBOARD_FAB2(SCH_1):PAGE131
     2    GND @BASEBOARD_FAB2_LIB.BASEBOARD_FAB2(SCH_1):GND    I14 @BASEBOARD_FAB2_LIB.BASEBOARD_FAB2(SCH_1):PAGE131

C8B10 CAP_A_0603V-22.0UF,4V,20%,X6S,A
     1 P1V05_PCH_STBY @BASEBOARD_FAB2_LIB.BASEBOARD_FAB2(SCH_1):P1V05_PCH_STBY     I8 @BASEBOARD_FAB2_LIB.BASEBOARD_FAB2(SCH_1):PAGE131
     2    GND @BASEBOARD_FAB2_LIB.BASEBOARD_FAB2(SCH_1):GND     I8 @BASEBOARD_FAB2_LIB.BASEBOARD_FAB2(SCH_1):PAGE131

C8B11 CAP_A_0603V-22.0UF,4V,20%,X6S,A
     1 P1V05_PCH_STBY @BASEBOARD_FAB2_LIB.BASEBOARD_FAB2(SCH_1):P1V05_PCH_STBY    I15 @BASEBOARD_FAB2_LIB.BASEBOARD_FAB2(SCH_1):PAGE131
     2    GND @BASEBOARD_FAB2_LIB.BASEBOARD_FAB2(SCH_1):GND    I15 @BASEBOARD_FAB2_LIB.BASEBOARD_FAB2(SCH_1):PAGE131

C8B12 CAP_0805-10UF,16V,10%,X6S,C953A
     1 P5V_STBY @BASEBOARD_FAB2_LIB.BASEBOARD_FAB2(SCH_1):P5V_STBY    I38 @BASEBOARD_FAB2_LIB.BASEBOARD_FAB2(SCH_1):PAGE198
     2    GND @BASEBOARD_FAB2_LIB.BASEBOARD_FAB2(SCH_1):GND    I38 @BASEBOARD_FAB2_LIB.BASEBOARD_FAB2(SCH_1):PAGE198

C8B13 CAP_A_0603V-22.0UF,4V,20%,X6S,A
     1 P1V05_PCH_STBY @BASEBOARD_FAB2_LIB.BASEBOARD_FAB2(SCH_1):P1V05_PCH_STBY    I20 @BASEBOARD_FAB2_LIB.BASEBOARD_FAB2(SCH_1):PAGE131
     2    GND @BASEBOARD_FAB2_LIB.BASEBOARD_FAB2(SCH_1):GND    I20 @BASEBOARD_FAB2_LIB.BASEBOARD_FAB2(SCH_1):PAGE131

C8B14 CAP_A_0603V-22.0UF,4V,20%,X6S,A
     1 P1V05_PCH_STBY @BASEBOARD_FAB2_LIB.BASEBOARD_FAB2(SCH_1):P1V05_PCH_STBY    I16 @BASEBOARD_FAB2_LIB.BASEBOARD_FAB2(SCH_1):PAGE131
     2    GND @BASEBOARD_FAB2_LIB.BASEBOARD_FAB2(SCH_1):GND    I16 @BASEBOARD_FAB2_LIB.BASEBOARD_FAB2(SCH_1):PAGE131

C8B15 CAP_0805-47UF,4V,20%,X6S,C9533A
     1 P1V05_PCH_STBY @BASEBOARD_FAB2_LIB.BASEBOARD_FAB2(SCH_1):P1V05_PCH_STBY    I24 @BASEBOARD_FAB2_LIB.BASEBOARD_FAB2(SCH_1):PAGE131
     2    GND @BASEBOARD_FAB2_LIB.BASEBOARD_FAB2(SCH_1):GND    I24 @BASEBOARD_FAB2_LIB.BASEBOARD_FAB2(SCH_1):PAGE131

C8B16 CAP_0805-47UF,4V,20%,X6S,C9533A
     1 P1V05_PCH_STBY @BASEBOARD_FAB2_LIB.BASEBOARD_FAB2(SCH_1):P1V05_PCH_STBY    I22 @BASEBOARD_FAB2_LIB.BASEBOARD_FAB2(SCH_1):PAGE131
     2    GND @BASEBOARD_FAB2_LIB.BASEBOARD_FAB2(SCH_1):GND    I22 @BASEBOARD_FAB2_LIB.BASEBOARD_FAB2(SCH_1):PAGE131

C8C1 CAP_0402LF-33.0PF,50V,5%,COG,AA
     1 XTAL_KR_25M_IN @BASEBOARD_FAB2_LIB.BASEBOARD_FAB2(SCH_1):XTAL_KR_25M_IN    I79 @BASEBOARD_FAB2_LIB.BASEBOARD_FAB2(SCH_1):PAGE118
     2    GND @BASEBOARD_FAB2_LIB.BASEBOARD_FAB2(SCH_1):GND    I79 @BASEBOARD_FAB2_LIB.BASEBOARD_FAB2(SCH_1):PAGE118

C8C2 CAP_0402LF-33.0PF,50V,5%,COG,AA
     1 XTAL_KR_25M_OUT @BASEBOARD_FAB2_LIB.BASEBOARD_FAB2(SCH_1):XTAL_KR_25M_OUT    I77 @BASEBOARD_FAB2_LIB.BASEBOARD_FAB2(SCH_1):PAGE118
     2    GND @BASEBOARD_FAB2_LIB.BASEBOARD_FAB2(SCH_1):GND    I77 @BASEBOARD_FAB2_LIB.BASEBOARD_FAB2(SCH_1):PAGE118

C8C3 CAP_0603-10UF,6.3V,20%,X6S,E15A
     1 P3V3_STBY @BASEBOARD_FAB2_LIB.BASEBOARD_FAB2(SCH_1):P3V3_STBY    I19 @BASEBOARD_FAB2_LIB.BASEBOARD_FAB2(SCH_1):PAGE130
     2    GND @BASEBOARD_FAB2_LIB.BASEBOARD_FAB2(SCH_1):GND    I19 @BASEBOARD_FAB2_LIB.BASEBOARD_FAB2(SCH_1):PAGE130

C8C4 CAP_0603-10UF,6.3V,20%,X6S,E15A
     1 P3V3_STBY @BASEBOARD_FAB2_LIB.BASEBOARD_FAB2(SCH_1):P3V3_STBY    I20 @BASEBOARD_FAB2_LIB.BASEBOARD_FAB2(SCH_1):PAGE130
     2    GND @BASEBOARD_FAB2_LIB.BASEBOARD_FAB2(SCH_1):GND    I20 @BASEBOARD_FAB2_LIB.BASEBOARD_FAB2(SCH_1):PAGE130

C8C5 CAP_0603-10UF,6.3V,20%,X6S,E15A
     1 P3V3_STBY @BASEBOARD_FAB2_LIB.BASEBOARD_FAB2(SCH_1):P3V3_STBY    I21 @BASEBOARD_FAB2_LIB.BASEBOARD_FAB2(SCH_1):PAGE130
     2    GND @BASEBOARD_FAB2_LIB.BASEBOARD_FAB2(SCH_1):GND    I21 @BASEBOARD_FAB2_LIB.BASEBOARD_FAB2(SCH_1):PAGE130

C8C6 CAP_0603-10UF,6.3V,20%,X6S,E15A
     1 P3V3_STBY @BASEBOARD_FAB2_LIB.BASEBOARD_FAB2(SCH_1):P3V3_STBY    I22 @BASEBOARD_FAB2_LIB.BASEBOARD_FAB2(SCH_1):PAGE130
     2    GND @BASEBOARD_FAB2_LIB.BASEBOARD_FAB2(SCH_1):GND    I22 @BASEBOARD_FAB2_LIB.BASEBOARD_FAB2(SCH_1):PAGE130

C8C8 CAP_A_0402V-0.1UF,16V,10%,X7R,A
     1 KR_P3_OCP_RX_DP @BASEBOARD_FAB2_LIB.BASEBOARD_FAB2(SCH_1):KR_P3_OCP_RX_DP    I64 @BASEBOARD_FAB2_LIB.BASEBOARD_FAB2(SCH_1):PAGE188
     2 KR_P3_OCP_RX_C_DP @BASEBOARD_FAB2_LIB.BASEBOARD_FAB2(SCH_1):KR_P3_OCP_RX_C_DP    I64 @BASEBOARD_FAB2_LIB.BASEBOARD_FAB2(SCH_1):PAGE188

C8C9 CAP_A_0402V-0.1UF,16V,10%,X7R,A
     1 KR_P3_OCP_RX_DN @BASEBOARD_FAB2_LIB.BASEBOARD_FAB2(SCH_1):KR_P3_OCP_RX_DN    I68 @BASEBOARD_FAB2_LIB.BASEBOARD_FAB2(SCH_1):PAGE188
     2 KR_P3_OCP_RX_C_DN @BASEBOARD_FAB2_LIB.BASEBOARD_FAB2(SCH_1):KR_P3_OCP_RX_C_DN    I68 @BASEBOARD_FAB2_LIB.BASEBOARD_FAB2(SCH_1):PAGE188

C8C10 CAP_A_0402V-0.1UF,16V,10%,X7R,A
     1 KR_P2_OCP_RX_DN @BASEBOARD_FAB2_LIB.BASEBOARD_FAB2(SCH_1):KR_P2_OCP_RX_DN    I73 @BASEBOARD_FAB2_LIB.BASEBOARD_FAB2(SCH_1):PAGE188
     2 KR_P2_OCP_RX_C_DN @BASEBOARD_FAB2_LIB.BASEBOARD_FAB2(SCH_1):KR_P2_OCP_RX_C_DN    I73 @BASEBOARD_FAB2_LIB.BASEBOARD_FAB2(SCH_1):PAGE188

C8C11 CAP_A_0402V-0.1UF,16V,10%,X7R,A
     1 KR_P2_OCP_RX_DP @BASEBOARD_FAB2_LIB.BASEBOARD_FAB2(SCH_1):KR_P2_OCP_RX_DP    I72 @BASEBOARD_FAB2_LIB.BASEBOARD_FAB2(SCH_1):PAGE188
     2 KR_P2_OCP_RX_C_DP @BASEBOARD_FAB2_LIB.BASEBOARD_FAB2(SCH_1):KR_P2_OCP_RX_C_DP    I72 @BASEBOARD_FAB2_LIB.BASEBOARD_FAB2(SCH_1):PAGE188

C8C12 CAP_A_0402V-0.1UF,16V,10%,X7R,A
     1 KR_P1_OCP_RX_DP @BASEBOARD_FAB2_LIB.BASEBOARD_FAB2(SCH_1):KR_P1_OCP_RX_DP    I80 @BASEBOARD_FAB2_LIB.BASEBOARD_FAB2(SCH_1):PAGE188
     2 KR_P1_OCP_RX_C_DP @BASEBOARD_FAB2_LIB.BASEBOARD_FAB2(SCH_1):KR_P1_OCP_RX_C_DP    I80 @BASEBOARD_FAB2_LIB.BASEBOARD_FAB2(SCH_1):PAGE188

C8C13 CAP_A_0402V-0.1UF,16V,10%,X7R,A
     1 KR_P1_OCP_RX_DN @BASEBOARD_FAB2_LIB.BASEBOARD_FAB2(SCH_1):KR_P1_OCP_RX_DN    I81 @BASEBOARD_FAB2_LIB.BASEBOARD_FAB2(SCH_1):PAGE188
     2 KR_P1_OCP_RX_C_DN @BASEBOARD_FAB2_LIB.BASEBOARD_FAB2(SCH_1):KR_P1_OCP_RX_C_DN    I81 @BASEBOARD_FAB2_LIB.BASEBOARD_FAB2(SCH_1):PAGE188

C8C14 CAP_A_0402V-0.1UF,16V,10%,X7R,A
     1 KR_P0_OCP_RX_DN @BASEBOARD_FAB2_LIB.BASEBOARD_FAB2(SCH_1):KR_P0_OCP_RX_DN    I86 @BASEBOARD_FAB2_LIB.BASEBOARD_FAB2(SCH_1):PAGE188
     2 KR_P0_OCP_RX_C_DN @BASEBOARD_FAB2_LIB.BASEBOARD_FAB2(SCH_1):KR_P0_OCP_RX_C_DN    I86 @BASEBOARD_FAB2_LIB.BASEBOARD_FAB2(SCH_1):PAGE188

C8C15 CAP_A_0402V-0.1UF,16V,10%,X7R,A
     1 KR_P0_OCP_RX_DP @BASEBOARD_FAB2_LIB.BASEBOARD_FAB2(SCH_1):KR_P0_OCP_RX_DP    I82 @BASEBOARD_FAB2_LIB.BASEBOARD_FAB2(SCH_1):PAGE188
     2 KR_P0_OCP_RX_C_DP @BASEBOARD_FAB2_LIB.BASEBOARD_FAB2(SCH_1):KR_P0_OCP_RX_C_DP    I82 @BASEBOARD_FAB2_LIB.BASEBOARD_FAB2(SCH_1):PAGE188

C8D1 CAP_A_0402V-0.1UF,16V,10%,X7R,A
     1 P3V3_STBY @BASEBOARD_FAB2_LIB.BASEBOARD_FAB2(SCH_1):P3V3_STBY   I376 @BASEBOARD_FAB2_LIB.BASEBOARD_FAB2(SCH_1):PAGE157
     2    GND @BASEBOARD_FAB2_LIB.BASEBOARD_FAB2(SCH_1):GND   I376 @BASEBOARD_FAB2_LIB.BASEBOARD_FAB2(SCH_1):PAGE157

C8D2 CAP_A_0402V-0.1UF,16V,10%,X7R,A
     1 P3V3_STBY @BASEBOARD_FAB2_LIB.BASEBOARD_FAB2(SCH_1):P3V3_STBY    I33 @BASEBOARD_FAB2_LIB.BASEBOARD_FAB2(SCH_1):PAGE170
     2    GND @BASEBOARD_FAB2_LIB.BASEBOARD_FAB2(SCH_1):GND    I33 @BASEBOARD_FAB2_LIB.BASEBOARD_FAB2(SCH_1):PAGE170

C8D3 CAP_0402LF-470PF,50V,10%,EMPTYA
     1 IRQ_SML1_PMBUS_ALERT_N @BASEBOARD_FAB2_LIB.BASEBOARD_FAB2(SCH_1):IRQ_SML1_PMBUS_ALERT_N    I42 @BASEBOARD_FAB2_LIB.BASEBOARD_FAB2(SCH_1):PAGE170
     2    GND @BASEBOARD_FAB2_LIB.BASEBOARD_FAB2(SCH_1):GND    I42 @BASEBOARD_FAB2_LIB.BASEBOARD_FAB2(SCH_1):PAGE170

C8D4 CAP_A_0402V-0.1UF,16V,10%,X7R,A
     1 P3V3_STBY @BASEBOARD_FAB2_LIB.BASEBOARD_FAB2(SCH_1):P3V3_STBY   I105 @BASEBOARD_FAB2_LIB.BASEBOARD_FAB2(SCH_1):PAGE196
     2    GND @BASEBOARD_FAB2_LIB.BASEBOARD_FAB2(SCH_1):GND   I105 @BASEBOARD_FAB2_LIB.BASEBOARD_FAB2(SCH_1):PAGE196

C8E1 CAP_A_0402V-0.1UF,16V,10%,X7R,A
     1 P3V3_STBY @BASEBOARD_FAB2_LIB.BASEBOARD_FAB2(SCH_1):P3V3_STBY   I253 @BASEBOARD_FAB2_LIB.BASEBOARD_FAB2(SCH_1):PAGE181
     2    GND @BASEBOARD_FAB2_LIB.BASEBOARD_FAB2(SCH_1):GND   I253 @BASEBOARD_FAB2_LIB.BASEBOARD_FAB2(SCH_1):PAGE181

C8E2 CAP_A_0402V-0.1UF,16V,10%,X7R,A
     1 P3V3_STBY @BASEBOARD_FAB2_LIB.BASEBOARD_FAB2(SCH_1):P3V3_STBY    I40 @BASEBOARD_FAB2_LIB.BASEBOARD_FAB2(SCH_1):PAGE170
     2    GND @BASEBOARD_FAB2_LIB.BASEBOARD_FAB2(SCH_1):GND    I40 @BASEBOARD_FAB2_LIB.BASEBOARD_FAB2(SCH_1):PAGE170

C8E3 CAP_A_0402V-0.1UF,16V,10%,X7R,A
     1 PWRGD_P12V_HSC @BASEBOARD_FAB2_LIB.BASEBOARD_FAB2(SCH_1):PWRGD_P12V_HSC    I94 @BASEBOARD_FAB2_LIB.BASEBOARD_FAB2(SCH_1):PAGE196
     2    GND @BASEBOARD_FAB2_LIB.BASEBOARD_FAB2(SCH_1):GND    I94 @BASEBOARD_FAB2_LIB.BASEBOARD_FAB2(SCH_1):PAGE196

C8E4 CAPP_3018-470UF,6.3V,20%,POSCAA
     1 P5V_STBY @BASEBOARD_FAB2_LIB.BASEBOARD_FAB2(SCH_1):P5V_STBY     I8 @BASEBOARD_FAB2_LIB.BASEBOARD_FAB2(SCH_1):PAGE241
     2    GND @BASEBOARD_FAB2_LIB.BASEBOARD_FAB2(SCH_1):GND     I8 @BASEBOARD_FAB2_LIB.BASEBOARD_FAB2(SCH_1):PAGE241

C8E5 CAP_A_0402V-0.1UF,16V,10%,X7R,A
     1 P3V3_STBY @BASEBOARD_FAB2_LIB.BASEBOARD_FAB2(SCH_1):P3V3_STBY    I20 @BASEBOARD_FAB2_LIB.BASEBOARD_FAB2(SCH_1):PAGE142
     2    GND @BASEBOARD_FAB2_LIB.BASEBOARD_FAB2(SCH_1):GND    I20 @BASEBOARD_FAB2_LIB.BASEBOARD_FAB2(SCH_1):PAGE142

C8E6 CAP_0603LF-0.1UF,25V,10%,X7R,6A
     1 VR_P5V_STBY_BOOT @BASEBOARD_FAB2_LIB.BASEBOARD_FAB2(SCH_1):VR_P5V_STBY_BOOT    I12 @BASEBOARD_FAB2_LIB.BASEBOARD_FAB2(SCH_1):PAGE241
     2 VR_P5V_STBY_PHASE @BASEBOARD_FAB2_LIB.BASEBOARD_FAB2(SCH_1):VR_P5V_STBY_PHASE    I12 @BASEBOARD_FAB2_LIB.BASEBOARD_FAB2(SCH_1):PAGE241

C8E7 CAP_0805-22UF,6.3V,20%,X6S,C95A
     1 P5V_STBY @BASEBOARD_FAB2_LIB.BASEBOARD_FAB2(SCH_1):P5V_STBY     I3 @BASEBOARD_FAB2_LIB.BASEBOARD_FAB2(SCH_1):PAGE241
     2    GND @BASEBOARD_FAB2_LIB.BASEBOARD_FAB2(SCH_1):GND     I3 @BASEBOARD_FAB2_LIB.BASEBOARD_FAB2(SCH_1):PAGE241

C8E8 CAP_A_0402V-0.1UF,16V,10%,X7R,A
     1 P3V3_STBY @BASEBOARD_FAB2_LIB.BASEBOARD_FAB2(SCH_1):P3V3_STBY   I128 @BASEBOARD_FAB2_LIB.BASEBOARD_FAB2(SCH_1):PAGE136
     2    GND @BASEBOARD_FAB2_LIB.BASEBOARD_FAB2(SCH_1):GND   I128 @BASEBOARD_FAB2_LIB.BASEBOARD_FAB2(SCH_1):PAGE136

C8E9 CAP_0805-22UF,6.3V,20%,X6S,C95A
     1 P5V_STBY @BASEBOARD_FAB2_LIB.BASEBOARD_FAB2(SCH_1):P5V_STBY     I2 @BASEBOARD_FAB2_LIB.BASEBOARD_FAB2(SCH_1):PAGE241
     2    GND @BASEBOARD_FAB2_LIB.BASEBOARD_FAB2(SCH_1):GND     I2 @BASEBOARD_FAB2_LIB.BASEBOARD_FAB2(SCH_1):PAGE241

C8E10 CAP_1206LF-22UF,16V,10%,X6S,D3A
     1 VR_FET_SW_P12V_STBY_P3V3_STBY @BASEBOARD_FAB2_LIB.BASEBOARD_FAB2(SCH_1):VR_FET_SW_P12V_STBY_P3V3_STBY   I137 @BASEBOARD_FAB2_LIB.BASEBOARD_FAB2(SCH_1):PAGE240
     2    GND @BASEBOARD_FAB2_LIB.BASEBOARD_FAB2(SCH_1):GND   I137 @BASEBOARD_FAB2_LIB.BASEBOARD_FAB2(SCH_1):PAGE240

C8E11 CAP_1210-47UF,16V,20%,X6S,D384A
     1 VR_FET_SW_P12V_STBY_P3V3_STBY @BASEBOARD_FAB2_LIB.BASEBOARD_FAB2(SCH_1):VR_FET_SW_P12V_STBY_P3V3_STBY   I135 @BASEBOARD_FAB2_LIB.BASEBOARD_FAB2(SCH_1):PAGE240
     2    GND @BASEBOARD_FAB2_LIB.BASEBOARD_FAB2(SCH_1):GND   I135 @BASEBOARD_FAB2_LIB.BASEBOARD_FAB2(SCH_1):PAGE240

C8E12 CAP_0603LF-0.1UF,25V,10%,X7R,6A
     1 VR_P3V3_STBY_PHASE @BASEBOARD_FAB2_LIB.BASEBOARD_FAB2(SCH_1):VR_P3V3_STBY_PHASE   I129 @BASEBOARD_FAB2_LIB.BASEBOARD_FAB2(SCH_1):PAGE240
     2 VR_P3V3_STBY_BOOT_R @BASEBOARD_FAB2_LIB.BASEBOARD_FAB2(SCH_1):VR_P3V3_STBY_BOOT_R   I129 @BASEBOARD_FAB2_LIB.BASEBOARD_FAB2(SCH_1):PAGE240

C8E13 CAP_0402LF-1000PF,50V,10%,EMPTA
     1 PWRGD_P12V_HSC_DLY @BASEBOARD_FAB2_LIB.BASEBOARD_FAB2(SCH_1):PWRGD_P12V_HSC_DLY    I41 @BASEBOARD_FAB2_LIB.BASEBOARD_FAB2(SCH_1):PAGE241
     2 AGND_P5V_STBY @BASEBOARD_FAB2_LIB.BASEBOARD_FAB2(SCH_1):AGND_P5V_STBY    I41 @BASEBOARD_FAB2_LIB.BASEBOARD_FAB2(SCH_1):PAGE241

C8E14 CAP_0402-1.0UF,16V,10%,X6S,D97A
     1 VR_FET_SW_P12V_STBY_P3V3_STBY @BASEBOARD_FAB2_LIB.BASEBOARD_FAB2(SCH_1):VR_FET_SW_P12V_STBY_P3V3_STBY   I139 @BASEBOARD_FAB2_LIB.BASEBOARD_FAB2(SCH_1):PAGE240
     2    GND @BASEBOARD_FAB2_LIB.BASEBOARD_FAB2(SCH_1):GND   I139 @BASEBOARD_FAB2_LIB.BASEBOARD_FAB2(SCH_1):PAGE240

C8E15 CAP_0402LF-0.022UF,16V,10%,X7RA
     1 VR_P5V_STBY_SS @BASEBOARD_FAB2_LIB.BASEBOARD_FAB2(SCH_1):VR_P5V_STBY_SS    I63 @BASEBOARD_FAB2_LIB.BASEBOARD_FAB2(SCH_1):PAGE241
     2 AGND_P5V_STBY @BASEBOARD_FAB2_LIB.BASEBOARD_FAB2(SCH_1):AGND_P5V_STBY    I63 @BASEBOARD_FAB2_LIB.BASEBOARD_FAB2(SCH_1):PAGE241

C8E16 CAP_0402LF-270PF,50V,10%,X7R,AA
     1 VR_P5V_STBY_COMP @BASEBOARD_FAB2_LIB.BASEBOARD_FAB2(SCH_1):VR_P5V_STBY_COMP    I53 @BASEBOARD_FAB2_LIB.BASEBOARD_FAB2(SCH_1):PAGE241
     2 AGND_P5V_STBY @BASEBOARD_FAB2_LIB.BASEBOARD_FAB2(SCH_1):AGND_P5V_STBY    I53 @BASEBOARD_FAB2_LIB.BASEBOARD_FAB2(SCH_1):PAGE241

C8E17 CAP_0402LF-1000PF,50V,10%,EMPTA
     1 PWRGD_P5V_STBY @BASEBOARD_FAB2_LIB.BASEBOARD_FAB2(SCH_1):PWRGD_P5V_STBY   I113 @BASEBOARD_FAB2_LIB.BASEBOARD_FAB2(SCH_1):PAGE240
     2 AGND_P3V3_STBY @BASEBOARD_FAB2_LIB.BASEBOARD_FAB2(SCH_1):AGND_P3V3_STBY   I113 @BASEBOARD_FAB2_LIB.BASEBOARD_FAB2(SCH_1):PAGE240

C8E18 CAP_A_0402V-0.1UF,16V,10%,X7R,A
     1 P3V3_STBY @BASEBOARD_FAB2_LIB.BASEBOARD_FAB2(SCH_1):P3V3_STBY    I14 @BASEBOARD_FAB2_LIB.BASEBOARD_FAB2(SCH_1):PAGE154
     2    GND @BASEBOARD_FAB2_LIB.BASEBOARD_FAB2(SCH_1):GND    I14 @BASEBOARD_FAB2_LIB.BASEBOARD_FAB2(SCH_1):PAGE154

C8E19 CAP_A_0402V-0.1UF,16V,10%,X7R,A
     1 P5V_STBY @BASEBOARD_FAB2_LIB.BASEBOARD_FAB2(SCH_1):P5V_STBY    I28 @BASEBOARD_FAB2_LIB.BASEBOARD_FAB2(SCH_1):PAGE198
     2    GND @BASEBOARD_FAB2_LIB.BASEBOARD_FAB2(SCH_1):GND    I28 @BASEBOARD_FAB2_LIB.BASEBOARD_FAB2(SCH_1):PAGE198

C8F1 CAP_0402LF-2200PF,50V,10%,X7R,A
     1 VR_P5V_STBY_RC_COMP @BASEBOARD_FAB2_LIB.BASEBOARD_FAB2(SCH_1):VR_P5V_STBY_RC_COMP    I57 @BASEBOARD_FAB2_LIB.BASEBOARD_FAB2(SCH_1):PAGE241
     2 AGND_P5V_STBY @BASEBOARD_FAB2_LIB.BASEBOARD_FAB2(SCH_1):AGND_P5V_STBY    I57 @BASEBOARD_FAB2_LIB.BASEBOARD_FAB2(SCH_1):PAGE241

C8F2 CAP_0402LF-1000PF,50V,10%,X7R,A
     1 PWRGD_P3V3_STBY_R @BASEBOARD_FAB2_LIB.BASEBOARD_FAB2(SCH_1):PWRGD_P3V3_STBY_R   I116 @BASEBOARD_FAB2_LIB.BASEBOARD_FAB2(SCH_1):PAGE240
     2    GND @BASEBOARD_FAB2_LIB.BASEBOARD_FAB2(SCH_1):GND   I116 @BASEBOARD_FAB2_LIB.BASEBOARD_FAB2(SCH_1):PAGE240

C8F3 CAP_0402LF-3300PF,50V,10%,EMPTA
     1 VR_P3V3_STBY_PHASE @BASEBOARD_FAB2_LIB.BASEBOARD_FAB2(SCH_1):VR_P3V3_STBY_PHASE   I163 @BASEBOARD_FAB2_LIB.BASEBOARD_FAB2(SCH_1):PAGE240
     2 VR_P3V3_STBY_SNUB @BASEBOARD_FAB2_LIB.BASEBOARD_FAB2(SCH_1):VR_P3V3_STBY_SNUB   I163 @BASEBOARD_FAB2_LIB.BASEBOARD_FAB2(SCH_1):PAGE240

C8F4 CAP_A_0402V-1.0UF,6.3V,10%,X6SA
     1 P3V3_STBY @BASEBOARD_FAB2_LIB.BASEBOARD_FAB2(SCH_1):P3V3_STBY    I30 @BASEBOARD_FAB2_LIB.BASEBOARD_FAB2(SCH_1):PAGE162
     2    GND @BASEBOARD_FAB2_LIB.BASEBOARD_FAB2(SCH_1):GND    I30 @BASEBOARD_FAB2_LIB.BASEBOARD_FAB2(SCH_1):PAGE162

C8F5 CAP_A_0402V-0.01UF,25V,10%,X7RA
     1 P3V3_STBY @BASEBOARD_FAB2_LIB.BASEBOARD_FAB2(SCH_1):P3V3_STBY    I28 @BASEBOARD_FAB2_LIB.BASEBOARD_FAB2(SCH_1):PAGE162
     2    GND @BASEBOARD_FAB2_LIB.BASEBOARD_FAB2(SCH_1):GND    I28 @BASEBOARD_FAB2_LIB.BASEBOARD_FAB2(SCH_1):PAGE162

C8F6 CAP_A_0402V-0.01UF,25V,10%,EMPA
     1 SATA6G_S0_TX_DP @BASEBOARD_FAB2_LIB.BASEBOARD_FAB2(SCH_1):SATA6G_S0_TX_DP    I95 @BASEBOARD_FAB2_LIB.BASEBOARD_FAB2(SCH_1):PAGE185
     2 P3E_PCH_M2_SATA6G_TX_R_DP @BASEBOARD_FAB2_LIB.BASEBOARD_FAB2(SCH_1):P3E_PCH_M2_SATA6G_TX_R_DP    I95 @BASEBOARD_FAB2_LIB.BASEBOARD_FAB2(SCH_1):PAGE185

C8F7 CAP_0402-0.22UF,16V,10%,X7R,A3A
     1 P3E_PCH_TX_0_DP @BASEBOARD_FAB2_LIB.BASEBOARD_FAB2(SCH_1):P3E_PCH_TX_0_DP    I96 @BASEBOARD_FAB2_LIB.BASEBOARD_FAB2(SCH_1):PAGE185
     2 P3E_PCH_M2_SATA6G_TX_R_DP @BASEBOARD_FAB2_LIB.BASEBOARD_FAB2(SCH_1):P3E_PCH_M2_SATA6G_TX_R_DP    I96 @BASEBOARD_FAB2_LIB.BASEBOARD_FAB2(SCH_1):PAGE185

C8F8 CAPP_3018-470UF,6.3V,20%,POSCAA
     1 P3V3_STBY @BASEBOARD_FAB2_LIB.BASEBOARD_FAB2(SCH_1):P3V3_STBY   I155 @BASEBOARD_FAB2_LIB.BASEBOARD_FAB2(SCH_1):PAGE240
     2    GND @BASEBOARD_FAB2_LIB.BASEBOARD_FAB2(SCH_1):GND   I155 @BASEBOARD_FAB2_LIB.BASEBOARD_FAB2(SCH_1):PAGE240

C8F11 CAP_A_0402V-0.01UF,25V,10%,EMPA
     1 SATA6G_S0_TX_DN @BASEBOARD_FAB2_LIB.BASEBOARD_FAB2(SCH_1):SATA6G_S0_TX_DN    I97 @BASEBOARD_FAB2_LIB.BASEBOARD_FAB2(SCH_1):PAGE185
     2 P3E_PCH_M2_SATA6G_TX_R_DN @BASEBOARD_FAB2_LIB.BASEBOARD_FAB2(SCH_1):P3E_PCH_M2_SATA6G_TX_R_DN    I97 @BASEBOARD_FAB2_LIB.BASEBOARD_FAB2(SCH_1):PAGE185

C8F12 CAP_0402-0.22UF,16V,10%,X7R,A3A
     1 P3E_PCH_TX_0_DN @BASEBOARD_FAB2_LIB.BASEBOARD_FAB2(SCH_1):P3E_PCH_TX_0_DN    I98 @BASEBOARD_FAB2_LIB.BASEBOARD_FAB2(SCH_1):PAGE185
     2 P3E_PCH_M2_SATA6G_TX_R_DN @BASEBOARD_FAB2_LIB.BASEBOARD_FAB2(SCH_1):P3E_PCH_M2_SATA6G_TX_R_DN    I98 @BASEBOARD_FAB2_LIB.BASEBOARD_FAB2(SCH_1):PAGE185

C8F13 CAP_A_0402V-0.01UF,25V,10%,EMPA
     1 SATA6G_S0_RX_DP @BASEBOARD_FAB2_LIB.BASEBOARD_FAB2(SCH_1):SATA6G_S0_RX_DP    I99 @BASEBOARD_FAB2_LIB.BASEBOARD_FAB2(SCH_1):PAGE185
     2 P3E_PCH_M2_SATA6G_RX_R_DP @BASEBOARD_FAB2_LIB.BASEBOARD_FAB2(SCH_1):P3E_PCH_M2_SATA6G_RX_R_DP    I99 @BASEBOARD_FAB2_LIB.BASEBOARD_FAB2(SCH_1):PAGE185

C8F14 CAPP_3018-470UF,6.3V,20%,POSCAA
     1 P3V3_STBY @BASEBOARD_FAB2_LIB.BASEBOARD_FAB2(SCH_1):P3V3_STBY   I154 @BASEBOARD_FAB2_LIB.BASEBOARD_FAB2(SCH_1):PAGE240
     2    GND @BASEBOARD_FAB2_LIB.BASEBOARD_FAB2(SCH_1):GND   I154 @BASEBOARD_FAB2_LIB.BASEBOARD_FAB2(SCH_1):PAGE240

C8F15 CAP_A_0402V-0.01UF,25V,10%,EMPA
     1 SATA6G_S0_RX_DN @BASEBOARD_FAB2_LIB.BASEBOARD_FAB2(SCH_1):SATA6G_S0_RX_DN    I90 @BASEBOARD_FAB2_LIB.BASEBOARD_FAB2(SCH_1):PAGE185
     2 P3E_PCH_M2_SATA6G_RX_R_DN @BASEBOARD_FAB2_LIB.BASEBOARD_FAB2(SCH_1):P3E_PCH_M2_SATA6G_RX_R_DN    I90 @BASEBOARD_FAB2_LIB.BASEBOARD_FAB2(SCH_1):PAGE185

C8F16 CAP_A_0402V-0.1UF,16V,10%,X7R,A
     1 P3V3_STBY @BASEBOARD_FAB2_LIB.BASEBOARD_FAB2(SCH_1):P3V3_STBY   I275 @BASEBOARD_FAB2_LIB.BASEBOARD_FAB2(SCH_1):PAGE156
     2    GND @BASEBOARD_FAB2_LIB.BASEBOARD_FAB2(SCH_1):GND   I275 @BASEBOARD_FAB2_LIB.BASEBOARD_FAB2(SCH_1):PAGE156

C8F17 CAP_A_0402V-0.1UF,16V,10%,X7R,A
     1 P5V_STBY @BASEBOARD_FAB2_LIB.BASEBOARD_FAB2(SCH_1):P5V_STBY    I24 @BASEBOARD_FAB2_LIB.BASEBOARD_FAB2(SCH_1):PAGE198
     2    GND @BASEBOARD_FAB2_LIB.BASEBOARD_FAB2(SCH_1):GND    I24 @BASEBOARD_FAB2_LIB.BASEBOARD_FAB2(SCH_1):PAGE198

C8F18 CAP_0402LF-27.0PF,50V,5%,COG,AA
     1 XTAL_CK_MNG_IN @BASEBOARD_FAB2_LIB.BASEBOARD_FAB2(SCH_1):XTAL_CK_MNG_IN    I49 @BASEBOARD_FAB2_LIB.BASEBOARD_FAB2(SCH_1):PAGE101
     2    GND @BASEBOARD_FAB2_LIB.BASEBOARD_FAB2(SCH_1):GND    I49 @BASEBOARD_FAB2_LIB.BASEBOARD_FAB2(SCH_1):PAGE101

C8F19 CAP_0402LF-27.0PF,50V,5%,COG,AA
     1 XTAL_CK_MNG_OUT @BASEBOARD_FAB2_LIB.BASEBOARD_FAB2(SCH_1):XTAL_CK_MNG_OUT    I53 @BASEBOARD_FAB2_LIB.BASEBOARD_FAB2(SCH_1):PAGE101
     2    GND @BASEBOARD_FAB2_LIB.BASEBOARD_FAB2(SCH_1):GND    I53 @BASEBOARD_FAB2_LIB.BASEBOARD_FAB2(SCH_1):PAGE101

C8G1 CAP_0402-0.22UF,16V,10%,X7R,A3A
     1 P3E_CPU0_PE2_SS_TXP<4> @BASEBOARD_FAB2_LIB.BASEBOARD_FAB2(SCH_1):P3E_CPU0_PE2_SS_TXP(4)    I70 @BASEBOARD_FAB2_LIB.BASEBOARD_FAB2(SCH_1):PAGE105
     2 P3E_CPU0_PE2_SS_C_TXP<4> @BASEBOARD_FAB2_LIB.BASEBOARD_FAB2(SCH_1):P3E_CPU0_PE2_SS_C_TXP(4)    I70 @BASEBOARD_FAB2_LIB.BASEBOARD_FAB2(SCH_1):PAGE105

C8G2 CAP_0402-0.22UF,16V,10%,X7R,A3A
     1 P3E_CPU0_PE2_SS_TXN<4> @BASEBOARD_FAB2_LIB.BASEBOARD_FAB2(SCH_1):P3E_CPU0_PE2_SS_TXN(4)    I58 @BASEBOARD_FAB2_LIB.BASEBOARD_FAB2(SCH_1):PAGE105
     2 P3E_CPU0_PE2_SS_C_TXN<4> @BASEBOARD_FAB2_LIB.BASEBOARD_FAB2(SCH_1):P3E_CPU0_PE2_SS_C_TXN(4)    I58 @BASEBOARD_FAB2_LIB.BASEBOARD_FAB2(SCH_1):PAGE105

C8G3 CAP_0402-0.22UF,16V,10%,X7R,A3A
     1 P3E_CPU0_PE2_SS_TXP<3> @BASEBOARD_FAB2_LIB.BASEBOARD_FAB2(SCH_1):P3E_CPU0_PE2_SS_TXP(3)    I71 @BASEBOARD_FAB2_LIB.BASEBOARD_FAB2(SCH_1):PAGE105
     2 P3E_CPU0_PE2_SS_C_TXP<3> @BASEBOARD_FAB2_LIB.BASEBOARD_FAB2(SCH_1):P3E_CPU0_PE2_SS_C_TXP(3)    I71 @BASEBOARD_FAB2_LIB.BASEBOARD_FAB2(SCH_1):PAGE105

C8G4 CAP_0402-0.22UF,16V,10%,X7R,A3A
     1 P3E_CPU0_PE2_SS_TXN<3> @BASEBOARD_FAB2_LIB.BASEBOARD_FAB2(SCH_1):P3E_CPU0_PE2_SS_TXN(3)    I56 @BASEBOARD_FAB2_LIB.BASEBOARD_FAB2(SCH_1):PAGE105
     2 P3E_CPU0_PE2_SS_C_TXN<3> @BASEBOARD_FAB2_LIB.BASEBOARD_FAB2(SCH_1):P3E_CPU0_PE2_SS_C_TXN(3)    I56 @BASEBOARD_FAB2_LIB.BASEBOARD_FAB2(SCH_1):PAGE105

C8G5 CAP_0402-0.22UF,16V,10%,X7R,A3A
     1 P3E_CPU0_PE2_SS_TXP<2> @BASEBOARD_FAB2_LIB.BASEBOARD_FAB2(SCH_1):P3E_CPU0_PE2_SS_TXP(2)    I75 @BASEBOARD_FAB2_LIB.BASEBOARD_FAB2(SCH_1):PAGE105
     2 P3E_CPU0_PE2_SS_C_TXP<2> @BASEBOARD_FAB2_LIB.BASEBOARD_FAB2(SCH_1):P3E_CPU0_PE2_SS_C_TXP(2)    I75 @BASEBOARD_FAB2_LIB.BASEBOARD_FAB2(SCH_1):PAGE105

C8G6 CAP_0402-0.22UF,16V,10%,X7R,A3A
     1 P3E_CPU0_PE2_SS_TXN<2> @BASEBOARD_FAB2_LIB.BASEBOARD_FAB2(SCH_1):P3E_CPU0_PE2_SS_TXN(2)    I61 @BASEBOARD_FAB2_LIB.BASEBOARD_FAB2(SCH_1):PAGE105
     2 P3E_CPU0_PE2_SS_C_TXN<2> @BASEBOARD_FAB2_LIB.BASEBOARD_FAB2(SCH_1):P3E_CPU0_PE2_SS_C_TXN(2)    I61 @BASEBOARD_FAB2_LIB.BASEBOARD_FAB2(SCH_1):PAGE105

C8G7 CAP_0402-0.22UF,16V,10%,X7R,A3A
     1 P3E_CPU0_PE2_SS_TXN<1> @BASEBOARD_FAB2_LIB.BASEBOARD_FAB2(SCH_1):P3E_CPU0_PE2_SS_TXN(1)    I62 @BASEBOARD_FAB2_LIB.BASEBOARD_FAB2(SCH_1):PAGE105
     2 P3E_CPU0_PE2_SS_C_TXN<1> @BASEBOARD_FAB2_LIB.BASEBOARD_FAB2(SCH_1):P3E_CPU0_PE2_SS_C_TXN(1)    I62 @BASEBOARD_FAB2_LIB.BASEBOARD_FAB2(SCH_1):PAGE105

C8G8 CAP_0402-0.22UF,16V,10%,X7R,A3A
     1 P3E_CPU0_PE2_SS_TXP<1> @BASEBOARD_FAB2_LIB.BASEBOARD_FAB2(SCH_1):P3E_CPU0_PE2_SS_TXP(1)    I76 @BASEBOARD_FAB2_LIB.BASEBOARD_FAB2(SCH_1):PAGE105
     2 P3E_CPU0_PE2_SS_C_TXP<1> @BASEBOARD_FAB2_LIB.BASEBOARD_FAB2(SCH_1):P3E_CPU0_PE2_SS_C_TXP(1)    I76 @BASEBOARD_FAB2_LIB.BASEBOARD_FAB2(SCH_1):PAGE105

C8G9 CAP_0402-0.22UF,16V,10%,X7R,A3A
     1 P3E_CPU0_PE2_SS_TXP<0> @BASEBOARD_FAB2_LIB.BASEBOARD_FAB2(SCH_1):P3E_CPU0_PE2_SS_TXP(0)    I93 @BASEBOARD_FAB2_LIB.BASEBOARD_FAB2(SCH_1):PAGE105
     2 P3E_CPU0_PE2_SS_C_TXP<0> @BASEBOARD_FAB2_LIB.BASEBOARD_FAB2(SCH_1):P3E_CPU0_PE2_SS_C_TXP(0)    I93 @BASEBOARD_FAB2_LIB.BASEBOARD_FAB2(SCH_1):PAGE105

C8G10 CAP_0402-0.22UF,16V,10%,X7R,A3A
     1 P3E_CPU0_PE2_SS_TXN<0> @BASEBOARD_FAB2_LIB.BASEBOARD_FAB2(SCH_1):P3E_CPU0_PE2_SS_TXN(0)    I96 @BASEBOARD_FAB2_LIB.BASEBOARD_FAB2(SCH_1):PAGE105
     2 P3E_CPU0_PE2_SS_C_TXN<0> @BASEBOARD_FAB2_LIB.BASEBOARD_FAB2(SCH_1):P3E_CPU0_PE2_SS_C_TXN(0)    I96 @BASEBOARD_FAB2_LIB.BASEBOARD_FAB2(SCH_1):PAGE105

C8L1 CAP_0805-100UF,4V,20%,X5R,6024A
     1 PVDDQ_KLM @BASEBOARD_FAB2_LIB.BASEBOARD_FAB2(SCH_1):PVDDQ_KLM   I110 @BASEBOARD_FAB2_LIB.BASEBOARD_FAB2(SCH_1):PAGE228
     2    GND @BASEBOARD_FAB2_LIB.BASEBOARD_FAB2(SCH_1):GND   I110 @BASEBOARD_FAB2_LIB.BASEBOARD_FAB2(SCH_1):PAGE228

C8L2 CAP_0805-100UF,4V,20%,X5R,6024A
     1 PVDDQ_KLM @BASEBOARD_FAB2_LIB.BASEBOARD_FAB2(SCH_1):PVDDQ_KLM    I83 @BASEBOARD_FAB2_LIB.BASEBOARD_FAB2(SCH_1):PAGE228
     2    GND @BASEBOARD_FAB2_LIB.BASEBOARD_FAB2(SCH_1):GND    I83 @BASEBOARD_FAB2_LIB.BASEBOARD_FAB2(SCH_1):PAGE228

C8L3 CAP_A_0603V-47UF,4V,20%,X5R,60A
     1 PVTT_KLM @BASEBOARD_FAB2_LIB.BASEBOARD_FAB2(SCH_1):PVTT_KLM    I48 @BASEBOARD_FAB2_LIB.BASEBOARD_FAB2(SCH_1):PAGE230
     2    GND @BASEBOARD_FAB2_LIB.BASEBOARD_FAB2(SCH_1):GND    I48 @BASEBOARD_FAB2_LIB.BASEBOARD_FAB2(SCH_1):PAGE230

C8L4 CAP_A_0603V-47UF,4V,20%,X5R,60A
     1 PVTT_KLM @BASEBOARD_FAB2_LIB.BASEBOARD_FAB2(SCH_1):PVTT_KLM    I49 @BASEBOARD_FAB2_LIB.BASEBOARD_FAB2(SCH_1):PAGE230
     2    GND @BASEBOARD_FAB2_LIB.BASEBOARD_FAB2(SCH_1):GND    I49 @BASEBOARD_FAB2_LIB.BASEBOARD_FAB2(SCH_1):PAGE230

C8L5 CAP_A_0603V-22.0UF,4V,20%,X6S,A
     1 PVDDQ_KLM @BASEBOARD_FAB2_LIB.BASEBOARD_FAB2(SCH_1):PVDDQ_KLM   I241 @BASEBOARD_FAB2_LIB.BASEBOARD_FAB2(SCH_1):PAGE228
     2    GND @BASEBOARD_FAB2_LIB.BASEBOARD_FAB2(SCH_1):GND   I241 @BASEBOARD_FAB2_LIB.BASEBOARD_FAB2(SCH_1):PAGE228

C8L6 CAP_A_0603V-22.0UF,4V,20%,X6S,A
     1 PVDDQ_KLM @BASEBOARD_FAB2_LIB.BASEBOARD_FAB2(SCH_1):PVDDQ_KLM   I240 @BASEBOARD_FAB2_LIB.BASEBOARD_FAB2(SCH_1):PAGE228
     2    GND @BASEBOARD_FAB2_LIB.BASEBOARD_FAB2(SCH_1):GND   I240 @BASEBOARD_FAB2_LIB.BASEBOARD_FAB2(SCH_1):PAGE228

C8L7 CAP_A_0603V-22.0UF,4V,20%,X6S,A
     1 PVDDQ_KLM @BASEBOARD_FAB2_LIB.BASEBOARD_FAB2(SCH_1):PVDDQ_KLM   I239 @BASEBOARD_FAB2_LIB.BASEBOARD_FAB2(SCH_1):PAGE228
     2    GND @BASEBOARD_FAB2_LIB.BASEBOARD_FAB2(SCH_1):GND   I239 @BASEBOARD_FAB2_LIB.BASEBOARD_FAB2(SCH_1):PAGE228

C8L8 CAP_A_0603V-22.0UF,4V,20%,X6S,A
     1 PVDDQ_KLM @BASEBOARD_FAB2_LIB.BASEBOARD_FAB2(SCH_1):PVDDQ_KLM   I237 @BASEBOARD_FAB2_LIB.BASEBOARD_FAB2(SCH_1):PAGE228
     2    GND @BASEBOARD_FAB2_LIB.BASEBOARD_FAB2(SCH_1):GND   I237 @BASEBOARD_FAB2_LIB.BASEBOARD_FAB2(SCH_1):PAGE228

C8L9 CAP_A_0603V-22.0UF,4V,20%,X6S,A
     1 PVDDQ_KLM @BASEBOARD_FAB2_LIB.BASEBOARD_FAB2(SCH_1):PVDDQ_KLM   I236 @BASEBOARD_FAB2_LIB.BASEBOARD_FAB2(SCH_1):PAGE228
     2    GND @BASEBOARD_FAB2_LIB.BASEBOARD_FAB2(SCH_1):GND   I236 @BASEBOARD_FAB2_LIB.BASEBOARD_FAB2(SCH_1):PAGE228

C8L10 CAP_A_0603V-22.0UF,4V,20%,X6S,A
     1 PVDDQ_KLM @BASEBOARD_FAB2_LIB.BASEBOARD_FAB2(SCH_1):PVDDQ_KLM   I229 @BASEBOARD_FAB2_LIB.BASEBOARD_FAB2(SCH_1):PAGE228
     2    GND @BASEBOARD_FAB2_LIB.BASEBOARD_FAB2(SCH_1):GND   I229 @BASEBOARD_FAB2_LIB.BASEBOARD_FAB2(SCH_1):PAGE228

C8L11 CAP_0805-100UF,4V,20%,X5R,6024A
     1 PVDDQ_KLM @BASEBOARD_FAB2_LIB.BASEBOARD_FAB2(SCH_1):PVDDQ_KLM    I88 @BASEBOARD_FAB2_LIB.BASEBOARD_FAB2(SCH_1):PAGE228
     2    GND @BASEBOARD_FAB2_LIB.BASEBOARD_FAB2(SCH_1):GND    I88 @BASEBOARD_FAB2_LIB.BASEBOARD_FAB2(SCH_1):PAGE228

C8L12 CAP_A_0603V-47UF,4V,20%,X5R,60A
     1 PVDDQ_KLM @BASEBOARD_FAB2_LIB.BASEBOARD_FAB2(SCH_1):PVDDQ_KLM   I201 @BASEBOARD_FAB2_LIB.BASEBOARD_FAB2(SCH_1):PAGE228
     2    GND @BASEBOARD_FAB2_LIB.BASEBOARD_FAB2(SCH_1):GND   I201 @BASEBOARD_FAB2_LIB.BASEBOARD_FAB2(SCH_1):PAGE228

C8M1 CAP_A_0603V-22.0UF,4V,20%,X6S,A
     1 PVDDQ_KLM @BASEBOARD_FAB2_LIB.BASEBOARD_FAB2(SCH_1):PVDDQ_KLM   I243 @BASEBOARD_FAB2_LIB.BASEBOARD_FAB2(SCH_1):PAGE228
     2    GND @BASEBOARD_FAB2_LIB.BASEBOARD_FAB2(SCH_1):GND   I243 @BASEBOARD_FAB2_LIB.BASEBOARD_FAB2(SCH_1):PAGE228

C8M2 CAP_A_0603V-47UF,4V,20%,X5R,60A
     1 PVDDQ_KLM @BASEBOARD_FAB2_LIB.BASEBOARD_FAB2(SCH_1):PVDDQ_KLM   I206 @BASEBOARD_FAB2_LIB.BASEBOARD_FAB2(SCH_1):PAGE228
     2    GND @BASEBOARD_FAB2_LIB.BASEBOARD_FAB2(SCH_1):GND   I206 @BASEBOARD_FAB2_LIB.BASEBOARD_FAB2(SCH_1):PAGE228

C8M3 CAP_A_0603V-22.0UF,4V,20%,X6S,A
     1 PVDDQ_KLM @BASEBOARD_FAB2_LIB.BASEBOARD_FAB2(SCH_1):PVDDQ_KLM   I227 @BASEBOARD_FAB2_LIB.BASEBOARD_FAB2(SCH_1):PAGE228
     2    GND @BASEBOARD_FAB2_LIB.BASEBOARD_FAB2(SCH_1):GND   I227 @BASEBOARD_FAB2_LIB.BASEBOARD_FAB2(SCH_1):PAGE228

C8M4 CAP_A_0603V-22.0UF,4V,20%,X6S,A
     1 PVDDQ_KLM @BASEBOARD_FAB2_LIB.BASEBOARD_FAB2(SCH_1):PVDDQ_KLM   I233 @BASEBOARD_FAB2_LIB.BASEBOARD_FAB2(SCH_1):PAGE228
     2    GND @BASEBOARD_FAB2_LIB.BASEBOARD_FAB2(SCH_1):GND   I233 @BASEBOARD_FAB2_LIB.BASEBOARD_FAB2(SCH_1):PAGE228

C8M5 CAP_A_0603V-22.0UF,4V,20%,X6S,A
     1 PVDDQ_KLM @BASEBOARD_FAB2_LIB.BASEBOARD_FAB2(SCH_1):PVDDQ_KLM   I228 @BASEBOARD_FAB2_LIB.BASEBOARD_FAB2(SCH_1):PAGE228
     2    GND @BASEBOARD_FAB2_LIB.BASEBOARD_FAB2(SCH_1):GND   I228 @BASEBOARD_FAB2_LIB.BASEBOARD_FAB2(SCH_1):PAGE228

C8M6 CAP_A_0603V-22.0UF,4V,20%,X6S,A
     1 PVDDQ_KLM @BASEBOARD_FAB2_LIB.BASEBOARD_FAB2(SCH_1):PVDDQ_KLM   I235 @BASEBOARD_FAB2_LIB.BASEBOARD_FAB2(SCH_1):PAGE228
     2    GND @BASEBOARD_FAB2_LIB.BASEBOARD_FAB2(SCH_1):GND   I235 @BASEBOARD_FAB2_LIB.BASEBOARD_FAB2(SCH_1):PAGE228

C8M7 CAP_0805-100UF,4V,20%,X5R,6024A
     1 PVDDQ_KLM @BASEBOARD_FAB2_LIB.BASEBOARD_FAB2(SCH_1):PVDDQ_KLM    I90 @BASEBOARD_FAB2_LIB.BASEBOARD_FAB2(SCH_1):PAGE228
     2    GND @BASEBOARD_FAB2_LIB.BASEBOARD_FAB2(SCH_1):GND    I90 @BASEBOARD_FAB2_LIB.BASEBOARD_FAB2(SCH_1):PAGE228

C8M8 CAP_A_0603V-47UF,4V,20%,X5R,60A
     1 PVDDQ_KLM @BASEBOARD_FAB2_LIB.BASEBOARD_FAB2(SCH_1):PVDDQ_KLM   I198 @BASEBOARD_FAB2_LIB.BASEBOARD_FAB2(SCH_1):PAGE228
     2    GND @BASEBOARD_FAB2_LIB.BASEBOARD_FAB2(SCH_1):GND   I198 @BASEBOARD_FAB2_LIB.BASEBOARD_FAB2(SCH_1):PAGE228

C8M9 CAP_A_0603V-47UF,4V,20%,X5R,60A
     1 PVDDQ_KLM @BASEBOARD_FAB2_LIB.BASEBOARD_FAB2(SCH_1):PVDDQ_KLM   I205 @BASEBOARD_FAB2_LIB.BASEBOARD_FAB2(SCH_1):PAGE228
     2    GND @BASEBOARD_FAB2_LIB.BASEBOARD_FAB2(SCH_1):GND   I205 @BASEBOARD_FAB2_LIB.BASEBOARD_FAB2(SCH_1):PAGE228

C8M10 CAP_A_0603V-47UF,4V,20%,X5R,60A
     1 PVDDQ_KLM @BASEBOARD_FAB2_LIB.BASEBOARD_FAB2(SCH_1):PVDDQ_KLM   I203 @BASEBOARD_FAB2_LIB.BASEBOARD_FAB2(SCH_1):PAGE228
     2    GND @BASEBOARD_FAB2_LIB.BASEBOARD_FAB2(SCH_1):GND   I203 @BASEBOARD_FAB2_LIB.BASEBOARD_FAB2(SCH_1):PAGE228

C8M11 CAP_0805-100UF,4V,20%,X5R,6024A
     1 PVDDQ_KLM @BASEBOARD_FAB2_LIB.BASEBOARD_FAB2(SCH_1):PVDDQ_KLM    I91 @BASEBOARD_FAB2_LIB.BASEBOARD_FAB2(SCH_1):PAGE228
     2    GND @BASEBOARD_FAB2_LIB.BASEBOARD_FAB2(SCH_1):GND    I91 @BASEBOARD_FAB2_LIB.BASEBOARD_FAB2(SCH_1):PAGE228

C8M12 CAP_A_0603V-47UF,4V,20%,X5R,60A
     1 PVTT_KLM @BASEBOARD_FAB2_LIB.BASEBOARD_FAB2(SCH_1):PVTT_KLM    I47 @BASEBOARD_FAB2_LIB.BASEBOARD_FAB2(SCH_1):PAGE230
     2    GND @BASEBOARD_FAB2_LIB.BASEBOARD_FAB2(SCH_1):GND    I47 @BASEBOARD_FAB2_LIB.BASEBOARD_FAB2(SCH_1):PAGE230

C8P1 CAP_0805LF-22UF,4V,20%,X6S,C95A
     1 PVDDQ_KLM @BASEBOARD_FAB2_LIB.BASEBOARD_FAB2(SCH_1):PVDDQ_KLM   I185 @BASEBOARD_FAB2_LIB.BASEBOARD_FAB2(SCH_1):PAGE228
     2    GND @BASEBOARD_FAB2_LIB.BASEBOARD_FAB2(SCH_1):GND   I185 @BASEBOARD_FAB2_LIB.BASEBOARD_FAB2(SCH_1):PAGE228

C8P2 CAP_0805LF-22UF,4V,20%,X6S,C95A
     1 PVDDQ_KLM @BASEBOARD_FAB2_LIB.BASEBOARD_FAB2(SCH_1):PVDDQ_KLM   I183 @BASEBOARD_FAB2_LIB.BASEBOARD_FAB2(SCH_1):PAGE228
     2    GND @BASEBOARD_FAB2_LIB.BASEBOARD_FAB2(SCH_1):GND   I183 @BASEBOARD_FAB2_LIB.BASEBOARD_FAB2(SCH_1):PAGE228

C8P3 CAP_0805-47UF,4V,20%,X6S,C9533A
     1 PVCCIN_CPU1 @BASEBOARD_FAB2_LIB.BASEBOARD_FAB2(SCH_1):PVCCIN_CPU1   I101 @BASEBOARD_FAB2_LIB.BASEBOARD_FAB2(SCH_1):PAGE76
     2    GND @BASEBOARD_FAB2_LIB.BASEBOARD_FAB2(SCH_1):GND   I101 @BASEBOARD_FAB2_LIB.BASEBOARD_FAB2(SCH_1):PAGE76

C8P4 CAP_0805-47UF,4V,20%,X6S,C9533A
     1 PVCCIN_CPU1 @BASEBOARD_FAB2_LIB.BASEBOARD_FAB2(SCH_1):PVCCIN_CPU1    I88 @BASEBOARD_FAB2_LIB.BASEBOARD_FAB2(SCH_1):PAGE76
     2    GND @BASEBOARD_FAB2_LIB.BASEBOARD_FAB2(SCH_1):GND    I88 @BASEBOARD_FAB2_LIB.BASEBOARD_FAB2(SCH_1):PAGE76

C8P5 CAP_0805LF-22UF,4V,20%,X6S,C95A
     1 PVSA_CPU1 @BASEBOARD_FAB2_LIB.BASEBOARD_FAB2(SCH_1):PVSA_CPU1    I58 @BASEBOARD_FAB2_LIB.BASEBOARD_FAB2(SCH_1):PAGE76
     2    GND @BASEBOARD_FAB2_LIB.BASEBOARD_FAB2(SCH_1):GND    I58 @BASEBOARD_FAB2_LIB.BASEBOARD_FAB2(SCH_1):PAGE76

C8P6 CAP_0805LF-22UF,4V,20%,X6S,C95A
     1 PVSA_CPU1 @BASEBOARD_FAB2_LIB.BASEBOARD_FAB2(SCH_1):PVSA_CPU1    I55 @BASEBOARD_FAB2_LIB.BASEBOARD_FAB2(SCH_1):PAGE76
     2    GND @BASEBOARD_FAB2_LIB.BASEBOARD_FAB2(SCH_1):GND    I55 @BASEBOARD_FAB2_LIB.BASEBOARD_FAB2(SCH_1):PAGE76

C8P7 CAP_0805LF-22UF,4V,20%,X6S,C95A
     1 PVSA_CPU1 @BASEBOARD_FAB2_LIB.BASEBOARD_FAB2(SCH_1):PVSA_CPU1    I50 @BASEBOARD_FAB2_LIB.BASEBOARD_FAB2(SCH_1):PAGE76
     2    GND @BASEBOARD_FAB2_LIB.BASEBOARD_FAB2(SCH_1):GND    I50 @BASEBOARD_FAB2_LIB.BASEBOARD_FAB2(SCH_1):PAGE76

C8P8 CAP_0805-47UF,4V,20%,X6S,C9533A
     1 PVCCMCP_CPU1 @BASEBOARD_FAB2_LIB.BASEBOARD_FAB2(SCH_1):PVCCMCP_CPU1   I213 @BASEBOARD_FAB2_LIB.BASEBOARD_FAB2(SCH_1):PAGE76
     2    GND @BASEBOARD_FAB2_LIB.BASEBOARD_FAB2(SCH_1):GND   I213 @BASEBOARD_FAB2_LIB.BASEBOARD_FAB2(SCH_1):PAGE76

C8P9 CAP_0805-47UF,4V,20%,X6S,C9533A
     1 PVCCMCP_CPU1 @BASEBOARD_FAB2_LIB.BASEBOARD_FAB2(SCH_1):PVCCMCP_CPU1   I214 @BASEBOARD_FAB2_LIB.BASEBOARD_FAB2(SCH_1):PAGE76
     2    GND @BASEBOARD_FAB2_LIB.BASEBOARD_FAB2(SCH_1):GND   I214 @BASEBOARD_FAB2_LIB.BASEBOARD_FAB2(SCH_1):PAGE76

C8P10 CAP_0805-47UF,4V,20%,X6S,C9533A
     1 PVCCIN_CPU1 @BASEBOARD_FAB2_LIB.BASEBOARD_FAB2(SCH_1):PVCCIN_CPU1   I127 @BASEBOARD_FAB2_LIB.BASEBOARD_FAB2(SCH_1):PAGE76
     2    GND @BASEBOARD_FAB2_LIB.BASEBOARD_FAB2(SCH_1):GND   I127 @BASEBOARD_FAB2_LIB.BASEBOARD_FAB2(SCH_1):PAGE76

C8P11 CAP_0805-47UF,4V,20%,X6S,C9533A
     1 PVCCIN_CPU1 @BASEBOARD_FAB2_LIB.BASEBOARD_FAB2(SCH_1):PVCCIN_CPU1   I139 @BASEBOARD_FAB2_LIB.BASEBOARD_FAB2(SCH_1):PAGE76
     2    GND @BASEBOARD_FAB2_LIB.BASEBOARD_FAB2(SCH_1):GND   I139 @BASEBOARD_FAB2_LIB.BASEBOARD_FAB2(SCH_1):PAGE76

C8P12 CAP_0805-47UF,4V,20%,X6S,C9533A
     1 PVCCIN_CPU1 @BASEBOARD_FAB2_LIB.BASEBOARD_FAB2(SCH_1):PVCCIN_CPU1   I107 @BASEBOARD_FAB2_LIB.BASEBOARD_FAB2(SCH_1):PAGE76
     2    GND @BASEBOARD_FAB2_LIB.BASEBOARD_FAB2(SCH_1):GND   I107 @BASEBOARD_FAB2_LIB.BASEBOARD_FAB2(SCH_1):PAGE76

C8P13 CAP_0805-47UF,4V,20%,X6S,C9533A
     1 PVCCIN_CPU1 @BASEBOARD_FAB2_LIB.BASEBOARD_FAB2(SCH_1):PVCCIN_CPU1   I132 @BASEBOARD_FAB2_LIB.BASEBOARD_FAB2(SCH_1):PAGE76
     2    GND @BASEBOARD_FAB2_LIB.BASEBOARD_FAB2(SCH_1):GND   I132 @BASEBOARD_FAB2_LIB.BASEBOARD_FAB2(SCH_1):PAGE76

C8P14 CAP_0805-47UF,4V,20%,X6S,C9533A
     1 PVCCMCP_CPU1 @BASEBOARD_FAB2_LIB.BASEBOARD_FAB2(SCH_1):PVCCMCP_CPU1   I211 @BASEBOARD_FAB2_LIB.BASEBOARD_FAB2(SCH_1):PAGE76
     2    GND @BASEBOARD_FAB2_LIB.BASEBOARD_FAB2(SCH_1):GND   I211 @BASEBOARD_FAB2_LIB.BASEBOARD_FAB2(SCH_1):PAGE76

C8P15 CAP_0805-47UF,4V,20%,X6S,C9533A
     1 PVCCMCP_CPU1 @BASEBOARD_FAB2_LIB.BASEBOARD_FAB2(SCH_1):PVCCMCP_CPU1   I212 @BASEBOARD_FAB2_LIB.BASEBOARD_FAB2(SCH_1):PAGE76
     2    GND @BASEBOARD_FAB2_LIB.BASEBOARD_FAB2(SCH_1):GND   I212 @BASEBOARD_FAB2_LIB.BASEBOARD_FAB2(SCH_1):PAGE76

C8P16 CAP_0805-47UF,4V,20%,X6S,C9533A
     1 PVCCIN_CPU1 @BASEBOARD_FAB2_LIB.BASEBOARD_FAB2(SCH_1):PVCCIN_CPU1   I129 @BASEBOARD_FAB2_LIB.BASEBOARD_FAB2(SCH_1):PAGE76
     2    GND @BASEBOARD_FAB2_LIB.BASEBOARD_FAB2(SCH_1):GND   I129 @BASEBOARD_FAB2_LIB.BASEBOARD_FAB2(SCH_1):PAGE76

C8P17 CAP_0805-47UF,4V,20%,X6S,C9533A
     1 PVCCIN_CPU1 @BASEBOARD_FAB2_LIB.BASEBOARD_FAB2(SCH_1):PVCCIN_CPU1   I133 @BASEBOARD_FAB2_LIB.BASEBOARD_FAB2(SCH_1):PAGE76
     2    GND @BASEBOARD_FAB2_LIB.BASEBOARD_FAB2(SCH_1):GND   I133 @BASEBOARD_FAB2_LIB.BASEBOARD_FAB2(SCH_1):PAGE76

C8P18 CAP_0805-47UF,4V,20%,X6S,C9533A
     1 PVCCIN_CPU1 @BASEBOARD_FAB2_LIB.BASEBOARD_FAB2(SCH_1):PVCCIN_CPU1    I92 @BASEBOARD_FAB2_LIB.BASEBOARD_FAB2(SCH_1):PAGE76
     2    GND @BASEBOARD_FAB2_LIB.BASEBOARD_FAB2(SCH_1):GND    I92 @BASEBOARD_FAB2_LIB.BASEBOARD_FAB2(SCH_1):PAGE76

C8P19 CAP_0805-47UF,4V,20%,X6S,C9533A
     1 PVCCIN_CPU1 @BASEBOARD_FAB2_LIB.BASEBOARD_FAB2(SCH_1):PVCCIN_CPU1   I103 @BASEBOARD_FAB2_LIB.BASEBOARD_FAB2(SCH_1):PAGE76
     2    GND @BASEBOARD_FAB2_LIB.BASEBOARD_FAB2(SCH_1):GND   I103 @BASEBOARD_FAB2_LIB.BASEBOARD_FAB2(SCH_1):PAGE76

C8P20 CAP_0805-47UF,4V,20%,X6S,C9533A
     1 PVCCIN_CPU1 @BASEBOARD_FAB2_LIB.BASEBOARD_FAB2(SCH_1):PVCCIN_CPU1    I89 @BASEBOARD_FAB2_LIB.BASEBOARD_FAB2(SCH_1):PAGE76
     2    GND @BASEBOARD_FAB2_LIB.BASEBOARD_FAB2(SCH_1):GND    I89 @BASEBOARD_FAB2_LIB.BASEBOARD_FAB2(SCH_1):PAGE76

C8P21 CAP_0805-47UF,4V,20%,X6S,C9533A
     1 PVCCIN_CPU1 @BASEBOARD_FAB2_LIB.BASEBOARD_FAB2(SCH_1):PVCCIN_CPU1   I135 @BASEBOARD_FAB2_LIB.BASEBOARD_FAB2(SCH_1):PAGE76
     2    GND @BASEBOARD_FAB2_LIB.BASEBOARD_FAB2(SCH_1):GND   I135 @BASEBOARD_FAB2_LIB.BASEBOARD_FAB2(SCH_1):PAGE76

C8P22 CAP_0805-47UF,4V,20%,X6S,C9533A
     1 PVCCMCP_CPU1 @BASEBOARD_FAB2_LIB.BASEBOARD_FAB2(SCH_1):PVCCMCP_CPU1    I28 @BASEBOARD_FAB2_LIB.BASEBOARD_FAB2(SCH_1):PAGE76
     2    GND @BASEBOARD_FAB2_LIB.BASEBOARD_FAB2(SCH_1):GND    I28 @BASEBOARD_FAB2_LIB.BASEBOARD_FAB2(SCH_1):PAGE76

C8P23 CAP_0805-47UF,4V,20%,X6S,C9533A
     1 PVCCMCP_CPU1 @BASEBOARD_FAB2_LIB.BASEBOARD_FAB2(SCH_1):PVCCMCP_CPU1    I48 @BASEBOARD_FAB2_LIB.BASEBOARD_FAB2(SCH_1):PAGE76
     2    GND @BASEBOARD_FAB2_LIB.BASEBOARD_FAB2(SCH_1):GND    I48 @BASEBOARD_FAB2_LIB.BASEBOARD_FAB2(SCH_1):PAGE76

C8P24 CAP_0805-47UF,4V,20%,X6S,C9533A
     1 PVCCIN_CPU1 @BASEBOARD_FAB2_LIB.BASEBOARD_FAB2(SCH_1):PVCCIN_CPU1   I217 @BASEBOARD_FAB2_LIB.BASEBOARD_FAB2(SCH_1):PAGE76
     2    GND @BASEBOARD_FAB2_LIB.BASEBOARD_FAB2(SCH_1):GND   I217 @BASEBOARD_FAB2_LIB.BASEBOARD_FAB2(SCH_1):PAGE76

C8P25 CAP_0805-47UF,4V,20%,X6S,C9533A
     1 PVCCIN_CPU1 @BASEBOARD_FAB2_LIB.BASEBOARD_FAB2(SCH_1):PVCCIN_CPU1   I136 @BASEBOARD_FAB2_LIB.BASEBOARD_FAB2(SCH_1):PAGE76
     2    GND @BASEBOARD_FAB2_LIB.BASEBOARD_FAB2(SCH_1):GND   I136 @BASEBOARD_FAB2_LIB.BASEBOARD_FAB2(SCH_1):PAGE76

C8P26 CAP_0805-47UF,4V,20%,X6S,C9533A
     1 PVCCIN_CPU1 @BASEBOARD_FAB2_LIB.BASEBOARD_FAB2(SCH_1):PVCCIN_CPU1   I118 @BASEBOARD_FAB2_LIB.BASEBOARD_FAB2(SCH_1):PAGE76
     2    GND @BASEBOARD_FAB2_LIB.BASEBOARD_FAB2(SCH_1):GND   I118 @BASEBOARD_FAB2_LIB.BASEBOARD_FAB2(SCH_1):PAGE76

C8P27 CAP_0805-47UF,4V,20%,X6S,C9533A
     1 PVCCIN_CPU1 @BASEBOARD_FAB2_LIB.BASEBOARD_FAB2(SCH_1):PVCCIN_CPU1   I141 @BASEBOARD_FAB2_LIB.BASEBOARD_FAB2(SCH_1):PAGE76
     2    GND @BASEBOARD_FAB2_LIB.BASEBOARD_FAB2(SCH_1):GND   I141 @BASEBOARD_FAB2_LIB.BASEBOARD_FAB2(SCH_1):PAGE76

C8P28 CAP_0805-47UF,4V,20%,X6S,C9533A
     1 PVCCIN_CPU1 @BASEBOARD_FAB2_LIB.BASEBOARD_FAB2(SCH_1):PVCCIN_CPU1   I137 @BASEBOARD_FAB2_LIB.BASEBOARD_FAB2(SCH_1):PAGE76
     2    GND @BASEBOARD_FAB2_LIB.BASEBOARD_FAB2(SCH_1):GND   I137 @BASEBOARD_FAB2_LIB.BASEBOARD_FAB2(SCH_1):PAGE76

C8P29 CAP_0805-47UF,4V,20%,X6S,C9533A
     1 PVCCIN_CPU1 @BASEBOARD_FAB2_LIB.BASEBOARD_FAB2(SCH_1):PVCCIN_CPU1   I125 @BASEBOARD_FAB2_LIB.BASEBOARD_FAB2(SCH_1):PAGE76
     2    GND @BASEBOARD_FAB2_LIB.BASEBOARD_FAB2(SCH_1):GND   I125 @BASEBOARD_FAB2_LIB.BASEBOARD_FAB2(SCH_1):PAGE76

C8P30 CAP_0805LF-22UF,4V,20%,X6S,C95A
     1 PVDDQ_GHJ @BASEBOARD_FAB2_LIB.BASEBOARD_FAB2(SCH_1):PVDDQ_GHJ   I184 @BASEBOARD_FAB2_LIB.BASEBOARD_FAB2(SCH_1):PAGE225
     2    GND @BASEBOARD_FAB2_LIB.BASEBOARD_FAB2(SCH_1):GND   I184 @BASEBOARD_FAB2_LIB.BASEBOARD_FAB2(SCH_1):PAGE225

C8P31 CAP_0805LF-22UF,4V,20%,X6S,C95A
     1 PVDDQ_GHJ @BASEBOARD_FAB2_LIB.BASEBOARD_FAB2(SCH_1):PVDDQ_GHJ   I178 @BASEBOARD_FAB2_LIB.BASEBOARD_FAB2(SCH_1):PAGE225
     2    GND @BASEBOARD_FAB2_LIB.BASEBOARD_FAB2(SCH_1):GND   I178 @BASEBOARD_FAB2_LIB.BASEBOARD_FAB2(SCH_1):PAGE225

C8P32 CAP_0805-47UF,4V,20%,X6S,C9533A
     1 PVCCIN_CPU1 @BASEBOARD_FAB2_LIB.BASEBOARD_FAB2(SCH_1):PVCCIN_CPU1   I216 @BASEBOARD_FAB2_LIB.BASEBOARD_FAB2(SCH_1):PAGE76
     2    GND @BASEBOARD_FAB2_LIB.BASEBOARD_FAB2(SCH_1):GND   I216 @BASEBOARD_FAB2_LIB.BASEBOARD_FAB2(SCH_1):PAGE76

C8P33 CAP_0805-47UF,4V,20%,X6S,C9533A
     1 PVCCIN_CPU1 @BASEBOARD_FAB2_LIB.BASEBOARD_FAB2(SCH_1):PVCCIN_CPU1   I131 @BASEBOARD_FAB2_LIB.BASEBOARD_FAB2(SCH_1):PAGE76
     2    GND @BASEBOARD_FAB2_LIB.BASEBOARD_FAB2(SCH_1):GND   I131 @BASEBOARD_FAB2_LIB.BASEBOARD_FAB2(SCH_1):PAGE76

C8P34 CAP_0805-47UF,4V,20%,X6S,C9533A
     1 PVCCIN_CPU1 @BASEBOARD_FAB2_LIB.BASEBOARD_FAB2(SCH_1):PVCCIN_CPU1   I106 @BASEBOARD_FAB2_LIB.BASEBOARD_FAB2(SCH_1):PAGE76
     2    GND @BASEBOARD_FAB2_LIB.BASEBOARD_FAB2(SCH_1):GND   I106 @BASEBOARD_FAB2_LIB.BASEBOARD_FAB2(SCH_1):PAGE76

C8T1 CAP_A_0603V-47UF,4V,20%,X5R,60A
     1 PVDDQ_GHJ @BASEBOARD_FAB2_LIB.BASEBOARD_FAB2(SCH_1):PVDDQ_GHJ   I202 @BASEBOARD_FAB2_LIB.BASEBOARD_FAB2(SCH_1):PAGE225
     2    GND @BASEBOARD_FAB2_LIB.BASEBOARD_FAB2(SCH_1):GND   I202 @BASEBOARD_FAB2_LIB.BASEBOARD_FAB2(SCH_1):PAGE225

C8T2 CAP_A_0603V-47UF,4V,20%,X5R,60A
     1 PVDDQ_GHJ @BASEBOARD_FAB2_LIB.BASEBOARD_FAB2(SCH_1):PVDDQ_GHJ   I198 @BASEBOARD_FAB2_LIB.BASEBOARD_FAB2(SCH_1):PAGE225
     2    GND @BASEBOARD_FAB2_LIB.BASEBOARD_FAB2(SCH_1):GND   I198 @BASEBOARD_FAB2_LIB.BASEBOARD_FAB2(SCH_1):PAGE225

C8T3 CAP_A_0603V-47UF,4V,20%,X5R,60A
     1 PVTT_GHJ @BASEBOARD_FAB2_LIB.BASEBOARD_FAB2(SCH_1):PVTT_GHJ    I48 @BASEBOARD_FAB2_LIB.BASEBOARD_FAB2(SCH_1):PAGE229
     2    GND @BASEBOARD_FAB2_LIB.BASEBOARD_FAB2(SCH_1):GND    I48 @BASEBOARD_FAB2_LIB.BASEBOARD_FAB2(SCH_1):PAGE229

C8T4 CAP_A_0603V-47UF,4V,20%,X5R,60A
     1 PVDDQ_GHJ @BASEBOARD_FAB2_LIB.BASEBOARD_FAB2(SCH_1):PVDDQ_GHJ   I196 @BASEBOARD_FAB2_LIB.BASEBOARD_FAB2(SCH_1):PAGE225
     2    GND @BASEBOARD_FAB2_LIB.BASEBOARD_FAB2(SCH_1):GND   I196 @BASEBOARD_FAB2_LIB.BASEBOARD_FAB2(SCH_1):PAGE225

C8T5 CAP_A_0603V-22.0UF,4V,20%,X6S,A
     1 PVDDQ_GHJ @BASEBOARD_FAB2_LIB.BASEBOARD_FAB2(SCH_1):PVDDQ_GHJ   I233 @BASEBOARD_FAB2_LIB.BASEBOARD_FAB2(SCH_1):PAGE225
     2    GND @BASEBOARD_FAB2_LIB.BASEBOARD_FAB2(SCH_1):GND   I233 @BASEBOARD_FAB2_LIB.BASEBOARD_FAB2(SCH_1):PAGE225

C8T6 CAP_A_0603V-22.0UF,4V,20%,X6S,A
     1 PVDDQ_GHJ @BASEBOARD_FAB2_LIB.BASEBOARD_FAB2(SCH_1):PVDDQ_GHJ   I231 @BASEBOARD_FAB2_LIB.BASEBOARD_FAB2(SCH_1):PAGE225
     2    GND @BASEBOARD_FAB2_LIB.BASEBOARD_FAB2(SCH_1):GND   I231 @BASEBOARD_FAB2_LIB.BASEBOARD_FAB2(SCH_1):PAGE225

C8T7 CAP_A_0603V-22.0UF,4V,20%,X6S,A
     1 PVDDQ_GHJ @BASEBOARD_FAB2_LIB.BASEBOARD_FAB2(SCH_1):PVDDQ_GHJ   I230 @BASEBOARD_FAB2_LIB.BASEBOARD_FAB2(SCH_1):PAGE225
     2    GND @BASEBOARD_FAB2_LIB.BASEBOARD_FAB2(SCH_1):GND   I230 @BASEBOARD_FAB2_LIB.BASEBOARD_FAB2(SCH_1):PAGE225

C8T8 CAP_A_0603V-22.0UF,4V,20%,X6S,A
     1 PVDDQ_GHJ @BASEBOARD_FAB2_LIB.BASEBOARD_FAB2(SCH_1):PVDDQ_GHJ   I229 @BASEBOARD_FAB2_LIB.BASEBOARD_FAB2(SCH_1):PAGE225
     2    GND @BASEBOARD_FAB2_LIB.BASEBOARD_FAB2(SCH_1):GND   I229 @BASEBOARD_FAB2_LIB.BASEBOARD_FAB2(SCH_1):PAGE225

C8T9 CAP_A_0603V-22.0UF,4V,20%,X6S,A
     1 PVDDQ_GHJ @BASEBOARD_FAB2_LIB.BASEBOARD_FAB2(SCH_1):PVDDQ_GHJ   I227 @BASEBOARD_FAB2_LIB.BASEBOARD_FAB2(SCH_1):PAGE225
     2    GND @BASEBOARD_FAB2_LIB.BASEBOARD_FAB2(SCH_1):GND   I227 @BASEBOARD_FAB2_LIB.BASEBOARD_FAB2(SCH_1):PAGE225

C8T10 CAP_A_0603V-22.0UF,4V,20%,X6S,A
     1 PVDDQ_GHJ @BASEBOARD_FAB2_LIB.BASEBOARD_FAB2(SCH_1):PVDDQ_GHJ   I226 @BASEBOARD_FAB2_LIB.BASEBOARD_FAB2(SCH_1):PAGE225
     2    GND @BASEBOARD_FAB2_LIB.BASEBOARD_FAB2(SCH_1):GND   I226 @BASEBOARD_FAB2_LIB.BASEBOARD_FAB2(SCH_1):PAGE225

C8T11 CAP_A_0603V-47UF,4V,20%,X5R,60A
     1 PVDDQ_GHJ @BASEBOARD_FAB2_LIB.BASEBOARD_FAB2(SCH_1):PVDDQ_GHJ   I204 @BASEBOARD_FAB2_LIB.BASEBOARD_FAB2(SCH_1):PAGE225
     2    GND @BASEBOARD_FAB2_LIB.BASEBOARD_FAB2(SCH_1):GND   I204 @BASEBOARD_FAB2_LIB.BASEBOARD_FAB2(SCH_1):PAGE225

C8U1 CAP_0805-100UF,4V,20%,X5R,6024A
     1 PVDDQ_GHJ @BASEBOARD_FAB2_LIB.BASEBOARD_FAB2(SCH_1):PVDDQ_GHJ    I82 @BASEBOARD_FAB2_LIB.BASEBOARD_FAB2(SCH_1):PAGE225
     2    GND @BASEBOARD_FAB2_LIB.BASEBOARD_FAB2(SCH_1):GND    I82 @BASEBOARD_FAB2_LIB.BASEBOARD_FAB2(SCH_1):PAGE225

C8U2 CAP_A_0603V-22.0UF,4V,20%,X6S,A
     1 PVDDQ_GHJ @BASEBOARD_FAB2_LIB.BASEBOARD_FAB2(SCH_1):PVDDQ_GHJ   I239 @BASEBOARD_FAB2_LIB.BASEBOARD_FAB2(SCH_1):PAGE225
     2    GND @BASEBOARD_FAB2_LIB.BASEBOARD_FAB2(SCH_1):GND   I239 @BASEBOARD_FAB2_LIB.BASEBOARD_FAB2(SCH_1):PAGE225

C8U3 CAP_A_0603V-22.0UF,4V,20%,X6S,A
     1 PVDDQ_GHJ @BASEBOARD_FAB2_LIB.BASEBOARD_FAB2(SCH_1):PVDDQ_GHJ   I236 @BASEBOARD_FAB2_LIB.BASEBOARD_FAB2(SCH_1):PAGE225
     2    GND @BASEBOARD_FAB2_LIB.BASEBOARD_FAB2(SCH_1):GND   I236 @BASEBOARD_FAB2_LIB.BASEBOARD_FAB2(SCH_1):PAGE225

C8U4 CAP_A_0603V-22.0UF,4V,20%,X6S,A
     1 PVDDQ_GHJ @BASEBOARD_FAB2_LIB.BASEBOARD_FAB2(SCH_1):PVDDQ_GHJ   I225 @BASEBOARD_FAB2_LIB.BASEBOARD_FAB2(SCH_1):PAGE225
     2    GND @BASEBOARD_FAB2_LIB.BASEBOARD_FAB2(SCH_1):GND   I225 @BASEBOARD_FAB2_LIB.BASEBOARD_FAB2(SCH_1):PAGE225

C8U5 CAP_A_0603V-22.0UF,4V,20%,X6S,A
     1 PVDDQ_GHJ @BASEBOARD_FAB2_LIB.BASEBOARD_FAB2(SCH_1):PVDDQ_GHJ   I228 @BASEBOARD_FAB2_LIB.BASEBOARD_FAB2(SCH_1):PAGE225
     2    GND @BASEBOARD_FAB2_LIB.BASEBOARD_FAB2(SCH_1):GND   I228 @BASEBOARD_FAB2_LIB.BASEBOARD_FAB2(SCH_1):PAGE225

C8U6 CAP_A_0603V-22.0UF,4V,20%,X6S,A
     1 PVDDQ_GHJ @BASEBOARD_FAB2_LIB.BASEBOARD_FAB2(SCH_1):PVDDQ_GHJ   I232 @BASEBOARD_FAB2_LIB.BASEBOARD_FAB2(SCH_1):PAGE225
     2    GND @BASEBOARD_FAB2_LIB.BASEBOARD_FAB2(SCH_1):GND   I232 @BASEBOARD_FAB2_LIB.BASEBOARD_FAB2(SCH_1):PAGE225

C8U7 CAP_A_0603V-22.0UF,4V,20%,X6S,A
     1 PVDDQ_GHJ @BASEBOARD_FAB2_LIB.BASEBOARD_FAB2(SCH_1):PVDDQ_GHJ   I241 @BASEBOARD_FAB2_LIB.BASEBOARD_FAB2(SCH_1):PAGE225
     2    GND @BASEBOARD_FAB2_LIB.BASEBOARD_FAB2(SCH_1):GND   I241 @BASEBOARD_FAB2_LIB.BASEBOARD_FAB2(SCH_1):PAGE225

C8U8 CAP_0805-100UF,4V,20%,X5R,6024A
     1 PVDDQ_GHJ @BASEBOARD_FAB2_LIB.BASEBOARD_FAB2(SCH_1):PVDDQ_GHJ    I83 @BASEBOARD_FAB2_LIB.BASEBOARD_FAB2(SCH_1):PAGE225
     2    GND @BASEBOARD_FAB2_LIB.BASEBOARD_FAB2(SCH_1):GND    I83 @BASEBOARD_FAB2_LIB.BASEBOARD_FAB2(SCH_1):PAGE225

C8U9 CAP_A_0603V-47UF,4V,20%,X5R,60A
     1 PVDDQ_GHJ @BASEBOARD_FAB2_LIB.BASEBOARD_FAB2(SCH_1):PVDDQ_GHJ   I203 @BASEBOARD_FAB2_LIB.BASEBOARD_FAB2(SCH_1):PAGE225
     2    GND @BASEBOARD_FAB2_LIB.BASEBOARD_FAB2(SCH_1):GND   I203 @BASEBOARD_FAB2_LIB.BASEBOARD_FAB2(SCH_1):PAGE225

C8U10 CAP_A_0603V-47UF,4V,20%,X5R,60A
     1 PVTT_GHJ @BASEBOARD_FAB2_LIB.BASEBOARD_FAB2(SCH_1):PVTT_GHJ    I49 @BASEBOARD_FAB2_LIB.BASEBOARD_FAB2(SCH_1):PAGE229
     2    GND @BASEBOARD_FAB2_LIB.BASEBOARD_FAB2(SCH_1):GND    I49 @BASEBOARD_FAB2_LIB.BASEBOARD_FAB2(SCH_1):PAGE229

C8U11 CAP_0805-100UF,4V,20%,X5R,6024A
     1 PVDDQ_GHJ @BASEBOARD_FAB2_LIB.BASEBOARD_FAB2(SCH_1):PVDDQ_GHJ    I89 @BASEBOARD_FAB2_LIB.BASEBOARD_FAB2(SCH_1):PAGE225
     2    GND @BASEBOARD_FAB2_LIB.BASEBOARD_FAB2(SCH_1):GND    I89 @BASEBOARD_FAB2_LIB.BASEBOARD_FAB2(SCH_1):PAGE225

C8U12 CAP_0805-100UF,4V,20%,X5R,6024A
     1 PVDDQ_GHJ @BASEBOARD_FAB2_LIB.BASEBOARD_FAB2(SCH_1):PVDDQ_GHJ    I88 @BASEBOARD_FAB2_LIB.BASEBOARD_FAB2(SCH_1):PAGE225
     2    GND @BASEBOARD_FAB2_LIB.BASEBOARD_FAB2(SCH_1):GND    I88 @BASEBOARD_FAB2_LIB.BASEBOARD_FAB2(SCH_1):PAGE225

C8U13 CAP_A_0603V-47UF,4V,20%,X5R,60A
     1 PVDDQ_GHJ @BASEBOARD_FAB2_LIB.BASEBOARD_FAB2(SCH_1):PVDDQ_GHJ   I199 @BASEBOARD_FAB2_LIB.BASEBOARD_FAB2(SCH_1):PAGE225
     2    GND @BASEBOARD_FAB2_LIB.BASEBOARD_FAB2(SCH_1):GND   I199 @BASEBOARD_FAB2_LIB.BASEBOARD_FAB2(SCH_1):PAGE225

C8W1 CAP_0603-10UF,6.3V,20%,X6S,E15A
     1 BMC_TPM_HW_RST @BASEBOARD_FAB2_LIB.BASEBOARD_FAB2(SCH_1):BMC_TPM_HW_RST    I32 @BASEBOARD_FAB2_LIB.BASEBOARD_FAB2(SCH_1):PAGE249
     2 BMC_TPM_HW_C_RST @BASEBOARD_FAB2_LIB.BASEBOARD_FAB2(SCH_1):BMC_TPM_HW_C_RST    I32 @BASEBOARD_FAB2_LIB.BASEBOARD_FAB2(SCH_1):PAGE249

C8W2 CAP_0402LF-0.1UF,16V,10%,X7R,AA
     1 P3V3_STBY @BASEBOARD_FAB2_LIB.BASEBOARD_FAB2(SCH_1):P3V3_STBY    I21 @BASEBOARD_FAB2_LIB.BASEBOARD_FAB2(SCH_1):PAGE249
     2    GND @BASEBOARD_FAB2_LIB.BASEBOARD_FAB2(SCH_1):GND    I21 @BASEBOARD_FAB2_LIB.BASEBOARD_FAB2(SCH_1):PAGE249

C9A1 CAP_A_0402V-0.1UF,16V,10%,X7R,A
     1 P5V_STBY_DGB_FS @BASEBOARD_FAB2_LIB.BASEBOARD_FAB2(SCH_1):P5V_STBY_DGB_FS   I127 @BASEBOARD_FAB2_LIB.BASEBOARD_FAB2(SCH_1):PAGE155
     2    GND @BASEBOARD_FAB2_LIB.BASEBOARD_FAB2(SCH_1):GND   I127 @BASEBOARD_FAB2_LIB.BASEBOARD_FAB2(SCH_1):PAGE155

C9A2 CAP_A_0402V-0.1UF,16V,10%,X7R,A
     1 XDP_SYSPWROK @BASEBOARD_FAB2_LIB.BASEBOARD_FAB2(SCH_1):XDP_SYSPWROK    I10 @BASEBOARD_FAB2_LIB.BASEBOARD_FAB2(SCH_1):PAGE111
     2    GND @BASEBOARD_FAB2_LIB.BASEBOARD_FAB2(SCH_1):GND    I10 @BASEBOARD_FAB2_LIB.BASEBOARD_FAB2(SCH_1):PAGE111

C9A3 CAP_A_0402V-0.1UF,16V,10%,X7R,A
     1 P3V3_STBY @BASEBOARD_FAB2_LIB.BASEBOARD_FAB2(SCH_1):P3V3_STBY    I40 @BASEBOARD_FAB2_LIB.BASEBOARD_FAB2(SCH_1):PAGE175
     2    GND @BASEBOARD_FAB2_LIB.BASEBOARD_FAB2(SCH_1):GND    I40 @BASEBOARD_FAB2_LIB.BASEBOARD_FAB2(SCH_1):PAGE175

C9A4 CAP_A_0402V-0.1UF,16V,10%,X7R,A
     1 XDP_CPU_PWR_DEBUG_N @BASEBOARD_FAB2_LIB.BASEBOARD_FAB2(SCH_1):XDP_CPU_PWR_DEBUG_N    I59 @BASEBOARD_FAB2_LIB.BASEBOARD_FAB2(SCH_1):PAGE111
     2    GND @BASEBOARD_FAB2_LIB.BASEBOARD_FAB2(SCH_1):GND    I59 @BASEBOARD_FAB2_LIB.BASEBOARD_FAB2(SCH_1):PAGE111

C9A5 CAP_A_0402V-0.1UF,16V,10%,X7R,A
     1 XDP_RST_CO_N @BASEBOARD_FAB2_LIB.BASEBOARD_FAB2(SCH_1):XDP_RST_CO_N    I12 @BASEBOARD_FAB2_LIB.BASEBOARD_FAB2(SCH_1):PAGE111
     2    GND @BASEBOARD_FAB2_LIB.BASEBOARD_FAB2(SCH_1):GND    I12 @BASEBOARD_FAB2_LIB.BASEBOARD_FAB2(SCH_1):PAGE111

C9A6 CAP_A_0402V-1.0UF,6.3V,10%,X6SA
     1 P1V05_PCH_STBY @BASEBOARD_FAB2_LIB.BASEBOARD_FAB2(SCH_1):P1V05_PCH_STBY    I25 @BASEBOARD_FAB2_LIB.BASEBOARD_FAB2(SCH_1):PAGE111
     2    GND @BASEBOARD_FAB2_LIB.BASEBOARD_FAB2(SCH_1):GND    I25 @BASEBOARD_FAB2_LIB.BASEBOARD_FAB2(SCH_1):PAGE111

C9B1 CAP_0805-10UF,16V,10%,X6S,C953A
     1 P5V_HDD_SATA @BASEBOARD_FAB2_LIB.BASEBOARD_FAB2(SCH_1):P5V_HDD_SATA    I39 @BASEBOARD_FAB2_LIB.BASEBOARD_FAB2(SCH_1):PAGE172
     2    GND @BASEBOARD_FAB2_LIB.BASEBOARD_FAB2(SCH_1):GND    I39 @BASEBOARD_FAB2_LIB.BASEBOARD_FAB2(SCH_1):PAGE172

C9B2 CAP_0805-10UF,16V,10%,X6S,C953A
     1 P12V_HDD_SATA @BASEBOARD_FAB2_LIB.BASEBOARD_FAB2(SCH_1):P12V_HDD_SATA    I36 @BASEBOARD_FAB2_LIB.BASEBOARD_FAB2(SCH_1):PAGE172
     2    GND @BASEBOARD_FAB2_LIB.BASEBOARD_FAB2(SCH_1):GND    I36 @BASEBOARD_FAB2_LIB.BASEBOARD_FAB2(SCH_1):PAGE172

C9B7 CAP_A_0402V-0.1UF,16V,10%,X7R,A
     1 P3V3_STBY @BASEBOARD_FAB2_LIB.BASEBOARD_FAB2(SCH_1):P3V3_STBY    I39 @BASEBOARD_FAB2_LIB.BASEBOARD_FAB2(SCH_1):PAGE167
     2    GND @BASEBOARD_FAB2_LIB.BASEBOARD_FAB2(SCH_1):GND    I39 @BASEBOARD_FAB2_LIB.BASEBOARD_FAB2(SCH_1):PAGE167

C9B8 CAPP_7343HLF-330UF,10V,20%,POSA
     1 P5V_USB @BASEBOARD_FAB2_LIB.BASEBOARD_FAB2(SCH_1):P5V_USB   I113 @BASEBOARD_FAB2_LIB.BASEBOARD_FAB2(SCH_1):PAGE176
     2    GND @BASEBOARD_FAB2_LIB.BASEBOARD_FAB2(SCH_1):GND   I113 @BASEBOARD_FAB2_LIB.BASEBOARD_FAB2(SCH_1):PAGE176

C9B9 CAP_A_0402V-1.0UF,6.3V,10%,X6SA
     1 P5V_STBY @BASEBOARD_FAB2_LIB.BASEBOARD_FAB2(SCH_1):P5V_STBY   I347 @BASEBOARD_FAB2_LIB.BASEBOARD_FAB2(SCH_1):PAGE186
     2    GND @BASEBOARD_FAB2_LIB.BASEBOARD_FAB2(SCH_1):GND   I347 @BASEBOARD_FAB2_LIB.BASEBOARD_FAB2(SCH_1):PAGE186

C9B10 CAP_A_0402V-0.1UF,16V,10%,X7R,A
     1 P5V_STBY @BASEBOARD_FAB2_LIB.BASEBOARD_FAB2(SCH_1):P5V_STBY   I345 @BASEBOARD_FAB2_LIB.BASEBOARD_FAB2(SCH_1):PAGE186
     2    GND @BASEBOARD_FAB2_LIB.BASEBOARD_FAB2(SCH_1):GND   I345 @BASEBOARD_FAB2_LIB.BASEBOARD_FAB2(SCH_1):PAGE186

C9E1 CAP_A_0603V-22.0UF,4V,20%,EMPTA
     1 P0V9_LAN @BASEBOARD_FAB2_LIB.BASEBOARD_FAB2(SCH_1):P0V9_LAN   I163 @BASEBOARD_FAB2_LIB.BASEBOARD_FAB2(SCH_1):PAGE139
     2    GND @BASEBOARD_FAB2_LIB.BASEBOARD_FAB2(SCH_1):GND   I163 @BASEBOARD_FAB2_LIB.BASEBOARD_FAB2(SCH_1):PAGE139

C9E4 CAP_A_0402V-0.1UF,16V,10%,X7R,A
     1 PE_PCH_SPRV_RX_DP @BASEBOARD_FAB2_LIB.BASEBOARD_FAB2(SCH_1):PE_PCH_SPRV_RX_DP    I88 @BASEBOARD_FAB2_LIB.BASEBOARD_FAB2(SCH_1):PAGE139
     2 PE_PCH_SPRV_RX_C_DP @BASEBOARD_FAB2_LIB.BASEBOARD_FAB2(SCH_1):PE_PCH_SPRV_RX_C_DP    I88 @BASEBOARD_FAB2_LIB.BASEBOARD_FAB2(SCH_1):PAGE139

C9E5 CAP_A_0402V-0.1UF,16V,10%,X7R,A
     1 PE_PCH_SPRV_RX_DN @BASEBOARD_FAB2_LIB.BASEBOARD_FAB2(SCH_1):PE_PCH_SPRV_RX_DN    I87 @BASEBOARD_FAB2_LIB.BASEBOARD_FAB2(SCH_1):PAGE139
     2 PE_PCH_SPRV_RX_C_DN @BASEBOARD_FAB2_LIB.BASEBOARD_FAB2(SCH_1):PE_PCH_SPRV_RX_C_DN    I87 @BASEBOARD_FAB2_LIB.BASEBOARD_FAB2(SCH_1):PAGE139

C9E6 CAP_1210-47UF,16V,20%,EMPTY,D3A
     1 P1V5_LAN @BASEBOARD_FAB2_LIB.BASEBOARD_FAB2(SCH_1):P1V5_LAN   I155 @BASEBOARD_FAB2_LIB.BASEBOARD_FAB2(SCH_1):PAGE139
     2    GND @BASEBOARD_FAB2_LIB.BASEBOARD_FAB2(SCH_1):GND   I155 @BASEBOARD_FAB2_LIB.BASEBOARD_FAB2(SCH_1):PAGE139

C9E7 CAP_0402LF-0.039UF,25V,10%,X7RA
     1 A_CTOP @BASEBOARD_FAB2_LIB.BASEBOARD_FAB2(SCH_1):A_CTOP    I76 @BASEBOARD_FAB2_LIB.BASEBOARD_FAB2(SCH_1):PAGE139
     2 A_CBOT @BASEBOARD_FAB2_LIB.BASEBOARD_FAB2(SCH_1):A_CBOT    I76 @BASEBOARD_FAB2_LIB.BASEBOARD_FAB2(SCH_1):PAGE139

C9E8 CAP_0402LF-22.0PF,50V,5%,COG,AA
     1 XTAL_25MHZ_OUT_R @BASEBOARD_FAB2_LIB.BASEBOARD_FAB2(SCH_1):XTAL_25MHZ_OUT_R   I111 @BASEBOARD_FAB2_LIB.BASEBOARD_FAB2(SCH_1):PAGE139
     2    GND @BASEBOARD_FAB2_LIB.BASEBOARD_FAB2(SCH_1):GND   I111 @BASEBOARD_FAB2_LIB.BASEBOARD_FAB2(SCH_1):PAGE139

C9E9 CAP_0402LF-22.0PF,50V,5%,COG,AA
     1 XTAL_25MHZ_IN @BASEBOARD_FAB2_LIB.BASEBOARD_FAB2(SCH_1):XTAL_25MHZ_IN   I112 @BASEBOARD_FAB2_LIB.BASEBOARD_FAB2(SCH_1):PAGE139
     2    GND @BASEBOARD_FAB2_LIB.BASEBOARD_FAB2(SCH_1):GND   I112 @BASEBOARD_FAB2_LIB.BASEBOARD_FAB2(SCH_1):PAGE139

C9E10 CAP_0603-10UF,6.3V,20%,X6S,E15A
     1 P1V15_AUX_BMC @BASEBOARD_FAB2_LIB.BASEBOARD_FAB2(SCH_1):P1V15_AUX_BMC    I23 @BASEBOARD_FAB2_LIB.BASEBOARD_FAB2(SCH_1):PAGE238
     2    GND @BASEBOARD_FAB2_LIB.BASEBOARD_FAB2(SCH_1):GND    I23 @BASEBOARD_FAB2_LIB.BASEBOARD_FAB2(SCH_1):PAGE238

C9E11 CAP_0402-1.0UF,16V,10%,X6S,D97A
     1 P3V3_STBY @BASEBOARD_FAB2_LIB.BASEBOARD_FAB2(SCH_1):P3V3_STBY    I39 @BASEBOARD_FAB2_LIB.BASEBOARD_FAB2(SCH_1):PAGE238
     2    GND @BASEBOARD_FAB2_LIB.BASEBOARD_FAB2(SCH_1):GND    I39 @BASEBOARD_FAB2_LIB.BASEBOARD_FAB2(SCH_1):PAGE238

C9E12 CAP_A_0603V-22.0UF,4V,20%,EMPTA
     1 P0V9_LAN @BASEBOARD_FAB2_LIB.BASEBOARD_FAB2(SCH_1):P0V9_LAN   I241 @BASEBOARD_FAB2_LIB.BASEBOARD_FAB2(SCH_1):PAGE139
     2    GND @BASEBOARD_FAB2_LIB.BASEBOARD_FAB2(SCH_1):GND   I241 @BASEBOARD_FAB2_LIB.BASEBOARD_FAB2(SCH_1):PAGE139

C9F1 CAP_1210-47UF,16V,20%,X6S,D384A
     1 VR_FET_SW_P12V_STBY_P3V3_STBY @BASEBOARD_FAB2_LIB.BASEBOARD_FAB2(SCH_1):VR_FET_SW_P12V_STBY_P3V3_STBY   I134 @BASEBOARD_FAB2_LIB.BASEBOARD_FAB2(SCH_1):PAGE240
     2    GND @BASEBOARD_FAB2_LIB.BASEBOARD_FAB2(SCH_1):GND   I134 @BASEBOARD_FAB2_LIB.BASEBOARD_FAB2(SCH_1):PAGE240

C9F2 CAP_1210-47UF,16V,20%,EMPTY,D3A
     1 P3V3_STBY @BASEBOARD_FAB2_LIB.BASEBOARD_FAB2(SCH_1):P3V3_STBY   I140 @BASEBOARD_FAB2_LIB.BASEBOARD_FAB2(SCH_1):PAGE139
     2    GND @BASEBOARD_FAB2_LIB.BASEBOARD_FAB2(SCH_1):GND   I140 @BASEBOARD_FAB2_LIB.BASEBOARD_FAB2(SCH_1):PAGE139

C9F3 CAP_0603-10UF,6.3V,20%,X6S,E15A
     1 P3V3_STBY @BASEBOARD_FAB2_LIB.BASEBOARD_FAB2(SCH_1):P3V3_STBY     I7 @BASEBOARD_FAB2_LIB.BASEBOARD_FAB2(SCH_1):PAGE238
     2    GND @BASEBOARD_FAB2_LIB.BASEBOARD_FAB2(SCH_1):GND     I7 @BASEBOARD_FAB2_LIB.BASEBOARD_FAB2(SCH_1):PAGE238

C9F4 CAP_0805LF-22UF,4V,20%,X6S,C95A
     1 P1V15_AUX_BMC @BASEBOARD_FAB2_LIB.BASEBOARD_FAB2(SCH_1):P1V15_AUX_BMC    I30 @BASEBOARD_FAB2_LIB.BASEBOARD_FAB2(SCH_1):PAGE238
     2    GND @BASEBOARD_FAB2_LIB.BASEBOARD_FAB2(SCH_1):GND    I30 @BASEBOARD_FAB2_LIB.BASEBOARD_FAB2(SCH_1):PAGE238

C9F5 CAP_A_0402V-0.1UF,16V,10%,X7R,A
     1 P3V3_STBY @BASEBOARD_FAB2_LIB.BASEBOARD_FAB2(SCH_1):P3V3_STBY    I71 @BASEBOARD_FAB2_LIB.BASEBOARD_FAB2(SCH_1):PAGE239
     2    GND @BASEBOARD_FAB2_LIB.BASEBOARD_FAB2(SCH_1):GND    I71 @BASEBOARD_FAB2_LIB.BASEBOARD_FAB2(SCH_1):PAGE239

C9F6 CAP_0402LF-1000PF,50V,10%,EMPTA
     1 PWRGD_P3V3_STBY @BASEBOARD_FAB2_LIB.BASEBOARD_FAB2(SCH_1):PWRGD_P3V3_STBY    I30 @BASEBOARD_FAB2_LIB.BASEBOARD_FAB2(SCH_1):PAGE239
     2    GND @BASEBOARD_FAB2_LIB.BASEBOARD_FAB2(SCH_1):GND    I30 @BASEBOARD_FAB2_LIB.BASEBOARD_FAB2(SCH_1):PAGE239

C9F8 CAP_0402LF-1000PF,50V,10%,X7R,A
     1 PWRGD_P1V26_BMC_STBY_R @BASEBOARD_FAB2_LIB.BASEBOARD_FAB2(SCH_1):PWRGD_P1V26_BMC_STBY_R    I19 @BASEBOARD_FAB2_LIB.BASEBOARD_FAB2(SCH_1):PAGE238
     2    GND @BASEBOARD_FAB2_LIB.BASEBOARD_FAB2(SCH_1):GND    I19 @BASEBOARD_FAB2_LIB.BASEBOARD_FAB2(SCH_1):PAGE238

C9F9 CAP_0402LF-1000PF,50V,10%,EMPTA
     1 PWRGD_P1V538_BMC_STBY @BASEBOARD_FAB2_LIB.BASEBOARD_FAB2(SCH_1):PWRGD_P1V538_BMC_STBY     I5 @BASEBOARD_FAB2_LIB.BASEBOARD_FAB2(SCH_1):PAGE238
     2    GND @BASEBOARD_FAB2_LIB.BASEBOARD_FAB2(SCH_1):GND     I5 @BASEBOARD_FAB2_LIB.BASEBOARD_FAB2(SCH_1):PAGE238

C9F10 CAP_0402LF-1000PF,50V,10%,X7R,A
     1 PWRGD_P1V538_BMC_STBY_R @BASEBOARD_FAB2_LIB.BASEBOARD_FAB2(SCH_1):PWRGD_P1V538_BMC_STBY_R     I4 @BASEBOARD_FAB2_LIB.BASEBOARD_FAB2(SCH_1):PAGE239
     2    GND @BASEBOARD_FAB2_LIB.BASEBOARD_FAB2(SCH_1):GND     I4 @BASEBOARD_FAB2_LIB.BASEBOARD_FAB2(SCH_1):PAGE239

C9F13 CAP_0805LF-22UF,4V,20%,X6S,C95A
     1 P1V2_AUX_BMC @BASEBOARD_FAB2_LIB.BASEBOARD_FAB2(SCH_1):P1V2_AUX_BMC     I7 @BASEBOARD_FAB2_LIB.BASEBOARD_FAB2(SCH_1):PAGE239
     2    GND @BASEBOARD_FAB2_LIB.BASEBOARD_FAB2(SCH_1):GND     I7 @BASEBOARD_FAB2_LIB.BASEBOARD_FAB2(SCH_1):PAGE239

C9F19 CAP_A_0402V-0.1UF,16V,10%,X7R,A
     1 P3V3_STBY @BASEBOARD_FAB2_LIB.BASEBOARD_FAB2(SCH_1):P3V3_STBY     I7 @BASEBOARD_FAB2_LIB.BASEBOARD_FAB2(SCH_1):PAGE183
     2    GND @BASEBOARD_FAB2_LIB.BASEBOARD_FAB2(SCH_1):GND     I7 @BASEBOARD_FAB2_LIB.BASEBOARD_FAB2(SCH_1):PAGE183

C9F20 CAP_0402LF-12.0PF,50V,5%,COG,AA
     1 XTAL_24MHZ_PI7C9X1172_IN @BASEBOARD_FAB2_LIB.BASEBOARD_FAB2(SCH_1):XTAL_24MHZ_PI7C9X1172_IN    I20 @BASEBOARD_FAB2_LIB.BASEBOARD_FAB2(SCH_1):PAGE183
     2    GND @BASEBOARD_FAB2_LIB.BASEBOARD_FAB2(SCH_1):GND    I20 @BASEBOARD_FAB2_LIB.BASEBOARD_FAB2(SCH_1):PAGE183

C9F21 CAP_0402LF-12.0PF,50V,5%,COG,AA
     1 XTAL_24MHZ_PI7C9X1172_OUT @BASEBOARD_FAB2_LIB.BASEBOARD_FAB2(SCH_1):XTAL_24MHZ_PI7C9X1172_OUT    I21 @BASEBOARD_FAB2_LIB.BASEBOARD_FAB2(SCH_1):PAGE183
     2    GND @BASEBOARD_FAB2_LIB.BASEBOARD_FAB2(SCH_1):GND    I21 @BASEBOARD_FAB2_LIB.BASEBOARD_FAB2(SCH_1):PAGE183

C9F22 CAP_0402LF-470PF,50V,10%,X7R,AA
     1 LED_LAN_1_N @BASEBOARD_FAB2_LIB.BASEBOARD_FAB2(SCH_1):LED_LAN_1_N    I60 @BASEBOARD_FAB2_LIB.BASEBOARD_FAB2(SCH_1):PAGE141
     2    GND @BASEBOARD_FAB2_LIB.BASEBOARD_FAB2(SCH_1):GND    I60 @BASEBOARD_FAB2_LIB.BASEBOARD_FAB2(SCH_1):PAGE141

C9F23 CAP_A_0402V-0.1UF,16V,10%,X7R,A
     1 P3V3_STBY @BASEBOARD_FAB2_LIB.BASEBOARD_FAB2(SCH_1):P3V3_STBY    I15 @BASEBOARD_FAB2_LIB.BASEBOARD_FAB2(SCH_1):PAGE145
     2    GND @BASEBOARD_FAB2_LIB.BASEBOARD_FAB2(SCH_1):GND    I15 @BASEBOARD_FAB2_LIB.BASEBOARD_FAB2(SCH_1):PAGE145

C9G1 CAP_0402LF-470PF,50V,10%,X7R,AA
     1 LED_LAN_2_N @BASEBOARD_FAB2_LIB.BASEBOARD_FAB2(SCH_1):LED_LAN_2_N    I58 @BASEBOARD_FAB2_LIB.BASEBOARD_FAB2(SCH_1):PAGE141
     2    GND @BASEBOARD_FAB2_LIB.BASEBOARD_FAB2(SCH_1):GND    I58 @BASEBOARD_FAB2_LIB.BASEBOARD_FAB2(SCH_1):PAGE141

C9G2 CAP_0402LF-470PF,50V,10%,X7R,AA
     1 P3V3_STBY @BASEBOARD_FAB2_LIB.BASEBOARD_FAB2(SCH_1):P3V3_STBY    I36 @BASEBOARD_FAB2_LIB.BASEBOARD_FAB2(SCH_1):PAGE141
     2    GND @BASEBOARD_FAB2_LIB.BASEBOARD_FAB2(SCH_1):GND    I36 @BASEBOARD_FAB2_LIB.BASEBOARD_FAB2(SCH_1):PAGE141

C9G3 CAP_0402LF-470PF,50V,10%,X7R,AA
     1 LED_LAN_0_N @BASEBOARD_FAB2_LIB.BASEBOARD_FAB2(SCH_1):LED_LAN_0_N    I59 @BASEBOARD_FAB2_LIB.BASEBOARD_FAB2(SCH_1):PAGE141
     2    GND @BASEBOARD_FAB2_LIB.BASEBOARD_FAB2(SCH_1):GND    I59 @BASEBOARD_FAB2_LIB.BASEBOARD_FAB2(SCH_1):PAGE141

C9G4 CAP_A_0402V-0.1UF,16V,10%,X7R,A
     1 GND_LAN_TRCT1234_C @BASEBOARD_FAB2_LIB.BASEBOARD_FAB2(SCH_1):GND_LAN_TRCT1234_C    I46 @BASEBOARD_FAB2_LIB.BASEBOARD_FAB2(SCH_1):PAGE141
     2    GND @BASEBOARD_FAB2_LIB.BASEBOARD_FAB2(SCH_1):GND    I46 @BASEBOARD_FAB2_LIB.BASEBOARD_FAB2(SCH_1):PAGE141

C9G5 CAP_0402-1.0UF,16V,10%,X7S,G71A
     1 GND_LAN_TRCT1234_C @BASEBOARD_FAB2_LIB.BASEBOARD_FAB2(SCH_1):GND_LAN_TRCT1234_C    I48 @BASEBOARD_FAB2_LIB.BASEBOARD_FAB2(SCH_1):PAGE141
     2    GND @BASEBOARD_FAB2_LIB.BASEBOARD_FAB2(SCH_1):GND    I48 @BASEBOARD_FAB2_LIB.BASEBOARD_FAB2(SCH_1):PAGE141

C9G6 CAP_A_0402V-0.1UF,16V,10%,X7R,A
     1 GND_LAN_TRCT1234_C @BASEBOARD_FAB2_LIB.BASEBOARD_FAB2(SCH_1):GND_LAN_TRCT1234_C    I47 @BASEBOARD_FAB2_LIB.BASEBOARD_FAB2(SCH_1):PAGE141
     2    GND @BASEBOARD_FAB2_LIB.BASEBOARD_FAB2(SCH_1):GND    I47 @BASEBOARD_FAB2_LIB.BASEBOARD_FAB2(SCH_1):PAGE141

C9G7 CAP_A_0402V-0.1UF,16V,10%,X7R,A
     1 P3V3_STBY @BASEBOARD_FAB2_LIB.BASEBOARD_FAB2(SCH_1):P3V3_STBY    I33 @BASEBOARD_FAB2_LIB.BASEBOARD_FAB2(SCH_1):PAGE141
     2    GND @BASEBOARD_FAB2_LIB.BASEBOARD_FAB2(SCH_1):GND    I33 @BASEBOARD_FAB2_LIB.BASEBOARD_FAB2(SCH_1):PAGE141

C9G9 CAP_0402LF-4700PF,50V,10%,EMPTA
     1 NIC_SER_P_MDI_3_DP @BASEBOARD_FAB2_LIB.BASEBOARD_FAB2(SCH_1):NIC_SER_P_MDI_3_DP    I99 @BASEBOARD_FAB2_LIB.BASEBOARD_FAB2(SCH_1):PAGE141
     2 NIC_MDI_MNG_RX_DP @BASEBOARD_FAB2_LIB.BASEBOARD_FAB2(SCH_1):NIC_MDI_MNG_RX_DP    I99 @BASEBOARD_FAB2_LIB.BASEBOARD_FAB2(SCH_1):PAGE141

C9G12 CAP_0402LF-4700PF,50V,10%,EMPTA
     1 NIC_SER_N_MDI_3_DN @BASEBOARD_FAB2_LIB.BASEBOARD_FAB2(SCH_1):NIC_SER_N_MDI_3_DN   I100 @BASEBOARD_FAB2_LIB.BASEBOARD_FAB2(SCH_1):PAGE141
     2 NIC_MDI_MNG_RX_DN @BASEBOARD_FAB2_LIB.BASEBOARD_FAB2(SCH_1):NIC_MDI_MNG_RX_DN   I100 @BASEBOARD_FAB2_LIB.BASEBOARD_FAB2(SCH_1):PAGE141

C9G13 CAP_0402LF-4700PF,50V,10%,EMPTA
     1 NIC_SET_N_MDI_2_DN @BASEBOARD_FAB2_LIB.BASEBOARD_FAB2(SCH_1):NIC_SET_N_MDI_2_DN   I102 @BASEBOARD_FAB2_LIB.BASEBOARD_FAB2(SCH_1):PAGE141
     2 NIC_MDI_MNG_TX_DN @BASEBOARD_FAB2_LIB.BASEBOARD_FAB2(SCH_1):NIC_MDI_MNG_TX_DN   I102 @BASEBOARD_FAB2_LIB.BASEBOARD_FAB2(SCH_1):PAGE141

C9G14 CAP_0402LF-47.0PF,50V,5%,COG,AA
     1 A_P3V3_SCALED @BASEBOARD_FAB2_LIB.BASEBOARD_FAB2(SCH_1):A_P3V3_SCALED   I146 @BASEBOARD_FAB2_LIB.BASEBOARD_FAB2(SCH_1):PAGE169
     2    GND @BASEBOARD_FAB2_LIB.BASEBOARD_FAB2(SCH_1):GND   I146 @BASEBOARD_FAB2_LIB.BASEBOARD_FAB2(SCH_1):PAGE169

C9G15 CAP_0402LF-47.0PF,50V,5%,COG,AA
     1 A_P5V_SCALED @BASEBOARD_FAB2_LIB.BASEBOARD_FAB2(SCH_1):A_P5V_SCALED   I139 @BASEBOARD_FAB2_LIB.BASEBOARD_FAB2(SCH_1):PAGE169
     2    GND @BASEBOARD_FAB2_LIB.BASEBOARD_FAB2(SCH_1):GND   I139 @BASEBOARD_FAB2_LIB.BASEBOARD_FAB2(SCH_1):PAGE169

C9G16 CAP_0402LF-4700PF,50V,10%,EMPTA
     1 NIC_SET_P_MDI_2_DP @BASEBOARD_FAB2_LIB.BASEBOARD_FAB2(SCH_1):NIC_SET_P_MDI_2_DP   I101 @BASEBOARD_FAB2_LIB.BASEBOARD_FAB2(SCH_1):PAGE141
     2 NIC_MDI_MNG_TX_DP @BASEBOARD_FAB2_LIB.BASEBOARD_FAB2(SCH_1):NIC_MDI_MNG_TX_DP   I101 @BASEBOARD_FAB2_LIB.BASEBOARD_FAB2(SCH_1):PAGE141

C9G17 CAP_0402LF-47.0PF,50V,5%,COG,AA
     1 A_P12V_STBY_SCALED @BASEBOARD_FAB2_LIB.BASEBOARD_FAB2(SCH_1):A_P12V_STBY_SCALED    I80 @BASEBOARD_FAB2_LIB.BASEBOARD_FAB2(SCH_1):PAGE169
     2    GND @BASEBOARD_FAB2_LIB.BASEBOARD_FAB2(SCH_1):GND    I80 @BASEBOARD_FAB2_LIB.BASEBOARD_FAB2(SCH_1):PAGE169

C9G18 CAP_0402LF-47.0PF,50V,5%,COG,AA
     1 A_PVNN_STBY_PCH_SENSOR @BASEBOARD_FAB2_LIB.BASEBOARD_FAB2(SCH_1):A_PVNN_STBY_PCH_SENSOR   I153 @BASEBOARD_FAB2_LIB.BASEBOARD_FAB2(SCH_1):PAGE169
     2    GND @BASEBOARD_FAB2_LIB.BASEBOARD_FAB2(SCH_1):GND   I153 @BASEBOARD_FAB2_LIB.BASEBOARD_FAB2(SCH_1):PAGE169

C9G19 CAP_A_0402V-0.1UF,16V,10%,X7R,A
     1 P3V3_FB_ADC128_VCC @BASEBOARD_FAB2_LIB.BASEBOARD_FAB2(SCH_1):P3V3_FB_ADC128_VCC    I61 @BASEBOARD_FAB2_LIB.BASEBOARD_FAB2(SCH_1):PAGE165
     2    GND @BASEBOARD_FAB2_LIB.BASEBOARD_FAB2(SCH_1):GND    I61 @BASEBOARD_FAB2_LIB.BASEBOARD_FAB2(SCH_1):PAGE165

C9G20 CAP_0402LF-47.0PF,50V,5%,COG,AA
     1 A_P3V3_STBY_SCALED @BASEBOARD_FAB2_LIB.BASEBOARD_FAB2(SCH_1):A_P3V3_STBY_SCALED    I86 @BASEBOARD_FAB2_LIB.BASEBOARD_FAB2(SCH_1):PAGE169
     2    GND @BASEBOARD_FAB2_LIB.BASEBOARD_FAB2(SCH_1):GND    I86 @BASEBOARD_FAB2_LIB.BASEBOARD_FAB2(SCH_1):PAGE169

C9G21 CAP_0402LF-47.0PF,50V,5%,COG,AA
     1 A_P5V_STBY_SCALED @BASEBOARD_FAB2_LIB.BASEBOARD_FAB2(SCH_1):A_P5V_STBY_SCALED    I68 @BASEBOARD_FAB2_LIB.BASEBOARD_FAB2(SCH_1):PAGE169
     2    GND @BASEBOARD_FAB2_LIB.BASEBOARD_FAB2(SCH_1):GND    I68 @BASEBOARD_FAB2_LIB.BASEBOARD_FAB2(SCH_1):PAGE169

C9G22 CAP_0402LF-10.0PF,50V,5%,COG,AA
     1 A_P3V_BAT_SCALED @BASEBOARD_FAB2_LIB.BASEBOARD_FAB2(SCH_1):A_P3V_BAT_SCALED   I108 @BASEBOARD_FAB2_LIB.BASEBOARD_FAB2(SCH_1):PAGE169
     2    GND @BASEBOARD_FAB2_LIB.BASEBOARD_FAB2(SCH_1):GND   I108 @BASEBOARD_FAB2_LIB.BASEBOARD_FAB2(SCH_1):PAGE169

C9L1 CAP_A_0402V-0.01UF,25V,10%,X7RA
     1 M_M_VREF @BASEBOARD_FAB2_LIB.BASEBOARD_FAB2(SCH_1):M_M_VREF   I177 @BASEBOARD_FAB2_LIB.BASEBOARD_FAB2(SCH_1):PAGE88
     2    GND @BASEBOARD_FAB2_LIB.BASEBOARD_FAB2(SCH_1):GND   I177 @BASEBOARD_FAB2_LIB.BASEBOARD_FAB2(SCH_1):PAGE88

C9L2 CAPP_3018-470UF,2.5V,20%,ALUM,A
     1 PVDDQ_KLM @BASEBOARD_FAB2_LIB.BASEBOARD_FAB2(SCH_1):PVDDQ_KLM    I78 @BASEBOARD_FAB2_LIB.BASEBOARD_FAB2(SCH_1):PAGE228
     2    GND @BASEBOARD_FAB2_LIB.BASEBOARD_FAB2(SCH_1):GND    I78 @BASEBOARD_FAB2_LIB.BASEBOARD_FAB2(SCH_1):PAGE228

C9L3 CAP_A_0402V-0.01UF,25V,10%,X7RA
     1 M_M_CPU_VREF @BASEBOARD_FAB2_LIB.BASEBOARD_FAB2(SCH_1):M_M_CPU_VREF    I46 @BASEBOARD_FAB2_LIB.BASEBOARD_FAB2(SCH_1):PAGE100
     2    GND @BASEBOARD_FAB2_LIB.BASEBOARD_FAB2(SCH_1):GND    I46 @BASEBOARD_FAB2_LIB.BASEBOARD_FAB2(SCH_1):PAGE100

C9L4 CAPP_3018-470UF,2.5V,20%,ALUM,A
     1 PVDDQ_KLM @BASEBOARD_FAB2_LIB.BASEBOARD_FAB2(SCH_1):PVDDQ_KLM    I77 @BASEBOARD_FAB2_LIB.BASEBOARD_FAB2(SCH_1):PAGE228
     2    GND @BASEBOARD_FAB2_LIB.BASEBOARD_FAB2(SCH_1):GND    I77 @BASEBOARD_FAB2_LIB.BASEBOARD_FAB2(SCH_1):PAGE228

C9L5 CAP_0805-10UF,16V,10%,X6S,C953A
     1 VR_FET_SW_P12V_STBY_PVDDQ_KLM @BASEBOARD_FAB2_LIB.BASEBOARD_FAB2(SCH_1):VR_FET_SW_P12V_STBY_PVDDQ_KLM    I80 @BASEBOARD_FAB2_LIB.BASEBOARD_FAB2(SCH_1):PAGE227
     2    GND @BASEBOARD_FAB2_LIB.BASEBOARD_FAB2(SCH_1):GND    I80 @BASEBOARD_FAB2_LIB.BASEBOARD_FAB2(SCH_1):PAGE227

C9L6 CAP_0805-10UF,16V,10%,X6S,C953A
     1 VR_FET_SW_P12V_STBY_PVDDQ_KLM @BASEBOARD_FAB2_LIB.BASEBOARD_FAB2(SCH_1):VR_FET_SW_P12V_STBY_PVDDQ_KLM    I47 @BASEBOARD_FAB2_LIB.BASEBOARD_FAB2(SCH_1):PAGE227
     2    GND @BASEBOARD_FAB2_LIB.BASEBOARD_FAB2(SCH_1):GND    I47 @BASEBOARD_FAB2_LIB.BASEBOARD_FAB2(SCH_1):PAGE227

C9L7 CAP_A_0402V-0.01UF,25V,10%,X7RA
     1 M_L_VREF @BASEBOARD_FAB2_LIB.BASEBOARD_FAB2(SCH_1):M_L_VREF   I181 @BASEBOARD_FAB2_LIB.BASEBOARD_FAB2(SCH_1):PAGE85
     2    GND @BASEBOARD_FAB2_LIB.BASEBOARD_FAB2(SCH_1):GND   I181 @BASEBOARD_FAB2_LIB.BASEBOARD_FAB2(SCH_1):PAGE85

C9L8 CAP_A_0402V-0.01UF,25V,10%,X7RA
     1 M_L_CPU_VREF @BASEBOARD_FAB2_LIB.BASEBOARD_FAB2(SCH_1):M_L_CPU_VREF    I30 @BASEBOARD_FAB2_LIB.BASEBOARD_FAB2(SCH_1):PAGE100
     2    GND @BASEBOARD_FAB2_LIB.BASEBOARD_FAB2(SCH_1):GND    I30 @BASEBOARD_FAB2_LIB.BASEBOARD_FAB2(SCH_1):PAGE100

C9L9 CAPP_3018-470UF,2.5V,20%,ALUM,A
     1 PVDDQ_KLM @BASEBOARD_FAB2_LIB.BASEBOARD_FAB2(SCH_1):PVDDQ_KLM    I75 @BASEBOARD_FAB2_LIB.BASEBOARD_FAB2(SCH_1):PAGE228
     2    GND @BASEBOARD_FAB2_LIB.BASEBOARD_FAB2(SCH_1):GND    I75 @BASEBOARD_FAB2_LIB.BASEBOARD_FAB2(SCH_1):PAGE228

C9L10 CAP_0805-10UF,16V,10%,X6S,C953A
     1 VR_FET_SW_P12V_STBY_PVDDQ_KLM @BASEBOARD_FAB2_LIB.BASEBOARD_FAB2(SCH_1):VR_FET_SW_P12V_STBY_PVDDQ_KLM    I46 @BASEBOARD_FAB2_LIB.BASEBOARD_FAB2(SCH_1):PAGE227
     2    GND @BASEBOARD_FAB2_LIB.BASEBOARD_FAB2(SCH_1):GND    I46 @BASEBOARD_FAB2_LIB.BASEBOARD_FAB2(SCH_1):PAGE227

C9L11 CAP_0805-10UF,16V,10%,X6S,C953A
     1 VR_FET_SW_P12V_STBY_PVDDQ_KLM @BASEBOARD_FAB2_LIB.BASEBOARD_FAB2(SCH_1):VR_FET_SW_P12V_STBY_PVDDQ_KLM    I45 @BASEBOARD_FAB2_LIB.BASEBOARD_FAB2(SCH_1):PAGE227
     2    GND @BASEBOARD_FAB2_LIB.BASEBOARD_FAB2(SCH_1):GND    I45 @BASEBOARD_FAB2_LIB.BASEBOARD_FAB2(SCH_1):PAGE227

C9L12 CAPP_3018-470UF,2.5V,20%,ALUM,A
     1 PVDDQ_KLM @BASEBOARD_FAB2_LIB.BASEBOARD_FAB2(SCH_1):PVDDQ_KLM    I76 @BASEBOARD_FAB2_LIB.BASEBOARD_FAB2(SCH_1):PAGE228
     2    GND @BASEBOARD_FAB2_LIB.BASEBOARD_FAB2(SCH_1):GND    I76 @BASEBOARD_FAB2_LIB.BASEBOARD_FAB2(SCH_1):PAGE228

C9L13 CAP_0805-10UF,16V,10%,X6S,C953A
     1 VR_FET_SW_P12V_STBY_PVDDQ_KLM @BASEBOARD_FAB2_LIB.BASEBOARD_FAB2(SCH_1):VR_FET_SW_P12V_STBY_PVDDQ_KLM    I81 @BASEBOARD_FAB2_LIB.BASEBOARD_FAB2(SCH_1):PAGE227
     2    GND @BASEBOARD_FAB2_LIB.BASEBOARD_FAB2(SCH_1):GND    I81 @BASEBOARD_FAB2_LIB.BASEBOARD_FAB2(SCH_1):PAGE227

C9L14 CAP_0805-10UF,16V,10%,X6S,C953A
     1 VR_FET_SW_P12V_STBY_PVDDQ_KLM @BASEBOARD_FAB2_LIB.BASEBOARD_FAB2(SCH_1):VR_FET_SW_P12V_STBY_PVDDQ_KLM    I84 @BASEBOARD_FAB2_LIB.BASEBOARD_FAB2(SCH_1):PAGE227
     2    GND @BASEBOARD_FAB2_LIB.BASEBOARD_FAB2(SCH_1):GND    I84 @BASEBOARD_FAB2_LIB.BASEBOARD_FAB2(SCH_1):PAGE227

C9M1 CAP_A_0402V-0.01UF,25V,10%,X7RA
     1 M_K_VREF @BASEBOARD_FAB2_LIB.BASEBOARD_FAB2(SCH_1):M_K_VREF     I4 @BASEBOARD_FAB2_LIB.BASEBOARD_FAB2(SCH_1):PAGE84
     2    GND @BASEBOARD_FAB2_LIB.BASEBOARD_FAB2(SCH_1):GND     I4 @BASEBOARD_FAB2_LIB.BASEBOARD_FAB2(SCH_1):PAGE84

C9M2 CAP_A_0402V-0.01UF,25V,10%,X7RA
     1 M_K_CPU_VREF @BASEBOARD_FAB2_LIB.BASEBOARD_FAB2(SCH_1):M_K_CPU_VREF    I15 @BASEBOARD_FAB2_LIB.BASEBOARD_FAB2(SCH_1):PAGE100
     2    GND @BASEBOARD_FAB2_LIB.BASEBOARD_FAB2(SCH_1):GND    I15 @BASEBOARD_FAB2_LIB.BASEBOARD_FAB2(SCH_1):PAGE100

C9M3 CAPP_3018-68UF,16V,20%,TANT,72A
     1 P12V_STBY @BASEBOARD_FAB2_LIB.BASEBOARD_FAB2(SCH_1):P12V_STBY    I99 @BASEBOARD_FAB2_LIB.BASEBOARD_FAB2(SCH_1):PAGE195
     2    GND @BASEBOARD_FAB2_LIB.BASEBOARD_FAB2(SCH_1):GND    I99 @BASEBOARD_FAB2_LIB.BASEBOARD_FAB2(SCH_1):PAGE195

C9M4 CAP_0805-10UF,16V,10%,X6S,C953A
     1 P12V_FAN @BASEBOARD_FAB2_LIB.BASEBOARD_FAB2(SCH_1):P12V_FAN    I27 @BASEBOARD_FAB2_LIB.BASEBOARD_FAB2(SCH_1):PAGE161
     2    GND @BASEBOARD_FAB2_LIB.BASEBOARD_FAB2(SCH_1):GND    I27 @BASEBOARD_FAB2_LIB.BASEBOARD_FAB2(SCH_1):PAGE161

C9M5 CAP_A_0402V-0.1UF,16V,10%,X7R,A
     1 P12V_FAN @BASEBOARD_FAB2_LIB.BASEBOARD_FAB2(SCH_1):P12V_FAN    I26 @BASEBOARD_FAB2_LIB.BASEBOARD_FAB2(SCH_1):PAGE161
     2    GND @BASEBOARD_FAB2_LIB.BASEBOARD_FAB2(SCH_1):GND    I26 @BASEBOARD_FAB2_LIB.BASEBOARD_FAB2(SCH_1):PAGE161

C9M6 CAP_A_0402V-0.1UF,16V,10%,X7R,A
     1 P5V_STBY @BASEBOARD_FAB2_LIB.BASEBOARD_FAB2(SCH_1):P5V_STBY    I67 @BASEBOARD_FAB2_LIB.BASEBOARD_FAB2(SCH_1):PAGE198
     2    GND @BASEBOARD_FAB2_LIB.BASEBOARD_FAB2(SCH_1):GND    I67 @BASEBOARD_FAB2_LIB.BASEBOARD_FAB2(SCH_1):PAGE198

C9M7 CAP_A_0402V-0.1UF,16V,10%,X7R,A
     1 P3V3_STBY @BASEBOARD_FAB2_LIB.BASEBOARD_FAB2(SCH_1):P3V3_STBY    I12 @BASEBOARD_FAB2_LIB.BASEBOARD_FAB2(SCH_1):PAGE163
     2    GND @BASEBOARD_FAB2_LIB.BASEBOARD_FAB2(SCH_1):GND    I12 @BASEBOARD_FAB2_LIB.BASEBOARD_FAB2(SCH_1):PAGE163

C9M8 CAP_A_0402V-0.1UF,16V,10%,X7R,A
     1 PVCCIO_CPU1 @BASEBOARD_FAB2_LIB.BASEBOARD_FAB2(SCH_1):PVCCIO_CPU1    I10 @BASEBOARD_FAB2_LIB.BASEBOARD_FAB2(SCH_1):PAGE163
     2    GND @BASEBOARD_FAB2_LIB.BASEBOARD_FAB2(SCH_1):GND    I10 @BASEBOARD_FAB2_LIB.BASEBOARD_FAB2(SCH_1):PAGE163

C9M9 CAP_A_0402V-0.1UF,16V,10%,X7R,A
     1 P12V_STBY @BASEBOARD_FAB2_LIB.BASEBOARD_FAB2(SCH_1):P12V_STBY    I76 @BASEBOARD_FAB2_LIB.BASEBOARD_FAB2(SCH_1):PAGE198
     2    GND @BASEBOARD_FAB2_LIB.BASEBOARD_FAB2(SCH_1):GND    I76 @BASEBOARD_FAB2_LIB.BASEBOARD_FAB2(SCH_1):PAGE198

C9M10 CAP_0805-10UF,16V,10%,X6S,C953A
     1 P12V_STBY @BASEBOARD_FAB2_LIB.BASEBOARD_FAB2(SCH_1):P12V_STBY    I74 @BASEBOARD_FAB2_LIB.BASEBOARD_FAB2(SCH_1):PAGE198
     2    GND @BASEBOARD_FAB2_LIB.BASEBOARD_FAB2(SCH_1):GND    I74 @BASEBOARD_FAB2_LIB.BASEBOARD_FAB2(SCH_1):PAGE198

C9M11 CAP_A_0402V-0.1UF,16V,10%,X7R,A
     1 VR_PVDDQ_KLM_AIINSEN @BASEBOARD_FAB2_LIB.BASEBOARD_FAB2(SCH_1):VR_PVDDQ_KLM_AIINSEN    I92 @BASEBOARD_FAB2_LIB.BASEBOARD_FAB2(SCH_1):PAGE226
     2    GND @BASEBOARD_FAB2_LIB.BASEBOARD_FAB2(SCH_1):GND    I92 @BASEBOARD_FAB2_LIB.BASEBOARD_FAB2(SCH_1):PAGE226

C9N1 CAP_0402-0.22UF,16V,10%,X7R,A3A
     1 P3E_CPU1_PE3_MP_C_TXP<10> @BASEBOARD_FAB2_LIB.BASEBOARD_FAB2(SCH_1):P3E_CPU1_PE3_MP_C_TXP(10)    I14 @BASEBOARD_FAB2_LIB.BASEBOARD_FAB2(SCH_1):PAGE182
     2 P3E_CPU1_PE3_MP_TXP<10> @BASEBOARD_FAB2_LIB.BASEBOARD_FAB2(SCH_1):P3E_CPU1_PE3_MP_TXP(10)    I14 @BASEBOARD_FAB2_LIB.BASEBOARD_FAB2(SCH_1):PAGE182

C9N2 CAP_0402-0.22UF,16V,10%,X7R,A3A
     1 P3E_CPU1_PE3_MP_C_TXN<10> @BASEBOARD_FAB2_LIB.BASEBOARD_FAB2(SCH_1):P3E_CPU1_PE3_MP_C_TXN(10)    I15 @BASEBOARD_FAB2_LIB.BASEBOARD_FAB2(SCH_1):PAGE182
     2 P3E_CPU1_PE3_MP_TXN<10> @BASEBOARD_FAB2_LIB.BASEBOARD_FAB2(SCH_1):P3E_CPU1_PE3_MP_TXN(10)    I15 @BASEBOARD_FAB2_LIB.BASEBOARD_FAB2(SCH_1):PAGE182

C9N3 CAP_0402-0.22UF,16V,10%,X7R,A3A
     1 P3E_CPU1_PE3_MP_C_TXN<11> @BASEBOARD_FAB2_LIB.BASEBOARD_FAB2(SCH_1):P3E_CPU1_PE3_MP_C_TXN(11)    I51 @BASEBOARD_FAB2_LIB.BASEBOARD_FAB2(SCH_1):PAGE182
     2 P3E_CPU1_PE3_MP_TXN<11> @BASEBOARD_FAB2_LIB.BASEBOARD_FAB2(SCH_1):P3E_CPU1_PE3_MP_TXN(11)    I51 @BASEBOARD_FAB2_LIB.BASEBOARD_FAB2(SCH_1):PAGE182

C9N4 CAP_0402-0.22UF,16V,10%,X7R,A3A
     1 P3E_CPU1_PE3_MP_C_TXP<11> @BASEBOARD_FAB2_LIB.BASEBOARD_FAB2(SCH_1):P3E_CPU1_PE3_MP_C_TXP(11)    I55 @BASEBOARD_FAB2_LIB.BASEBOARD_FAB2(SCH_1):PAGE182
     2 P3E_CPU1_PE3_MP_TXP<11> @BASEBOARD_FAB2_LIB.BASEBOARD_FAB2(SCH_1):P3E_CPU1_PE3_MP_TXP(11)    I55 @BASEBOARD_FAB2_LIB.BASEBOARD_FAB2(SCH_1):PAGE182

C9N5 CAP_0402-0.22UF,16V,10%,X7R,A3A
     1 P3E_CPU1_PE3_MP_C_TXP<13> @BASEBOARD_FAB2_LIB.BASEBOARD_FAB2(SCH_1):P3E_CPU1_PE3_MP_C_TXP(13)    I83 @BASEBOARD_FAB2_LIB.BASEBOARD_FAB2(SCH_1):PAGE182
     2 P3E_CPU1_PE3_MP_TXP<13> @BASEBOARD_FAB2_LIB.BASEBOARD_FAB2(SCH_1):P3E_CPU1_PE3_MP_TXP(13)    I83 @BASEBOARD_FAB2_LIB.BASEBOARD_FAB2(SCH_1):PAGE182

C9N6 CAP_0402-0.22UF,16V,10%,X7R,A3A
     1 P3E_CPU1_PE3_MP_C_TXN<13> @BASEBOARD_FAB2_LIB.BASEBOARD_FAB2(SCH_1):P3E_CPU1_PE3_MP_C_TXN(13)    I81 @BASEBOARD_FAB2_LIB.BASEBOARD_FAB2(SCH_1):PAGE182
     2 P3E_CPU1_PE3_MP_TXN<13> @BASEBOARD_FAB2_LIB.BASEBOARD_FAB2(SCH_1):P3E_CPU1_PE3_MP_TXN(13)    I81 @BASEBOARD_FAB2_LIB.BASEBOARD_FAB2(SCH_1):PAGE182

C9N7 CAP_0402-0.22UF,16V,10%,X7R,A3A
     1 P3E_CPU1_PE3_MP_C_TXP<15> @BASEBOARD_FAB2_LIB.BASEBOARD_FAB2(SCH_1):P3E_CPU1_PE3_MP_C_TXP(15)    I54 @BASEBOARD_FAB2_LIB.BASEBOARD_FAB2(SCH_1):PAGE182
     2 P3E_CPU1_PE3_MP_TXP<15> @BASEBOARD_FAB2_LIB.BASEBOARD_FAB2(SCH_1):P3E_CPU1_PE3_MP_TXP(15)    I54 @BASEBOARD_FAB2_LIB.BASEBOARD_FAB2(SCH_1):PAGE182

C9N8 CAP_0402-0.22UF,16V,10%,X7R,A3A
     1 P3E_CPU1_PE3_MP_C_TXN<14> @BASEBOARD_FAB2_LIB.BASEBOARD_FAB2(SCH_1):P3E_CPU1_PE3_MP_C_TXN(14)    I50 @BASEBOARD_FAB2_LIB.BASEBOARD_FAB2(SCH_1):PAGE182
     2 P3E_CPU1_PE3_MP_TXN<14> @BASEBOARD_FAB2_LIB.BASEBOARD_FAB2(SCH_1):P3E_CPU1_PE3_MP_TXN(14)    I50 @BASEBOARD_FAB2_LIB.BASEBOARD_FAB2(SCH_1):PAGE182

C9N9 CAP_0402-0.22UF,16V,10%,X7R,A3A
     1 P3E_CPU1_PE3_MP_C_TXN<15> @BASEBOARD_FAB2_LIB.BASEBOARD_FAB2(SCH_1):P3E_CPU1_PE3_MP_C_TXN(15)    I49 @BASEBOARD_FAB2_LIB.BASEBOARD_FAB2(SCH_1):PAGE182
     2 P3E_CPU1_PE3_MP_TXN<15> @BASEBOARD_FAB2_LIB.BASEBOARD_FAB2(SCH_1):P3E_CPU1_PE3_MP_TXN(15)    I49 @BASEBOARD_FAB2_LIB.BASEBOARD_FAB2(SCH_1):PAGE182

C9N10 CAP_0402-0.22UF,16V,10%,X7R,A3A
     1 P3E_CPU1_PE3_MP_C_TXP<14> @BASEBOARD_FAB2_LIB.BASEBOARD_FAB2(SCH_1):P3E_CPU1_PE3_MP_C_TXP(14)    I53 @BASEBOARD_FAB2_LIB.BASEBOARD_FAB2(SCH_1):PAGE182
     2 P3E_CPU1_PE3_MP_TXP<14> @BASEBOARD_FAB2_LIB.BASEBOARD_FAB2(SCH_1):P3E_CPU1_PE3_MP_TXP(14)    I53 @BASEBOARD_FAB2_LIB.BASEBOARD_FAB2(SCH_1):PAGE182

C9N11 CAPP_3018-470UF,2.5V,20%,ALUM,A
     1 PVSA_CPU1 @BASEBOARD_FAB2_LIB.BASEBOARD_FAB2(SCH_1):PVSA_CPU1    I12 @BASEBOARD_FAB2_LIB.BASEBOARD_FAB2(SCH_1):PAGE210
     2    GND @BASEBOARD_FAB2_LIB.BASEBOARD_FAB2(SCH_1):GND    I12 @BASEBOARD_FAB2_LIB.BASEBOARD_FAB2(SCH_1):PAGE210

C9N12 CAP_0402-0.22UF,16V,10%,X7R,A3A
     1 P3E_CPU1_PE3_MP_C_TXP<9> @BASEBOARD_FAB2_LIB.BASEBOARD_FAB2(SCH_1):P3E_CPU1_PE3_MP_C_TXP(9)    I16 @BASEBOARD_FAB2_LIB.BASEBOARD_FAB2(SCH_1):PAGE182
     2 P3E_CPU1_PE3_MP_TXP<9> @BASEBOARD_FAB2_LIB.BASEBOARD_FAB2(SCH_1):P3E_CPU1_PE3_MP_TXP(9)    I16 @BASEBOARD_FAB2_LIB.BASEBOARD_FAB2(SCH_1):PAGE182

C9N13 CAP_0805-10UF,16V,10%,X6S,C953A
     1 VR_FET_SW_P12V_STBY_PVCCIN_CPU1 @BASEBOARD_FAB2_LIB.BASEBOARD_FAB2(SCH_1):VR_FET_SW_P12V_STBY_PVCCIN_CPU1    I35 @BASEBOARD_FAB2_LIB.BASEBOARD_FAB2(SCH_1):PAGE210
     2    GND @BASEBOARD_FAB2_LIB.BASEBOARD_FAB2(SCH_1):GND    I35 @BASEBOARD_FAB2_LIB.BASEBOARD_FAB2(SCH_1):PAGE210

C9N14 CAP_0402-0.22UF,16V,10%,X7R,A3A
     1 P3E_CPU1_PE3_MP_C_TXP<12> @BASEBOARD_FAB2_LIB.BASEBOARD_FAB2(SCH_1):P3E_CPU1_PE3_MP_C_TXP(12)    I56 @BASEBOARD_FAB2_LIB.BASEBOARD_FAB2(SCH_1):PAGE182
     2 P3E_CPU1_PE3_MP_TXP<12> @BASEBOARD_FAB2_LIB.BASEBOARD_FAB2(SCH_1):P3E_CPU1_PE3_MP_TXP(12)    I56 @BASEBOARD_FAB2_LIB.BASEBOARD_FAB2(SCH_1):PAGE182

C9N15 CAP_0402-0.22UF,16V,10%,X7R,A3A
     1 P3E_CPU1_PE3_MP_C_TXN<9> @BASEBOARD_FAB2_LIB.BASEBOARD_FAB2(SCH_1):P3E_CPU1_PE3_MP_C_TXN(9)    I13 @BASEBOARD_FAB2_LIB.BASEBOARD_FAB2(SCH_1):PAGE182
     2 P3E_CPU1_PE3_MP_TXN<9> @BASEBOARD_FAB2_LIB.BASEBOARD_FAB2(SCH_1):P3E_CPU1_PE3_MP_TXN(9)    I13 @BASEBOARD_FAB2_LIB.BASEBOARD_FAB2(SCH_1):PAGE182

C9N16 CAP_0402-0.22UF,16V,10%,X7R,A3A
     1 P3E_CPU1_PE3_MP_C_TXN<12> @BASEBOARD_FAB2_LIB.BASEBOARD_FAB2(SCH_1):P3E_CPU1_PE3_MP_C_TXN(12)    I52 @BASEBOARD_FAB2_LIB.BASEBOARD_FAB2(SCH_1):PAGE182
     2 P3E_CPU1_PE3_MP_TXN<12> @BASEBOARD_FAB2_LIB.BASEBOARD_FAB2(SCH_1):P3E_CPU1_PE3_MP_TXN(12)    I52 @BASEBOARD_FAB2_LIB.BASEBOARD_FAB2(SCH_1):PAGE182

C9N17 CAP_0402-0.22UF,16V,10%,X7R,A3A
     1 P3E_CPU1_PE3_MP_C_TXP<8> @BASEBOARD_FAB2_LIB.BASEBOARD_FAB2(SCH_1):P3E_CPU1_PE3_MP_C_TXP(8)    I12 @BASEBOARD_FAB2_LIB.BASEBOARD_FAB2(SCH_1):PAGE182
     2 P3E_CPU1_PE3_MP_TXP<8> @BASEBOARD_FAB2_LIB.BASEBOARD_FAB2(SCH_1):P3E_CPU1_PE3_MP_TXP(8)    I12 @BASEBOARD_FAB2_LIB.BASEBOARD_FAB2(SCH_1):PAGE182

C9N18 CAP_0402-0.22UF,16V,10%,X7R,A3A
     1 P3E_CPU1_PE3_MP_C_TXN<8> @BASEBOARD_FAB2_LIB.BASEBOARD_FAB2(SCH_1):P3E_CPU1_PE3_MP_C_TXN(8)     I9 @BASEBOARD_FAB2_LIB.BASEBOARD_FAB2(SCH_1):PAGE182
     2 P3E_CPU1_PE3_MP_TXN<8> @BASEBOARD_FAB2_LIB.BASEBOARD_FAB2(SCH_1):P3E_CPU1_PE3_MP_TXN(8)     I9 @BASEBOARD_FAB2_LIB.BASEBOARD_FAB2(SCH_1):PAGE182

C9N19 CAP_0805-10UF,16V,10%,X6S,C953A
     1 VR_FET_SW_P12V_STBY_PVCCIN_CPU1 @BASEBOARD_FAB2_LIB.BASEBOARD_FAB2(SCH_1):VR_FET_SW_P12V_STBY_PVCCIN_CPU1    I36 @BASEBOARD_FAB2_LIB.BASEBOARD_FAB2(SCH_1):PAGE210
     2    GND @BASEBOARD_FAB2_LIB.BASEBOARD_FAB2(SCH_1):GND    I36 @BASEBOARD_FAB2_LIB.BASEBOARD_FAB2(SCH_1):PAGE210

C9N20 CAPP_3018-470UF,2.5V,20%,ALUM,A
     1 PVSA_CPU1 @BASEBOARD_FAB2_LIB.BASEBOARD_FAB2(SCH_1):PVSA_CPU1    I14 @BASEBOARD_FAB2_LIB.BASEBOARD_FAB2(SCH_1):PAGE210
     2    GND @BASEBOARD_FAB2_LIB.BASEBOARD_FAB2(SCH_1):GND    I14 @BASEBOARD_FAB2_LIB.BASEBOARD_FAB2(SCH_1):PAGE210

C9N21 CAP_0805-10UF,16V,10%,X6S,C953A
     1 VR_FET_SW_P12V_STBY_PVCCIN_CPU1 @BASEBOARD_FAB2_LIB.BASEBOARD_FAB2(SCH_1):VR_FET_SW_P12V_STBY_PVCCIN_CPU1    I38 @BASEBOARD_FAB2_LIB.BASEBOARD_FAB2(SCH_1):PAGE210
     2    GND @BASEBOARD_FAB2_LIB.BASEBOARD_FAB2(SCH_1):GND    I38 @BASEBOARD_FAB2_LIB.BASEBOARD_FAB2(SCH_1):PAGE210

C9N22 CAP_A_0603V-22.0UF,4V,20%,X6S,A
     1 PVSA_CPU1 @BASEBOARD_FAB2_LIB.BASEBOARD_FAB2(SCH_1):PVSA_CPU1    I44 @BASEBOARD_FAB2_LIB.BASEBOARD_FAB2(SCH_1):PAGE210
     2    GND @BASEBOARD_FAB2_LIB.BASEBOARD_FAB2(SCH_1):GND    I44 @BASEBOARD_FAB2_LIB.BASEBOARD_FAB2(SCH_1):PAGE210

C9N24 CAPP_3018-470UF,2.5V,20%,ALUM,A
     1 PVCCIN_CPU1 @BASEBOARD_FAB2_LIB.BASEBOARD_FAB2(SCH_1):PVCCIN_CPU1    I24 @BASEBOARD_FAB2_LIB.BASEBOARD_FAB2(SCH_1):PAGE208
     2    GND @BASEBOARD_FAB2_LIB.BASEBOARD_FAB2(SCH_1):GND    I24 @BASEBOARD_FAB2_LIB.BASEBOARD_FAB2(SCH_1):PAGE208

C9N25 CAP_0805-10UF,16V,10%,X6S,C953A
     1 VR_FET_SW_P12V_STBY_PVCCIN_CPU1 @BASEBOARD_FAB2_LIB.BASEBOARD_FAB2(SCH_1):VR_FET_SW_P12V_STBY_PVCCIN_CPU1     I8 @BASEBOARD_FAB2_LIB.BASEBOARD_FAB2(SCH_1):PAGE209
     2    GND @BASEBOARD_FAB2_LIB.BASEBOARD_FAB2(SCH_1):GND     I8 @BASEBOARD_FAB2_LIB.BASEBOARD_FAB2(SCH_1):PAGE209

C9N26 CAP_0805-10UF,16V,10%,X6S,C953A
     1 VR_FET_SW_P12V_STBY_PVCCIN_CPU1 @BASEBOARD_FAB2_LIB.BASEBOARD_FAB2(SCH_1):VR_FET_SW_P12V_STBY_PVCCIN_CPU1     I7 @BASEBOARD_FAB2_LIB.BASEBOARD_FAB2(SCH_1):PAGE209
     2    GND @BASEBOARD_FAB2_LIB.BASEBOARD_FAB2(SCH_1):GND     I7 @BASEBOARD_FAB2_LIB.BASEBOARD_FAB2(SCH_1):PAGE209

C9N27 CAP_0805-10UF,16V,10%,X6S,C953A
     1 VR_FET_SW_P12V_STBY_PVCCIN_CPU1 @BASEBOARD_FAB2_LIB.BASEBOARD_FAB2(SCH_1):VR_FET_SW_P12V_STBY_PVCCIN_CPU1     I5 @BASEBOARD_FAB2_LIB.BASEBOARD_FAB2(SCH_1):PAGE209
     2    GND @BASEBOARD_FAB2_LIB.BASEBOARD_FAB2(SCH_1):GND     I5 @BASEBOARD_FAB2_LIB.BASEBOARD_FAB2(SCH_1):PAGE209

C9P1 CAP_0805-10UF,16V,10%,X6S,C953A
     1 VR_FET_SW_P12V_STBY_PVCCIN_CPU1 @BASEBOARD_FAB2_LIB.BASEBOARD_FAB2(SCH_1):VR_FET_SW_P12V_STBY_PVCCIN_CPU1    I59 @BASEBOARD_FAB2_LIB.BASEBOARD_FAB2(SCH_1):PAGE208
     2    GND @BASEBOARD_FAB2_LIB.BASEBOARD_FAB2(SCH_1):GND    I59 @BASEBOARD_FAB2_LIB.BASEBOARD_FAB2(SCH_1):PAGE208

C9P2 CAP_0805-10UF,16V,10%,X6S,C953A
     1 VR_FET_SW_P12V_STBY_PVCCIN_CPU1 @BASEBOARD_FAB2_LIB.BASEBOARD_FAB2(SCH_1):VR_FET_SW_P12V_STBY_PVCCIN_CPU1    I60 @BASEBOARD_FAB2_LIB.BASEBOARD_FAB2(SCH_1):PAGE208
     2    GND @BASEBOARD_FAB2_LIB.BASEBOARD_FAB2(SCH_1):GND    I60 @BASEBOARD_FAB2_LIB.BASEBOARD_FAB2(SCH_1):PAGE208

C9P3 CAP_A_0603V-22.0UF,4V,20%,X6S,A
     1 PVCCIN_CPU1 @BASEBOARD_FAB2_LIB.BASEBOARD_FAB2(SCH_1):PVCCIN_CPU1    I59 @BASEBOARD_FAB2_LIB.BASEBOARD_FAB2(SCH_1):PAGE207
     2    GND @BASEBOARD_FAB2_LIB.BASEBOARD_FAB2(SCH_1):GND    I59 @BASEBOARD_FAB2_LIB.BASEBOARD_FAB2(SCH_1):PAGE207

C9P4 CAP_0805-10UF,16V,10%,X6S,C953A
     1 VR_FET_SW_P12V_STBY_PVCCIN_CPU1 @BASEBOARD_FAB2_LIB.BASEBOARD_FAB2(SCH_1):VR_FET_SW_P12V_STBY_PVCCIN_CPU1    I53 @BASEBOARD_FAB2_LIB.BASEBOARD_FAB2(SCH_1):PAGE208
     2    GND @BASEBOARD_FAB2_LIB.BASEBOARD_FAB2(SCH_1):GND    I53 @BASEBOARD_FAB2_LIB.BASEBOARD_FAB2(SCH_1):PAGE208

C9P5 CAPP_3018-470UF,2.5V,20%,ALUM,A
     1 PVCCIN_CPU1 @BASEBOARD_FAB2_LIB.BASEBOARD_FAB2(SCH_1):PVCCIN_CPU1    I14 @BASEBOARD_FAB2_LIB.BASEBOARD_FAB2(SCH_1):PAGE208
     2    GND @BASEBOARD_FAB2_LIB.BASEBOARD_FAB2(SCH_1):GND    I14 @BASEBOARD_FAB2_LIB.BASEBOARD_FAB2(SCH_1):PAGE208

C9P6 CAP_A_0402V-0.1UF,16V,10%,X7R,A
     1 P12V_STBY @BASEBOARD_FAB2_LIB.BASEBOARD_FAB2(SCH_1):P12V_STBY   I185 @BASEBOARD_FAB2_LIB.BASEBOARD_FAB2(SCH_1):PAGE200
     2 AGND_HSC @BASEBOARD_FAB2_LIB.BASEBOARD_FAB2(SCH_1):AGND_HSC   I185 @BASEBOARD_FAB2_LIB.BASEBOARD_FAB2(SCH_1):PAGE200

C9P7 CAP_0805-10UF,16V,10%,X6S,C953A
     1 VR_FET_SW_P12V_STBY_PVCCIN_CPU1 @BASEBOARD_FAB2_LIB.BASEBOARD_FAB2(SCH_1):VR_FET_SW_P12V_STBY_PVCCIN_CPU1    I54 @BASEBOARD_FAB2_LIB.BASEBOARD_FAB2(SCH_1):PAGE208
     2    GND @BASEBOARD_FAB2_LIB.BASEBOARD_FAB2(SCH_1):GND    I54 @BASEBOARD_FAB2_LIB.BASEBOARD_FAB2(SCH_1):PAGE208

C9P8 CAPP_3018-470UF,2.5V,20%,ALUM,A
     1 PVCCIN_CPU1 @BASEBOARD_FAB2_LIB.BASEBOARD_FAB2(SCH_1):PVCCIN_CPU1    I12 @BASEBOARD_FAB2_LIB.BASEBOARD_FAB2(SCH_1):PAGE208
     2    GND @BASEBOARD_FAB2_LIB.BASEBOARD_FAB2(SCH_1):GND    I12 @BASEBOARD_FAB2_LIB.BASEBOARD_FAB2(SCH_1):PAGE208

C9P9 CAP_0805-10UF,16V,10%,X6S,C953A
     1 VR_FET_SW_P12V_STBY_PVCCIN_CPU1 @BASEBOARD_FAB2_LIB.BASEBOARD_FAB2(SCH_1):VR_FET_SW_P12V_STBY_PVCCIN_CPU1    I55 @BASEBOARD_FAB2_LIB.BASEBOARD_FAB2(SCH_1):PAGE208
     2    GND @BASEBOARD_FAB2_LIB.BASEBOARD_FAB2(SCH_1):GND    I55 @BASEBOARD_FAB2_LIB.BASEBOARD_FAB2(SCH_1):PAGE208

C9P10 CAP_A_0603V-22.0UF,4V,20%,X6S,A
     1 PVCCIN_CPU1 @BASEBOARD_FAB2_LIB.BASEBOARD_FAB2(SCH_1):PVCCIN_CPU1    I66 @BASEBOARD_FAB2_LIB.BASEBOARD_FAB2(SCH_1):PAGE208
     2    GND @BASEBOARD_FAB2_LIB.BASEBOARD_FAB2(SCH_1):GND    I66 @BASEBOARD_FAB2_LIB.BASEBOARD_FAB2(SCH_1):PAGE208

C9P11 CAP_A_0402V-0.1UF,16V,10%,X7R,A
     1 P3V3_STBY @BASEBOARD_FAB2_LIB.BASEBOARD_FAB2(SCH_1):P3V3_STBY   I201 @BASEBOARD_FAB2_LIB.BASEBOARD_FAB2(SCH_1):PAGE200
     2    GND @BASEBOARD_FAB2_LIB.BASEBOARD_FAB2(SCH_1):GND   I201 @BASEBOARD_FAB2_LIB.BASEBOARD_FAB2(SCH_1):PAGE200

C9P12 CAP_A_0402V-0.1UF,16V,10%,EMPTA
     1 A_HSC_VOUT @BASEBOARD_FAB2_LIB.BASEBOARD_FAB2(SCH_1):A_HSC_VOUT    I67 @BASEBOARD_FAB2_LIB.BASEBOARD_FAB2(SCH_1):PAGE199
     2 AGND_HSC @BASEBOARD_FAB2_LIB.BASEBOARD_FAB2(SCH_1):AGND_HSC    I67 @BASEBOARD_FAB2_LIB.BASEBOARD_FAB2(SCH_1):PAGE199

C9P14 CAP_0603LF-0.033UF,50V,10%,X7RA
     1 A_HSC_TIMER @BASEBOARD_FAB2_LIB.BASEBOARD_FAB2(SCH_1):A_HSC_TIMER    I24 @BASEBOARD_FAB2_LIB.BASEBOARD_FAB2(SCH_1):PAGE199
     2 AGND_HSC @BASEBOARD_FAB2_LIB.BASEBOARD_FAB2(SCH_1):AGND_HSC    I24 @BASEBOARD_FAB2_LIB.BASEBOARD_FAB2(SCH_1):PAGE199

C9P15 CAP_A_0402V-0.1UF,16V,10%,X7R,A
     1 A_HSC_ISET @BASEBOARD_FAB2_LIB.BASEBOARD_FAB2(SCH_1):A_HSC_ISET   I105 @BASEBOARD_FAB2_LIB.BASEBOARD_FAB2(SCH_1):PAGE199
     2 AGND_HSC @BASEBOARD_FAB2_LIB.BASEBOARD_FAB2(SCH_1):AGND_HSC   I105 @BASEBOARD_FAB2_LIB.BASEBOARD_FAB2(SCH_1):PAGE199

C9P16 CAP_A_0402V-0.1UF,16V,10%,EMPTA
     1 A_HSC_MOP @BASEBOARD_FAB2_LIB.BASEBOARD_FAB2(SCH_1):A_HSC_MOP    I40 @BASEBOARD_FAB2_LIB.BASEBOARD_FAB2(SCH_1):PAGE200
     2 AGND_HSC @BASEBOARD_FAB2_LIB.BASEBOARD_FAB2(SCH_1):AGND_HSC    I40 @BASEBOARD_FAB2_LIB.BASEBOARD_FAB2(SCH_1):PAGE200

C9P17 CAP_A_0402V-0.1UF,16V,10%,EMPTA
     1 A_HSC_MON @BASEBOARD_FAB2_LIB.BASEBOARD_FAB2(SCH_1):A_HSC_MON    I36 @BASEBOARD_FAB2_LIB.BASEBOARD_FAB2(SCH_1):PAGE200
     2 AGND_HSC @BASEBOARD_FAB2_LIB.BASEBOARD_FAB2(SCH_1):AGND_HSC    I36 @BASEBOARD_FAB2_LIB.BASEBOARD_FAB2(SCH_1):PAGE200

C9P18 CAPP_3018-470UF,2.5V,20%,ALUM,A
     1 PVCCIN_CPU1 @BASEBOARD_FAB2_LIB.BASEBOARD_FAB2(SCH_1):PVCCIN_CPU1    I30 @BASEBOARD_FAB2_LIB.BASEBOARD_FAB2(SCH_1):PAGE208
     2    GND @BASEBOARD_FAB2_LIB.BASEBOARD_FAB2(SCH_1):GND    I30 @BASEBOARD_FAB2_LIB.BASEBOARD_FAB2(SCH_1):PAGE208

C9P20 CAP_A_0603V-22.0UF,4V,20%,X6S,A
     1 PVCCIN_CPU1 @BASEBOARD_FAB2_LIB.BASEBOARD_FAB2(SCH_1):PVCCIN_CPU1    I55 @BASEBOARD_FAB2_LIB.BASEBOARD_FAB2(SCH_1):PAGE209
     2    GND @BASEBOARD_FAB2_LIB.BASEBOARD_FAB2(SCH_1):GND    I55 @BASEBOARD_FAB2_LIB.BASEBOARD_FAB2(SCH_1):PAGE209

C9P22 CAP_0805-10UF,16V,10%,X6S,C953A
     1 VR_FET_SW_P12V_STBY_PVCCIN_CPU1 @BASEBOARD_FAB2_LIB.BASEBOARD_FAB2(SCH_1):VR_FET_SW_P12V_STBY_PVCCIN_CPU1    I50 @BASEBOARD_FAB2_LIB.BASEBOARD_FAB2(SCH_1):PAGE207
     2    GND @BASEBOARD_FAB2_LIB.BASEBOARD_FAB2(SCH_1):GND    I50 @BASEBOARD_FAB2_LIB.BASEBOARD_FAB2(SCH_1):PAGE207

C9P23 CAPP_3018-470UF,2.5V,20%,ALUM,A
     1 PVCCIN_CPU1 @BASEBOARD_FAB2_LIB.BASEBOARD_FAB2(SCH_1):PVCCIN_CPU1    I28 @BASEBOARD_FAB2_LIB.BASEBOARD_FAB2(SCH_1):PAGE208
     2    GND @BASEBOARD_FAB2_LIB.BASEBOARD_FAB2(SCH_1):GND    I28 @BASEBOARD_FAB2_LIB.BASEBOARD_FAB2(SCH_1):PAGE208

C9P24 CAP_0805-10UF,16V,10%,X6S,C953A
     1 VR_FET_SW_P12V_STBY_PVCCIN_CPU1 @BASEBOARD_FAB2_LIB.BASEBOARD_FAB2(SCH_1):VR_FET_SW_P12V_STBY_PVCCIN_CPU1    I58 @BASEBOARD_FAB2_LIB.BASEBOARD_FAB2(SCH_1):PAGE208
     2    GND @BASEBOARD_FAB2_LIB.BASEBOARD_FAB2(SCH_1):GND    I58 @BASEBOARD_FAB2_LIB.BASEBOARD_FAB2(SCH_1):PAGE208

C9P25 CAP_0805-10UF,16V,10%,X6S,C953A
     1 VR_FET_SW_P12V_STBY_PVCCIN_CPU1 @BASEBOARD_FAB2_LIB.BASEBOARD_FAB2(SCH_1):VR_FET_SW_P12V_STBY_PVCCIN_CPU1    I51 @BASEBOARD_FAB2_LIB.BASEBOARD_FAB2(SCH_1):PAGE207
     2    GND @BASEBOARD_FAB2_LIB.BASEBOARD_FAB2(SCH_1):GND    I51 @BASEBOARD_FAB2_LIB.BASEBOARD_FAB2(SCH_1):PAGE207

C9P26 CAP_0805-10UF,16V,10%,X6S,C953A
     1 VR_FET_SW_P12V_STBY_PVCCIN_CPU1 @BASEBOARD_FAB2_LIB.BASEBOARD_FAB2(SCH_1):VR_FET_SW_P12V_STBY_PVCCIN_CPU1    I54 @BASEBOARD_FAB2_LIB.BASEBOARD_FAB2(SCH_1):PAGE207
     2    GND @BASEBOARD_FAB2_LIB.BASEBOARD_FAB2(SCH_1):GND    I54 @BASEBOARD_FAB2_LIB.BASEBOARD_FAB2(SCH_1):PAGE207

C9R2 CAP_A_0603V-22.0UF,4V,20%,X6S,A
     1 PVCCIN_CPU1 @BASEBOARD_FAB2_LIB.BASEBOARD_FAB2(SCH_1):PVCCIN_CPU1    I67 @BASEBOARD_FAB2_LIB.BASEBOARD_FAB2(SCH_1):PAGE208
     2    GND @BASEBOARD_FAB2_LIB.BASEBOARD_FAB2(SCH_1):GND    I67 @BASEBOARD_FAB2_LIB.BASEBOARD_FAB2(SCH_1):PAGE208

C9R3 CAPP_3018-470UF,2.5V,20%,ALUM,A
     1 PVCCIN_CPU1 @BASEBOARD_FAB2_LIB.BASEBOARD_FAB2(SCH_1):PVCCIN_CPU1    I26 @BASEBOARD_FAB2_LIB.BASEBOARD_FAB2(SCH_1):PAGE208
     2    GND @BASEBOARD_FAB2_LIB.BASEBOARD_FAB2(SCH_1):GND    I26 @BASEBOARD_FAB2_LIB.BASEBOARD_FAB2(SCH_1):PAGE208

C9R5 CAP_0805-10UF,16V,10%,X6S,C953A
     1 P12V_PSU @BASEBOARD_FAB2_LIB.BASEBOARD_FAB2(SCH_1):P12V_PSU    I31 @BASEBOARD_FAB2_LIB.BASEBOARD_FAB2(SCH_1):PAGE195
     2    GND @BASEBOARD_FAB2_LIB.BASEBOARD_FAB2(SCH_1):GND    I31 @BASEBOARD_FAB2_LIB.BASEBOARD_FAB2(SCH_1):PAGE195

C9R6 CAP_A_0402V-0.1UF,16V,10%,X7R,A
     1 P12V_PSU @BASEBOARD_FAB2_LIB.BASEBOARD_FAB2(SCH_1):P12V_PSU    I37 @BASEBOARD_FAB2_LIB.BASEBOARD_FAB2(SCH_1):PAGE195
     2    GND @BASEBOARD_FAB2_LIB.BASEBOARD_FAB2(SCH_1):GND    I37 @BASEBOARD_FAB2_LIB.BASEBOARD_FAB2(SCH_1):PAGE195

C9R7 CAP_0805-10UF,16V,10%,X6S,C953A
     1 VR_FET_SW_P12V_STBY_PVCCIN_CPU1 @BASEBOARD_FAB2_LIB.BASEBOARD_FAB2(SCH_1):VR_FET_SW_P12V_STBY_PVCCIN_CPU1    I43 @BASEBOARD_FAB2_LIB.BASEBOARD_FAB2(SCH_1):PAGE207
     2    GND @BASEBOARD_FAB2_LIB.BASEBOARD_FAB2(SCH_1):GND    I43 @BASEBOARD_FAB2_LIB.BASEBOARD_FAB2(SCH_1):PAGE207

C9R8 CAP_A_0603V-22.0UF,4V,20%,X6S,A
     1 PVCCIN_CPU1 @BASEBOARD_FAB2_LIB.BASEBOARD_FAB2(SCH_1):PVCCIN_CPU1     I8 @BASEBOARD_FAB2_LIB.BASEBOARD_FAB2(SCH_1):PAGE207
     2    GND @BASEBOARD_FAB2_LIB.BASEBOARD_FAB2(SCH_1):GND     I8 @BASEBOARD_FAB2_LIB.BASEBOARD_FAB2(SCH_1):PAGE207

C9R9 CAPP_3018-470UF,2.5V,20%,ALUM,A
     1 PVCCIN_CPU1 @BASEBOARD_FAB2_LIB.BASEBOARD_FAB2(SCH_1):PVCCIN_CPU1    I25 @BASEBOARD_FAB2_LIB.BASEBOARD_FAB2(SCH_1):PAGE208
     2    GND @BASEBOARD_FAB2_LIB.BASEBOARD_FAB2(SCH_1):GND    I25 @BASEBOARD_FAB2_LIB.BASEBOARD_FAB2(SCH_1):PAGE208

C9R10 CAP_0805-10UF,16V,10%,X6S,C953A
     1 VR_FET_SW_P12V_STBY_PVCCIN_CPU1 @BASEBOARD_FAB2_LIB.BASEBOARD_FAB2(SCH_1):VR_FET_SW_P12V_STBY_PVCCIN_CPU1    I44 @BASEBOARD_FAB2_LIB.BASEBOARD_FAB2(SCH_1):PAGE207
     2    GND @BASEBOARD_FAB2_LIB.BASEBOARD_FAB2(SCH_1):GND    I44 @BASEBOARD_FAB2_LIB.BASEBOARD_FAB2(SCH_1):PAGE207

C9R11 CAP_0805-10UF,16V,10%,X6S,C953A
     1 VR_FET_SW_P12V_STBY_PVCCIN_CPU1 @BASEBOARD_FAB2_LIB.BASEBOARD_FAB2(SCH_1):VR_FET_SW_P12V_STBY_PVCCIN_CPU1    I48 @BASEBOARD_FAB2_LIB.BASEBOARD_FAB2(SCH_1):PAGE207
     2    GND @BASEBOARD_FAB2_LIB.BASEBOARD_FAB2(SCH_1):GND    I48 @BASEBOARD_FAB2_LIB.BASEBOARD_FAB2(SCH_1):PAGE207

C9R12 CAP_A_0402V-0.1UF,16V,10%,X7R,A
     1 P12V_PSU @BASEBOARD_FAB2_LIB.BASEBOARD_FAB2(SCH_1):P12V_PSU    I36 @BASEBOARD_FAB2_LIB.BASEBOARD_FAB2(SCH_1):PAGE195
     2    GND @BASEBOARD_FAB2_LIB.BASEBOARD_FAB2(SCH_1):GND    I36 @BASEBOARD_FAB2_LIB.BASEBOARD_FAB2(SCH_1):PAGE195

C9R13 CAP_A_0402V-0.1UF,16V,10%,X7R,A
     1 P3V3_STBY @BASEBOARD_FAB2_LIB.BASEBOARD_FAB2(SCH_1):P3V3_STBY    I42 @BASEBOARD_FAB2_LIB.BASEBOARD_FAB2(SCH_1):PAGE167
     2    GND @BASEBOARD_FAB2_LIB.BASEBOARD_FAB2(SCH_1):GND    I42 @BASEBOARD_FAB2_LIB.BASEBOARD_FAB2(SCH_1):PAGE167

C9R14 CAP_A_0402V-0.1UF,16V,10%,X7R,A
     1 P3V3_STBY @BASEBOARD_FAB2_LIB.BASEBOARD_FAB2(SCH_1):P3V3_STBY    I41 @BASEBOARD_FAB2_LIB.BASEBOARD_FAB2(SCH_1):PAGE167
     2    GND @BASEBOARD_FAB2_LIB.BASEBOARD_FAB2(SCH_1):GND    I41 @BASEBOARD_FAB2_LIB.BASEBOARD_FAB2(SCH_1):PAGE167

C9T1 CAP_A_0402V-0.01UF,25V,10%,X7RA
     1 FAN_TACH1 @BASEBOARD_FAB2_LIB.BASEBOARD_FAB2(SCH_1):FAN_TACH1   I137 @BASEBOARD_FAB2_LIB.BASEBOARD_FAB2(SCH_1):PAGE161
     2    GND @BASEBOARD_FAB2_LIB.BASEBOARD_FAB2(SCH_1):GND   I137 @BASEBOARD_FAB2_LIB.BASEBOARD_FAB2(SCH_1):PAGE161

C9T3 CAPP_3018-68UF,16V,20%,TANT,72A
     1 P12V_STBY @BASEBOARD_FAB2_LIB.BASEBOARD_FAB2(SCH_1):P12V_STBY   I111 @BASEBOARD_FAB2_LIB.BASEBOARD_FAB2(SCH_1):PAGE195
     2    GND @BASEBOARD_FAB2_LIB.BASEBOARD_FAB2(SCH_1):GND   I111 @BASEBOARD_FAB2_LIB.BASEBOARD_FAB2(SCH_1):PAGE195

C9T4 CAP_0805-10UF,16V,10%,X6S,C953A
     1 VR_FET_SW_P12V_STBY_PVDDQ_GHJ @BASEBOARD_FAB2_LIB.BASEBOARD_FAB2(SCH_1):VR_FET_SW_P12V_STBY_PVDDQ_GHJ    I47 @BASEBOARD_FAB2_LIB.BASEBOARD_FAB2(SCH_1):PAGE224
     2    GND @BASEBOARD_FAB2_LIB.BASEBOARD_FAB2(SCH_1):GND    I47 @BASEBOARD_FAB2_LIB.BASEBOARD_FAB2(SCH_1):PAGE224

C9T5 CAPP_3018-470UF,2.5V,20%,ALUM,A
     1 PVDDQ_GHJ @BASEBOARD_FAB2_LIB.BASEBOARD_FAB2(SCH_1):PVDDQ_GHJ    I75 @BASEBOARD_FAB2_LIB.BASEBOARD_FAB2(SCH_1):PAGE225
     2    GND @BASEBOARD_FAB2_LIB.BASEBOARD_FAB2(SCH_1):GND    I75 @BASEBOARD_FAB2_LIB.BASEBOARD_FAB2(SCH_1):PAGE225

C9T6 CAP_0805-10UF,16V,10%,X6S,C953A
     1 VR_FET_SW_P12V_STBY_PVDDQ_GHJ @BASEBOARD_FAB2_LIB.BASEBOARD_FAB2(SCH_1):VR_FET_SW_P12V_STBY_PVDDQ_GHJ    I81 @BASEBOARD_FAB2_LIB.BASEBOARD_FAB2(SCH_1):PAGE224
     2    GND @BASEBOARD_FAB2_LIB.BASEBOARD_FAB2(SCH_1):GND    I81 @BASEBOARD_FAB2_LIB.BASEBOARD_FAB2(SCH_1):PAGE224

C9T7 CAP_A_0402V-0.01UF,25V,10%,X7RA
     1 M_G_VREF @BASEBOARD_FAB2_LIB.BASEBOARD_FAB2(SCH_1):M_G_VREF     I2 @BASEBOARD_FAB2_LIB.BASEBOARD_FAB2(SCH_1):PAGE78
     2    GND @BASEBOARD_FAB2_LIB.BASEBOARD_FAB2(SCH_1):GND     I2 @BASEBOARD_FAB2_LIB.BASEBOARD_FAB2(SCH_1):PAGE78

C9T8 CAP_0805-10UF,16V,10%,X7R,G106A
     1 P12V_NVDIMM_GHJ @BASEBOARD_FAB2_LIB.BASEBOARD_FAB2(SCH_1):P12V_NVDIMM_GHJ    I70 @BASEBOARD_FAB2_LIB.BASEBOARD_FAB2(SCH_1):PAGE197
     2    GND @BASEBOARD_FAB2_LIB.BASEBOARD_FAB2(SCH_1):GND    I70 @BASEBOARD_FAB2_LIB.BASEBOARD_FAB2(SCH_1):PAGE197

C9T9 CAP_0805-10UF,16V,10%,X6S,C953A
     1 VR_FET_SW_P12V_STBY_PVDDQ_GHJ @BASEBOARD_FAB2_LIB.BASEBOARD_FAB2(SCH_1):VR_FET_SW_P12V_STBY_PVDDQ_GHJ    I84 @BASEBOARD_FAB2_LIB.BASEBOARD_FAB2(SCH_1):PAGE224
     2    GND @BASEBOARD_FAB2_LIB.BASEBOARD_FAB2(SCH_1):GND    I84 @BASEBOARD_FAB2_LIB.BASEBOARD_FAB2(SCH_1):PAGE224

C9U2 CAPP_3018-470UF,2.5V,20%,ALUM,A
     1 PVDDQ_GHJ @BASEBOARD_FAB2_LIB.BASEBOARD_FAB2(SCH_1):PVDDQ_GHJ    I76 @BASEBOARD_FAB2_LIB.BASEBOARD_FAB2(SCH_1):PAGE225
     2    GND @BASEBOARD_FAB2_LIB.BASEBOARD_FAB2(SCH_1):GND    I76 @BASEBOARD_FAB2_LIB.BASEBOARD_FAB2(SCH_1):PAGE225

C9U3 CAP_0805-10UF,16V,10%,X6S,C953A
     1 VR_FET_SW_P12V_STBY_PVDDQ_GHJ @BASEBOARD_FAB2_LIB.BASEBOARD_FAB2(SCH_1):VR_FET_SW_P12V_STBY_PVDDQ_GHJ    I80 @BASEBOARD_FAB2_LIB.BASEBOARD_FAB2(SCH_1):PAGE224
     2    GND @BASEBOARD_FAB2_LIB.BASEBOARD_FAB2(SCH_1):GND    I80 @BASEBOARD_FAB2_LIB.BASEBOARD_FAB2(SCH_1):PAGE224

C9U4 CAP_0805-10UF,16V,10%,X6S,C953A
     1 VR_FET_SW_P12V_STBY_PVDDQ_GHJ @BASEBOARD_FAB2_LIB.BASEBOARD_FAB2(SCH_1):VR_FET_SW_P12V_STBY_PVDDQ_GHJ    I46 @BASEBOARD_FAB2_LIB.BASEBOARD_FAB2(SCH_1):PAGE224
     2    GND @BASEBOARD_FAB2_LIB.BASEBOARD_FAB2(SCH_1):GND    I46 @BASEBOARD_FAB2_LIB.BASEBOARD_FAB2(SCH_1):PAGE224

C9U5 CAPP_3018-470UF,2.5V,20%,ALUM,A
     1 PVDDQ_GHJ @BASEBOARD_FAB2_LIB.BASEBOARD_FAB2(SCH_1):PVDDQ_GHJ    I78 @BASEBOARD_FAB2_LIB.BASEBOARD_FAB2(SCH_1):PAGE225
     2    GND @BASEBOARD_FAB2_LIB.BASEBOARD_FAB2(SCH_1):GND    I78 @BASEBOARD_FAB2_LIB.BASEBOARD_FAB2(SCH_1):PAGE225

C9U6 CAP_0805-10UF,16V,10%,X6S,C953A
     1 VR_FET_SW_P12V_STBY_PVDDQ_GHJ @BASEBOARD_FAB2_LIB.BASEBOARD_FAB2(SCH_1):VR_FET_SW_P12V_STBY_PVDDQ_GHJ    I45 @BASEBOARD_FAB2_LIB.BASEBOARD_FAB2(SCH_1):PAGE224
     2    GND @BASEBOARD_FAB2_LIB.BASEBOARD_FAB2(SCH_1):GND    I45 @BASEBOARD_FAB2_LIB.BASEBOARD_FAB2(SCH_1):PAGE224

C9U7 CAP_A_0402V-0.01UF,25V,10%,X7RA
     1 M_H_VREF @BASEBOARD_FAB2_LIB.BASEBOARD_FAB2(SCH_1):M_H_VREF   I178 @BASEBOARD_FAB2_LIB.BASEBOARD_FAB2(SCH_1):PAGE79
     2    GND @BASEBOARD_FAB2_LIB.BASEBOARD_FAB2(SCH_1):GND   I178 @BASEBOARD_FAB2_LIB.BASEBOARD_FAB2(SCH_1):PAGE79

C9U8 CAP_0805-10UF,16V,10%,X7R,G106A
     1 P12V_NVDIMM_GHJ @BASEBOARD_FAB2_LIB.BASEBOARD_FAB2(SCH_1):P12V_NVDIMM_GHJ    I76 @BASEBOARD_FAB2_LIB.BASEBOARD_FAB2(SCH_1):PAGE197
     2    GND @BASEBOARD_FAB2_LIB.BASEBOARD_FAB2(SCH_1):GND    I76 @BASEBOARD_FAB2_LIB.BASEBOARD_FAB2(SCH_1):PAGE197

C9U9 CAPP_3018-470UF,2.5V,20%,ALUM,A
     1 PVDDQ_GHJ @BASEBOARD_FAB2_LIB.BASEBOARD_FAB2(SCH_1):PVDDQ_GHJ    I77 @BASEBOARD_FAB2_LIB.BASEBOARD_FAB2(SCH_1):PAGE225
     2    GND @BASEBOARD_FAB2_LIB.BASEBOARD_FAB2(SCH_1):GND    I77 @BASEBOARD_FAB2_LIB.BASEBOARD_FAB2(SCH_1):PAGE225

C9U10 CAP_A_0402V-0.01UF,25V,10%,X7RA
     1 M_J_VREF @BASEBOARD_FAB2_LIB.BASEBOARD_FAB2(SCH_1):M_J_VREF   I178 @BASEBOARD_FAB2_LIB.BASEBOARD_FAB2(SCH_1):PAGE81
     2    GND @BASEBOARD_FAB2_LIB.BASEBOARD_FAB2(SCH_1):GND   I178 @BASEBOARD_FAB2_LIB.BASEBOARD_FAB2(SCH_1):PAGE81

C9U11 CAP_0805-10UF,16V,10%,X7R,G106A
     1 P12V_NVDIMM_GHJ @BASEBOARD_FAB2_LIB.BASEBOARD_FAB2(SCH_1):P12V_NVDIMM_GHJ    I73 @BASEBOARD_FAB2_LIB.BASEBOARD_FAB2(SCH_1):PAGE197
     2    GND @BASEBOARD_FAB2_LIB.BASEBOARD_FAB2(SCH_1):GND    I73 @BASEBOARD_FAB2_LIB.BASEBOARD_FAB2(SCH_1):PAGE197

C9U12 CAP_A_0402V-0.1UF,16V,10%,X7R,A
     1 VR_PVDDQ_GHJ_AIINSEN @BASEBOARD_FAB2_LIB.BASEBOARD_FAB2(SCH_1):VR_PVDDQ_GHJ_AIINSEN    I92 @BASEBOARD_FAB2_LIB.BASEBOARD_FAB2(SCH_1):PAGE223
     2    GND @BASEBOARD_FAB2_LIB.BASEBOARD_FAB2(SCH_1):GND    I92 @BASEBOARD_FAB2_LIB.BASEBOARD_FAB2(SCH_1):PAGE223

C9W1 SC22P50V2JN-4GP_SMD-BCG-SC22P5A
     1 A_P12V_STBY_FP_TRIGGER @BASEBOARD_FAB2_LIB.BASEBOARD_FAB2(SCH_1):A_P12V_STBY_FP_TRIGGER   I235 @BASEBOARD_FAB2_LIB.BASEBOARD_FAB2(SCH_1):PAGE200
     2 AGND_HSC @BASEBOARD_FAB2_LIB.BASEBOARD_FAB2(SCH_1):AGND_HSC   I235 @BASEBOARD_FAB2_LIB.BASEBOARD_FAB2(SCH_1):PAGE200

C9W2 SC22P50V2JN-4GP_SMD-BCG-SC22P5A
     1 A_P12V_STBY_ADR_TRIGGER @BASEBOARD_FAB2_LIB.BASEBOARD_FAB2(SCH_1):A_P12V_STBY_ADR_TRIGGER   I236 @BASEBOARD_FAB2_LIB.BASEBOARD_FAB2(SCH_1):PAGE200
     2 AGND_HSC @BASEBOARD_FAB2_LIB.BASEBOARD_FAB2(SCH_1):AGND_HSC   I236 @BASEBOARD_FAB2_LIB.BASEBOARD_FAB2(SCH_1):PAGE200

C9W5 CAP_A_0402V-0.1UF,16V,10%,X7R,A
     1 P3V3_STBY @BASEBOARD_FAB2_LIB.BASEBOARD_FAB2(SCH_1):P3V3_STBY    I90 @BASEBOARD_FAB2_LIB.BASEBOARD_FAB2(SCH_1):PAGE239
     2    GND @BASEBOARD_FAB2_LIB.BASEBOARD_FAB2(SCH_1):GND    I90 @BASEBOARD_FAB2_LIB.BASEBOARD_FAB2(SCH_1):PAGE239

C9W6 CAP_0402LF-1000PF,50V,10%,EMPTA
     1 UNNAMED_239_CAP_I91_A @BASEBOARD_FAB2_LIB.BASEBOARD_FAB2(SCH_1):UNNAMED_239_CAP_I91_A    I91 @BASEBOARD_FAB2_LIB.BASEBOARD_FAB2(SCH_1):PAGE239
     2    GND @BASEBOARD_FAB2_LIB.BASEBOARD_FAB2(SCH_1):GND    I91 @BASEBOARD_FAB2_LIB.BASEBOARD_FAB2(SCH_1):PAGE239

C9W10 CAP_0402LF-1000PF,50V,10%,X7R,A
     1 UNNAMED_239_CAP_I84_A @BASEBOARD_FAB2_LIB.BASEBOARD_FAB2(SCH_1):UNNAMED_239_CAP_I84_A    I84 @BASEBOARD_FAB2_LIB.BASEBOARD_FAB2(SCH_1):PAGE239
     2    GND @BASEBOARD_FAB2_LIB.BASEBOARD_FAB2(SCH_1):GND    I84 @BASEBOARD_FAB2_LIB.BASEBOARD_FAB2(SCH_1):PAGE239

C9W13 CAP_0805LF-22UF,4V,20%,X6S,C95A
     1 P2V5_AUX_BMC @BASEBOARD_FAB2_LIB.BASEBOARD_FAB2(SCH_1):P2V5_AUX_BMC    I81 @BASEBOARD_FAB2_LIB.BASEBOARD_FAB2(SCH_1):PAGE239
     2    GND @BASEBOARD_FAB2_LIB.BASEBOARD_FAB2(SCH_1):GND    I81 @BASEBOARD_FAB2_LIB.BASEBOARD_FAB2(SCH_1):PAGE239

C25W1 CAP_0402-1.0UF,16V,10%,X6S,D97A
     1 P1V2_AUX_BMC @BASEBOARD_FAB2_LIB.BASEBOARD_FAB2(SCH_1):P1V2_AUX_BMC    I71 @BASEBOARD_FAB2_LIB.BASEBOARD_FAB2(SCH_1):PAGE149
     2    GND @BASEBOARD_FAB2_LIB.BASEBOARD_FAB2(SCH_1):GND    I71 @BASEBOARD_FAB2_LIB.BASEBOARD_FAB2(SCH_1):PAGE149

C25W2 CAP_0402-1.0UF,16V,10%,X6S,D97A
     1 P1V2_AUX_BMC @BASEBOARD_FAB2_LIB.BASEBOARD_FAB2(SCH_1):P1V2_AUX_BMC    I72 @BASEBOARD_FAB2_LIB.BASEBOARD_FAB2(SCH_1):PAGE149
     2    GND @BASEBOARD_FAB2_LIB.BASEBOARD_FAB2(SCH_1):GND    I72 @BASEBOARD_FAB2_LIB.BASEBOARD_FAB2(SCH_1):PAGE149

C25W3 CAP_0402-1.0UF,16V,10%,X6S,D97A
     1 P1V2_AUX_BMC @BASEBOARD_FAB2_LIB.BASEBOARD_FAB2(SCH_1):P1V2_AUX_BMC    I73 @BASEBOARD_FAB2_LIB.BASEBOARD_FAB2(SCH_1):PAGE149
     2    GND @BASEBOARD_FAB2_LIB.BASEBOARD_FAB2(SCH_1):GND    I73 @BASEBOARD_FAB2_LIB.BASEBOARD_FAB2(SCH_1):PAGE149

C25W4 CAP_0402-1.0UF,16V,10%,X6S,D97A
     1 P1V2_AUX_BMC @BASEBOARD_FAB2_LIB.BASEBOARD_FAB2(SCH_1):P1V2_AUX_BMC    I74 @BASEBOARD_FAB2_LIB.BASEBOARD_FAB2(SCH_1):PAGE149
     2    GND @BASEBOARD_FAB2_LIB.BASEBOARD_FAB2(SCH_1):GND    I74 @BASEBOARD_FAB2_LIB.BASEBOARD_FAB2(SCH_1):PAGE149

C25W5 CAP_0402-1.0UF,16V,10%,X6S,D97A
     1 P1V2_AUX_BMC @BASEBOARD_FAB2_LIB.BASEBOARD_FAB2(SCH_1):P1V2_AUX_BMC    I96 @BASEBOARD_FAB2_LIB.BASEBOARD_FAB2(SCH_1):PAGE149
     2    GND @BASEBOARD_FAB2_LIB.BASEBOARD_FAB2(SCH_1):GND    I96 @BASEBOARD_FAB2_LIB.BASEBOARD_FAB2(SCH_1):PAGE149

C25W6 CAP_0402-1.0UF,16V,10%,X6S,D97A
     1 P1V2_AUX_BMC @BASEBOARD_FAB2_LIB.BASEBOARD_FAB2(SCH_1):P1V2_AUX_BMC    I97 @BASEBOARD_FAB2_LIB.BASEBOARD_FAB2(SCH_1):PAGE149
     2    GND @BASEBOARD_FAB2_LIB.BASEBOARD_FAB2(SCH_1):GND    I97 @BASEBOARD_FAB2_LIB.BASEBOARD_FAB2(SCH_1):PAGE149

C25W7 CAP_0402-0.1UF,16V,10%,EMPTY,AA
     1 P3V3_STBY_BMC_ADCVREFP @BASEBOARD_FAB2_LIB.BASEBOARD_FAB2(SCH_1):P3V3_STBY_BMC_ADCVREFP    I36 @BASEBOARD_FAB2_LIB.BASEBOARD_FAB2(SCH_1):PAGE147
     2 VCC_ADCAV3V3 @BASEBOARD_FAB2_LIB.BASEBOARD_FAB2(SCH_1):VCC_ADCAV3V3    I36 @BASEBOARD_FAB2_LIB.BASEBOARD_FAB2(SCH_1):PAGE147

C25W8 CAP_0402-0.1UF,16V,10%,EMPTY,AA
     1 P3V3_STBY_BMC_ADCVREFN @BASEBOARD_FAB2_LIB.BASEBOARD_FAB2(SCH_1):P3V3_STBY_BMC_ADCVREFN    I38 @BASEBOARD_FAB2_LIB.BASEBOARD_FAB2(SCH_1):PAGE147
     2    GND @BASEBOARD_FAB2_LIB.BASEBOARD_FAB2(SCH_1):GND    I38 @BASEBOARD_FAB2_LIB.BASEBOARD_FAB2(SCH_1):PAGE147

C25W9 CAP_0402-0.1UF,16V,10%,EMPTY,AA
     1 P3V3_STBY_BMC_ADCVREFN @BASEBOARD_FAB2_LIB.BASEBOARD_FAB2(SCH_1):P3V3_STBY_BMC_ADCVREFN    I39 @BASEBOARD_FAB2_LIB.BASEBOARD_FAB2(SCH_1):PAGE147
     2 P3V3_STBY_BMC_ADCVREFP @BASEBOARD_FAB2_LIB.BASEBOARD_FAB2(SCH_1):P3V3_STBY_BMC_ADCVREFP    I39 @BASEBOARD_FAB2_LIB.BASEBOARD_FAB2(SCH_1):PAGE147

C25W10 CAP_0402LF-0.01UF,25V,10%,X7R,A
     1 P1V2_AUX_BMC @BASEBOARD_FAB2_LIB.BASEBOARD_FAB2(SCH_1):P1V2_AUX_BMC   I158 @BASEBOARD_FAB2_LIB.BASEBOARD_FAB2(SCH_1):PAGE149
     2 BMC_M_VREFCA @BASEBOARD_FAB2_LIB.BASEBOARD_FAB2(SCH_1):BMC_M_VREFCA   I158 @BASEBOARD_FAB2_LIB.BASEBOARD_FAB2(SCH_1):PAGE149

C25W11 CAP_0402LF-0.01UF,25V,10%,X7R,A
     1 BMC_M_VREFCA @BASEBOARD_FAB2_LIB.BASEBOARD_FAB2(SCH_1):BMC_M_VREFCA   I159 @BASEBOARD_FAB2_LIB.BASEBOARD_FAB2(SCH_1):PAGE149
     2    GND @BASEBOARD_FAB2_LIB.BASEBOARD_FAB2(SCH_1):GND   I159 @BASEBOARD_FAB2_LIB.BASEBOARD_FAB2(SCH_1):PAGE149

C25W12 CAP_0402-1.0UF,6.3V,10%,X6S,D9A
     1 BMC_M_VREFCA @BASEBOARD_FAB2_LIB.BASEBOARD_FAB2(SCH_1):BMC_M_VREFCA   I126 @BASEBOARD_FAB2_LIB.BASEBOARD_FAB2(SCH_1):PAGE149
     2    GND @BASEBOARD_FAB2_LIB.BASEBOARD_FAB2(SCH_1):GND   I126 @BASEBOARD_FAB2_LIB.BASEBOARD_FAB2(SCH_1):PAGE149

C25W13 CAP_0402LF-0.1UF,16V,10%,X7R,AA
     1 BMC_M_VREFCA @BASEBOARD_FAB2_LIB.BASEBOARD_FAB2(SCH_1):BMC_M_VREFCA    I65 @BASEBOARD_FAB2_LIB.BASEBOARD_FAB2(SCH_1):PAGE149
     2    GND @BASEBOARD_FAB2_LIB.BASEBOARD_FAB2(SCH_1):GND    I65 @BASEBOARD_FAB2_LIB.BASEBOARD_FAB2(SCH_1):PAGE149

C25W14 SCD1U16V2KX-3GP_SMD-BCG-SCD1U1A
     1 P2V5_AUX_BMC @BASEBOARD_FAB2_LIB.BASEBOARD_FAB2(SCH_1):P2V5_AUX_BMC    I44 @BASEBOARD_FAB2_LIB.BASEBOARD_FAB2(SCH_1):PAGE149
     2    GND @BASEBOARD_FAB2_LIB.BASEBOARD_FAB2(SCH_1):GND    I44 @BASEBOARD_FAB2_LIB.BASEBOARD_FAB2(SCH_1):PAGE149

C25W15 SCD1U16V2KX-3GP_SMD-BCG-SCD1U1A
     1 P2V5_AUX_BMC @BASEBOARD_FAB2_LIB.BASEBOARD_FAB2(SCH_1):P2V5_AUX_BMC    I39 @BASEBOARD_FAB2_LIB.BASEBOARD_FAB2(SCH_1):PAGE149
     2    GND @BASEBOARD_FAB2_LIB.BASEBOARD_FAB2(SCH_1):GND    I39 @BASEBOARD_FAB2_LIB.BASEBOARD_FAB2(SCH_1):PAGE149

C25W16 CAP_0402LF-100.0PF,50V,5%,COG,A
     1 P1V2_AUX_BMC @BASEBOARD_FAB2_LIB.BASEBOARD_FAB2(SCH_1):P1V2_AUX_BMC    I37 @BASEBOARD_FAB2_LIB.BASEBOARD_FAB2(SCH_1):PAGE149
     2    GND @BASEBOARD_FAB2_LIB.BASEBOARD_FAB2(SCH_1):GND    I37 @BASEBOARD_FAB2_LIB.BASEBOARD_FAB2(SCH_1):PAGE149

C25W17 SC1U16V3KX-2GP_SMD-BCG-SC1U16VA
     1 P1V2_AUX_BMC @BASEBOARD_FAB2_LIB.BASEBOARD_FAB2(SCH_1):P1V2_AUX_BMC    I38 @BASEBOARD_FAB2_LIB.BASEBOARD_FAB2(SCH_1):PAGE149
     2    GND @BASEBOARD_FAB2_LIB.BASEBOARD_FAB2(SCH_1):GND    I38 @BASEBOARD_FAB2_LIB.BASEBOARD_FAB2(SCH_1):PAGE149

C25W18 SC1U16V3KX-2GP_SMD-BCG-SC1U16VA
     1 P1V2_AUX_BMC @BASEBOARD_FAB2_LIB.BASEBOARD_FAB2(SCH_1):P1V2_AUX_BMC    I68 @BASEBOARD_FAB2_LIB.BASEBOARD_FAB2(SCH_1):PAGE149
     2    GND @BASEBOARD_FAB2_LIB.BASEBOARD_FAB2(SCH_1):GND    I68 @BASEBOARD_FAB2_LIB.BASEBOARD_FAB2(SCH_1):PAGE149

C25W19 SC4D7U10V3KX-GP_SMD-BCG-SC4D7UA
     1 P1V2_AUX_BMC @BASEBOARD_FAB2_LIB.BASEBOARD_FAB2(SCH_1):P1V2_AUX_BMC    I69 @BASEBOARD_FAB2_LIB.BASEBOARD_FAB2(SCH_1):PAGE149
     2    GND @BASEBOARD_FAB2_LIB.BASEBOARD_FAB2(SCH_1):GND    I69 @BASEBOARD_FAB2_LIB.BASEBOARD_FAB2(SCH_1):PAGE149

C25W20 CAP_A_0402V-0.1UF,16V,10%,EMPTA
     1 P2E_SSB_BMC_RX_DP @BASEBOARD_FAB2_LIB.BASEBOARD_FAB2(SCH_1):P2E_SSB_BMC_RX_DP    I45 @BASEBOARD_FAB2_LIB.BASEBOARD_FAB2(SCH_1):PAGE145
     2 P2E_SSB_BMC_RX_C_DP @BASEBOARD_FAB2_LIB.BASEBOARD_FAB2(SCH_1):P2E_SSB_BMC_RX_C_DP    I45 @BASEBOARD_FAB2_LIB.BASEBOARD_FAB2(SCH_1):PAGE145

C25W21 CAP_A_0402V-0.1UF,16V,10%,EMPTA
     1 P2E_SSB_BMC_RX_DN @BASEBOARD_FAB2_LIB.BASEBOARD_FAB2(SCH_1):P2E_SSB_BMC_RX_DN    I44 @BASEBOARD_FAB2_LIB.BASEBOARD_FAB2(SCH_1):PAGE145
     2 P2E_SSB_BMC_RX_C_DN @BASEBOARD_FAB2_LIB.BASEBOARD_FAB2(SCH_1):P2E_SSB_BMC_RX_C_DN    I44 @BASEBOARD_FAB2_LIB.BASEBOARD_FAB2(SCH_1):PAGE145

C25W22 CAP_0402LF-0.1UF,16V,10%,X7R,AA
     1 BMC_M_VREFCA @BASEBOARD_FAB2_LIB.BASEBOARD_FAB2(SCH_1):BMC_M_VREFCA    I55 @BASEBOARD_FAB2_LIB.BASEBOARD_FAB2(SCH_1):PAGE143
     2    GND @BASEBOARD_FAB2_LIB.BASEBOARD_FAB2(SCH_1):GND    I55 @BASEBOARD_FAB2_LIB.BASEBOARD_FAB2(SCH_1):PAGE143

C25W23 CAP_0402-1.0UF,6.3V,10%,X6S,D9A
     1 P1V15_AUX_BMC @BASEBOARD_FAB2_LIB.BASEBOARD_FAB2(SCH_1):P1V15_AUX_BMC    I75 @BASEBOARD_FAB2_LIB.BASEBOARD_FAB2(SCH_1):PAGE150
     2    GND @BASEBOARD_FAB2_LIB.BASEBOARD_FAB2(SCH_1):GND    I75 @BASEBOARD_FAB2_LIB.BASEBOARD_FAB2(SCH_1):PAGE150

C25W24 CAP_0402-1.0UF,6.3V,10%,X6S,D9A
     1 P1V15_AUX_BMC @BASEBOARD_FAB2_LIB.BASEBOARD_FAB2(SCH_1):P1V15_AUX_BMC    I73 @BASEBOARD_FAB2_LIB.BASEBOARD_FAB2(SCH_1):PAGE150
     2    GND @BASEBOARD_FAB2_LIB.BASEBOARD_FAB2(SCH_1):GND    I73 @BASEBOARD_FAB2_LIB.BASEBOARD_FAB2(SCH_1):PAGE150

C25W25 CAP_0402-1.0UF,6.3V,10%,X6S,D9A
     1 P1V15_AUX_BMC @BASEBOARD_FAB2_LIB.BASEBOARD_FAB2(SCH_1):P1V15_AUX_BMC    I72 @BASEBOARD_FAB2_LIB.BASEBOARD_FAB2(SCH_1):PAGE150
     2    GND @BASEBOARD_FAB2_LIB.BASEBOARD_FAB2(SCH_1):GND    I72 @BASEBOARD_FAB2_LIB.BASEBOARD_FAB2(SCH_1):PAGE150

C25W26 CAP_0402-1.0UF,6.3V,10%,X6S,D9A
     1 P1V15_AUX_BMC @BASEBOARD_FAB2_LIB.BASEBOARD_FAB2(SCH_1):P1V15_AUX_BMC    I71 @BASEBOARD_FAB2_LIB.BASEBOARD_FAB2(SCH_1):PAGE150
     2    GND @BASEBOARD_FAB2_LIB.BASEBOARD_FAB2(SCH_1):GND    I71 @BASEBOARD_FAB2_LIB.BASEBOARD_FAB2(SCH_1):PAGE150

C25W27 CAP_0402-1.0UF,6.3V,10%,X6S,D9A
     1 P1V15_AUX_BMC @BASEBOARD_FAB2_LIB.BASEBOARD_FAB2(SCH_1):P1V15_AUX_BMC    I48 @BASEBOARD_FAB2_LIB.BASEBOARD_FAB2(SCH_1):PAGE150
     2    GND @BASEBOARD_FAB2_LIB.BASEBOARD_FAB2(SCH_1):GND    I48 @BASEBOARD_FAB2_LIB.BASEBOARD_FAB2(SCH_1):PAGE150

C25W28 CAP_0402-1.0UF,6.3V,10%,X6S,D9A
     1 P1V15_AUX_BMC @BASEBOARD_FAB2_LIB.BASEBOARD_FAB2(SCH_1):P1V15_AUX_BMC    I46 @BASEBOARD_FAB2_LIB.BASEBOARD_FAB2(SCH_1):PAGE150
     2    GND @BASEBOARD_FAB2_LIB.BASEBOARD_FAB2(SCH_1):GND    I46 @BASEBOARD_FAB2_LIB.BASEBOARD_FAB2(SCH_1):PAGE150

C25W29 CAP_0805-10UF,16V,10%,X6S,C953A
     1 P1V15_AUX_BMC @BASEBOARD_FAB2_LIB.BASEBOARD_FAB2(SCH_1):P1V15_AUX_BMC    I45 @BASEBOARD_FAB2_LIB.BASEBOARD_FAB2(SCH_1):PAGE150
     2    GND @BASEBOARD_FAB2_LIB.BASEBOARD_FAB2(SCH_1):GND    I45 @BASEBOARD_FAB2_LIB.BASEBOARD_FAB2(SCH_1):PAGE150

C25W30 SC4D7U10V3KX-GP_SMD-BCG-SC4D7UA
     1 P1V15_AUX_BMC @BASEBOARD_FAB2_LIB.BASEBOARD_FAB2(SCH_1):P1V15_AUX_BMC    I43 @BASEBOARD_FAB2_LIB.BASEBOARD_FAB2(SCH_1):PAGE150
     2    GND @BASEBOARD_FAB2_LIB.BASEBOARD_FAB2(SCH_1):GND    I43 @BASEBOARD_FAB2_LIB.BASEBOARD_FAB2(SCH_1):PAGE150

C25W31 SCD1U16V2KX-3GP_SMD-BCG-SCD1U1A
     1 VCC_ADCAV3V3 @BASEBOARD_FAB2_LIB.BASEBOARD_FAB2(SCH_1):VCC_ADCAV3V3    I79 @BASEBOARD_FAB2_LIB.BASEBOARD_FAB2(SCH_1):PAGE150
     2    GND @BASEBOARD_FAB2_LIB.BASEBOARD_FAB2(SCH_1):GND    I79 @BASEBOARD_FAB2_LIB.BASEBOARD_FAB2(SCH_1):PAGE150

C25W32 CAP_0402-1.0UF,6.3V,10%,X6S,D9A
     1 VCC_ADCAV3V3 @BASEBOARD_FAB2_LIB.BASEBOARD_FAB2(SCH_1):VCC_ADCAV3V3    I78 @BASEBOARD_FAB2_LIB.BASEBOARD_FAB2(SCH_1):PAGE150
     2    GND @BASEBOARD_FAB2_LIB.BASEBOARD_FAB2(SCH_1):GND    I78 @BASEBOARD_FAB2_LIB.BASEBOARD_FAB2(SCH_1):PAGE150

C25W33 CAP_0402-1.0UF,6.3V,10%,X6S,D9A
     1 VCC_ADCAV3V3 @BASEBOARD_FAB2_LIB.BASEBOARD_FAB2(SCH_1):VCC_ADCAV3V3    I59 @BASEBOARD_FAB2_LIB.BASEBOARD_FAB2(SCH_1):PAGE150
     2    GND @BASEBOARD_FAB2_LIB.BASEBOARD_FAB2(SCH_1):GND    I59 @BASEBOARD_FAB2_LIB.BASEBOARD_FAB2(SCH_1):PAGE150

C25W34 SCD1U16V2KX-3GP_SMD-BCG-SCD1U1A
     1 VCC_DACAV3V3 @BASEBOARD_FAB2_LIB.BASEBOARD_FAB2(SCH_1):VCC_DACAV3V3    I53 @BASEBOARD_FAB2_LIB.BASEBOARD_FAB2(SCH_1):PAGE150
     2    GND @BASEBOARD_FAB2_LIB.BASEBOARD_FAB2(SCH_1):GND    I53 @BASEBOARD_FAB2_LIB.BASEBOARD_FAB2(SCH_1):PAGE150

C25W35 CAP_0402-1.0UF,6.3V,10%,X6S,D9A
     1 VCC_DACAV3V3 @BASEBOARD_FAB2_LIB.BASEBOARD_FAB2(SCH_1):VCC_DACAV3V3    I51 @BASEBOARD_FAB2_LIB.BASEBOARD_FAB2(SCH_1):PAGE150
     2    GND @BASEBOARD_FAB2_LIB.BASEBOARD_FAB2(SCH_1):GND    I51 @BASEBOARD_FAB2_LIB.BASEBOARD_FAB2(SCH_1):PAGE150

C25W36 SC4D7U10V3KX-GP_SMD-BCG-SC4D7UA
     1 VCC_DACAV3V3 @BASEBOARD_FAB2_LIB.BASEBOARD_FAB2(SCH_1):VCC_DACAV3V3    I50 @BASEBOARD_FAB2_LIB.BASEBOARD_FAB2(SCH_1):PAGE150
     2    GND @BASEBOARD_FAB2_LIB.BASEBOARD_FAB2(SCH_1):GND    I50 @BASEBOARD_FAB2_LIB.BASEBOARD_FAB2(SCH_1):PAGE150

C25W37 CAP_0402-1.0UF,6.3V,10%,X6S,D9A
     1 VCC_A_1V1 @BASEBOARD_FAB2_LIB.BASEBOARD_FAB2(SCH_1):VCC_A_1V1    I35 @BASEBOARD_FAB2_LIB.BASEBOARD_FAB2(SCH_1):PAGE150
     2    GND @BASEBOARD_FAB2_LIB.BASEBOARD_FAB2(SCH_1):GND    I35 @BASEBOARD_FAB2_LIB.BASEBOARD_FAB2(SCH_1):PAGE150

C25W38 SCD1U16V2KX-3GP_SMD-BCG-SCD1U1A
     1 VCC_A_1V1 @BASEBOARD_FAB2_LIB.BASEBOARD_FAB2(SCH_1):VCC_A_1V1    I18 @BASEBOARD_FAB2_LIB.BASEBOARD_FAB2(SCH_1):PAGE150
     2    GND @BASEBOARD_FAB2_LIB.BASEBOARD_FAB2(SCH_1):GND    I18 @BASEBOARD_FAB2_LIB.BASEBOARD_FAB2(SCH_1):PAGE150

C25W39 SC4D7U10V3KX-GP_SMD-BCG-SC4D7UA
     1 VCC_A_1V1 @BASEBOARD_FAB2_LIB.BASEBOARD_FAB2(SCH_1):VCC_A_1V1    I17 @BASEBOARD_FAB2_LIB.BASEBOARD_FAB2(SCH_1):PAGE150
     2    GND @BASEBOARD_FAB2_LIB.BASEBOARD_FAB2(SCH_1):GND    I17 @BASEBOARD_FAB2_LIB.BASEBOARD_FAB2(SCH_1):PAGE150

C25W40 CAP_0402-1.0UF,6.3V,10%,X6S,D9A
     1 VCC_D_3V3 @BASEBOARD_FAB2_LIB.BASEBOARD_FAB2(SCH_1):VCC_D_3V3    I82 @BASEBOARD_FAB2_LIB.BASEBOARD_FAB2(SCH_1):PAGE150
     2    GND @BASEBOARD_FAB2_LIB.BASEBOARD_FAB2(SCH_1):GND    I82 @BASEBOARD_FAB2_LIB.BASEBOARD_FAB2(SCH_1):PAGE150

C25W41 CAP_0402-1.0UF,6.3V,10%,X6S,D9A
     1 VCC_D_3V3 @BASEBOARD_FAB2_LIB.BASEBOARD_FAB2(SCH_1):VCC_D_3V3    I81 @BASEBOARD_FAB2_LIB.BASEBOARD_FAB2(SCH_1):PAGE150
     2    GND @BASEBOARD_FAB2_LIB.BASEBOARD_FAB2(SCH_1):GND    I81 @BASEBOARD_FAB2_LIB.BASEBOARD_FAB2(SCH_1):PAGE150

C25W42 CAP_0402-1.0UF,6.3V,10%,X6S,D9A
     1 VCC_D_3V3 @BASEBOARD_FAB2_LIB.BASEBOARD_FAB2(SCH_1):VCC_D_3V3    I80 @BASEBOARD_FAB2_LIB.BASEBOARD_FAB2(SCH_1):PAGE150
     2    GND @BASEBOARD_FAB2_LIB.BASEBOARD_FAB2(SCH_1):GND    I80 @BASEBOARD_FAB2_LIB.BASEBOARD_FAB2(SCH_1):PAGE150

C25W43 CAP_0402-1.0UF,6.3V,10%,X6S,D9A
     1 VCC_D_3V3 @BASEBOARD_FAB2_LIB.BASEBOARD_FAB2(SCH_1):VCC_D_3V3    I63 @BASEBOARD_FAB2_LIB.BASEBOARD_FAB2(SCH_1):PAGE150
     2    GND @BASEBOARD_FAB2_LIB.BASEBOARD_FAB2(SCH_1):GND    I63 @BASEBOARD_FAB2_LIB.BASEBOARD_FAB2(SCH_1):PAGE150

C25W44 CAP_0402-1.0UF,6.3V,10%,X6S,D9A
     1 VCC_D_3V3 @BASEBOARD_FAB2_LIB.BASEBOARD_FAB2(SCH_1):VCC_D_3V3    I62 @BASEBOARD_FAB2_LIB.BASEBOARD_FAB2(SCH_1):PAGE150
     2    GND @BASEBOARD_FAB2_LIB.BASEBOARD_FAB2(SCH_1):GND    I62 @BASEBOARD_FAB2_LIB.BASEBOARD_FAB2(SCH_1):PAGE150

C25W45 SCD1U16V2KX-3GP_SMD-BCG-SCD1U1A
     1 VCC_D_3V3 @BASEBOARD_FAB2_LIB.BASEBOARD_FAB2(SCH_1):VCC_D_3V3    I61 @BASEBOARD_FAB2_LIB.BASEBOARD_FAB2(SCH_1):PAGE150
     2    GND @BASEBOARD_FAB2_LIB.BASEBOARD_FAB2(SCH_1):GND    I61 @BASEBOARD_FAB2_LIB.BASEBOARD_FAB2(SCH_1):PAGE150

C25W46 CAP_0805-10UF,16V,10%,X6S,C953A
     1 VCC_D_3V3 @BASEBOARD_FAB2_LIB.BASEBOARD_FAB2(SCH_1):VCC_D_3V3    I55 @BASEBOARD_FAB2_LIB.BASEBOARD_FAB2(SCH_1):PAGE150
     2    GND @BASEBOARD_FAB2_LIB.BASEBOARD_FAB2(SCH_1):GND    I55 @BASEBOARD_FAB2_LIB.BASEBOARD_FAB2(SCH_1):PAGE150

C25W47 SC4D7U10V3KX-GP_SMD-BCG-SC4D7UA
     1 VCC_D_3V3 @BASEBOARD_FAB2_LIB.BASEBOARD_FAB2(SCH_1):VCC_D_3V3    I54 @BASEBOARD_FAB2_LIB.BASEBOARD_FAB2(SCH_1):PAGE150
     2    GND @BASEBOARD_FAB2_LIB.BASEBOARD_FAB2(SCH_1):GND    I54 @BASEBOARD_FAB2_LIB.BASEBOARD_FAB2(SCH_1):PAGE150

C25W48 CAP_0402-1.0UF,6.3V,10%,X6S,D9A
     1 P3V3_STBY @BASEBOARD_FAB2_LIB.BASEBOARD_FAB2(SCH_1):P3V3_STBY    I38 @BASEBOARD_FAB2_LIB.BASEBOARD_FAB2(SCH_1):PAGE150
     2    GND @BASEBOARD_FAB2_LIB.BASEBOARD_FAB2(SCH_1):GND    I38 @BASEBOARD_FAB2_LIB.BASEBOARD_FAB2(SCH_1):PAGE150

C25W49 SCD1U16V2KX-3GP_SMD-BCG-SCD1U1A
     1 P3V3_STBY @BASEBOARD_FAB2_LIB.BASEBOARD_FAB2(SCH_1):P3V3_STBY    I36 @BASEBOARD_FAB2_LIB.BASEBOARD_FAB2(SCH_1):PAGE150
     2    GND @BASEBOARD_FAB2_LIB.BASEBOARD_FAB2(SCH_1):GND    I36 @BASEBOARD_FAB2_LIB.BASEBOARD_FAB2(SCH_1):PAGE150

C25W50 SC4D7U10V3KX-GP_SMD-BCG-SC4D7UA
     1 P3V3_STBY @BASEBOARD_FAB2_LIB.BASEBOARD_FAB2(SCH_1):P3V3_STBY    I21 @BASEBOARD_FAB2_LIB.BASEBOARD_FAB2(SCH_1):PAGE150
     2    GND @BASEBOARD_FAB2_LIB.BASEBOARD_FAB2(SCH_1):GND    I21 @BASEBOARD_FAB2_LIB.BASEBOARD_FAB2(SCH_1):PAGE150

C25W51 CAP_0402-1.0UF,6.3V,10%,X6S,D9A
     1 P1V2_AUX_BMC @BASEBOARD_FAB2_LIB.BASEBOARD_FAB2(SCH_1):P1V2_AUX_BMC    I19 @BASEBOARD_FAB2_LIB.BASEBOARD_FAB2(SCH_1):PAGE150
     2    GND @BASEBOARD_FAB2_LIB.BASEBOARD_FAB2(SCH_1):GND    I19 @BASEBOARD_FAB2_LIB.BASEBOARD_FAB2(SCH_1):PAGE150

C25W52 CAP_0402-1.0UF,6.3V,10%,X6S,D9A
     1 P1V2_AUX_BMC @BASEBOARD_FAB2_LIB.BASEBOARD_FAB2(SCH_1):P1V2_AUX_BMC    I14 @BASEBOARD_FAB2_LIB.BASEBOARD_FAB2(SCH_1):PAGE150
     2    GND @BASEBOARD_FAB2_LIB.BASEBOARD_FAB2(SCH_1):GND    I14 @BASEBOARD_FAB2_LIB.BASEBOARD_FAB2(SCH_1):PAGE150

C25W53 CAP_0402-1.0UF,6.3V,10%,X6S,D9A
     1 P1V2_AUX_BMC @BASEBOARD_FAB2_LIB.BASEBOARD_FAB2(SCH_1):P1V2_AUX_BMC    I13 @BASEBOARD_FAB2_LIB.BASEBOARD_FAB2(SCH_1):PAGE150
     2    GND @BASEBOARD_FAB2_LIB.BASEBOARD_FAB2(SCH_1):GND    I13 @BASEBOARD_FAB2_LIB.BASEBOARD_FAB2(SCH_1):PAGE150

C25W54 CAP_0402-1.0UF,6.3V,10%,X6S,D9A
     1 P1V2_AUX_BMC @BASEBOARD_FAB2_LIB.BASEBOARD_FAB2(SCH_1):P1V2_AUX_BMC    I12 @BASEBOARD_FAB2_LIB.BASEBOARD_FAB2(SCH_1):PAGE150
     2    GND @BASEBOARD_FAB2_LIB.BASEBOARD_FAB2(SCH_1):GND    I12 @BASEBOARD_FAB2_LIB.BASEBOARD_FAB2(SCH_1):PAGE150

C25W55 SCD1U16V2KX-3GP_SMD-BCG-SCD1U1A
     1 P1V2_AUX_BMC @BASEBOARD_FAB2_LIB.BASEBOARD_FAB2(SCH_1):P1V2_AUX_BMC    I10 @BASEBOARD_FAB2_LIB.BASEBOARD_FAB2(SCH_1):PAGE150
     2    GND @BASEBOARD_FAB2_LIB.BASEBOARD_FAB2(SCH_1):GND    I10 @BASEBOARD_FAB2_LIB.BASEBOARD_FAB2(SCH_1):PAGE150

C25W56 CAP_0402-1.0UF,6.3V,10%,X6S,D9A
     1 VCC_PA_3V3 @BASEBOARD_FAB2_LIB.BASEBOARD_FAB2(SCH_1):VCC_PA_3V3    I87 @BASEBOARD_FAB2_LIB.BASEBOARD_FAB2(SCH_1):PAGE150
     2    GND @BASEBOARD_FAB2_LIB.BASEBOARD_FAB2(SCH_1):GND    I87 @BASEBOARD_FAB2_LIB.BASEBOARD_FAB2(SCH_1):PAGE150

C25W57 CAP_0402-1.0UF,6.3V,10%,X6S,D9A
     1 VCC_PA_3V3 @BASEBOARD_FAB2_LIB.BASEBOARD_FAB2(SCH_1):VCC_PA_3V3    I86 @BASEBOARD_FAB2_LIB.BASEBOARD_FAB2(SCH_1):PAGE150
     2    GND @BASEBOARD_FAB2_LIB.BASEBOARD_FAB2(SCH_1):GND    I86 @BASEBOARD_FAB2_LIB.BASEBOARD_FAB2(SCH_1):PAGE150

C25W58 SCD1U16V2KX-3GP_SMD-BCG-SCD1U1A
     1 VCC_PA_3V3 @BASEBOARD_FAB2_LIB.BASEBOARD_FAB2(SCH_1):VCC_PA_3V3    I85 @BASEBOARD_FAB2_LIB.BASEBOARD_FAB2(SCH_1):PAGE150
     2    GND @BASEBOARD_FAB2_LIB.BASEBOARD_FAB2(SCH_1):GND    I85 @BASEBOARD_FAB2_LIB.BASEBOARD_FAB2(SCH_1):PAGE150

C25W59 SC4D7U10V3KX-GP_SMD-BCG-SC4D7UA
     1 VCC_PA_3V3 @BASEBOARD_FAB2_LIB.BASEBOARD_FAB2(SCH_1):VCC_PA_3V3    I69 @BASEBOARD_FAB2_LIB.BASEBOARD_FAB2(SCH_1):PAGE150
     2    GND @BASEBOARD_FAB2_LIB.BASEBOARD_FAB2(SCH_1):GND    I69 @BASEBOARD_FAB2_LIB.BASEBOARD_FAB2(SCH_1):PAGE150

C25W60 CAP_0402-1.0UF,6.3V,10%,X6S,D9A
     1 P3V3_STBY @BASEBOARD_FAB2_LIB.BASEBOARD_FAB2(SCH_1):P3V3_STBY     I1 @BASEBOARD_FAB2_LIB.BASEBOARD_FAB2(SCH_1):PAGE150
     2    GND @BASEBOARD_FAB2_LIB.BASEBOARD_FAB2(SCH_1):GND     I1 @BASEBOARD_FAB2_LIB.BASEBOARD_FAB2(SCH_1):PAGE150

C25W61 SCD1U16V2KX-3GP_SMD-BCG-SCD1U1A
     1 P3V3_STBY @BASEBOARD_FAB2_LIB.BASEBOARD_FAB2(SCH_1):P3V3_STBY    I67 @BASEBOARD_FAB2_LIB.BASEBOARD_FAB2(SCH_1):PAGE150
     2    GND @BASEBOARD_FAB2_LIB.BASEBOARD_FAB2(SCH_1):GND    I67 @BASEBOARD_FAB2_LIB.BASEBOARD_FAB2(SCH_1):PAGE150

C25W62 SC4D7U10V3KX-GP_SMD-BCG-SC4D7UA
     1 P3V3_STBY @BASEBOARD_FAB2_LIB.BASEBOARD_FAB2(SCH_1):P3V3_STBY    I65 @BASEBOARD_FAB2_LIB.BASEBOARD_FAB2(SCH_1):PAGE150
     2    GND @BASEBOARD_FAB2_LIB.BASEBOARD_FAB2(SCH_1):GND    I65 @BASEBOARD_FAB2_LIB.BASEBOARD_FAB2(SCH_1):PAGE150

C25W63 CAP_0402-1.0UF,6.3V,10%,X6S,D9A
     1 VCC_D_PLL_3V3 @BASEBOARD_FAB2_LIB.BASEBOARD_FAB2(SCH_1):VCC_D_PLL_3V3    I25 @BASEBOARD_FAB2_LIB.BASEBOARD_FAB2(SCH_1):PAGE150
     2    GND @BASEBOARD_FAB2_LIB.BASEBOARD_FAB2(SCH_1):GND    I25 @BASEBOARD_FAB2_LIB.BASEBOARD_FAB2(SCH_1):PAGE150

C25W64 SCD1U16V2KX-3GP_SMD-BCG-SCD1U1A
     1 VCC_D_PLL_3V3 @BASEBOARD_FAB2_LIB.BASEBOARD_FAB2(SCH_1):VCC_D_PLL_3V3    I24 @BASEBOARD_FAB2_LIB.BASEBOARD_FAB2(SCH_1):PAGE150
     2    GND @BASEBOARD_FAB2_LIB.BASEBOARD_FAB2(SCH_1):GND    I24 @BASEBOARD_FAB2_LIB.BASEBOARD_FAB2(SCH_1):PAGE150

C25W65 SC4D7U10V3KX-GP_SMD-BCG-SC4D7UA
     1 VCC_D_PLL_3V3 @BASEBOARD_FAB2_LIB.BASEBOARD_FAB2(SCH_1):VCC_D_PLL_3V3     I2 @BASEBOARD_FAB2_LIB.BASEBOARD_FAB2(SCH_1):PAGE150
     2    GND @BASEBOARD_FAB2_LIB.BASEBOARD_FAB2(SCH_1):GND     I2 @BASEBOARD_FAB2_LIB.BASEBOARD_FAB2(SCH_1):PAGE150

C25W66 CAP_0402-1.0UF,6.3V,10%,X6S,D9A
     1 VCC_VA_3V3 @BASEBOARD_FAB2_LIB.BASEBOARD_FAB2(SCH_1):VCC_VA_3V3    I33 @BASEBOARD_FAB2_LIB.BASEBOARD_FAB2(SCH_1):PAGE150
     2    GND @BASEBOARD_FAB2_LIB.BASEBOARD_FAB2(SCH_1):GND    I33 @BASEBOARD_FAB2_LIB.BASEBOARD_FAB2(SCH_1):PAGE150

C25W67 CAP_0402-1.0UF,6.3V,10%,X6S,D9A
     1 VCC_VA_3V3 @BASEBOARD_FAB2_LIB.BASEBOARD_FAB2(SCH_1):VCC_VA_3V3    I31 @BASEBOARD_FAB2_LIB.BASEBOARD_FAB2(SCH_1):PAGE150
     2    GND @BASEBOARD_FAB2_LIB.BASEBOARD_FAB2(SCH_1):GND    I31 @BASEBOARD_FAB2_LIB.BASEBOARD_FAB2(SCH_1):PAGE150

C25W68 SCD1U16V2KX-3GP_SMD-BCG-SCD1U1A
     1 VCC_VA_3V3 @BASEBOARD_FAB2_LIB.BASEBOARD_FAB2(SCH_1):VCC_VA_3V3    I30 @BASEBOARD_FAB2_LIB.BASEBOARD_FAB2(SCH_1):PAGE150
     2    GND @BASEBOARD_FAB2_LIB.BASEBOARD_FAB2(SCH_1):GND    I30 @BASEBOARD_FAB2_LIB.BASEBOARD_FAB2(SCH_1):PAGE150

C25W69 SC4D7U10V3KX-GP_SMD-BCG-SC4D7UA
     1 VCC_VA_3V3 @BASEBOARD_FAB2_LIB.BASEBOARD_FAB2(SCH_1):VCC_VA_3V3    I28 @BASEBOARD_FAB2_LIB.BASEBOARD_FAB2(SCH_1):PAGE150
     2    GND @BASEBOARD_FAB2_LIB.BASEBOARD_FAB2(SCH_1):GND    I28 @BASEBOARD_FAB2_LIB.BASEBOARD_FAB2(SCH_1):PAGE150

C25W70 SC4D7U10V3KX-GP_SMD-BCG-SC4D7UA
     1 P3V3_USB2A_ALG @BASEBOARD_FAB2_LIB.BASEBOARD_FAB2(SCH_1):P3V3_USB2A_ALG     I6 @BASEBOARD_FAB2_LIB.BASEBOARD_FAB2(SCH_1):PAGE150
     2    GND @BASEBOARD_FAB2_LIB.BASEBOARD_FAB2(SCH_1):GND     I6 @BASEBOARD_FAB2_LIB.BASEBOARD_FAB2(SCH_1):PAGE150

C25W71 CAP_0402-1.0UF,6.3V,10%,X6S,D9A
     1 P3V3_USB2A_ALG @BASEBOARD_FAB2_LIB.BASEBOARD_FAB2(SCH_1):P3V3_USB2A_ALG     I4 @BASEBOARD_FAB2_LIB.BASEBOARD_FAB2(SCH_1):PAGE150
     2    GND @BASEBOARD_FAB2_LIB.BASEBOARD_FAB2(SCH_1):GND     I4 @BASEBOARD_FAB2_LIB.BASEBOARD_FAB2(SCH_1):PAGE150

C826 CAP_0402-0.22UF,16V,10%,X7R,A3A
     1 P3E_CPU0_PE1_PCH_TXN<14> @BASEBOARD_FAB2_LIB.BASEBOARD_FAB2(SCH_1):P3E_CPU0_PE1_PCH_TXN(14)    I24 @BASEBOARD_FAB2_LIB.BASEBOARD_FAB2(SCH_1):PAGE244
     2 P3E_CPU0_PE1_PCH_CON_TXN<14> @BASEBOARD_FAB2_LIB.BASEBOARD_FAB2(SCH_1):P3E_CPU0_PE1_PCH_CON_TXN(14)    I24 @BASEBOARD_FAB2_LIB.BASEBOARD_FAB2(SCH_1):PAGE244

C827 CAP_0402-0.22UF,16V,10%,X7R,A3A
     1 P3E_CPU0_PE1_PCH_TXP<14> @BASEBOARD_FAB2_LIB.BASEBOARD_FAB2(SCH_1):P3E_CPU0_PE1_PCH_TXP(14)    I12 @BASEBOARD_FAB2_LIB.BASEBOARD_FAB2(SCH_1):PAGE244
     2 P3E_CPU0_PE1_PCH_CON_TXP<14> @BASEBOARD_FAB2_LIB.BASEBOARD_FAB2(SCH_1):P3E_CPU0_PE1_PCH_CON_TXP(14)    I12 @BASEBOARD_FAB2_LIB.BASEBOARD_FAB2(SCH_1):PAGE244

C828 CAP_0402-0.22UF,16V,10%,X7R,A3A
     1 P3E_CPU0_PE1_PCH_TXN<13> @BASEBOARD_FAB2_LIB.BASEBOARD_FAB2(SCH_1):P3E_CPU0_PE1_PCH_TXN(13)    I28 @BASEBOARD_FAB2_LIB.BASEBOARD_FAB2(SCH_1):PAGE244
     2 P3E_CPU0_PE1_PCH_CON_TXN<13> @BASEBOARD_FAB2_LIB.BASEBOARD_FAB2(SCH_1):P3E_CPU0_PE1_PCH_CON_TXN(13)    I28 @BASEBOARD_FAB2_LIB.BASEBOARD_FAB2(SCH_1):PAGE244

C829 CAP_0402-0.22UF,16V,10%,X7R,A3A
     1 P3E_CPU0_PE1_PCH_TXP<13> @BASEBOARD_FAB2_LIB.BASEBOARD_FAB2(SCH_1):P3E_CPU0_PE1_PCH_TXP(13)     I5 @BASEBOARD_FAB2_LIB.BASEBOARD_FAB2(SCH_1):PAGE244
     2 P3E_CPU0_PE1_PCH_CON_TXP<13> @BASEBOARD_FAB2_LIB.BASEBOARD_FAB2(SCH_1):P3E_CPU0_PE1_PCH_CON_TXP(13)     I5 @BASEBOARD_FAB2_LIB.BASEBOARD_FAB2(SCH_1):PAGE244

C830 CAP_0402-0.22UF,16V,10%,X7R,A3A
     1 P3E_CPU0_PE1_PCH_TXN<15> @BASEBOARD_FAB2_LIB.BASEBOARD_FAB2(SCH_1):P3E_CPU0_PE1_PCH_TXN(15)    I23 @BASEBOARD_FAB2_LIB.BASEBOARD_FAB2(SCH_1):PAGE244
     2 P3E_CPU0_PE1_PCH_CON_TXN<15> @BASEBOARD_FAB2_LIB.BASEBOARD_FAB2(SCH_1):P3E_CPU0_PE1_PCH_CON_TXN(15)    I23 @BASEBOARD_FAB2_LIB.BASEBOARD_FAB2(SCH_1):PAGE244

C831 CAP_0402-0.22UF,16V,10%,X7R,A3A
     1 P3E_CPU0_PE1_PCH_TXP<15> @BASEBOARD_FAB2_LIB.BASEBOARD_FAB2(SCH_1):P3E_CPU0_PE1_PCH_TXP(15)     I2 @BASEBOARD_FAB2_LIB.BASEBOARD_FAB2(SCH_1):PAGE244
     2 P3E_CPU0_PE1_PCH_CON_TXP<15> @BASEBOARD_FAB2_LIB.BASEBOARD_FAB2(SCH_1):P3E_CPU0_PE1_PCH_CON_TXP(15)     I2 @BASEBOARD_FAB2_LIB.BASEBOARD_FAB2(SCH_1):PAGE244

C832 CAP_0402-0.22UF,16V,10%,X7R,A3A
     1 P3E_CPU0_PE1_PCH_TXN<11> @BASEBOARD_FAB2_LIB.BASEBOARD_FAB2(SCH_1):P3E_CPU0_PE1_PCH_TXN(11)    I30 @BASEBOARD_FAB2_LIB.BASEBOARD_FAB2(SCH_1):PAGE244
     2 P3E_CPU0_PE1_PCH_CON_TXN<11> @BASEBOARD_FAB2_LIB.BASEBOARD_FAB2(SCH_1):P3E_CPU0_PE1_PCH_CON_TXN(11)    I30 @BASEBOARD_FAB2_LIB.BASEBOARD_FAB2(SCH_1):PAGE244

C833 CAP_0402-0.22UF,16V,10%,X7R,A3A
     1 P3E_CPU0_PE1_PCH_TXP<11> @BASEBOARD_FAB2_LIB.BASEBOARD_FAB2(SCH_1):P3E_CPU0_PE1_PCH_TXP(11)     I8 @BASEBOARD_FAB2_LIB.BASEBOARD_FAB2(SCH_1):PAGE244
     2 P3E_CPU0_PE1_PCH_CON_TXP<11> @BASEBOARD_FAB2_LIB.BASEBOARD_FAB2(SCH_1):P3E_CPU0_PE1_PCH_CON_TXP(11)     I8 @BASEBOARD_FAB2_LIB.BASEBOARD_FAB2(SCH_1):PAGE244

C834 CAP_0402-0.22UF,16V,10%,X7R,A3A
     1 P3E_CPU0_PE1_PCH_TXN<10> @BASEBOARD_FAB2_LIB.BASEBOARD_FAB2(SCH_1):P3E_CPU0_PE1_PCH_TXN(10)    I50 @BASEBOARD_FAB2_LIB.BASEBOARD_FAB2(SCH_1):PAGE244
     2 P3E_CPU0_PE1_PCH_CON_TXN<10> @BASEBOARD_FAB2_LIB.BASEBOARD_FAB2(SCH_1):P3E_CPU0_PE1_PCH_CON_TXN(10)    I50 @BASEBOARD_FAB2_LIB.BASEBOARD_FAB2(SCH_1):PAGE244

C835 CAP_0402-0.22UF,16V,10%,X7R,A3A
     1 P3E_CPU0_PE1_PCH_TXP<10> @BASEBOARD_FAB2_LIB.BASEBOARD_FAB2(SCH_1):P3E_CPU0_PE1_PCH_TXP(10)    I41 @BASEBOARD_FAB2_LIB.BASEBOARD_FAB2(SCH_1):PAGE244
     2 P3E_CPU0_PE1_PCH_CON_TXP<10> @BASEBOARD_FAB2_LIB.BASEBOARD_FAB2(SCH_1):P3E_CPU0_PE1_PCH_CON_TXP(10)    I41 @BASEBOARD_FAB2_LIB.BASEBOARD_FAB2(SCH_1):PAGE244

C840 CAP_0402-0.22UF,16V,10%,X7R,A3A
     1 P3E_CPU0_PE1_PCH_TXN<12> @BASEBOARD_FAB2_LIB.BASEBOARD_FAB2(SCH_1):P3E_CPU0_PE1_PCH_TXN(12)    I29 @BASEBOARD_FAB2_LIB.BASEBOARD_FAB2(SCH_1):PAGE244
     2 P3E_CPU0_PE1_PCH_CON_TXN<12> @BASEBOARD_FAB2_LIB.BASEBOARD_FAB2(SCH_1):P3E_CPU0_PE1_PCH_CON_TXN(12)    I29 @BASEBOARD_FAB2_LIB.BASEBOARD_FAB2(SCH_1):PAGE244

C841 CAP_0402-0.22UF,16V,10%,X7R,A3A
     1 P3E_CPU0_PE1_PCH_TXP<12> @BASEBOARD_FAB2_LIB.BASEBOARD_FAB2(SCH_1):P3E_CPU0_PE1_PCH_TXP(12)    I17 @BASEBOARD_FAB2_LIB.BASEBOARD_FAB2(SCH_1):PAGE244
     2 P3E_CPU0_PE1_PCH_CON_TXP<12> @BASEBOARD_FAB2_LIB.BASEBOARD_FAB2(SCH_1):P3E_CPU0_PE1_PCH_CON_TXP(12)    I17 @BASEBOARD_FAB2_LIB.BASEBOARD_FAB2(SCH_1):PAGE244

C842 CAP_0402-0.22UF,16V,10%,X7R,A3A
     1 P3E_CPU0_PE1_PCH_TXN<8> @BASEBOARD_FAB2_LIB.BASEBOARD_FAB2(SCH_1):P3E_CPU0_PE1_PCH_TXN(8)    I52 @BASEBOARD_FAB2_LIB.BASEBOARD_FAB2(SCH_1):PAGE244
     2 P3E_CPU0_PE1_PCH_CON_TXN<8> @BASEBOARD_FAB2_LIB.BASEBOARD_FAB2(SCH_1):P3E_CPU0_PE1_PCH_CON_TXN(8)    I52 @BASEBOARD_FAB2_LIB.BASEBOARD_FAB2(SCH_1):PAGE244

C843 CAP_0402-0.22UF,16V,10%,X7R,A3A
     1 P3E_CPU0_PE1_PCH_TXP<8> @BASEBOARD_FAB2_LIB.BASEBOARD_FAB2(SCH_1):P3E_CPU0_PE1_PCH_TXP(8)    I47 @BASEBOARD_FAB2_LIB.BASEBOARD_FAB2(SCH_1):PAGE244
     2 P3E_CPU0_PE1_PCH_CON_TXP<8> @BASEBOARD_FAB2_LIB.BASEBOARD_FAB2(SCH_1):P3E_CPU0_PE1_PCH_CON_TXP(8)    I47 @BASEBOARD_FAB2_LIB.BASEBOARD_FAB2(SCH_1):PAGE244

C844 CAP_0402-0.22UF,16V,10%,X7R,A3A
     1 P3E_CPU0_PE1_PCH_TXN<9> @BASEBOARD_FAB2_LIB.BASEBOARD_FAB2(SCH_1):P3E_CPU0_PE1_PCH_TXN(9)    I51 @BASEBOARD_FAB2_LIB.BASEBOARD_FAB2(SCH_1):PAGE244
     2 P3E_CPU0_PE1_PCH_CON_TXN<9> @BASEBOARD_FAB2_LIB.BASEBOARD_FAB2(SCH_1):P3E_CPU0_PE1_PCH_CON_TXN(9)    I51 @BASEBOARD_FAB2_LIB.BASEBOARD_FAB2(SCH_1):PAGE244

C845 CAP_0402-0.22UF,16V,10%,X7R,A3A
     1 P3E_CPU0_PE1_PCH_TXP<9> @BASEBOARD_FAB2_LIB.BASEBOARD_FAB2(SCH_1):P3E_CPU0_PE1_PCH_TXP(9)    I35 @BASEBOARD_FAB2_LIB.BASEBOARD_FAB2(SCH_1):PAGE244
     2 P3E_CPU0_PE1_PCH_CON_TXP<9> @BASEBOARD_FAB2_LIB.BASEBOARD_FAB2(SCH_1):P3E_CPU0_PE1_PCH_CON_TXP(9)    I35 @BASEBOARD_FAB2_LIB.BASEBOARD_FAB2(SCH_1):PAGE244

CN8F1 CAP_0402-1.0UF,6.3V,10%,X6S,D9A
     1 P3V3_STBY @BASEBOARD_FAB2_LIB.BASEBOARD_FAB2(SCH_1):P3V3_STBY    I15 @BASEBOARD_FAB2_LIB.BASEBOARD_FAB2(SCH_1):PAGE246
     2    GND @BASEBOARD_FAB2_LIB.BASEBOARD_FAB2(SCH_1):GND    I15 @BASEBOARD_FAB2_LIB.BASEBOARD_FAB2(SCH_1):PAGE246

CN8F2 CAP_0402LF-0.01UF,25V,10%,X7R,A
     1 P3V3_STBY @BASEBOARD_FAB2_LIB.BASEBOARD_FAB2(SCH_1):P3V3_STBY    I16 @BASEBOARD_FAB2_LIB.BASEBOARD_FAB2(SCH_1):PAGE246
     2    GND @BASEBOARD_FAB2_LIB.BASEBOARD_FAB2(SCH_1):GND    I16 @BASEBOARD_FAB2_LIB.BASEBOARD_FAB2(SCH_1):PAGE246

CONX8 SMC-CONN60A-22-GP_CONN-G7-SMC-A
     1    GND @BASEBOARD_FAB2_LIB.BASEBOARD_FAB2(SCH_1):GND    I48 @BASEBOARD_FAB2_LIB.BASEBOARD_FAB2(SCH_1):PAGE245
     3 P3E_CPU0_PE2_SS_C_TXP<8> @BASEBOARD_FAB2_LIB.BASEBOARD_FAB2(SCH_1):P3E_CPU0_PE2_SS_C_TXP(8)    I48 @BASEBOARD_FAB2_LIB.BASEBOARD_FAB2(SCH_1):PAGE245
     5 P3E_CPU0_PE2_SS_C_TXN<8> @BASEBOARD_FAB2_LIB.BASEBOARD_FAB2(SCH_1):P3E_CPU0_PE2_SS_C_TXN(8)    I48 @BASEBOARD_FAB2_LIB.BASEBOARD_FAB2(SCH_1):PAGE245
     7    GND @BASEBOARD_FAB2_LIB.BASEBOARD_FAB2(SCH_1):GND    I48 @BASEBOARD_FAB2_LIB.BASEBOARD_FAB2(SCH_1):PAGE245
     2     NC     NC    I48 @BASEBOARD_FAB2_LIB.BASEBOARD_FAB2(SCH_1):PAGE245
     4    GND @BASEBOARD_FAB2_LIB.BASEBOARD_FAB2(SCH_1):GND    I48 @BASEBOARD_FAB2_LIB.BASEBOARD_FAB2(SCH_1):PAGE245
     6 P3E_CPU0_PE2_SS_RXN<8> @BASEBOARD_FAB2_LIB.BASEBOARD_FAB2(SCH_1):P3E_CPU0_PE2_SS_RXN(8)    I48 @BASEBOARD_FAB2_LIB.BASEBOARD_FAB2(SCH_1):PAGE245
     8 P3E_CPU0_PE2_SS_RXP<8> @BASEBOARD_FAB2_LIB.BASEBOARD_FAB2(SCH_1):P3E_CPU0_PE2_SS_RXP(8)    I48 @BASEBOARD_FAB2_LIB.BASEBOARD_FAB2(SCH_1):PAGE245
     9 P3E_CPU0_PE2_SS_C_TXN<9> @BASEBOARD_FAB2_LIB.BASEBOARD_FAB2(SCH_1):P3E_CPU0_PE2_SS_C_TXN(9)    I48 @BASEBOARD_FAB2_LIB.BASEBOARD_FAB2(SCH_1):PAGE245
    11 P3E_CPU0_PE2_SS_C_TXP<9> @BASEBOARD_FAB2_LIB.BASEBOARD_FAB2(SCH_1):P3E_CPU0_PE2_SS_C_TXP(9)    I48 @BASEBOARD_FAB2_LIB.BASEBOARD_FAB2(SCH_1):PAGE245
    13    GND @BASEBOARD_FAB2_LIB.BASEBOARD_FAB2(SCH_1):GND    I48 @BASEBOARD_FAB2_LIB.BASEBOARD_FAB2(SCH_1):PAGE245
    15 P3E_CPU0_PE2_SS_C_TXN<10> @BASEBOARD_FAB2_LIB.BASEBOARD_FAB2(SCH_1):P3E_CPU0_PE2_SS_C_TXN(10)    I48 @BASEBOARD_FAB2_LIB.BASEBOARD_FAB2(SCH_1):PAGE245
    17 P3E_CPU0_PE2_SS_C_TXP<10> @BASEBOARD_FAB2_LIB.BASEBOARD_FAB2(SCH_1):P3E_CPU0_PE2_SS_C_TXP(10)    I48 @BASEBOARD_FAB2_LIB.BASEBOARD_FAB2(SCH_1):PAGE245
    19    GND @BASEBOARD_FAB2_LIB.BASEBOARD_FAB2(SCH_1):GND    I48 @BASEBOARD_FAB2_LIB.BASEBOARD_FAB2(SCH_1):PAGE245
    21 P3E_CPU0_PE2_SS_C_TXP<11> @BASEBOARD_FAB2_LIB.BASEBOARD_FAB2(SCH_1):P3E_CPU0_PE2_SS_C_TXP(11)    I48 @BASEBOARD_FAB2_LIB.BASEBOARD_FAB2(SCH_1):PAGE245
    23 P3E_CPU0_PE2_SS_C_TXN<11> @BASEBOARD_FAB2_LIB.BASEBOARD_FAB2(SCH_1):P3E_CPU0_PE2_SS_C_TXN(11)    I48 @BASEBOARD_FAB2_LIB.BASEBOARD_FAB2(SCH_1):PAGE245
    25    GND @BASEBOARD_FAB2_LIB.BASEBOARD_FAB2(SCH_1):GND    I48 @BASEBOARD_FAB2_LIB.BASEBOARD_FAB2(SCH_1):PAGE245
    27 P3E_CPU0_PE2_SS_C_TXN<12> @BASEBOARD_FAB2_LIB.BASEBOARD_FAB2(SCH_1):P3E_CPU0_PE2_SS_C_TXN(12)    I48 @BASEBOARD_FAB2_LIB.BASEBOARD_FAB2(SCH_1):PAGE245
    29 P3E_CPU0_PE2_SS_C_TXP<12> @BASEBOARD_FAB2_LIB.BASEBOARD_FAB2(SCH_1):P3E_CPU0_PE2_SS_C_TXP(12)    I48 @BASEBOARD_FAB2_LIB.BASEBOARD_FAB2(SCH_1):PAGE245
    31    GND @BASEBOARD_FAB2_LIB.BASEBOARD_FAB2(SCH_1):GND    I48 @BASEBOARD_FAB2_LIB.BASEBOARD_FAB2(SCH_1):PAGE245
    33 P3E_CPU0_PE2_SS_C_TXN<13> @BASEBOARD_FAB2_LIB.BASEBOARD_FAB2(SCH_1):P3E_CPU0_PE2_SS_C_TXN(13)    I48 @BASEBOARD_FAB2_LIB.BASEBOARD_FAB2(SCH_1):PAGE245
    35 P3E_CPU0_PE2_SS_C_TXP<13> @BASEBOARD_FAB2_LIB.BASEBOARD_FAB2(SCH_1):P3E_CPU0_PE2_SS_C_TXP(13)    I48 @BASEBOARD_FAB2_LIB.BASEBOARD_FAB2(SCH_1):PAGE245
    37    GND @BASEBOARD_FAB2_LIB.BASEBOARD_FAB2(SCH_1):GND    I48 @BASEBOARD_FAB2_LIB.BASEBOARD_FAB2(SCH_1):PAGE245
    39 P3E_CPU0_PE2_SS_C_TXP<14> @BASEBOARD_FAB2_LIB.BASEBOARD_FAB2(SCH_1):P3E_CPU0_PE2_SS_C_TXP(14)    I48 @BASEBOARD_FAB2_LIB.BASEBOARD_FAB2(SCH_1):PAGE245
    41 P3E_CPU0_PE2_SS_C_TXN<14> @BASEBOARD_FAB2_LIB.BASEBOARD_FAB2(SCH_1):P3E_CPU0_PE2_SS_C_TXN(14)    I48 @BASEBOARD_FAB2_LIB.BASEBOARD_FAB2(SCH_1):PAGE245
    43    GND @BASEBOARD_FAB2_LIB.BASEBOARD_FAB2(SCH_1):GND    I48 @BASEBOARD_FAB2_LIB.BASEBOARD_FAB2(SCH_1):PAGE245
    45 P3E_CPU0_PE2_SS_C_TXN<15> @BASEBOARD_FAB2_LIB.BASEBOARD_FAB2(SCH_1):P3E_CPU0_PE2_SS_C_TXN(15)    I48 @BASEBOARD_FAB2_LIB.BASEBOARD_FAB2(SCH_1):PAGE245
    47 P3E_CPU0_PE2_SS_C_TXP<15> @BASEBOARD_FAB2_LIB.BASEBOARD_FAB2(SCH_1):P3E_CPU0_PE2_SS_C_TXP(15)    I48 @BASEBOARD_FAB2_LIB.BASEBOARD_FAB2(SCH_1):PAGE245
    49    GND @BASEBOARD_FAB2_LIB.BASEBOARD_FAB2(SCH_1):GND    I48 @BASEBOARD_FAB2_LIB.BASEBOARD_FAB2(SCH_1):PAGE245
    51 CLK_100M_SRC12_DP @BASEBOARD_FAB2_LIB.BASEBOARD_FAB2(SCH_1):CLK_100M_SRC12_DP    I48 @BASEBOARD_FAB2_LIB.BASEBOARD_FAB2(SCH_1):PAGE245
    53 CLK_100M_SRC12_DN @BASEBOARD_FAB2_LIB.BASEBOARD_FAB2(SCH_1):CLK_100M_SRC12_DN    I48 @BASEBOARD_FAB2_LIB.BASEBOARD_FAB2(SCH_1):PAGE245
    55    GND @BASEBOARD_FAB2_LIB.BASEBOARD_FAB2(SCH_1):GND    I48 @BASEBOARD_FAB2_LIB.BASEBOARD_FAB2(SCH_1):PAGE245
    57 USB2_P02_DP @BASEBOARD_FAB2_LIB.BASEBOARD_FAB2(SCH_1):USB2_P02_DP    I48 @BASEBOARD_FAB2_LIB.BASEBOARD_FAB2(SCH_1):PAGE245
    59 USB2_P02_DN @BASEBOARD_FAB2_LIB.BASEBOARD_FAB2(SCH_1):USB2_P02_DN    I48 @BASEBOARD_FAB2_LIB.BASEBOARD_FAB2(SCH_1):PAGE245
    10    GND @BASEBOARD_FAB2_LIB.BASEBOARD_FAB2(SCH_1):GND    I48 @BASEBOARD_FAB2_LIB.BASEBOARD_FAB2(SCH_1):PAGE245
    12 P3E_CPU0_PE2_SS_RXN<9> @BASEBOARD_FAB2_LIB.BASEBOARD_FAB2(SCH_1):P3E_CPU0_PE2_SS_RXN(9)    I48 @BASEBOARD_FAB2_LIB.BASEBOARD_FAB2(SCH_1):PAGE245
    14 P3E_CPU0_PE2_SS_RXP<9> @BASEBOARD_FAB2_LIB.BASEBOARD_FAB2(SCH_1):P3E_CPU0_PE2_SS_RXP(9)    I48 @BASEBOARD_FAB2_LIB.BASEBOARD_FAB2(SCH_1):PAGE245
    16    GND @BASEBOARD_FAB2_LIB.BASEBOARD_FAB2(SCH_1):GND    I48 @BASEBOARD_FAB2_LIB.BASEBOARD_FAB2(SCH_1):PAGE245
    18 P3E_CPU0_PE2_SS_RXN<10> @BASEBOARD_FAB2_LIB.BASEBOARD_FAB2(SCH_1):P3E_CPU0_PE2_SS_RXN(10)    I48 @BASEBOARD_FAB2_LIB.BASEBOARD_FAB2(SCH_1):PAGE245
    20 P3E_CPU0_PE2_SS_RXP<10> @BASEBOARD_FAB2_LIB.BASEBOARD_FAB2(SCH_1):P3E_CPU0_PE2_SS_RXP(10)    I48 @BASEBOARD_FAB2_LIB.BASEBOARD_FAB2(SCH_1):PAGE245
    22    GND @BASEBOARD_FAB2_LIB.BASEBOARD_FAB2(SCH_1):GND    I48 @BASEBOARD_FAB2_LIB.BASEBOARD_FAB2(SCH_1):PAGE245
    24 P3E_CPU0_PE2_SS_RXN<11> @BASEBOARD_FAB2_LIB.BASEBOARD_FAB2(SCH_1):P3E_CPU0_PE2_SS_RXN(11)    I48 @BASEBOARD_FAB2_LIB.BASEBOARD_FAB2(SCH_1):PAGE245
    26 P3E_CPU0_PE2_SS_RXP<11> @BASEBOARD_FAB2_LIB.BASEBOARD_FAB2(SCH_1):P3E_CPU0_PE2_SS_RXP(11)    I48 @BASEBOARD_FAB2_LIB.BASEBOARD_FAB2(SCH_1):PAGE245
    28    GND @BASEBOARD_FAB2_LIB.BASEBOARD_FAB2(SCH_1):GND    I48 @BASEBOARD_FAB2_LIB.BASEBOARD_FAB2(SCH_1):PAGE245
    30 P3E_CPU0_PE2_SS_RXN<12> @BASEBOARD_FAB2_LIB.BASEBOARD_FAB2(SCH_1):P3E_CPU0_PE2_SS_RXN(12)    I48 @BASEBOARD_FAB2_LIB.BASEBOARD_FAB2(SCH_1):PAGE245
    32 P3E_CPU0_PE2_SS_RXP<12> @BASEBOARD_FAB2_LIB.BASEBOARD_FAB2(SCH_1):P3E_CPU0_PE2_SS_RXP(12)    I48 @BASEBOARD_FAB2_LIB.BASEBOARD_FAB2(SCH_1):PAGE245
    34    GND @BASEBOARD_FAB2_LIB.BASEBOARD_FAB2(SCH_1):GND    I48 @BASEBOARD_FAB2_LIB.BASEBOARD_FAB2(SCH_1):PAGE245
    36 P3E_CPU0_PE2_SS_RXP<13> @BASEBOARD_FAB2_LIB.BASEBOARD_FAB2(SCH_1):P3E_CPU0_PE2_SS_RXP(13)    I48 @BASEBOARD_FAB2_LIB.BASEBOARD_FAB2(SCH_1):PAGE245
    38 P3E_CPU0_PE2_SS_RXN<13> @BASEBOARD_FAB2_LIB.BASEBOARD_FAB2(SCH_1):P3E_CPU0_PE2_SS_RXN(13)    I48 @BASEBOARD_FAB2_LIB.BASEBOARD_FAB2(SCH_1):PAGE245
    40    GND @BASEBOARD_FAB2_LIB.BASEBOARD_FAB2(SCH_1):GND    I48 @BASEBOARD_FAB2_LIB.BASEBOARD_FAB2(SCH_1):PAGE245
    42 P3E_CPU0_PE2_SS_RXN<14> @BASEBOARD_FAB2_LIB.BASEBOARD_FAB2(SCH_1):P3E_CPU0_PE2_SS_RXN(14)    I48 @BASEBOARD_FAB2_LIB.BASEBOARD_FAB2(SCH_1):PAGE245
    44 P3E_CPU0_PE2_SS_RXP<14> @BASEBOARD_FAB2_LIB.BASEBOARD_FAB2(SCH_1):P3E_CPU0_PE2_SS_RXP(14)    I48 @BASEBOARD_FAB2_LIB.BASEBOARD_FAB2(SCH_1):PAGE245
    46    GND @BASEBOARD_FAB2_LIB.BASEBOARD_FAB2(SCH_1):GND    I48 @BASEBOARD_FAB2_LIB.BASEBOARD_FAB2(SCH_1):PAGE245
    48 P3E_CPU0_PE2_SS_RXN<15> @BASEBOARD_FAB2_LIB.BASEBOARD_FAB2(SCH_1):P3E_CPU0_PE2_SS_RXN(15)    I48 @BASEBOARD_FAB2_LIB.BASEBOARD_FAB2(SCH_1):PAGE245
    50 P3E_CPU0_PE2_SS_RXP<15> @BASEBOARD_FAB2_LIB.BASEBOARD_FAB2(SCH_1):P3E_CPU0_PE2_SS_RXP(15)    I48 @BASEBOARD_FAB2_LIB.BASEBOARD_FAB2(SCH_1):PAGE245
    52    GND @BASEBOARD_FAB2_LIB.BASEBOARD_FAB2(SCH_1):GND    I48 @BASEBOARD_FAB2_LIB.BASEBOARD_FAB2(SCH_1):PAGE245
    54 CLK_100M_SRC13_DP @BASEBOARD_FAB2_LIB.BASEBOARD_FAB2(SCH_1):CLK_100M_SRC13_DP    I48 @BASEBOARD_FAB2_LIB.BASEBOARD_FAB2(SCH_1):PAGE245
    56 CLK_100M_SRC13_DN @BASEBOARD_FAB2_LIB.BASEBOARD_FAB2(SCH_1):CLK_100M_SRC13_DN    I48 @BASEBOARD_FAB2_LIB.BASEBOARD_FAB2(SCH_1):PAGE245
    58    GND @BASEBOARD_FAB2_LIB.BASEBOARD_FAB2(SCH_1):GND    I48 @BASEBOARD_FAB2_LIB.BASEBOARD_FAB2(SCH_1):PAGE245
    60     NC     NC    I48 @BASEBOARD_FAB2_LIB.BASEBOARD_FAB2(SCH_1):PAGE245
   NP1    GND @BASEBOARD_FAB2_LIB.BASEBOARD_FAB2(SCH_1):GND    I48 @BASEBOARD_FAB2_LIB.BASEBOARD_FAB2(SCH_1):PAGE245
   NP2    GND @BASEBOARD_FAB2_LIB.BASEBOARD_FAB2(SCH_1):GND    I48 @BASEBOARD_FAB2_LIB.BASEBOARD_FAB2(SCH_1):PAGE245
  PTH1    GND @BASEBOARD_FAB2_LIB.BASEBOARD_FAB2(SCH_1):GND    I48 @BASEBOARD_FAB2_LIB.BASEBOARD_FAB2(SCH_1):PAGE245
  PTH2    GND @BASEBOARD_FAB2_LIB.BASEBOARD_FAB2(SCH_1):GND    I48 @BASEBOARD_FAB2_LIB.BASEBOARD_FAB2(SCH_1):PAGE245

CR1B1 DIODE_SM-SDMK0340L,EMPTY,H7179A
     1 P5V_STBY @BASEBOARD_FAB2_LIB.BASEBOARD_FAB2(SCH_1):P5V_STBY    I64 @BASEBOARD_FAB2_LIB.BASEBOARD_FAB2(SCH_1):PAGE161
     2 FAN_PWM_OUT_SYS1_R @BASEBOARD_FAB2_LIB.BASEBOARD_FAB2(SCH_1):FAN_PWM_OUT_SYS1_R    I64 @BASEBOARD_FAB2_LIB.BASEBOARD_FAB2(SCH_1):PAGE161

CR1B2 DIODE_SM-SDMK0340L,IC,H71799-0A
     1 FAN_TACH2_CPU1_D1 @BASEBOARD_FAB2_LIB.BASEBOARD_FAB2(SCH_1):FAN_TACH2_CPU1_D1    I62 @BASEBOARD_FAB2_LIB.BASEBOARD_FAB2(SCH_1):PAGE161
     2 FAN_TACH2_CPU1_D2 @BASEBOARD_FAB2_LIB.BASEBOARD_FAB2(SCH_1):FAN_TACH2_CPU1_D2    I62 @BASEBOARD_FAB2_LIB.BASEBOARD_FAB2(SCH_1):PAGE161

CR1B3 DIODE_SM-SDMK0340L,IC,H71799-0A
     1 FAN_TACH3_CPU1_D1 @BASEBOARD_FAB2_LIB.BASEBOARD_FAB2(SCH_1):FAN_TACH3_CPU1_D1   I123 @BASEBOARD_FAB2_LIB.BASEBOARD_FAB2(SCH_1):PAGE161
     2 FAN_TACH3_CPU1_D2 @BASEBOARD_FAB2_LIB.BASEBOARD_FAB2(SCH_1):FAN_TACH3_CPU1_D2   I123 @BASEBOARD_FAB2_LIB.BASEBOARD_FAB2(SCH_1):PAGE161

CR1E1 DIODE_SM-SDMK0340L,EMPTY,H7179A
     1 P5V_STBY @BASEBOARD_FAB2_LIB.BASEBOARD_FAB2(SCH_1):P5V_STBY    I50 @BASEBOARD_FAB2_LIB.BASEBOARD_FAB2(SCH_1):PAGE161
     2 FAN_PWM_OUT_SYS0_R @BASEBOARD_FAB2_LIB.BASEBOARD_FAB2(SCH_1):FAN_PWM_OUT_SYS0_R    I50 @BASEBOARD_FAB2_LIB.BASEBOARD_FAB2(SCH_1):PAGE161

CR1F1 DIODE_SM-SDMK0340L,IC,H71799-0A
     1 FAN_TACH0_CPU0_D1 @BASEBOARD_FAB2_LIB.BASEBOARD_FAB2(SCH_1):FAN_TACH0_CPU0_D1    I42 @BASEBOARD_FAB2_LIB.BASEBOARD_FAB2(SCH_1):PAGE161
     2 FAN_TACH0_CPU0_D2 @BASEBOARD_FAB2_LIB.BASEBOARD_FAB2(SCH_1):FAN_TACH0_CPU0_D2    I42 @BASEBOARD_FAB2_LIB.BASEBOARD_FAB2(SCH_1):PAGE161

CR1F2 DIODE_SM-SDMK0340L,IC,H71799-0A
     1 FAN_TACH1_CPU1_D1 @BASEBOARD_FAB2_LIB.BASEBOARD_FAB2(SCH_1):FAN_TACH1_CPU1_D1   I133 @BASEBOARD_FAB2_LIB.BASEBOARD_FAB2(SCH_1):PAGE161
     2 FAN_TACH1_CPU1_D2 @BASEBOARD_FAB2_LIB.BASEBOARD_FAB2(SCH_1):FAN_TACH1_CPU1_D2   I133 @BASEBOARD_FAB2_LIB.BASEBOARD_FAB2(SCH_1):PAGE161

CR1F3 DIODE_SM-SDMK0340L,IC,H71799-0A
     1 FM_MATED_IN_D2_N @BASEBOARD_FAB2_LIB.BASEBOARD_FAB2(SCH_1):FM_MATED_IN_D2_N   I180 @BASEBOARD_FAB2_LIB.BASEBOARD_FAB2(SCH_1):PAGE181
     2 FM_MATED_IN_D1_N @BASEBOARD_FAB2_LIB.BASEBOARD_FAB2(SCH_1):FM_MATED_IN_D1_N   I180 @BASEBOARD_FAB2_LIB.BASEBOARD_FAB2(SCH_1):PAGE181

CR1F4 DIODE_SM-SDMK0340L,IC,H71799-0A
     1 FM_MATED_IN_D1_N @BASEBOARD_FAB2_LIB.BASEBOARD_FAB2(SCH_1):FM_MATED_IN_D1_N   I178 @BASEBOARD_FAB2_LIB.BASEBOARD_FAB2(SCH_1):PAGE181
     2 FM_MATED_IN_N @BASEBOARD_FAB2_LIB.BASEBOARD_FAB2(SCH_1):FM_MATED_IN_N   I178 @BASEBOARD_FAB2_LIB.BASEBOARD_FAB2(SCH_1):PAGE181

CR1F5 DIODE_SM-MBRS340T3G,EMPTY,C819A
     1 P12V_STBY @BASEBOARD_FAB2_LIB.BASEBOARD_FAB2(SCH_1):P12V_STBY   I220 @BASEBOARD_FAB2_LIB.BASEBOARD_FAB2(SCH_1):PAGE200
     2    GND @BASEBOARD_FAB2_LIB.BASEBOARD_FAB2(SCH_1):GND   I220 @BASEBOARD_FAB2_LIB.BASEBOARD_FAB2(SCH_1):PAGE200

CR1L1 DIODE_SM-1N4148W,IC,D89194-001
     1 FM_DB_UART_SEL1_N @BASEBOARD_FAB2_LIB.BASEBOARD_FAB2(SCH_1):FM_DB_UART_SEL1_N     I2 @BASEBOARD_FAB2_LIB.BASEBOARD_FAB2(SCH_1):PAGE168
     2 FM_DB_UART_SEL0_N @BASEBOARD_FAB2_LIB.BASEBOARD_FAB2(SCH_1):FM_DB_UART_SEL0_N     I2 @BASEBOARD_FAB2_LIB.BASEBOARD_FAB2(SCH_1):PAGE168

CR1L2 DIODE_SM-1N4148W,IC,D89194-001
     1 FM_DB_UART_SEL2_N @BASEBOARD_FAB2_LIB.BASEBOARD_FAB2(SCH_1):FM_DB_UART_SEL2_N     I3 @BASEBOARD_FAB2_LIB.BASEBOARD_FAB2(SCH_1):PAGE168
     2 FM_DB_UART_SEL1_N @BASEBOARD_FAB2_LIB.BASEBOARD_FAB2(SCH_1):FM_DB_UART_SEL1_N     I3 @BASEBOARD_FAB2_LIB.BASEBOARD_FAB2(SCH_1):PAGE168

CR1L3 DIODE_SM-1N4148W,IC,D89194-001
     1 FM_DB_UART_SEL3_N @BASEBOARD_FAB2_LIB.BASEBOARD_FAB2(SCH_1):FM_DB_UART_SEL3_N     I4 @BASEBOARD_FAB2_LIB.BASEBOARD_FAB2(SCH_1):PAGE168
     2 FM_DB_UART_SEL2_N @BASEBOARD_FAB2_LIB.BASEBOARD_FAB2(SCH_1):FM_DB_UART_SEL2_N     I4 @BASEBOARD_FAB2_LIB.BASEBOARD_FAB2(SCH_1):PAGE168

CR1L4 DIODE_SM-1N4148W,IC,D89194-001
     1 FM_DB_UART_SEL4_N @BASEBOARD_FAB2_LIB.BASEBOARD_FAB2(SCH_1):FM_DB_UART_SEL4_N     I5 @BASEBOARD_FAB2_LIB.BASEBOARD_FAB2(SCH_1):PAGE168
     2 FM_DB_UART_SEL3_N @BASEBOARD_FAB2_LIB.BASEBOARD_FAB2(SCH_1):FM_DB_UART_SEL3_N     I5 @BASEBOARD_FAB2_LIB.BASEBOARD_FAB2(SCH_1):PAGE168

CR1M2 DIODEAC_DUAL_ARRAY_SM9-ESD3V3UA
     1 USB2_P01_ESD_DP @BASEBOARD_FAB2_LIB.BASEBOARD_FAB2(SCH_1):USB2_P01_ESD_DP    I98 @BASEBOARD_FAB2_LIB.BASEBOARD_FAB2(SCH_1):PAGE176
     2 USB2_P01_ESD_DN @BASEBOARD_FAB2_LIB.BASEBOARD_FAB2(SCH_1):USB2_P01_ESD_DN    I98 @BASEBOARD_FAB2_LIB.BASEBOARD_FAB2(SCH_1):PAGE176
     4 TP_USB_ESD_AC2 @BASEBOARD_FAB2_LIB.BASEBOARD_FAB2(SCH_1):TP_USB_ESD_AC2    I98 @BASEBOARD_FAB2_LIB.BASEBOARD_FAB2(SCH_1):PAGE176
     5 TP_USB_ESD_AC3 @BASEBOARD_FAB2_LIB.BASEBOARD_FAB2(SCH_1):TP_USB_ESD_AC3    I98 @BASEBOARD_FAB2_LIB.BASEBOARD_FAB2(SCH_1):PAGE176
     3    GND @BASEBOARD_FAB2_LIB.BASEBOARD_FAB2(SCH_1):GND    I98 @BASEBOARD_FAB2_LIB.BASEBOARD_FAB2(SCH_1):PAGE176
     9 USB2_P01_ESD_DP @BASEBOARD_FAB2_LIB.BASEBOARD_FAB2(SCH_1):USB2_P01_ESD_DP    I98 @BASEBOARD_FAB2_LIB.BASEBOARD_FAB2(SCH_1):PAGE176
     8 USB2_P01_ESD_DN @BASEBOARD_FAB2_LIB.BASEBOARD_FAB2(SCH_1):USB2_P01_ESD_DN    I98 @BASEBOARD_FAB2_LIB.BASEBOARD_FAB2(SCH_1):PAGE176
     7 TP_USB_ESD_OUT2 @BASEBOARD_FAB2_LIB.BASEBOARD_FAB2(SCH_1):TP_USB_ESD_OUT2    I98 @BASEBOARD_FAB2_LIB.BASEBOARD_FAB2(SCH_1):PAGE176
     6 TP_USB_ESD_OUT3 @BASEBOARD_FAB2_LIB.BASEBOARD_FAB2(SCH_1):TP_USB_ESD_OUT3    I98 @BASEBOARD_FAB2_LIB.BASEBOARD_FAB2(SCH_1):PAGE176

CR2U1 DIODE2A_DUAL_SMLF-BAS70-05,DIOA
     3 P3V3_RTC_STBY @BASEBOARD_FAB2_LIB.BASEBOARD_FAB2(SCH_1):P3V3_RTC_STBY    I53 @BASEBOARD_FAB2_LIB.BASEBOARD_FAB2(SCH_1):PAGE196
     1 P3V3_STBY @BASEBOARD_FAB2_LIB.BASEBOARD_FAB2(SCH_1):P3V3_STBY    I53 @BASEBOARD_FAB2_LIB.BASEBOARD_FAB2(SCH_1):PAGE196
     2 A_P3V_BAT_R @BASEBOARD_FAB2_LIB.BASEBOARD_FAB2(SCH_1):A_P3V_BAT_R    I53 @BASEBOARD_FAB2_LIB.BASEBOARD_FAB2(SCH_1):PAGE196

CR3U1 DIODE_SMLF-1N5819HW,IC,D55839-A
     1 P3V3_STBY_PLD_D @BASEBOARD_FAB2_LIB.BASEBOARD_FAB2(SCH_1):P3V3_STBY_PLD_D    I49 @BASEBOARD_FAB2_LIB.BASEBOARD_FAB2(SCH_1):PAGE189
     2 P3V3_STBY @BASEBOARD_FAB2_LIB.BASEBOARD_FAB2(SCH_1):P3V3_STBY    I49 @BASEBOARD_FAB2_LIB.BASEBOARD_FAB2(SCH_1):PAGE189

CR7E1 DIODE_SMLF-BAT54WS,IC,C73510-0A
     1 PWRGD_P3V3_STBY @BASEBOARD_FAB2_LIB.BASEBOARD_FAB2(SCH_1):PWRGD_P3V3_STBY   I103 @BASEBOARD_FAB2_LIB.BASEBOARD_FAB2(SCH_1):PAGE196
     2 PWRGD_DSW_PWROK @BASEBOARD_FAB2_LIB.BASEBOARD_FAB2(SCH_1):PWRGD_DSW_PWROK   I103 @BASEBOARD_FAB2_LIB.BASEBOARD_FAB2(SCH_1):PAGE196

CR8E1 DIODE_SMLF-BAT54WS,IC,C73510-0A
     1 PWRGD_P12V_HSC @BASEBOARD_FAB2_LIB.BASEBOARD_FAB2(SCH_1):PWRGD_P12V_HSC   I128 @BASEBOARD_FAB2_LIB.BASEBOARD_FAB2(SCH_1):PAGE196
     2 PWRGD_P12V_HSC_DLY @BASEBOARD_FAB2_LIB.BASEBOARD_FAB2(SCH_1):PWRGD_P12V_HSC_DLY   I128 @BASEBOARD_FAB2_LIB.BASEBOARD_FAB2(SCH_1):PAGE196

CR9P1 DIODE_SMLF-BAT54WS,IC,C73510-0A
     1 IRQ_UV_DETECT_N @BASEBOARD_FAB2_LIB.BASEBOARD_FAB2(SCH_1):IRQ_UV_DETECT_N   I214 @BASEBOARD_FAB2_LIB.BASEBOARD_FAB2(SCH_1):PAGE200
     2 FM_DISABLE_FAN_N @BASEBOARD_FAB2_LIB.BASEBOARD_FAB2(SCH_1):FM_DISABLE_FAN_N   I214 @BASEBOARD_FAB2_LIB.BASEBOARD_FAB2(SCH_1):PAGE200

CR9P2 DIODE_SMLF-BAT54WS,IC,C73510-0A
     1 FM_UV_ADR_TRIGGER_N @BASEBOARD_FAB2_LIB.BASEBOARD_FAB2(SCH_1):FM_UV_ADR_TRIGGER_N   I213 @BASEBOARD_FAB2_LIB.BASEBOARD_FAB2(SCH_1):PAGE200
     2 FM_DISABLE_FAN_N @BASEBOARD_FAB2_LIB.BASEBOARD_FAB2(SCH_1):FM_DISABLE_FAN_N   I213 @BASEBOARD_FAB2_LIB.BASEBOARD_FAB2(SCH_1):PAGE200

 CT1 CAP_A_0402V-0.1UF,16V,10%,X7R,A
     1 VR_PVCCIN_CPU0_AIREF1 @BASEBOARD_FAB2_LIB.BASEBOARD_FAB2(SCH_1):VR_PVCCIN_CPU0_AIREF1    I70 @BASEBOARD_FAB2_LIB.BASEBOARD_FAB2(SCH_1):PAGE202
     2    GND @BASEBOARD_FAB2_LIB.BASEBOARD_FAB2(SCH_1):GND    I70 @BASEBOARD_FAB2_LIB.BASEBOARD_FAB2(SCH_1):PAGE202

 CT2 CAP_0402LF-1000PF,50V,10%,X7R,A
     1 A_TSENSE_PVCCIN_CPU0 @BASEBOARD_FAB2_LIB.BASEBOARD_FAB2(SCH_1):A_TSENSE_PVCCIN_CPU0    I78 @BASEBOARD_FAB2_LIB.BASEBOARD_FAB2(SCH_1):PAGE202
     2    GND @BASEBOARD_FAB2_LIB.BASEBOARD_FAB2(SCH_1):GND    I78 @BASEBOARD_FAB2_LIB.BASEBOARD_FAB2(SCH_1):PAGE202

 CT3 SC2K2P50V3KX-GP_SMD-BCG6-SC2K2A
     1 VR_PVCCIN_CPU0_PHASE1 @BASEBOARD_FAB2_LIB.BASEBOARD_FAB2(SCH_1):VR_PVCCIN_CPU0_PHASE1    I76 @BASEBOARD_FAB2_LIB.BASEBOARD_FAB2(SCH_1):PAGE202
     2 UNNAMED_202_3D01R5F-GP_I75_2 @BASEBOARD_FAB2_LIB.BASEBOARD_FAB2(SCH_1):UNNAMED_202_3D01R5F-GP_I75_2    I76 @BASEBOARD_FAB2_LIB.BASEBOARD_FAB2(SCH_1):PAGE202

 CT4 CAP_0402LF-1000PF,50V,10%,X7R,A
     1 A_TSENSE_PVCCIN_CPU0 @BASEBOARD_FAB2_LIB.BASEBOARD_FAB2(SCH_1):A_TSENSE_PVCCIN_CPU0    I87 @BASEBOARD_FAB2_LIB.BASEBOARD_FAB2(SCH_1):PAGE202
     2    GND @BASEBOARD_FAB2_LIB.BASEBOARD_FAB2(SCH_1):GND    I87 @BASEBOARD_FAB2_LIB.BASEBOARD_FAB2(SCH_1):PAGE202

 CT5 SC2K2P50V3KX-GP_SMD-BCG6-SC2K2A
     1 VR_PVCCIN_CPU0_PHASE2 @BASEBOARD_FAB2_LIB.BASEBOARD_FAB2(SCH_1):VR_PVCCIN_CPU0_PHASE2    I82 @BASEBOARD_FAB2_LIB.BASEBOARD_FAB2(SCH_1):PAGE202
     2 UNNAMED_202_3D01R5F-GP_I83_2 @BASEBOARD_FAB2_LIB.BASEBOARD_FAB2(SCH_1):UNNAMED_202_3D01R5F-GP_I83_2    I82 @BASEBOARD_FAB2_LIB.BASEBOARD_FAB2(SCH_1):PAGE202

 CT6 CAP_A_0402V-0.1UF,16V,10%,X7R,A
     1 VR_PVCCIN_CPU0_AIREF2 @BASEBOARD_FAB2_LIB.BASEBOARD_FAB2(SCH_1):VR_PVCCIN_CPU0_AIREF2    I81 @BASEBOARD_FAB2_LIB.BASEBOARD_FAB2(SCH_1):PAGE202
     2    GND @BASEBOARD_FAB2_LIB.BASEBOARD_FAB2(SCH_1):GND    I81 @BASEBOARD_FAB2_LIB.BASEBOARD_FAB2(SCH_1):PAGE202

 CT7 CAP_A_0402V-0.1UF,16V,10%,X7R,A
     1 VR_PVDDQ_KLM_AIREF1 @BASEBOARD_FAB2_LIB.BASEBOARD_FAB2(SCH_1):VR_PVDDQ_KLM_AIREF1   I109 @BASEBOARD_FAB2_LIB.BASEBOARD_FAB2(SCH_1):PAGE227
     2    GND @BASEBOARD_FAB2_LIB.BASEBOARD_FAB2(SCH_1):GND   I109 @BASEBOARD_FAB2_LIB.BASEBOARD_FAB2(SCH_1):PAGE227

 CT8 CAP_0402LF-1000PF,50V,10%,X7R,A
     1 A_TSENSE_PVDDQ_KLM @BASEBOARD_FAB2_LIB.BASEBOARD_FAB2(SCH_1):A_TSENSE_PVDDQ_KLM   I114 @BASEBOARD_FAB2_LIB.BASEBOARD_FAB2(SCH_1):PAGE227
     2    GND @BASEBOARD_FAB2_LIB.BASEBOARD_FAB2(SCH_1):GND   I114 @BASEBOARD_FAB2_LIB.BASEBOARD_FAB2(SCH_1):PAGE227

 CT9 SC2K2P50V3KX-GP_SMD-BCG6-SC2K2A
     1 VR_PVDDQ_KLM_PH1_SW @BASEBOARD_FAB2_LIB.BASEBOARD_FAB2(SCH_1):VR_PVDDQ_KLM_PH1_SW   I111 @BASEBOARD_FAB2_LIB.BASEBOARD_FAB2(SCH_1):PAGE227
     2 UNNAMED_227_3D01R5F-GP_I125_1 @BASEBOARD_FAB2_LIB.BASEBOARD_FAB2(SCH_1):UNNAMED_227_3D01R5F-GP_I125_1   I111 @BASEBOARD_FAB2_LIB.BASEBOARD_FAB2(SCH_1):PAGE227

CT10 CAP_0402LF-1000PF,50V,10%,X7R,A
     1 A_TSENSE_PVDDQ_KLM @BASEBOARD_FAB2_LIB.BASEBOARD_FAB2(SCH_1):A_TSENSE_PVDDQ_KLM   I119 @BASEBOARD_FAB2_LIB.BASEBOARD_FAB2(SCH_1):PAGE227
     2    GND @BASEBOARD_FAB2_LIB.BASEBOARD_FAB2(SCH_1):GND   I119 @BASEBOARD_FAB2_LIB.BASEBOARD_FAB2(SCH_1):PAGE227

CT11 SC2K2P50V3KX-GP_SMD-BCG6-SC2K2A
     1 VR_PVDDQ_KLM_PH2_SW @BASEBOARD_FAB2_LIB.BASEBOARD_FAB2(SCH_1):VR_PVDDQ_KLM_PH2_SW   I116 @BASEBOARD_FAB2_LIB.BASEBOARD_FAB2(SCH_1):PAGE227
     2 UNNAMED_227_3D01R5F-GP_I124_1 @BASEBOARD_FAB2_LIB.BASEBOARD_FAB2(SCH_1):UNNAMED_227_3D01R5F-GP_I124_1   I116 @BASEBOARD_FAB2_LIB.BASEBOARD_FAB2(SCH_1):PAGE227

CT12 CAP_A_0402V-0.1UF,16V,10%,X7R,A
     1 VR_PVDDQ_KLM_AIREF2 @BASEBOARD_FAB2_LIB.BASEBOARD_FAB2(SCH_1):VR_PVDDQ_KLM_AIREF2   I122 @BASEBOARD_FAB2_LIB.BASEBOARD_FAB2(SCH_1):PAGE227
     2    GND @BASEBOARD_FAB2_LIB.BASEBOARD_FAB2(SCH_1):GND   I122 @BASEBOARD_FAB2_LIB.BASEBOARD_FAB2(SCH_1):PAGE227

CT13 CAP_A_0402V-0.1UF,16V,10%,X7R,A
     1 VR_PVCCIN_CPU1_AIREF5 @BASEBOARD_FAB2_LIB.BASEBOARD_FAB2(SCH_1):VR_PVCCIN_CPU1_AIREF5    I62 @BASEBOARD_FAB2_LIB.BASEBOARD_FAB2(SCH_1):PAGE209
     2    GND @BASEBOARD_FAB2_LIB.BASEBOARD_FAB2(SCH_1):GND    I62 @BASEBOARD_FAB2_LIB.BASEBOARD_FAB2(SCH_1):PAGE209

CT14 SC2K2P50V3KX-GP_SMD-BCG6-SC2K2A
     1 VR_PVCCIN_CPU1_PHASE5 @BASEBOARD_FAB2_LIB.BASEBOARD_FAB2(SCH_1):VR_PVCCIN_CPU1_PHASE5    I64 @BASEBOARD_FAB2_LIB.BASEBOARD_FAB2(SCH_1):PAGE209
     2 UNNAMED_209_3D01R5F-GP_I66_2 @BASEBOARD_FAB2_LIB.BASEBOARD_FAB2(SCH_1):UNNAMED_209_3D01R5F-GP_I66_2    I64 @BASEBOARD_FAB2_LIB.BASEBOARD_FAB2(SCH_1):PAGE209

CT15 CAP_0402LF-1000PF,50V,10%,X7R,A
     1 A_TSENSE_PVCCIN_CPU1 @BASEBOARD_FAB2_LIB.BASEBOARD_FAB2(SCH_1):A_TSENSE_PVCCIN_CPU1    I67 @BASEBOARD_FAB2_LIB.BASEBOARD_FAB2(SCH_1):PAGE209
     2    GND @BASEBOARD_FAB2_LIB.BASEBOARD_FAB2(SCH_1):GND    I67 @BASEBOARD_FAB2_LIB.BASEBOARD_FAB2(SCH_1):PAGE209

CT16 CAP_A_0402V-0.1UF,16V,10%,X7R,A
     1 VR_PVCCIN_CPU1_AIREF3 @BASEBOARD_FAB2_LIB.BASEBOARD_FAB2(SCH_1):VR_PVCCIN_CPU1_AIREF3    I80 @BASEBOARD_FAB2_LIB.BASEBOARD_FAB2(SCH_1):PAGE208
     2    GND @BASEBOARD_FAB2_LIB.BASEBOARD_FAB2(SCH_1):GND    I80 @BASEBOARD_FAB2_LIB.BASEBOARD_FAB2(SCH_1):PAGE208

CT18 SC2K2P50V3KX-GP_SMD-BCG6-SC2K2A
     1 VR_PVCCIN_CPU1_PHASE3 @BASEBOARD_FAB2_LIB.BASEBOARD_FAB2(SCH_1):VR_PVCCIN_CPU1_PHASE3    I84 @BASEBOARD_FAB2_LIB.BASEBOARD_FAB2(SCH_1):PAGE208
     2 UNNAMED_208_3D01R5F-GP_I86_2 @BASEBOARD_FAB2_LIB.BASEBOARD_FAB2(SCH_1):UNNAMED_208_3D01R5F-GP_I86_2    I84 @BASEBOARD_FAB2_LIB.BASEBOARD_FAB2(SCH_1):PAGE208

CT19 CAP_0402LF-1000PF,50V,10%,X7R,A
     1 A_TSENSE_PVCCIN_CPU1 @BASEBOARD_FAB2_LIB.BASEBOARD_FAB2(SCH_1):A_TSENSE_PVCCIN_CPU1    I90 @BASEBOARD_FAB2_LIB.BASEBOARD_FAB2(SCH_1):PAGE208
     2    GND @BASEBOARD_FAB2_LIB.BASEBOARD_FAB2(SCH_1):GND    I90 @BASEBOARD_FAB2_LIB.BASEBOARD_FAB2(SCH_1):PAGE208

CT20 SC2K2P50V3KX-GP_SMD-BCG6-SC2K2A
     1 VR_PVCCIN_CPU1_PHASE4 @BASEBOARD_FAB2_LIB.BASEBOARD_FAB2(SCH_1):VR_PVCCIN_CPU1_PHASE4    I92 @BASEBOARD_FAB2_LIB.BASEBOARD_FAB2(SCH_1):PAGE208
     2 UNNAMED_208_3D01R5F-GP_I94_2 @BASEBOARD_FAB2_LIB.BASEBOARD_FAB2(SCH_1):UNNAMED_208_3D01R5F-GP_I94_2    I92 @BASEBOARD_FAB2_LIB.BASEBOARD_FAB2(SCH_1):PAGE208

CT21 CAP_A_0402V-0.1UF,16V,10%,X7R,A
     1 VR_PVCCIN_CPU1_AIREF4 @BASEBOARD_FAB2_LIB.BASEBOARD_FAB2(SCH_1):VR_PVCCIN_CPU1_AIREF4    I87 @BASEBOARD_FAB2_LIB.BASEBOARD_FAB2(SCH_1):PAGE208
     2    GND @BASEBOARD_FAB2_LIB.BASEBOARD_FAB2(SCH_1):GND    I87 @BASEBOARD_FAB2_LIB.BASEBOARD_FAB2(SCH_1):PAGE208

CT22 CAP_0402LF-1000PF,50V,10%,X7R,A
     1 A_TSENSE_PVCCIN_CPU1 @BASEBOARD_FAB2_LIB.BASEBOARD_FAB2(SCH_1):A_TSENSE_PVCCIN_CPU1    I74 @BASEBOARD_FAB2_LIB.BASEBOARD_FAB2(SCH_1):PAGE207
     2    GND @BASEBOARD_FAB2_LIB.BASEBOARD_FAB2(SCH_1):GND    I74 @BASEBOARD_FAB2_LIB.BASEBOARD_FAB2(SCH_1):PAGE207

CT23 SC2K2P50V3KX-GP_SMD-BCG6-SC2K2A
     1 VR_PVCCIN_CPU1_PHASE1 @BASEBOARD_FAB2_LIB.BASEBOARD_FAB2(SCH_1):VR_PVCCIN_CPU1_PHASE1    I77 @BASEBOARD_FAB2_LIB.BASEBOARD_FAB2(SCH_1):PAGE207
     2 UNNAMED_207_3D01R5F-GP_I76_2 @BASEBOARD_FAB2_LIB.BASEBOARD_FAB2(SCH_1):UNNAMED_207_3D01R5F-GP_I76_2    I77 @BASEBOARD_FAB2_LIB.BASEBOARD_FAB2(SCH_1):PAGE207

CT24 CAP_A_0402V-0.1UF,16V,10%,X7R,A
     1 VR_PVCCIN_CPU1_AIREF1 @BASEBOARD_FAB2_LIB.BASEBOARD_FAB2(SCH_1):VR_PVCCIN_CPU1_AIREF1    I71 @BASEBOARD_FAB2_LIB.BASEBOARD_FAB2(SCH_1):PAGE207
     2    GND @BASEBOARD_FAB2_LIB.BASEBOARD_FAB2(SCH_1):GND    I71 @BASEBOARD_FAB2_LIB.BASEBOARD_FAB2(SCH_1):PAGE207

CT25 CAP_A_0402V-0.1UF,16V,10%,X7R,A
     1 VR_PVCCIN_CPU1_AIREF2 @BASEBOARD_FAB2_LIB.BASEBOARD_FAB2(SCH_1):VR_PVCCIN_CPU1_AIREF2    I81 @BASEBOARD_FAB2_LIB.BASEBOARD_FAB2(SCH_1):PAGE207
     2    GND @BASEBOARD_FAB2_LIB.BASEBOARD_FAB2(SCH_1):GND    I81 @BASEBOARD_FAB2_LIB.BASEBOARD_FAB2(SCH_1):PAGE207

CT26 CAP_0402LF-1000PF,50V,10%,X7R,A
     1 A_TSENSE_PVCCIN_CPU1 @BASEBOARD_FAB2_LIB.BASEBOARD_FAB2(SCH_1):A_TSENSE_PVCCIN_CPU1    I82 @BASEBOARD_FAB2_LIB.BASEBOARD_FAB2(SCH_1):PAGE207
     2    GND @BASEBOARD_FAB2_LIB.BASEBOARD_FAB2(SCH_1):GND    I82 @BASEBOARD_FAB2_LIB.BASEBOARD_FAB2(SCH_1):PAGE207

CT27 SC2K2P50V3KX-GP_SMD-BCG6-SC2K2A
     1 VR_PVCCIN_CPU1_PHASE2 @BASEBOARD_FAB2_LIB.BASEBOARD_FAB2(SCH_1):VR_PVCCIN_CPU1_PHASE2    I84 @BASEBOARD_FAB2_LIB.BASEBOARD_FAB2(SCH_1):PAGE207
     2 UNNAMED_207_3D01R5F-GP_I85_2 @BASEBOARD_FAB2_LIB.BASEBOARD_FAB2(SCH_1):UNNAMED_207_3D01R5F-GP_I85_2    I84 @BASEBOARD_FAB2_LIB.BASEBOARD_FAB2(SCH_1):PAGE207

CT28 CAP_0402LF-1000PF,50V,10%,X7R,A
     1 A_TSENSE_PVDDQ_GHJ @BASEBOARD_FAB2_LIB.BASEBOARD_FAB2(SCH_1):A_TSENSE_PVDDQ_GHJ   I122 @BASEBOARD_FAB2_LIB.BASEBOARD_FAB2(SCH_1):PAGE224
     2    GND @BASEBOARD_FAB2_LIB.BASEBOARD_FAB2(SCH_1):GND   I122 @BASEBOARD_FAB2_LIB.BASEBOARD_FAB2(SCH_1):PAGE224

CT29 SC2K2P50V3KX-GP_SMD-BCG6-SC2K2A
     1 VR_PVDDQ_GHJ_PH1_SW @BASEBOARD_FAB2_LIB.BASEBOARD_FAB2(SCH_1):VR_PVDDQ_GHJ_PH1_SW   I121 @BASEBOARD_FAB2_LIB.BASEBOARD_FAB2(SCH_1):PAGE224
     2 UNNAMED_224_3D01R5F-GP_I119_2 @BASEBOARD_FAB2_LIB.BASEBOARD_FAB2(SCH_1):UNNAMED_224_3D01R5F-GP_I119_2   I121 @BASEBOARD_FAB2_LIB.BASEBOARD_FAB2(SCH_1):PAGE224

CT30 CAP_A_0402V-0.1UF,16V,10%,X7R,A
     1 VR_PVDDQ_GHJ_AIREF1 @BASEBOARD_FAB2_LIB.BASEBOARD_FAB2(SCH_1):VR_PVDDQ_GHJ_AIREF1   I117 @BASEBOARD_FAB2_LIB.BASEBOARD_FAB2(SCH_1):PAGE224
     2    GND @BASEBOARD_FAB2_LIB.BASEBOARD_FAB2(SCH_1):GND   I117 @BASEBOARD_FAB2_LIB.BASEBOARD_FAB2(SCH_1):PAGE224

CT31 CAP_A_0402V-0.1UF,16V,10%,X7R,A
     1 VR_PVDDQ_GHJ_AIREF2 @BASEBOARD_FAB2_LIB.BASEBOARD_FAB2(SCH_1):VR_PVDDQ_GHJ_AIREF2   I124 @BASEBOARD_FAB2_LIB.BASEBOARD_FAB2(SCH_1):PAGE224
     2    GND @BASEBOARD_FAB2_LIB.BASEBOARD_FAB2(SCH_1):GND   I124 @BASEBOARD_FAB2_LIB.BASEBOARD_FAB2(SCH_1):PAGE224

CT32 CAP_0402LF-1000PF,50V,10%,X7R,A
     1 A_TSENSE_PVDDQ_GHJ @BASEBOARD_FAB2_LIB.BASEBOARD_FAB2(SCH_1):A_TSENSE_PVDDQ_GHJ   I130 @BASEBOARD_FAB2_LIB.BASEBOARD_FAB2(SCH_1):PAGE224
     2    GND @BASEBOARD_FAB2_LIB.BASEBOARD_FAB2(SCH_1):GND   I130 @BASEBOARD_FAB2_LIB.BASEBOARD_FAB2(SCH_1):PAGE224

CT33 SC2K2P50V3KX-GP_SMD-BCG6-SC2K2A
     1 VR_PVDDQ_GHJ_PH2_SW @BASEBOARD_FAB2_LIB.BASEBOARD_FAB2(SCH_1):VR_PVDDQ_GHJ_PH2_SW   I127 @BASEBOARD_FAB2_LIB.BASEBOARD_FAB2(SCH_1):PAGE224
     2 UNNAMED_224_3D01R5F-GP_I129_2 @BASEBOARD_FAB2_LIB.BASEBOARD_FAB2(SCH_1):UNNAMED_224_3D01R5F-GP_I129_2   I127 @BASEBOARD_FAB2_LIB.BASEBOARD_FAB2(SCH_1):PAGE224

CT34 CAP_0402LF-1000PF,50V,10%,X7R,A
     1 A_TSENSE_PVCCIN_CPU0 @BASEBOARD_FAB2_LIB.BASEBOARD_FAB2(SCH_1):A_TSENSE_PVCCIN_CPU0    I88 @BASEBOARD_FAB2_LIB.BASEBOARD_FAB2(SCH_1):PAGE204
     2    GND @BASEBOARD_FAB2_LIB.BASEBOARD_FAB2(SCH_1):GND    I88 @BASEBOARD_FAB2_LIB.BASEBOARD_FAB2(SCH_1):PAGE204

CT35 SC2K2P50V3KX-GP_SMD-BCG6-SC2K2A
     1 VR_PVCCIN_CPU0_PHASE5 @BASEBOARD_FAB2_LIB.BASEBOARD_FAB2(SCH_1):VR_PVCCIN_CPU0_PHASE5    I90 @BASEBOARD_FAB2_LIB.BASEBOARD_FAB2(SCH_1):PAGE204
     2 UNNAMED_204_3D01R5F-GP_I91_2 @BASEBOARD_FAB2_LIB.BASEBOARD_FAB2(SCH_1):UNNAMED_204_3D01R5F-GP_I91_2    I90 @BASEBOARD_FAB2_LIB.BASEBOARD_FAB2(SCH_1):PAGE204

CT36 CAP_A_0402V-0.1UF,16V,10%,X7R,A
     1 VR_PVCCIN_CPU0_AIREF5 @BASEBOARD_FAB2_LIB.BASEBOARD_FAB2(SCH_1):VR_PVCCIN_CPU0_AIREF5    I85 @BASEBOARD_FAB2_LIB.BASEBOARD_FAB2(SCH_1):PAGE204
     2    GND @BASEBOARD_FAB2_LIB.BASEBOARD_FAB2(SCH_1):GND    I85 @BASEBOARD_FAB2_LIB.BASEBOARD_FAB2(SCH_1):PAGE204

CT37 CAP_0402LF-1000PF,50V,10%,X7R,A
     1 A_TSENSE_PVCCIN_CPU0 @BASEBOARD_FAB2_LIB.BASEBOARD_FAB2(SCH_1):A_TSENSE_PVCCIN_CPU0    I99 @BASEBOARD_FAB2_LIB.BASEBOARD_FAB2(SCH_1):PAGE203
     2    GND @BASEBOARD_FAB2_LIB.BASEBOARD_FAB2(SCH_1):GND    I99 @BASEBOARD_FAB2_LIB.BASEBOARD_FAB2(SCH_1):PAGE203

CT38 SC2K2P50V3KX-GP_SMD-BCG6-SC2K2A
     1 VR_PVCCIN_CPU0_PHASE3 @BASEBOARD_FAB2_LIB.BASEBOARD_FAB2(SCH_1):VR_PVCCIN_CPU0_PHASE3   I101 @BASEBOARD_FAB2_LIB.BASEBOARD_FAB2(SCH_1):PAGE203
     2 UNNAMED_203_3D01R5F-GP_I102_2 @BASEBOARD_FAB2_LIB.BASEBOARD_FAB2(SCH_1):UNNAMED_203_3D01R5F-GP_I102_2   I101 @BASEBOARD_FAB2_LIB.BASEBOARD_FAB2(SCH_1):PAGE203

CT39 CAP_A_0402V-0.1UF,16V,10%,X7R,A
     1 VR_PVCCIN_CPU0_AIREF3 @BASEBOARD_FAB2_LIB.BASEBOARD_FAB2(SCH_1):VR_PVCCIN_CPU0_AIREF3    I96 @BASEBOARD_FAB2_LIB.BASEBOARD_FAB2(SCH_1):PAGE203
     2    GND @BASEBOARD_FAB2_LIB.BASEBOARD_FAB2(SCH_1):GND    I96 @BASEBOARD_FAB2_LIB.BASEBOARD_FAB2(SCH_1):PAGE203

CT40 CAP_A_0402V-0.1UF,16V,10%,X7R,A
     1 VR_PVCCIN_CPU0_AIREF4 @BASEBOARD_FAB2_LIB.BASEBOARD_FAB2(SCH_1):VR_PVCCIN_CPU0_AIREF4    I93 @BASEBOARD_FAB2_LIB.BASEBOARD_FAB2(SCH_1):PAGE203
     2    GND @BASEBOARD_FAB2_LIB.BASEBOARD_FAB2(SCH_1):GND    I93 @BASEBOARD_FAB2_LIB.BASEBOARD_FAB2(SCH_1):PAGE203

CT41 SC2K2P50V3KX-GP_SMD-BCG6-SC2K2A
     1 VR_PVCCIN_CPU0_PHASE4 @BASEBOARD_FAB2_LIB.BASEBOARD_FAB2(SCH_1):VR_PVCCIN_CPU0_PHASE4   I106 @BASEBOARD_FAB2_LIB.BASEBOARD_FAB2(SCH_1):PAGE203
     2 UNNAMED_203_3D01R5F-GP_I105_2 @BASEBOARD_FAB2_LIB.BASEBOARD_FAB2(SCH_1):UNNAMED_203_3D01R5F-GP_I105_2   I106 @BASEBOARD_FAB2_LIB.BASEBOARD_FAB2(SCH_1):PAGE203

CT42 CAP_0402LF-1000PF,50V,10%,X7R,A
     1 A_TSENSE_PVCCIN_CPU0 @BASEBOARD_FAB2_LIB.BASEBOARD_FAB2(SCH_1):A_TSENSE_PVCCIN_CPU0   I108 @BASEBOARD_FAB2_LIB.BASEBOARD_FAB2(SCH_1):PAGE203
     2    GND @BASEBOARD_FAB2_LIB.BASEBOARD_FAB2(SCH_1):GND   I108 @BASEBOARD_FAB2_LIB.BASEBOARD_FAB2(SCH_1):PAGE203

CT43 CAP_0402LF-1000PF,50V,10%,X7R,A
     1 A_TSENSE_PVDDQ_DEF @BASEBOARD_FAB2_LIB.BASEBOARD_FAB2(SCH_1):A_TSENSE_PVDDQ_DEF   I124 @BASEBOARD_FAB2_LIB.BASEBOARD_FAB2(SCH_1):PAGE219
     2    GND @BASEBOARD_FAB2_LIB.BASEBOARD_FAB2(SCH_1):GND   I124 @BASEBOARD_FAB2_LIB.BASEBOARD_FAB2(SCH_1):PAGE219

CT44 SC2K2P50V3KX-GP_SMD-BCG6-SC2K2A
     1 VR_PVDDQ_DEF_PH1_SW @BASEBOARD_FAB2_LIB.BASEBOARD_FAB2(SCH_1):VR_PVDDQ_DEF_PH1_SW   I127 @BASEBOARD_FAB2_LIB.BASEBOARD_FAB2(SCH_1):PAGE219
     2 UNNAMED_219_3D01R5F-GP_I126_2 @BASEBOARD_FAB2_LIB.BASEBOARD_FAB2(SCH_1):UNNAMED_219_3D01R5F-GP_I126_2   I127 @BASEBOARD_FAB2_LIB.BASEBOARD_FAB2(SCH_1):PAGE219

CT45 CAP_A_0402V-0.1UF,16V,10%,X7R,A
     1 VR_PVDDQ_DEF_AIREF1 @BASEBOARD_FAB2_LIB.BASEBOARD_FAB2(SCH_1):VR_PVDDQ_DEF_AIREF1   I116 @BASEBOARD_FAB2_LIB.BASEBOARD_FAB2(SCH_1):PAGE219
     2    GND @BASEBOARD_FAB2_LIB.BASEBOARD_FAB2(SCH_1):GND   I116 @BASEBOARD_FAB2_LIB.BASEBOARD_FAB2(SCH_1):PAGE219

CT46 CAP_A_0402V-0.1UF,16V,10%,X7R,A
     1 VR_PVDDQ_DEF_AIREF2 @BASEBOARD_FAB2_LIB.BASEBOARD_FAB2(SCH_1):VR_PVDDQ_DEF_AIREF2   I113 @BASEBOARD_FAB2_LIB.BASEBOARD_FAB2(SCH_1):PAGE219
     2    GND @BASEBOARD_FAB2_LIB.BASEBOARD_FAB2(SCH_1):GND   I113 @BASEBOARD_FAB2_LIB.BASEBOARD_FAB2(SCH_1):PAGE219

CT47 SC2K2P50V3KX-GP_SMD-BCG6-SC2K2A
     1 VR_PVDDQ_DEF_PH2_SW @BASEBOARD_FAB2_LIB.BASEBOARD_FAB2(SCH_1):VR_PVDDQ_DEF_PH2_SW   I121 @BASEBOARD_FAB2_LIB.BASEBOARD_FAB2(SCH_1):PAGE219
     2 UNNAMED_219_3D01R5F-GP_I123_2 @BASEBOARD_FAB2_LIB.BASEBOARD_FAB2(SCH_1):UNNAMED_219_3D01R5F-GP_I123_2   I121 @BASEBOARD_FAB2_LIB.BASEBOARD_FAB2(SCH_1):PAGE219

CT48 CAP_0402LF-1000PF,50V,10%,X7R,A
     1 A_TSENSE_PVDDQ_DEF @BASEBOARD_FAB2_LIB.BASEBOARD_FAB2(SCH_1):A_TSENSE_PVDDQ_DEF   I119 @BASEBOARD_FAB2_LIB.BASEBOARD_FAB2(SCH_1):PAGE219
     2    GND @BASEBOARD_FAB2_LIB.BASEBOARD_FAB2(SCH_1):GND   I119 @BASEBOARD_FAB2_LIB.BASEBOARD_FAB2(SCH_1):PAGE219

CT49 CAP_0402LF-1000PF,50V,10%,X7R,A
     1 A_TSENSE_PVDDQ_ABC @BASEBOARD_FAB2_LIB.BASEBOARD_FAB2(SCH_1):A_TSENSE_PVDDQ_ABC   I118 @BASEBOARD_FAB2_LIB.BASEBOARD_FAB2(SCH_1):PAGE216
     2    GND @BASEBOARD_FAB2_LIB.BASEBOARD_FAB2(SCH_1):GND   I118 @BASEBOARD_FAB2_LIB.BASEBOARD_FAB2(SCH_1):PAGE216

CT50 SC2K2P50V3KX-GP_SMD-BCG6-SC2K2A
     1 VR_PVDDQ_ABC_PH1_SW @BASEBOARD_FAB2_LIB.BASEBOARD_FAB2(SCH_1):VR_PVDDQ_ABC_PH1_SW   I124 @BASEBOARD_FAB2_LIB.BASEBOARD_FAB2(SCH_1):PAGE216
     2 UNNAMED_216_3D01R5F-GP_I114_2 @BASEBOARD_FAB2_LIB.BASEBOARD_FAB2(SCH_1):UNNAMED_216_3D01R5F-GP_I114_2   I124 @BASEBOARD_FAB2_LIB.BASEBOARD_FAB2(SCH_1):PAGE216

CT51 CAP_A_0402V-0.1UF,16V,10%,X7R,A
     1 VR_PVDDQ_ABC_AIREF1 @BASEBOARD_FAB2_LIB.BASEBOARD_FAB2(SCH_1):VR_PVDDQ_ABC_AIREF1   I108 @BASEBOARD_FAB2_LIB.BASEBOARD_FAB2(SCH_1):PAGE216
     2    GND @BASEBOARD_FAB2_LIB.BASEBOARD_FAB2(SCH_1):GND   I108 @BASEBOARD_FAB2_LIB.BASEBOARD_FAB2(SCH_1):PAGE216

CT52 CAP_A_0402V-0.1UF,16V,10%,X7R,A
     1 VR_PVDDQ_ABC_AIREF2 @BASEBOARD_FAB2_LIB.BASEBOARD_FAB2(SCH_1):VR_PVDDQ_ABC_AIREF2   I111 @BASEBOARD_FAB2_LIB.BASEBOARD_FAB2(SCH_1):PAGE216
     2    GND @BASEBOARD_FAB2_LIB.BASEBOARD_FAB2(SCH_1):GND   I111 @BASEBOARD_FAB2_LIB.BASEBOARD_FAB2(SCH_1):PAGE216

CT53 SC2K2P50V3KX-GP_SMD-BCG6-SC2K2A
     1 VR_PVDDQ_ABC_PH2_SW @BASEBOARD_FAB2_LIB.BASEBOARD_FAB2(SCH_1):VR_PVDDQ_ABC_PH2_SW   I119 @BASEBOARD_FAB2_LIB.BASEBOARD_FAB2(SCH_1):PAGE216
     2 UNNAMED_216_3D01R5F-GP_I123_2 @BASEBOARD_FAB2_LIB.BASEBOARD_FAB2(SCH_1):UNNAMED_216_3D01R5F-GP_I123_2   I119 @BASEBOARD_FAB2_LIB.BASEBOARD_FAB2(SCH_1):PAGE216

CT54 CAP_0402LF-1000PF,50V,10%,X7R,A
     1 A_TSENSE_PVDDQ_ABC @BASEBOARD_FAB2_LIB.BASEBOARD_FAB2(SCH_1):A_TSENSE_PVDDQ_ABC   I121 @BASEBOARD_FAB2_LIB.BASEBOARD_FAB2(SCH_1):PAGE216
     2    GND @BASEBOARD_FAB2_LIB.BASEBOARD_FAB2(SCH_1):GND   I121 @BASEBOARD_FAB2_LIB.BASEBOARD_FAB2(SCH_1):PAGE216

CT55 CAP_0402LF-1000PF,50V,10%,X7R,A
     1 A_TSENSE_PVSA_CPU1 @BASEBOARD_FAB2_LIB.BASEBOARD_FAB2(SCH_1):A_TSENSE_PVSA_CPU1    I60 @BASEBOARD_FAB2_LIB.BASEBOARD_FAB2(SCH_1):PAGE210
     2    GND @BASEBOARD_FAB2_LIB.BASEBOARD_FAB2(SCH_1):GND    I60 @BASEBOARD_FAB2_LIB.BASEBOARD_FAB2(SCH_1):PAGE210

CT56 SC2K2P50V3KX-GP_SMD-BCG6-SC2K2A
     1 VR_PVSA_CPU1_PHASE_SW @BASEBOARD_FAB2_LIB.BASEBOARD_FAB2(SCH_1):VR_PVSA_CPU1_PHASE_SW    I57 @BASEBOARD_FAB2_LIB.BASEBOARD_FAB2(SCH_1):PAGE210
     2 UNNAMED_210_3D01R5F-GP_I59_2 @BASEBOARD_FAB2_LIB.BASEBOARD_FAB2(SCH_1):UNNAMED_210_3D01R5F-GP_I59_2    I57 @BASEBOARD_FAB2_LIB.BASEBOARD_FAB2(SCH_1):PAGE210

CT57 CAP_A_0402V-0.1UF,16V,10%,X7R,A
     1 VR_PVSA_CPU1_BIREF1 @BASEBOARD_FAB2_LIB.BASEBOARD_FAB2(SCH_1):VR_PVSA_CPU1_BIREF1    I55 @BASEBOARD_FAB2_LIB.BASEBOARD_FAB2(SCH_1):PAGE210
     2    GND @BASEBOARD_FAB2_LIB.BASEBOARD_FAB2(SCH_1):GND    I55 @BASEBOARD_FAB2_LIB.BASEBOARD_FAB2(SCH_1):PAGE210

CT58 CAP_0402LF-1000PF,50V,10%,X7R,A
     1 A_TSENSE_PVSA_CPU0 @BASEBOARD_FAB2_LIB.BASEBOARD_FAB2(SCH_1):A_TSENSE_PVSA_CPU0    I65 @BASEBOARD_FAB2_LIB.BASEBOARD_FAB2(SCH_1):PAGE205
     2    GND @BASEBOARD_FAB2_LIB.BASEBOARD_FAB2(SCH_1):GND    I65 @BASEBOARD_FAB2_LIB.BASEBOARD_FAB2(SCH_1):PAGE205

CT59 SC2K2P50V3KX-GP_SMD-BCG6-SC2K2A
     1 VR_PVSA_CPU0_PHASE_SW @BASEBOARD_FAB2_LIB.BASEBOARD_FAB2(SCH_1):VR_PVSA_CPU0_PHASE_SW    I64 @BASEBOARD_FAB2_LIB.BASEBOARD_FAB2(SCH_1):PAGE205
     2 UNNAMED_205_3D01R5F-GP_I68_2 @BASEBOARD_FAB2_LIB.BASEBOARD_FAB2(SCH_1):UNNAMED_205_3D01R5F-GP_I68_2    I64 @BASEBOARD_FAB2_LIB.BASEBOARD_FAB2(SCH_1):PAGE205

CT60 CAP_A_0402V-0.1UF,16V,10%,X7R,A
     1 VR_PVSA_CPU0_BIREF1 @BASEBOARD_FAB2_LIB.BASEBOARD_FAB2(SCH_1):VR_PVSA_CPU0_BIREF1    I69 @BASEBOARD_FAB2_LIB.BASEBOARD_FAB2(SCH_1):PAGE205
     2    GND @BASEBOARD_FAB2_LIB.BASEBOARD_FAB2(SCH_1):GND    I69 @BASEBOARD_FAB2_LIB.BASEBOARD_FAB2(SCH_1):PAGE205

CT61 CAP_0402LF-1000PF,50V,10%,X7R,A
     1 A_TSENSE_PVCCIO_CPU1 @BASEBOARD_FAB2_LIB.BASEBOARD_FAB2(SCH_1):A_TSENSE_PVCCIO_CPU1   I134 @BASEBOARD_FAB2_LIB.BASEBOARD_FAB2(SCH_1):PAGE214
     2    GND @BASEBOARD_FAB2_LIB.BASEBOARD_FAB2(SCH_1):GND   I134 @BASEBOARD_FAB2_LIB.BASEBOARD_FAB2(SCH_1):PAGE214

CT62 SC2K2P50V3KX-GP_SMD-BCG6-SC2K2A
     1 VR_PVCCIO_CPU1_PH1_SW @BASEBOARD_FAB2_LIB.BASEBOARD_FAB2(SCH_1):VR_PVCCIO_CPU1_PH1_SW   I131 @BASEBOARD_FAB2_LIB.BASEBOARD_FAB2(SCH_1):PAGE214
     2 UNNAMED_214_3D01R5F-GP_I132_2 @BASEBOARD_FAB2_LIB.BASEBOARD_FAB2(SCH_1):UNNAMED_214_3D01R5F-GP_I132_2   I131 @BASEBOARD_FAB2_LIB.BASEBOARD_FAB2(SCH_1):PAGE214

CT63 CAP_A_0402V-0.1UF,16V,10%,X7R,A
     1 VR_PVCCIO_CPU1_AIREF1 @BASEBOARD_FAB2_LIB.BASEBOARD_FAB2(SCH_1):VR_PVCCIO_CPU1_AIREF1   I137 @BASEBOARD_FAB2_LIB.BASEBOARD_FAB2(SCH_1):PAGE214
     2    GND @BASEBOARD_FAB2_LIB.BASEBOARD_FAB2(SCH_1):GND   I137 @BASEBOARD_FAB2_LIB.BASEBOARD_FAB2(SCH_1):PAGE214

CT64 CAP_0402LF-1000PF,50V,10%,X7R,A
     1 A_TSENSE_PVNN_PCH_TMON @BASEBOARD_FAB2_LIB.BASEBOARD_FAB2(SCH_1):A_TSENSE_PVNN_PCH_TMON   I136 @BASEBOARD_FAB2_LIB.BASEBOARD_FAB2(SCH_1):PAGE236
     2    GND @BASEBOARD_FAB2_LIB.BASEBOARD_FAB2(SCH_1):GND   I136 @BASEBOARD_FAB2_LIB.BASEBOARD_FAB2(SCH_1):PAGE236

CT65 SC2K2P50V3KX-GP_SMD-BCG6-SC2K2A
     1 VR_PVNN_PCH_PH1_PHASE_SW @BASEBOARD_FAB2_LIB.BASEBOARD_FAB2(SCH_1):VR_PVNN_PCH_PH1_PHASE_SW   I131 @BASEBOARD_FAB2_LIB.BASEBOARD_FAB2(SCH_1):PAGE236
     2 UNNAMED_236_3D01R5F-GP_I132_2 @BASEBOARD_FAB2_LIB.BASEBOARD_FAB2(SCH_1):UNNAMED_236_3D01R5F-GP_I132_2   I131 @BASEBOARD_FAB2_LIB.BASEBOARD_FAB2(SCH_1):PAGE236

CT66 CAP_A_0402V-0.1UF,16V,10%,X7R,A
     1 VR_PVNN_PCH_AIREF1 @BASEBOARD_FAB2_LIB.BASEBOARD_FAB2(SCH_1):VR_PVNN_PCH_AIREF1   I127 @BASEBOARD_FAB2_LIB.BASEBOARD_FAB2(SCH_1):PAGE236
     2    GND @BASEBOARD_FAB2_LIB.BASEBOARD_FAB2(SCH_1):GND   I127 @BASEBOARD_FAB2_LIB.BASEBOARD_FAB2(SCH_1):PAGE236

CT67 CAP_A_0402V-0.1UF,16V,10%,X7R,A
     1 VR_P1V05_PCH_BIREF1 @BASEBOARD_FAB2_LIB.BASEBOARD_FAB2(SCH_1):VR_P1V05_PCH_BIREF1   I124 @BASEBOARD_FAB2_LIB.BASEBOARD_FAB2(SCH_1):PAGE236
     2    GND @BASEBOARD_FAB2_LIB.BASEBOARD_FAB2(SCH_1):GND   I124 @BASEBOARD_FAB2_LIB.BASEBOARD_FAB2(SCH_1):PAGE236

CT68 SC2K2P50V3KX-GP_SMD-BCG6-SC2K2A
     1 VR_P1V05_PCH_STBY_PH1_PHASE_SW @BASEBOARD_FAB2_LIB.BASEBOARD_FAB2(SCH_1):VR_P1V05_PCH_STBY_PH1_PHASE_SW   I140 @BASEBOARD_FAB2_LIB.BASEBOARD_FAB2(SCH_1):PAGE236
     2 UNNAMED_236_3D01R5F-GP_I137_2 @BASEBOARD_FAB2_LIB.BASEBOARD_FAB2(SCH_1):UNNAMED_236_3D01R5F-GP_I137_2   I140 @BASEBOARD_FAB2_LIB.BASEBOARD_FAB2(SCH_1):PAGE236

CT69 CAP_0402LF-1000PF,50V,10%,X7R,A
     1 A_TSENSE_P1V05_PCH_STBY_TMON @BASEBOARD_FAB2_LIB.BASEBOARD_FAB2(SCH_1):A_TSENSE_P1V05_PCH_STBY_TMON   I134 @BASEBOARD_FAB2_LIB.BASEBOARD_FAB2(SCH_1):PAGE236
     2    GND @BASEBOARD_FAB2_LIB.BASEBOARD_FAB2(SCH_1):GND   I134 @BASEBOARD_FAB2_LIB.BASEBOARD_FAB2(SCH_1):PAGE236

CT70 CAP_A_0402V-0.1UF,16V,10%,X7R,A
     1 VR_PVCCIO_CPU0_AIREF1 @BASEBOARD_FAB2_LIB.BASEBOARD_FAB2(SCH_1):VR_PVCCIO_CPU0_AIREF1   I106 @BASEBOARD_FAB2_LIB.BASEBOARD_FAB2(SCH_1):PAGE212
     2    GND @BASEBOARD_FAB2_LIB.BASEBOARD_FAB2(SCH_1):GND   I106 @BASEBOARD_FAB2_LIB.BASEBOARD_FAB2(SCH_1):PAGE212

CT71 CAP_0402LF-1000PF,50V,10%,X7R,A
     1 A_TSENSE_PVCCIO_CPU0 @BASEBOARD_FAB2_LIB.BASEBOARD_FAB2(SCH_1):A_TSENSE_PVCCIO_CPU0   I109 @BASEBOARD_FAB2_LIB.BASEBOARD_FAB2(SCH_1):PAGE212
     2    GND @BASEBOARD_FAB2_LIB.BASEBOARD_FAB2(SCH_1):GND   I109 @BASEBOARD_FAB2_LIB.BASEBOARD_FAB2(SCH_1):PAGE212

CT72 SC2K2P50V3KX-GP_SMD-BCG6-SC2K2A
     1 VR_PVCCIO_CPU0_PH1_SW @BASEBOARD_FAB2_LIB.BASEBOARD_FAB2(SCH_1):VR_PVCCIO_CPU0_PH1_SW   I111 @BASEBOARD_FAB2_LIB.BASEBOARD_FAB2(SCH_1):PAGE212
     2 UNNAMED_212_3D01R5F-GP_I112_2 @BASEBOARD_FAB2_LIB.BASEBOARD_FAB2(SCH_1):UNNAMED_212_3D01R5F-GP_I112_2   I111 @BASEBOARD_FAB2_LIB.BASEBOARD_FAB2(SCH_1):PAGE212

CTI7 CAP_0402LF-1000PF,50V,10%,X7R,A
     1 A_TSENSE_PVCCIN_CPU1 @BASEBOARD_FAB2_LIB.BASEBOARD_FAB2(SCH_1):A_TSENSE_PVCCIN_CPU1    I82 @BASEBOARD_FAB2_LIB.BASEBOARD_FAB2(SCH_1):PAGE208
     2    GND @BASEBOARD_FAB2_LIB.BASEBOARD_FAB2(SCH_1):GND    I82 @BASEBOARD_FAB2_LIB.BASEBOARD_FAB2(SCH_1):PAGE208

DS9A1 LED_1NC-BLUE,IC,C96565-012
     1 FP_ID_LED_P5V_STBY_N @BASEBOARD_FAB2_LIB.BASEBOARD_FAB2(SCH_1):FP_ID_LED_P5V_STBY_N    I50 @BASEBOARD_FAB2_LIB.BASEBOARD_FAB2(SCH_1):PAGE175
     2 FP_ID_LED_XOR_R @BASEBOARD_FAB2_LIB.BASEBOARD_FAB2(SCH_1):FP_ID_LED_XOR_R    I50 @BASEBOARD_FAB2_LIB.BASEBOARD_FAB2(SCH_1):PAGE175

DS9A2 LED_1NCLF-GREEN,IC,C96565-011
     1 FP_LED_HDD_ACTIVITY_AND_N @BASEBOARD_FAB2_LIB.BASEBOARD_FAB2(SCH_1):FP_LED_HDD_ACTIVITY_AND_N    I42 @BASEBOARD_FAB2_LIB.BASEBOARD_FAB2(SCH_1):PAGE177
     2 FP_LED_HDD_ACTIVITY_AND_R_N @BASEBOARD_FAB2_LIB.BASEBOARD_FAB2(SCH_1):FP_LED_HDD_ACTIVITY_AND_R_N    I42 @BASEBOARD_FAB2_LIB.BASEBOARD_FAB2(SCH_1):PAGE177

DS9A3 LED_1NCLF-YELLOW,IC,C96565-003
     1 FM_SPEAKER_PCH_N_R @BASEBOARD_FAB2_LIB.BASEBOARD_FAB2(SCH_1):FM_SPEAKER_PCH_N_R    I67 @BASEBOARD_FAB2_LIB.BASEBOARD_FAB2(SCH_1):PAGE175
     2 FM_BEEP_LED_P @BASEBOARD_FAB2_LIB.BASEBOARD_FAB2(SCH_1):FM_BEEP_LED_P    I67 @BASEBOARD_FAB2_LIB.BASEBOARD_FAB2(SCH_1):PAGE175

DS9A4 LED_A1LF-GREEN,IC,D14725-022
     2 FM_UARTSW_LSB_N @BASEBOARD_FAB2_LIB.BASEBOARD_FAB2(SCH_1):FM_UARTSW_LSB_N   I130 @BASEBOARD_FAB2_LIB.BASEBOARD_FAB2(SCH_1):PAGE158
     1 FM_UARTSW_LSB_R_N @BASEBOARD_FAB2_LIB.BASEBOARD_FAB2(SCH_1):FM_UARTSW_LSB_R_N   I130 @BASEBOARD_FAB2_LIB.BASEBOARD_FAB2(SCH_1):PAGE158

DS9A5 LED_A1LF-GREEN,IC,C97278-010
     2 FM_PWR_LED_K @BASEBOARD_FAB2_LIB.BASEBOARD_FAB2(SCH_1):FM_PWR_LED_K   I179 @BASEBOARD_FAB2_LIB.BASEBOARD_FAB2(SCH_1):PAGE119
     1 FM_PWR_LED_A @BASEBOARD_FAB2_LIB.BASEBOARD_FAB2(SCH_1):FM_PWR_LED_A   I179 @BASEBOARD_FAB2_LIB.BASEBOARD_FAB2(SCH_1):PAGE119

DS9A6 LED_A1LF-GREEN,IC,C97278-010
     2    GND @BASEBOARD_FAB2_LIB.BASEBOARD_FAB2(SCH_1):GND    I31 @BASEBOARD_FAB2_LIB.BASEBOARD_FAB2(SCH_1):PAGE177
     1 LED_P5V_STBY @BASEBOARD_FAB2_LIB.BASEBOARD_FAB2(SCH_1):LED_P5V_STBY    I31 @BASEBOARD_FAB2_LIB.BASEBOARD_FAB2(SCH_1):PAGE177

DS9A7 LED_A1LF-GREEN,IC,D14725-022
     2 FM_UARTSW_MSB_N @BASEBOARD_FAB2_LIB.BASEBOARD_FAB2(SCH_1):FM_UARTSW_MSB_N   I134 @BASEBOARD_FAB2_LIB.BASEBOARD_FAB2(SCH_1):PAGE158
     1 FM_UARTSW_MSB_R_N @BASEBOARD_FAB2_LIB.BASEBOARD_FAB2(SCH_1):FM_UARTSW_MSB_R_N   I134 @BASEBOARD_FAB2_LIB.BASEBOARD_FAB2(SCH_1):PAGE158

DS9E1 LED_A1LF-GREEN,IC,C97278-010
     2 FM_HEARTBEAT_LED_K @BASEBOARD_FAB2_LIB.BASEBOARD_FAB2(SCH_1):FM_HEARTBEAT_LED_K    I98 @BASEBOARD_FAB2_LIB.BASEBOARD_FAB2(SCH_1):PAGE149
     1 FM_HEARTBEAT_LED_A @BASEBOARD_FAB2_LIB.BASEBOARD_FAB2(SCH_1):FM_HEARTBEAT_LED_A    I98 @BASEBOARD_FAB2_LIB.BASEBOARD_FAB2(SCH_1):PAGE149

DS9F1 LED_A1-RED,IC,D14725-005
     2 FM_RED_LED_CATHODE @BASEBOARD_FAB2_LIB.BASEBOARD_FAB2(SCH_1):FM_RED_LED_CATHODE    I71 @BASEBOARD_FAB2_LIB.BASEBOARD_FAB2(SCH_1):PAGE177
     1 FM_RED_LED_ANODE @BASEBOARD_FAB2_LIB.BASEBOARD_FAB2(SCH_1):FM_RED_LED_ANODE    I71 @BASEBOARD_FAB2_LIB.BASEBOARD_FAB2(SCH_1):PAGE177

EU1A1 IR354XX_SM-IR35411,IC,H73688-0A
    33 VR_PVDDQ_KLM_PH2_BOOT_R @BASEBOARD_FAB2_LIB.BASEBOARD_FAB2(SCH_1):VR_PVDDQ_KLM_PH2_BOOT_R   I102 @BASEBOARD_FAB2_LIB.BASEBOARD_FAB2(SCH_1):PAGE227
    35 P5V_STBY @BASEBOARD_FAB2_LIB.BASEBOARD_FAB2(SCH_1):P5V_STBY   I102 @BASEBOARD_FAB2_LIB.BASEBOARD_FAB2(SCH_1):PAGE227
    41 TP_PVDDQ_KLM_PH2_GL_1 @BASEBOARD_FAB2_LIB.BASEBOARD_FAB2(SCH_1):TP_PVDDQ_KLM_PH2_GL_1   I102 @BASEBOARD_FAB2_LIB.BASEBOARD_FAB2(SCH_1):PAGE227
     6 TP_PVDDQ_KLM_PH2_GL_0 @BASEBOARD_FAB2_LIB.BASEBOARD_FAB2(SCH_1):TP_PVDDQ_KLM_PH2_GL_0   I102 @BASEBOARD_FAB2_LIB.BASEBOARD_FAB2(SCH_1):PAGE227
    38 ISENSE_PVDDQ_KLM_PH2_IMON @BASEBOARD_FAB2_LIB.BASEBOARD_FAB2(SCH_1):ISENSE_PVDDQ_KLM_PH2_IMON   I102 @BASEBOARD_FAB2_LIB.BASEBOARD_FAB2(SCH_1):PAGE227
     2    GND @BASEBOARD_FAB2_LIB.BASEBOARD_FAB2(SCH_1):GND   I102 @BASEBOARD_FAB2_LIB.BASEBOARD_FAB2(SCH_1):PAGE227
    31 NC_PVDDQ_KLM_PH2_P31 @BASEBOARD_FAB2_LIB.BASEBOARD_FAB2(SCH_1):NC_PVDDQ_KLM_PH2_P31   I102 @BASEBOARD_FAB2_LIB.BASEBOARD_FAB2(SCH_1):PAGE227
    37 VR_PVDDQ_KLM_PH2_OCSET @BASEBOARD_FAB2_LIB.BASEBOARD_FAB2(SCH_1):VR_PVDDQ_KLM_PH2_OCSET   I102 @BASEBOARD_FAB2_LIB.BASEBOARD_FAB2(SCH_1):PAGE227
    40    GND @BASEBOARD_FAB2_LIB.BASEBOARD_FAB2(SCH_1):GND   I102 @BASEBOARD_FAB2_LIB.BASEBOARD_FAB2(SCH_1):PAGE227
     7    GND @BASEBOARD_FAB2_LIB.BASEBOARD_FAB2(SCH_1):GND   I102 @BASEBOARD_FAB2_LIB.BASEBOARD_FAB2(SCH_1):PAGE227
     5    GND @BASEBOARD_FAB2_LIB.BASEBOARD_FAB2(SCH_1):GND   I102 @BASEBOARD_FAB2_LIB.BASEBOARD_FAB2(SCH_1):PAGE227
    32 VR_PVDDQ_KLM_PH2_PHASE @BASEBOARD_FAB2_LIB.BASEBOARD_FAB2(SCH_1):VR_PVDDQ_KLM_PH2_PHASE   I102 @BASEBOARD_FAB2_LIB.BASEBOARD_FAB2(SCH_1):PAGE227
    34 VR_PVDDQ_KLM_PWM2 @BASEBOARD_FAB2_LIB.BASEBOARD_FAB2(SCH_1):VR_PVDDQ_KLM_PWM2   I102 @BASEBOARD_FAB2_LIB.BASEBOARD_FAB2(SCH_1):PAGE227
    39 VR_PVDDQ_KLM_AIREF2 @BASEBOARD_FAB2_LIB.BASEBOARD_FAB2(SCH_1):VR_PVDDQ_KLM_AIREF2   I102 @BASEBOARD_FAB2_LIB.BASEBOARD_FAB2(SCH_1):PAGE227
    10 VR_PVDDQ_KLM_PH2_SW @BASEBOARD_FAB2_LIB.BASEBOARD_FAB2(SCH_1):VR_PVDDQ_KLM_PH2_SW   I102 @BASEBOARD_FAB2_LIB.BASEBOARD_FAB2(SCH_1):PAGE227
    36 A_TSENSE_PVDDQ_KLM @BASEBOARD_FAB2_LIB.BASEBOARD_FAB2(SCH_1):A_TSENSE_PVDDQ_KLM   I102 @BASEBOARD_FAB2_LIB.BASEBOARD_FAB2(SCH_1):PAGE227
     3 VR_PVDDQ_KLM_PH2_VCIN @BASEBOARD_FAB2_LIB.BASEBOARD_FAB2(SCH_1):VR_PVDDQ_KLM_PH2_VCIN   I102 @BASEBOARD_FAB2_LIB.BASEBOARD_FAB2(SCH_1):PAGE227
     4 P5V_STBY @BASEBOARD_FAB2_LIB.BASEBOARD_FAB2(SCH_1):P5V_STBY   I102 @BASEBOARD_FAB2_LIB.BASEBOARD_FAB2(SCH_1):PAGE227
    30 VR_FET_SW_P12V_STBY_PVDDQ_KLM @BASEBOARD_FAB2_LIB.BASEBOARD_FAB2(SCH_1):VR_FET_SW_P12V_STBY_PVDDQ_KLM   I102 @BASEBOARD_FAB2_LIB.BASEBOARD_FAB2(SCH_1):PAGE227
    25 VR_FET_SW_P12V_STBY_PVDDQ_KLM @BASEBOARD_FAB2_LIB.BASEBOARD_FAB2(SCH_1):VR_FET_SW_P12V_STBY_PVDDQ_KLM   I102 @BASEBOARD_FAB2_LIB.BASEBOARD_FAB2(SCH_1):PAGE227
     1 PVDDQ_KLM @BASEBOARD_FAB2_LIB.BASEBOARD_FAB2(SCH_1):PVDDQ_KLM   I102 @BASEBOARD_FAB2_LIB.BASEBOARD_FAB2(SCH_1):PAGE227

EU1A2 IR354XX_SM-IR35411,IC,H73688-0A
    33 VR_PVDDQ_KLM_PH1_BOOT_R @BASEBOARD_FAB2_LIB.BASEBOARD_FAB2(SCH_1):VR_PVDDQ_KLM_PH1_BOOT_R   I101 @BASEBOARD_FAB2_LIB.BASEBOARD_FAB2(SCH_1):PAGE227
    35 P5V_STBY @BASEBOARD_FAB2_LIB.BASEBOARD_FAB2(SCH_1):P5V_STBY   I101 @BASEBOARD_FAB2_LIB.BASEBOARD_FAB2(SCH_1):PAGE227
    41 TP_PVDDQ_KLM_PH1_GL_1 @BASEBOARD_FAB2_LIB.BASEBOARD_FAB2(SCH_1):TP_PVDDQ_KLM_PH1_GL_1   I101 @BASEBOARD_FAB2_LIB.BASEBOARD_FAB2(SCH_1):PAGE227
     6 TP_PVDDQ_KLM_PH1_GL_0 @BASEBOARD_FAB2_LIB.BASEBOARD_FAB2(SCH_1):TP_PVDDQ_KLM_PH1_GL_0   I101 @BASEBOARD_FAB2_LIB.BASEBOARD_FAB2(SCH_1):PAGE227
    38 ISENSE_PVDDQ_KLM_PH1_IMON @BASEBOARD_FAB2_LIB.BASEBOARD_FAB2(SCH_1):ISENSE_PVDDQ_KLM_PH1_IMON   I101 @BASEBOARD_FAB2_LIB.BASEBOARD_FAB2(SCH_1):PAGE227
     2    GND @BASEBOARD_FAB2_LIB.BASEBOARD_FAB2(SCH_1):GND   I101 @BASEBOARD_FAB2_LIB.BASEBOARD_FAB2(SCH_1):PAGE227
    31 NC_PVDDQ_KLM_PH1_P31 @BASEBOARD_FAB2_LIB.BASEBOARD_FAB2(SCH_1):NC_PVDDQ_KLM_PH1_P31   I101 @BASEBOARD_FAB2_LIB.BASEBOARD_FAB2(SCH_1):PAGE227
    37 VR_PVDDQ_KLM_PH1_OCSET @BASEBOARD_FAB2_LIB.BASEBOARD_FAB2(SCH_1):VR_PVDDQ_KLM_PH1_OCSET   I101 @BASEBOARD_FAB2_LIB.BASEBOARD_FAB2(SCH_1):PAGE227
    40    GND @BASEBOARD_FAB2_LIB.BASEBOARD_FAB2(SCH_1):GND   I101 @BASEBOARD_FAB2_LIB.BASEBOARD_FAB2(SCH_1):PAGE227
     7    GND @BASEBOARD_FAB2_LIB.BASEBOARD_FAB2(SCH_1):GND   I101 @BASEBOARD_FAB2_LIB.BASEBOARD_FAB2(SCH_1):PAGE227
     5    GND @BASEBOARD_FAB2_LIB.BASEBOARD_FAB2(SCH_1):GND   I101 @BASEBOARD_FAB2_LIB.BASEBOARD_FAB2(SCH_1):PAGE227
    32 VR_PVDDQ_KLM_PH1_PHASE @BASEBOARD_FAB2_LIB.BASEBOARD_FAB2(SCH_1):VR_PVDDQ_KLM_PH1_PHASE   I101 @BASEBOARD_FAB2_LIB.BASEBOARD_FAB2(SCH_1):PAGE227
    34 VR_PVDDQ_KLM_PWM1 @BASEBOARD_FAB2_LIB.BASEBOARD_FAB2(SCH_1):VR_PVDDQ_KLM_PWM1   I101 @BASEBOARD_FAB2_LIB.BASEBOARD_FAB2(SCH_1):PAGE227
    39 VR_PVDDQ_KLM_AIREF1 @BASEBOARD_FAB2_LIB.BASEBOARD_FAB2(SCH_1):VR_PVDDQ_KLM_AIREF1   I101 @BASEBOARD_FAB2_LIB.BASEBOARD_FAB2(SCH_1):PAGE227
    10 VR_PVDDQ_KLM_PH1_SW @BASEBOARD_FAB2_LIB.BASEBOARD_FAB2(SCH_1):VR_PVDDQ_KLM_PH1_SW   I101 @BASEBOARD_FAB2_LIB.BASEBOARD_FAB2(SCH_1):PAGE227
    36 A_TSENSE_PVDDQ_KLM @BASEBOARD_FAB2_LIB.BASEBOARD_FAB2(SCH_1):A_TSENSE_PVDDQ_KLM   I101 @BASEBOARD_FAB2_LIB.BASEBOARD_FAB2(SCH_1):PAGE227
     3 VR_PVDDQ_KLM_PH1_VCIN @BASEBOARD_FAB2_LIB.BASEBOARD_FAB2(SCH_1):VR_PVDDQ_KLM_PH1_VCIN   I101 @BASEBOARD_FAB2_LIB.BASEBOARD_FAB2(SCH_1):PAGE227
     4 P5V_STBY @BASEBOARD_FAB2_LIB.BASEBOARD_FAB2(SCH_1):P5V_STBY   I101 @BASEBOARD_FAB2_LIB.BASEBOARD_FAB2(SCH_1):PAGE227
    30 VR_FET_SW_P12V_STBY_PVDDQ_KLM @BASEBOARD_FAB2_LIB.BASEBOARD_FAB2(SCH_1):VR_FET_SW_P12V_STBY_PVDDQ_KLM   I101 @BASEBOARD_FAB2_LIB.BASEBOARD_FAB2(SCH_1):PAGE227
    25 VR_FET_SW_P12V_STBY_PVDDQ_KLM @BASEBOARD_FAB2_LIB.BASEBOARD_FAB2(SCH_1):VR_FET_SW_P12V_STBY_PVDDQ_KLM   I101 @BASEBOARD_FAB2_LIB.BASEBOARD_FAB2(SCH_1):PAGE227
     1 PVDDQ_KLM @BASEBOARD_FAB2_LIB.BASEBOARD_FAB2(SCH_1):PVDDQ_KLM   I101 @BASEBOARD_FAB2_LIB.BASEBOARD_FAB2(SCH_1):PAGE227

EU1B1 PXM1310B_QFN-IC,H89186-001
     1 TP_PVDDQ_KLM_BPWM1 @BASEBOARD_FAB2_LIB.BASEBOARD_FAB2(SCH_1):TP_PVDDQ_KLM_BPWM1    I90 @BASEBOARD_FAB2_LIB.BASEBOARD_FAB2(SCH_1):PAGE226
     2 NC_PVDDQ_KLM_DNC0 @BASEBOARD_FAB2_LIB.BASEBOARD_FAB2(SCH_1):NC_PVDDQ_KLM_DNC0    I90 @BASEBOARD_FAB2_LIB.BASEBOARD_FAB2(SCH_1):PAGE226
     3 NC_PVDDQ_KLM_PWM3 @BASEBOARD_FAB2_LIB.BASEBOARD_FAB2(SCH_1):NC_PVDDQ_KLM_PWM3    I90 @BASEBOARD_FAB2_LIB.BASEBOARD_FAB2(SCH_1):PAGE226
     4 VR_PVDDQ_KLM_PWM2 @BASEBOARD_FAB2_LIB.BASEBOARD_FAB2(SCH_1):VR_PVDDQ_KLM_PWM2    I90 @BASEBOARD_FAB2_LIB.BASEBOARD_FAB2(SCH_1):PAGE226
     5 VR_PVDDQ_KLM_PWM1 @BASEBOARD_FAB2_LIB.BASEBOARD_FAB2(SCH_1):VR_PVDDQ_KLM_PWM1    I90 @BASEBOARD_FAB2_LIB.BASEBOARD_FAB2(SCH_1):PAGE226
     6 SMB_VR_SDA_VDDQ_KLM @BASEBOARD_FAB2_LIB.BASEBOARD_FAB2(SCH_1):SMB_VR_SDA_VDDQ_KLM    I90 @BASEBOARD_FAB2_LIB.BASEBOARD_FAB2(SCH_1):PAGE226
     7 SMB_VR_SCL_VDDQ_KLM @BASEBOARD_FAB2_LIB.BASEBOARD_FAB2(SCH_1):SMB_VR_SCL_VDDQ_KLM    I90 @BASEBOARD_FAB2_LIB.BASEBOARD_FAB2(SCH_1):PAGE226
     8 TP_PVDDQ_KLM_RESET_N @BASEBOARD_FAB2_LIB.BASEBOARD_FAB2(SCH_1):TP_PVDDQ_KLM_RESET_N    I90 @BASEBOARD_FAB2_LIB.BASEBOARD_FAB2(SCH_1):PAGE226
     9 PWRGD_PVDDQ_KLM_R @BASEBOARD_FAB2_LIB.BASEBOARD_FAB2(SCH_1):PWRGD_PVDDQ_KLM_R    I90 @BASEBOARD_FAB2_LIB.BASEBOARD_FAB2(SCH_1):PAGE226
    10 VR_PVDDQ_KLM_VREN @BASEBOARD_FAB2_LIB.BASEBOARD_FAB2(SCH_1):VR_PVDDQ_KLM_VREN    I90 @BASEBOARD_FAB2_LIB.BASEBOARD_FAB2(SCH_1):PAGE226
    11 IRQ_PVDDQ_KLM_VRHOT_LVT3_R_N @BASEBOARD_FAB2_LIB.BASEBOARD_FAB2(SCH_1):IRQ_PVDDQ_KLM_VRHOT_LVT3_R_N    I90 @BASEBOARD_FAB2_LIB.BASEBOARD_FAB2(SCH_1):PAGE226
    12 NC_PVDDQ_KLM_PINALRT_N @BASEBOARD_FAB2_LIB.BASEBOARD_FAB2(SCH_1):NC_PVDDQ_KLM_PINALRT_N    I90 @BASEBOARD_FAB2_LIB.BASEBOARD_FAB2(SCH_1):PAGE226
    13 PU_VR_PVDDQ_KLM_FAULT1 @BASEBOARD_FAB2_LIB.BASEBOARD_FAB2(SCH_1):PU_VR_PVDDQ_KLM_FAULT1    I90 @BASEBOARD_FAB2_LIB.BASEBOARD_FAB2(SCH_1):PAGE226
    14 NC_PVDDQ_KLM_GP1 @BASEBOARD_FAB2_LIB.BASEBOARD_FAB2(SCH_1):NC_PVDDQ_KLM_GP1    I90 @BASEBOARD_FAB2_LIB.BASEBOARD_FAB2(SCH_1):PAGE226
    15 SVID_CLK_PVDDQ_KLM @BASEBOARD_FAB2_LIB.BASEBOARD_FAB2(SCH_1):SVID_CLK_PVDDQ_KLM    I90 @BASEBOARD_FAB2_LIB.BASEBOARD_FAB2(SCH_1):PAGE226
    16 SVID_VDIO_PVDDQ_KLM @BASEBOARD_FAB2_LIB.BASEBOARD_FAB2(SCH_1):SVID_VDIO_PVDDQ_KLM    I90 @BASEBOARD_FAB2_LIB.BASEBOARD_FAB2(SCH_1):PAGE226
    17 SVID_ALERT_PVDDQ_KLM @BASEBOARD_FAB2_LIB.BASEBOARD_FAB2(SCH_1):SVID_ALERT_PVDDQ_KLM    I90 @BASEBOARD_FAB2_LIB.BASEBOARD_FAB2(SCH_1):PAGE226
    18 NC_PVDDQ_KLM_GP0 @BASEBOARD_FAB2_LIB.BASEBOARD_FAB2(SCH_1):NC_PVDDQ_KLM_GP0    I90 @BASEBOARD_FAB2_LIB.BASEBOARD_FAB2(SCH_1):PAGE226
    19 VR_PVDDQ_KLM_AVSP @BASEBOARD_FAB2_LIB.BASEBOARD_FAB2(SCH_1):VR_PVDDQ_KLM_AVSP    I90 @BASEBOARD_FAB2_LIB.BASEBOARD_FAB2(SCH_1):PAGE226
    20 VSENSE_PVDDQ_KLM_N @BASEBOARD_FAB2_LIB.BASEBOARD_FAB2(SCH_1):VSENSE_PVDDQ_KLM_N    I90 @BASEBOARD_FAB2_LIB.BASEBOARD_FAB2(SCH_1):PAGE226
    21 VR_PVDDQ_KLM_AIREF1 @BASEBOARD_FAB2_LIB.BASEBOARD_FAB2(SCH_1):VR_PVDDQ_KLM_AIREF1    I90 @BASEBOARD_FAB2_LIB.BASEBOARD_FAB2(SCH_1):PAGE226
    22 ISENSE_PVDDQ_KLM_PH1_IMON @BASEBOARD_FAB2_LIB.BASEBOARD_FAB2(SCH_1):ISENSE_PVDDQ_KLM_PH1_IMON    I90 @BASEBOARD_FAB2_LIB.BASEBOARD_FAB2(SCH_1):PAGE226
    23 VR_PVDDQ_KLM_AIREF2 @BASEBOARD_FAB2_LIB.BASEBOARD_FAB2(SCH_1):VR_PVDDQ_KLM_AIREF2    I90 @BASEBOARD_FAB2_LIB.BASEBOARD_FAB2(SCH_1):PAGE226
    24 ISENSE_PVDDQ_KLM_PH2_IMON @BASEBOARD_FAB2_LIB.BASEBOARD_FAB2(SCH_1):ISENSE_PVDDQ_KLM_PH2_IMON    I90 @BASEBOARD_FAB2_LIB.BASEBOARD_FAB2(SCH_1):PAGE226
    25 TP_PVDDQ_KLM_PH3_IMON_REF @BASEBOARD_FAB2_LIB.BASEBOARD_FAB2(SCH_1):TP_PVDDQ_KLM_PH3_IMON_REF    I90 @BASEBOARD_FAB2_LIB.BASEBOARD_FAB2(SCH_1):PAGE226
    26 TP_PVDDQ_KLM_PH3_IMON @BASEBOARD_FAB2_LIB.BASEBOARD_FAB2(SCH_1):TP_PVDDQ_KLM_PH3_IMON    I90 @BASEBOARD_FAB2_LIB.BASEBOARD_FAB2(SCH_1):PAGE226
    27    GND @BASEBOARD_FAB2_LIB.BASEBOARD_FAB2(SCH_1):GND    I90 @BASEBOARD_FAB2_LIB.BASEBOARD_FAB2(SCH_1):PAGE226
    28 NC_PVDDQ_KLM_DNC1 @BASEBOARD_FAB2_LIB.BASEBOARD_FAB2(SCH_1):NC_PVDDQ_KLM_DNC1    I90 @BASEBOARD_FAB2_LIB.BASEBOARD_FAB2(SCH_1):PAGE226
    29 TP_PVDDQ_KLM_BVSEN @BASEBOARD_FAB2_LIB.BASEBOARD_FAB2(SCH_1):TP_PVDDQ_KLM_BVSEN    I90 @BASEBOARD_FAB2_LIB.BASEBOARD_FAB2(SCH_1):PAGE226
    30 TP_PVDDQ_KLM_BVREF @BASEBOARD_FAB2_LIB.BASEBOARD_FAB2(SCH_1):TP_PVDDQ_KLM_BVREF    I90 @BASEBOARD_FAB2_LIB.BASEBOARD_FAB2(SCH_1):PAGE226
    31 TP_PVDDQ_KLM_BREF1 @BASEBOARD_FAB2_LIB.BASEBOARD_FAB2(SCH_1):TP_PVDDQ_KLM_BREF1    I90 @BASEBOARD_FAB2_LIB.BASEBOARD_FAB2(SCH_1):PAGE226
    32    GND @BASEBOARD_FAB2_LIB.BASEBOARD_FAB2(SCH_1):GND    I90 @BASEBOARD_FAB2_LIB.BASEBOARD_FAB2(SCH_1):PAGE226
    33 VR_PVDDQ_KLM_XADDR2 @BASEBOARD_FAB2_LIB.BASEBOARD_FAB2(SCH_1):VR_PVDDQ_KLM_XADDR2    I90 @BASEBOARD_FAB2_LIB.BASEBOARD_FAB2(SCH_1):PAGE226
    34 TP_PVDDQ_KLM_BTSEN @BASEBOARD_FAB2_LIB.BASEBOARD_FAB2(SCH_1):TP_PVDDQ_KLM_BTSEN    I90 @BASEBOARD_FAB2_LIB.BASEBOARD_FAB2(SCH_1):PAGE226
    35 A_TSENSE_PVDDQ_KLM @BASEBOARD_FAB2_LIB.BASEBOARD_FAB2(SCH_1):A_TSENSE_PVDDQ_KLM    I90 @BASEBOARD_FAB2_LIB.BASEBOARD_FAB2(SCH_1):PAGE226
    36 VR_PVDDQ_KLM_XADDR1 @BASEBOARD_FAB2_LIB.BASEBOARD_FAB2(SCH_1):VR_PVDDQ_KLM_XADDR1    I90 @BASEBOARD_FAB2_LIB.BASEBOARD_FAB2(SCH_1):PAGE226
    37 VR_PVDDQ_KLM_VINSEN @BASEBOARD_FAB2_LIB.BASEBOARD_FAB2(SCH_1):VR_PVDDQ_KLM_VINSEN    I90 @BASEBOARD_FAB2_LIB.BASEBOARD_FAB2(SCH_1):PAGE226
    38 VR_PVDDQ_KLM_AIINSEN @BASEBOARD_FAB2_LIB.BASEBOARD_FAB2(SCH_1):VR_PVDDQ_KLM_AIINSEN    I90 @BASEBOARD_FAB2_LIB.BASEBOARD_FAB2(SCH_1):PAGE226
    39 VR_PVDDQ_KLM_VDD @BASEBOARD_FAB2_LIB.BASEBOARD_FAB2(SCH_1):VR_PVDDQ_KLM_VDD    I90 @BASEBOARD_FAB2_LIB.BASEBOARD_FAB2(SCH_1):PAGE226
    40 VR_PVDDQ_KLM_VD12 @BASEBOARD_FAB2_LIB.BASEBOARD_FAB2(SCH_1):VR_PVDDQ_KLM_VD12    I90 @BASEBOARD_FAB2_LIB.BASEBOARD_FAB2(SCH_1):PAGE226
    41    GND @BASEBOARD_FAB2_LIB.BASEBOARD_FAB2(SCH_1):GND    I90 @BASEBOARD_FAB2_LIB.BASEBOARD_FAB2(SCH_1):PAGE226

EU1C1 IR354XX_SM-IR35412,IC,H73684-0A
    33 VR_PVSA_CPU1_BOOT_R @BASEBOARD_FAB2_LIB.BASEBOARD_FAB2(SCH_1):VR_PVSA_CPU1_BOOT_R    I51 @BASEBOARD_FAB2_LIB.BASEBOARD_FAB2(SCH_1):PAGE210
    35 P5V_STBY @BASEBOARD_FAB2_LIB.BASEBOARD_FAB2(SCH_1):P5V_STBY    I51 @BASEBOARD_FAB2_LIB.BASEBOARD_FAB2(SCH_1):PAGE210
    41 TP_PVSA_CPU1_GL_1 @BASEBOARD_FAB2_LIB.BASEBOARD_FAB2(SCH_1):TP_PVSA_CPU1_GL_1    I51 @BASEBOARD_FAB2_LIB.BASEBOARD_FAB2(SCH_1):PAGE210
     6 TP_PVSA_CPU1_GL_0 @BASEBOARD_FAB2_LIB.BASEBOARD_FAB2(SCH_1):TP_PVSA_CPU1_GL_0    I51 @BASEBOARD_FAB2_LIB.BASEBOARD_FAB2(SCH_1):PAGE210
    38 ISENSE_PVSA_CPU1_IMON @BASEBOARD_FAB2_LIB.BASEBOARD_FAB2(SCH_1):ISENSE_PVSA_CPU1_IMON    I51 @BASEBOARD_FAB2_LIB.BASEBOARD_FAB2(SCH_1):PAGE210
     2    GND @BASEBOARD_FAB2_LIB.BASEBOARD_FAB2(SCH_1):GND    I51 @BASEBOARD_FAB2_LIB.BASEBOARD_FAB2(SCH_1):PAGE210
    31 NC_PVSA_CPU1_P31 @BASEBOARD_FAB2_LIB.BASEBOARD_FAB2(SCH_1):NC_PVSA_CPU1_P31    I51 @BASEBOARD_FAB2_LIB.BASEBOARD_FAB2(SCH_1):PAGE210
    37 VR_PVSA_CPU1_OCSET @BASEBOARD_FAB2_LIB.BASEBOARD_FAB2(SCH_1):VR_PVSA_CPU1_OCSET    I51 @BASEBOARD_FAB2_LIB.BASEBOARD_FAB2(SCH_1):PAGE210
    40    GND @BASEBOARD_FAB2_LIB.BASEBOARD_FAB2(SCH_1):GND    I51 @BASEBOARD_FAB2_LIB.BASEBOARD_FAB2(SCH_1):PAGE210
     7    GND @BASEBOARD_FAB2_LIB.BASEBOARD_FAB2(SCH_1):GND    I51 @BASEBOARD_FAB2_LIB.BASEBOARD_FAB2(SCH_1):PAGE210
     5    GND @BASEBOARD_FAB2_LIB.BASEBOARD_FAB2(SCH_1):GND    I51 @BASEBOARD_FAB2_LIB.BASEBOARD_FAB2(SCH_1):PAGE210
    32 VR_PVSA_CPU1_PHASE @BASEBOARD_FAB2_LIB.BASEBOARD_FAB2(SCH_1):VR_PVSA_CPU1_PHASE    I51 @BASEBOARD_FAB2_LIB.BASEBOARD_FAB2(SCH_1):PAGE210
    34 VR_PVSA_CPU1_PWM @BASEBOARD_FAB2_LIB.BASEBOARD_FAB2(SCH_1):VR_PVSA_CPU1_PWM    I51 @BASEBOARD_FAB2_LIB.BASEBOARD_FAB2(SCH_1):PAGE210
    39 VR_PVSA_CPU1_BIREF1 @BASEBOARD_FAB2_LIB.BASEBOARD_FAB2(SCH_1):VR_PVSA_CPU1_BIREF1    I51 @BASEBOARD_FAB2_LIB.BASEBOARD_FAB2(SCH_1):PAGE210
    10 VR_PVSA_CPU1_PHASE_SW @BASEBOARD_FAB2_LIB.BASEBOARD_FAB2(SCH_1):VR_PVSA_CPU1_PHASE_SW    I51 @BASEBOARD_FAB2_LIB.BASEBOARD_FAB2(SCH_1):PAGE210
    36 A_TSENSE_PVSA_CPU1 @BASEBOARD_FAB2_LIB.BASEBOARD_FAB2(SCH_1):A_TSENSE_PVSA_CPU1    I51 @BASEBOARD_FAB2_LIB.BASEBOARD_FAB2(SCH_1):PAGE210
     3 VR_PVSA_CPU1_VCIN @BASEBOARD_FAB2_LIB.BASEBOARD_FAB2(SCH_1):VR_PVSA_CPU1_VCIN    I51 @BASEBOARD_FAB2_LIB.BASEBOARD_FAB2(SCH_1):PAGE210
     4 P5V_STBY @BASEBOARD_FAB2_LIB.BASEBOARD_FAB2(SCH_1):P5V_STBY    I51 @BASEBOARD_FAB2_LIB.BASEBOARD_FAB2(SCH_1):PAGE210
    30 VR_FET_SW_P12V_STBY_PVCCIN_CPU1 @BASEBOARD_FAB2_LIB.BASEBOARD_FAB2(SCH_1):VR_FET_SW_P12V_STBY_PVCCIN_CPU1    I51 @BASEBOARD_FAB2_LIB.BASEBOARD_FAB2(SCH_1):PAGE210
    25 VR_FET_SW_P12V_STBY_PVCCIN_CPU1 @BASEBOARD_FAB2_LIB.BASEBOARD_FAB2(SCH_1):VR_FET_SW_P12V_STBY_PVCCIN_CPU1    I51 @BASEBOARD_FAB2_LIB.BASEBOARD_FAB2(SCH_1):PAGE210
     1 PVSA_CPU1 @BASEBOARD_FAB2_LIB.BASEBOARD_FAB2(SCH_1):PVSA_CPU1    I51 @BASEBOARD_FAB2_LIB.BASEBOARD_FAB2(SCH_1):PAGE210

EU1C2 PXE1610B_QFN-IC,H79206-001
     1 VR_PVSA_CPU1_PWM @BASEBOARD_FAB2_LIB.BASEBOARD_FAB2(SCH_1):VR_PVSA_CPU1_PWM   I130 @BASEBOARD_FAB2_LIB.BASEBOARD_FAB2(SCH_1):PAGE206
     2 TP_PVCCIN_CPU1_APWM6 @BASEBOARD_FAB2_LIB.BASEBOARD_FAB2(SCH_1):TP_PVCCIN_CPU1_APWM6   I130 @BASEBOARD_FAB2_LIB.BASEBOARD_FAB2(SCH_1):PAGE206
     3 VR_PVCCIN_CPU1_PWM5 @BASEBOARD_FAB2_LIB.BASEBOARD_FAB2(SCH_1):VR_PVCCIN_CPU1_PWM5   I130 @BASEBOARD_FAB2_LIB.BASEBOARD_FAB2(SCH_1):PAGE206
     4 VR_PVCCIN_CPU1_PWM4 @BASEBOARD_FAB2_LIB.BASEBOARD_FAB2(SCH_1):VR_PVCCIN_CPU1_PWM4   I130 @BASEBOARD_FAB2_LIB.BASEBOARD_FAB2(SCH_1):PAGE206
     5 VR_PVCCIN_CPU1_PWM3 @BASEBOARD_FAB2_LIB.BASEBOARD_FAB2(SCH_1):VR_PVCCIN_CPU1_PWM3   I130 @BASEBOARD_FAB2_LIB.BASEBOARD_FAB2(SCH_1):PAGE206
     6 VR_PVCCIN_CPU1_PWM2 @BASEBOARD_FAB2_LIB.BASEBOARD_FAB2(SCH_1):VR_PVCCIN_CPU1_PWM2   I130 @BASEBOARD_FAB2_LIB.BASEBOARD_FAB2(SCH_1):PAGE206
     7 VR_PVCCIN_CPU1_PWM1 @BASEBOARD_FAB2_LIB.BASEBOARD_FAB2(SCH_1):VR_PVCCIN_CPU1_PWM1   I130 @BASEBOARD_FAB2_LIB.BASEBOARD_FAB2(SCH_1):PAGE206
     8 SMB_VR_SDA_R1 @BASEBOARD_FAB2_LIB.BASEBOARD_FAB2(SCH_1):SMB_VR_SDA_R1   I130 @BASEBOARD_FAB2_LIB.BASEBOARD_FAB2(SCH_1):PAGE206
     9 SMB_VR_SCL_R1 @BASEBOARD_FAB2_LIB.BASEBOARD_FAB2(SCH_1):SMB_VR_SCL_R1   I130 @BASEBOARD_FAB2_LIB.BASEBOARD_FAB2(SCH_1):PAGE206
    10 TP_PVCCIN_CPU1_RESET_N @BASEBOARD_FAB2_LIB.BASEBOARD_FAB2(SCH_1):TP_PVCCIN_CPU1_RESET_N   I130 @BASEBOARD_FAB2_LIB.BASEBOARD_FAB2(SCH_1):PAGE206
    11 VR_VRRDY_PVCCIN_CPU1 @BASEBOARD_FAB2_LIB.BASEBOARD_FAB2(SCH_1):VR_VRRDY_PVCCIN_CPU1   I130 @BASEBOARD_FAB2_LIB.BASEBOARD_FAB2(SCH_1):PAGE206
    12 VR_PVCCIN_CPU1_VREN @BASEBOARD_FAB2_LIB.BASEBOARD_FAB2(SCH_1):VR_PVCCIN_CPU1_VREN   I130 @BASEBOARD_FAB2_LIB.BASEBOARD_FAB2(SCH_1):PAGE206
    13 IRQ_PVCCIN_CPU1_VRHOT_LVC3_R_N @BASEBOARD_FAB2_LIB.BASEBOARD_FAB2(SCH_1):IRQ_PVCCIN_CPU1_VRHOT_LVC3_R_N   I130 @BASEBOARD_FAB2_LIB.BASEBOARD_FAB2(SCH_1):PAGE206
    14 FM_PVCCIN_CPU1_PWR_IN_ALERT_N @BASEBOARD_FAB2_LIB.BASEBOARD_FAB2(SCH_1):FM_PVCCIN_CPU1_PWR_IN_ALERT_N   I130 @BASEBOARD_FAB2_LIB.BASEBOARD_FAB2(SCH_1):PAGE206
    15 PWRGD_PVSA_CPU1_R @BASEBOARD_FAB2_LIB.BASEBOARD_FAB2(SCH_1):PWRGD_PVSA_CPU1_R   I130 @BASEBOARD_FAB2_LIB.BASEBOARD_FAB2(SCH_1):PAGE206
    16 TP_PVCCIN_CPU1_GP1 @BASEBOARD_FAB2_LIB.BASEBOARD_FAB2(SCH_1):TP_PVCCIN_CPU1_GP1   I130 @BASEBOARD_FAB2_LIB.BASEBOARD_FAB2(SCH_1):PAGE206
    17 SVID_VCLK_PVCCIN_CPU1 @BASEBOARD_FAB2_LIB.BASEBOARD_FAB2(SCH_1):SVID_VCLK_PVCCIN_CPU1   I130 @BASEBOARD_FAB2_LIB.BASEBOARD_FAB2(SCH_1):PAGE206
    18 SVID_VDIO_PVCCIN_CPU1 @BASEBOARD_FAB2_LIB.BASEBOARD_FAB2(SCH_1):SVID_VDIO_PVCCIN_CPU1   I130 @BASEBOARD_FAB2_LIB.BASEBOARD_FAB2(SCH_1):PAGE206
    19 SVID_VALERT_VCCIN_CPU1 @BASEBOARD_FAB2_LIB.BASEBOARD_FAB2(SCH_1):SVID_VALERT_VCCIN_CPU1   I130 @BASEBOARD_FAB2_LIB.BASEBOARD_FAB2(SCH_1):PAGE206
    20 PU_VR_PVCCIN_CPU1_FLT1_SMBALT_N @BASEBOARD_FAB2_LIB.BASEBOARD_FAB2(SCH_1):PU_VR_PVCCIN_CPU1_FLT1_SMBALT_N_IMON   I130 @BASEBOARD_FAB2_LIB.BASEBOARD_FAB2(SCH_1):PAGE206
    21 VSENSE_PVCCIN_CPU1_AVSP @BASEBOARD_FAB2_LIB.BASEBOARD_FAB2(SCH_1):VSENSE_PVCCIN_CPU1_AVSP   I130 @BASEBOARD_FAB2_LIB.BASEBOARD_FAB2(SCH_1):PAGE206
    22 VSENSE_PVCCIN_CPU1_N @BASEBOARD_FAB2_LIB.BASEBOARD_FAB2(SCH_1):VSENSE_PVCCIN_CPU1_N   I130 @BASEBOARD_FAB2_LIB.BASEBOARD_FAB2(SCH_1):PAGE206
    23 VR_PVCCIN_CPU1_AIREF1 @BASEBOARD_FAB2_LIB.BASEBOARD_FAB2(SCH_1):VR_PVCCIN_CPU1_AIREF1   I130 @BASEBOARD_FAB2_LIB.BASEBOARD_FAB2(SCH_1):PAGE206
    24 ISENSE_PVCCIN_CPU1_PH1_IMON @BASEBOARD_FAB2_LIB.BASEBOARD_FAB2(SCH_1):ISENSE_PVCCIN_CPU1_PH1_IMON   I130 @BASEBOARD_FAB2_LIB.BASEBOARD_FAB2(SCH_1):PAGE206
    25 VR_PVCCIN_CPU1_AIREF2 @BASEBOARD_FAB2_LIB.BASEBOARD_FAB2(SCH_1):VR_PVCCIN_CPU1_AIREF2   I130 @BASEBOARD_FAB2_LIB.BASEBOARD_FAB2(SCH_1):PAGE206
    26 ISENSE_PVCCIN_CPU1_PH2_IMON @BASEBOARD_FAB2_LIB.BASEBOARD_FAB2(SCH_1):ISENSE_PVCCIN_CPU1_PH2_IMON   I130 @BASEBOARD_FAB2_LIB.BASEBOARD_FAB2(SCH_1):PAGE206
    27 VR_PVCCIN_CPU1_AIREF3 @BASEBOARD_FAB2_LIB.BASEBOARD_FAB2(SCH_1):VR_PVCCIN_CPU1_AIREF3   I130 @BASEBOARD_FAB2_LIB.BASEBOARD_FAB2(SCH_1):PAGE206
    28 ISENSE_PVCCIN_CPU1_PH3_IMON @BASEBOARD_FAB2_LIB.BASEBOARD_FAB2(SCH_1):ISENSE_PVCCIN_CPU1_PH3_IMON   I130 @BASEBOARD_FAB2_LIB.BASEBOARD_FAB2(SCH_1):PAGE206
    29 VR_PVCCIN_CPU1_AIREF4 @BASEBOARD_FAB2_LIB.BASEBOARD_FAB2(SCH_1):VR_PVCCIN_CPU1_AIREF4   I130 @BASEBOARD_FAB2_LIB.BASEBOARD_FAB2(SCH_1):PAGE206
    30 ISENSE_PVCCIN_CPU1_PH4_IMON @BASEBOARD_FAB2_LIB.BASEBOARD_FAB2(SCH_1):ISENSE_PVCCIN_CPU1_PH4_IMON   I130 @BASEBOARD_FAB2_LIB.BASEBOARD_FAB2(SCH_1):PAGE206
    31 VR_PVCCIN_CPU1_AIREF5 @BASEBOARD_FAB2_LIB.BASEBOARD_FAB2(SCH_1):VR_PVCCIN_CPU1_AIREF5   I130 @BASEBOARD_FAB2_LIB.BASEBOARD_FAB2(SCH_1):PAGE206
    32 ISENSE_PVCCIN_CPU1_PH5_IMON @BASEBOARD_FAB2_LIB.BASEBOARD_FAB2(SCH_1):ISENSE_PVCCIN_CPU1_PH5_IMON   I130 @BASEBOARD_FAB2_LIB.BASEBOARD_FAB2(SCH_1):PAGE206
    33 TP_PVCCIN_CPU1_AIREF6 @BASEBOARD_FAB2_LIB.BASEBOARD_FAB2(SCH_1):TP_PVCCIN_CPU1_AIREF6   I130 @BASEBOARD_FAB2_LIB.BASEBOARD_FAB2(SCH_1):PAGE206
    34 TP_PVCCIN_CPU1_AISEN6 @BASEBOARD_FAB2_LIB.BASEBOARD_FAB2(SCH_1):TP_PVCCIN_CPU1_AISEN6   I130 @BASEBOARD_FAB2_LIB.BASEBOARD_FAB2(SCH_1):PAGE206
    35 VSENSE_PVSA_CPU1_BVSP @BASEBOARD_FAB2_LIB.BASEBOARD_FAB2(SCH_1):VSENSE_PVSA_CPU1_BVSP   I130 @BASEBOARD_FAB2_LIB.BASEBOARD_FAB2(SCH_1):PAGE206
    36 VSENSE_PVSA_CPU1_N @BASEBOARD_FAB2_LIB.BASEBOARD_FAB2(SCH_1):VSENSE_PVSA_CPU1_N   I130 @BASEBOARD_FAB2_LIB.BASEBOARD_FAB2(SCH_1):PAGE206
    37 VR_PVSA_CPU1_BIREF1 @BASEBOARD_FAB2_LIB.BASEBOARD_FAB2(SCH_1):VR_PVSA_CPU1_BIREF1   I130 @BASEBOARD_FAB2_LIB.BASEBOARD_FAB2(SCH_1):PAGE206
    38 ISENSE_PVSA_CPU1_IMON @BASEBOARD_FAB2_LIB.BASEBOARD_FAB2(SCH_1):ISENSE_PVSA_CPU1_IMON   I130 @BASEBOARD_FAB2_LIB.BASEBOARD_FAB2(SCH_1):PAGE206
    39 PU_VR_PVCCIN_CPU1_IMON @BASEBOARD_FAB2_LIB.BASEBOARD_FAB2(SCH_1):PU_VR_PVCCIN_CPU1_IMON   I130 @BASEBOARD_FAB2_LIB.BASEBOARD_FAB2(SCH_1):PAGE206
    40 TP_PVCCIN_CPU1_FAULT1_20 @BASEBOARD_FAB2_LIB.BASEBOARD_FAB2(SCH_1):TP_PVCCIN_CPU1_FAULT1_20   I130 @BASEBOARD_FAB2_LIB.BASEBOARD_FAB2(SCH_1):PAGE206
    41 VR_PVCCIN_CPU1_XADDR2 @BASEBOARD_FAB2_LIB.BASEBOARD_FAB2(SCH_1):VR_PVCCIN_CPU1_XADDR2   I130 @BASEBOARD_FAB2_LIB.BASEBOARD_FAB2(SCH_1):PAGE206
    42 A_TSENSE_PVSA_CPU1 @BASEBOARD_FAB2_LIB.BASEBOARD_FAB2(SCH_1):A_TSENSE_PVSA_CPU1   I130 @BASEBOARD_FAB2_LIB.BASEBOARD_FAB2(SCH_1):PAGE206
    43 A_TSENSE_PVCCIN_CPU1 @BASEBOARD_FAB2_LIB.BASEBOARD_FAB2(SCH_1):A_TSENSE_PVCCIN_CPU1   I130 @BASEBOARD_FAB2_LIB.BASEBOARD_FAB2(SCH_1):PAGE206
    44 VR_PVCCIN_CPU1_XADDR1 @BASEBOARD_FAB2_LIB.BASEBOARD_FAB2(SCH_1):VR_PVCCIN_CPU1_XADDR1   I130 @BASEBOARD_FAB2_LIB.BASEBOARD_FAB2(SCH_1):PAGE206
    45 VR_PVCCIN_CPU1_AVINSEN @BASEBOARD_FAB2_LIB.BASEBOARD_FAB2(SCH_1):VR_PVCCIN_CPU1_AVINSEN   I130 @BASEBOARD_FAB2_LIB.BASEBOARD_FAB2(SCH_1):PAGE206
    46 PVCCIN_PVSA_CPU1_IINSEN @BASEBOARD_FAB2_LIB.BASEBOARD_FAB2(SCH_1):PVCCIN_PVSA_CPU1_IINSEN   I130 @BASEBOARD_FAB2_LIB.BASEBOARD_FAB2(SCH_1):PAGE206
    47 VR_PVCCIN_CPU1_VDD @BASEBOARD_FAB2_LIB.BASEBOARD_FAB2(SCH_1):VR_PVCCIN_CPU1_VDD   I130 @BASEBOARD_FAB2_LIB.BASEBOARD_FAB2(SCH_1):PAGE206
    48 VR_PVCCIN_CPU1_VD12 @BASEBOARD_FAB2_LIB.BASEBOARD_FAB2(SCH_1):VR_PVCCIN_CPU1_VD12   I130 @BASEBOARD_FAB2_LIB.BASEBOARD_FAB2(SCH_1):PAGE206
    49    GND @BASEBOARD_FAB2_LIB.BASEBOARD_FAB2(SCH_1):GND   I130 @BASEBOARD_FAB2_LIB.BASEBOARD_FAB2(SCH_1):PAGE206

EU1C3 IR354XX_SM-IR35411,IC,H73688-0A
    33 VR_PVCCIN_CPU1_PH5_BOOT_R @BASEBOARD_FAB2_LIB.BASEBOARD_FAB2(SCH_1):VR_PVCCIN_CPU1_PH5_BOOT_R    I56 @BASEBOARD_FAB2_LIB.BASEBOARD_FAB2(SCH_1):PAGE209
    35 P5V_STBY @BASEBOARD_FAB2_LIB.BASEBOARD_FAB2(SCH_1):P5V_STBY    I56 @BASEBOARD_FAB2_LIB.BASEBOARD_FAB2(SCH_1):PAGE209
    41 TP_PVCCIN_CPU1_PH5_GL_1 @BASEBOARD_FAB2_LIB.BASEBOARD_FAB2(SCH_1):TP_PVCCIN_CPU1_PH5_GL_1    I56 @BASEBOARD_FAB2_LIB.BASEBOARD_FAB2(SCH_1):PAGE209
     6 TP_PVCCIN_CPU1_PH5_GL_0 @BASEBOARD_FAB2_LIB.BASEBOARD_FAB2(SCH_1):TP_PVCCIN_CPU1_PH5_GL_0    I56 @BASEBOARD_FAB2_LIB.BASEBOARD_FAB2(SCH_1):PAGE209
    38 ISENSE_PVCCIN_CPU1_PH5_IMON @BASEBOARD_FAB2_LIB.BASEBOARD_FAB2(SCH_1):ISENSE_PVCCIN_CPU1_PH5_IMON    I56 @BASEBOARD_FAB2_LIB.BASEBOARD_FAB2(SCH_1):PAGE209
     2    GND @BASEBOARD_FAB2_LIB.BASEBOARD_FAB2(SCH_1):GND    I56 @BASEBOARD_FAB2_LIB.BASEBOARD_FAB2(SCH_1):PAGE209
    31 NC_PVCCIN_CPU1_PH5_P31 @BASEBOARD_FAB2_LIB.BASEBOARD_FAB2(SCH_1):NC_PVCCIN_CPU1_PH5_P31    I56 @BASEBOARD_FAB2_LIB.BASEBOARD_FAB2(SCH_1):PAGE209
    37 VR_PVCCIN_CPU1_PH5_OCSET @BASEBOARD_FAB2_LIB.BASEBOARD_FAB2(SCH_1):VR_PVCCIN_CPU1_PH5_OCSET    I56 @BASEBOARD_FAB2_LIB.BASEBOARD_FAB2(SCH_1):PAGE209
    40    GND @BASEBOARD_FAB2_LIB.BASEBOARD_FAB2(SCH_1):GND    I56 @BASEBOARD_FAB2_LIB.BASEBOARD_FAB2(SCH_1):PAGE209
     7    GND @BASEBOARD_FAB2_LIB.BASEBOARD_FAB2(SCH_1):GND    I56 @BASEBOARD_FAB2_LIB.BASEBOARD_FAB2(SCH_1):PAGE209
     5    GND @BASEBOARD_FAB2_LIB.BASEBOARD_FAB2(SCH_1):GND    I56 @BASEBOARD_FAB2_LIB.BASEBOARD_FAB2(SCH_1):PAGE209
    32 VR_PVCCIN_CPU1_PH5_PHASE @BASEBOARD_FAB2_LIB.BASEBOARD_FAB2(SCH_1):VR_PVCCIN_CPU1_PH5_PHASE    I56 @BASEBOARD_FAB2_LIB.BASEBOARD_FAB2(SCH_1):PAGE209
    34 VR_PVCCIN_CPU1_PWM5 @BASEBOARD_FAB2_LIB.BASEBOARD_FAB2(SCH_1):VR_PVCCIN_CPU1_PWM5    I56 @BASEBOARD_FAB2_LIB.BASEBOARD_FAB2(SCH_1):PAGE209
    39 VR_PVCCIN_CPU1_AIREF5 @BASEBOARD_FAB2_LIB.BASEBOARD_FAB2(SCH_1):VR_PVCCIN_CPU1_AIREF5    I56 @BASEBOARD_FAB2_LIB.BASEBOARD_FAB2(SCH_1):PAGE209
    10 VR_PVCCIN_CPU1_PHASE5 @BASEBOARD_FAB2_LIB.BASEBOARD_FAB2(SCH_1):VR_PVCCIN_CPU1_PHASE5    I56 @BASEBOARD_FAB2_LIB.BASEBOARD_FAB2(SCH_1):PAGE209
    36 A_TSENSE_PVCCIN_CPU1 @BASEBOARD_FAB2_LIB.BASEBOARD_FAB2(SCH_1):A_TSENSE_PVCCIN_CPU1    I56 @BASEBOARD_FAB2_LIB.BASEBOARD_FAB2(SCH_1):PAGE209
     3 VR_PVCCIN_CPU1_PH5_VCIN @BASEBOARD_FAB2_LIB.BASEBOARD_FAB2(SCH_1):VR_PVCCIN_CPU1_PH5_VCIN    I56 @BASEBOARD_FAB2_LIB.BASEBOARD_FAB2(SCH_1):PAGE209
     4 P5V_STBY @BASEBOARD_FAB2_LIB.BASEBOARD_FAB2(SCH_1):P5V_STBY    I56 @BASEBOARD_FAB2_LIB.BASEBOARD_FAB2(SCH_1):PAGE209
    30 VR_FET_SW_P12V_STBY_PVCCIN_CPU1 @BASEBOARD_FAB2_LIB.BASEBOARD_FAB2(SCH_1):VR_FET_SW_P12V_STBY_PVCCIN_CPU1    I56 @BASEBOARD_FAB2_LIB.BASEBOARD_FAB2(SCH_1):PAGE209
    25 VR_FET_SW_P12V_STBY_PVCCIN_CPU1 @BASEBOARD_FAB2_LIB.BASEBOARD_FAB2(SCH_1):VR_FET_SW_P12V_STBY_PVCCIN_CPU1    I56 @BASEBOARD_FAB2_LIB.BASEBOARD_FAB2(SCH_1):PAGE209
     1 PVCCIN_CPU1 @BASEBOARD_FAB2_LIB.BASEBOARD_FAB2(SCH_1):PVCCIN_CPU1    I56 @BASEBOARD_FAB2_LIB.BASEBOARD_FAB2(SCH_1):PAGE209

EU1D1 IR354XX_SM-IR35411,IC,H73688-0A
    33 VR_PVCCIN_CPU1_PH4_BOOT_R @BASEBOARD_FAB2_LIB.BASEBOARD_FAB2(SCH_1):VR_PVCCIN_CPU1_PH4_BOOT_R    I71 @BASEBOARD_FAB2_LIB.BASEBOARD_FAB2(SCH_1):PAGE208
    35 P5V_STBY @BASEBOARD_FAB2_LIB.BASEBOARD_FAB2(SCH_1):P5V_STBY    I71 @BASEBOARD_FAB2_LIB.BASEBOARD_FAB2(SCH_1):PAGE208
    41 TP_PVCCIN_CPU1_PH4_GL_1 @BASEBOARD_FAB2_LIB.BASEBOARD_FAB2(SCH_1):TP_PVCCIN_CPU1_PH4_GL_1    I71 @BASEBOARD_FAB2_LIB.BASEBOARD_FAB2(SCH_1):PAGE208
     6 TP_PVCCIN_CPU1_PH4_GL_0 @BASEBOARD_FAB2_LIB.BASEBOARD_FAB2(SCH_1):TP_PVCCIN_CPU1_PH4_GL_0    I71 @BASEBOARD_FAB2_LIB.BASEBOARD_FAB2(SCH_1):PAGE208
    38 ISENSE_PVCCIN_CPU1_PH4_IMON @BASEBOARD_FAB2_LIB.BASEBOARD_FAB2(SCH_1):ISENSE_PVCCIN_CPU1_PH4_IMON    I71 @BASEBOARD_FAB2_LIB.BASEBOARD_FAB2(SCH_1):PAGE208
     2    GND @BASEBOARD_FAB2_LIB.BASEBOARD_FAB2(SCH_1):GND    I71 @BASEBOARD_FAB2_LIB.BASEBOARD_FAB2(SCH_1):PAGE208
    31 NC_PVCCIN_CPU1_PH4_P31 @BASEBOARD_FAB2_LIB.BASEBOARD_FAB2(SCH_1):NC_PVCCIN_CPU1_PH4_P31    I71 @BASEBOARD_FAB2_LIB.BASEBOARD_FAB2(SCH_1):PAGE208
    37 VR_PVCCIN_CPU1_PH4_OCSET @BASEBOARD_FAB2_LIB.BASEBOARD_FAB2(SCH_1):VR_PVCCIN_CPU1_PH4_OCSET    I71 @BASEBOARD_FAB2_LIB.BASEBOARD_FAB2(SCH_1):PAGE208
    40    GND @BASEBOARD_FAB2_LIB.BASEBOARD_FAB2(SCH_1):GND    I71 @BASEBOARD_FAB2_LIB.BASEBOARD_FAB2(SCH_1):PAGE208
     7    GND @BASEBOARD_FAB2_LIB.BASEBOARD_FAB2(SCH_1):GND    I71 @BASEBOARD_FAB2_LIB.BASEBOARD_FAB2(SCH_1):PAGE208
     5    GND @BASEBOARD_FAB2_LIB.BASEBOARD_FAB2(SCH_1):GND    I71 @BASEBOARD_FAB2_LIB.BASEBOARD_FAB2(SCH_1):PAGE208
    32 VR_PVCCIN_CPU1_PH4_PHASE @BASEBOARD_FAB2_LIB.BASEBOARD_FAB2(SCH_1):VR_PVCCIN_CPU1_PH4_PHASE    I71 @BASEBOARD_FAB2_LIB.BASEBOARD_FAB2(SCH_1):PAGE208
    34 VR_PVCCIN_CPU1_PWM4 @BASEBOARD_FAB2_LIB.BASEBOARD_FAB2(SCH_1):VR_PVCCIN_CPU1_PWM4    I71 @BASEBOARD_FAB2_LIB.BASEBOARD_FAB2(SCH_1):PAGE208
    39 VR_PVCCIN_CPU1_AIREF4 @BASEBOARD_FAB2_LIB.BASEBOARD_FAB2(SCH_1):VR_PVCCIN_CPU1_AIREF4    I71 @BASEBOARD_FAB2_LIB.BASEBOARD_FAB2(SCH_1):PAGE208
    10 VR_PVCCIN_CPU1_PHASE4 @BASEBOARD_FAB2_LIB.BASEBOARD_FAB2(SCH_1):VR_PVCCIN_CPU1_PHASE4    I71 @BASEBOARD_FAB2_LIB.BASEBOARD_FAB2(SCH_1):PAGE208
    36 A_TSENSE_PVCCIN_CPU1 @BASEBOARD_FAB2_LIB.BASEBOARD_FAB2(SCH_1):A_TSENSE_PVCCIN_CPU1    I71 @BASEBOARD_FAB2_LIB.BASEBOARD_FAB2(SCH_1):PAGE208
     3 VR_PVCCIN_CPU1_PH4_VCIN @BASEBOARD_FAB2_LIB.BASEBOARD_FAB2(SCH_1):VR_PVCCIN_CPU1_PH4_VCIN    I71 @BASEBOARD_FAB2_LIB.BASEBOARD_FAB2(SCH_1):PAGE208
     4 P5V_STBY @BASEBOARD_FAB2_LIB.BASEBOARD_FAB2(SCH_1):P5V_STBY    I71 @BASEBOARD_FAB2_LIB.BASEBOARD_FAB2(SCH_1):PAGE208
    30 VR_FET_SW_P12V_STBY_PVCCIN_CPU1 @BASEBOARD_FAB2_LIB.BASEBOARD_FAB2(SCH_1):VR_FET_SW_P12V_STBY_PVCCIN_CPU1    I71 @BASEBOARD_FAB2_LIB.BASEBOARD_FAB2(SCH_1):PAGE208
    25 VR_FET_SW_P12V_STBY_PVCCIN_CPU1 @BASEBOARD_FAB2_LIB.BASEBOARD_FAB2(SCH_1):VR_FET_SW_P12V_STBY_PVCCIN_CPU1    I71 @BASEBOARD_FAB2_LIB.BASEBOARD_FAB2(SCH_1):PAGE208
     1 PVCCIN_CPU1 @BASEBOARD_FAB2_LIB.BASEBOARD_FAB2(SCH_1):PVCCIN_CPU1    I71 @BASEBOARD_FAB2_LIB.BASEBOARD_FAB2(SCH_1):PAGE208

EU1D2 ADM1278_SM-IC,G99251-001
     7 FM_P12V_HSC_ADR1 @BASEBOARD_FAB2_LIB.BASEBOARD_FAB2(SCH_1):FM_P12V_HSC_ADR1    I10 @BASEBOARD_FAB2_LIB.BASEBOARD_FAB2(SCH_1):PAGE199
     8 FM_P12V_HSC_ADR2 @BASEBOARD_FAB2_LIB.BASEBOARD_FAB2(SCH_1):FM_P12V_HSC_ADR2    I10 @BASEBOARD_FAB2_LIB.BASEBOARD_FAB2(SCH_1):PAGE199
    19 A_HSC_CSOUT @BASEBOARD_FAB2_LIB.BASEBOARD_FAB2(SCH_1):A_HSC_CSOUT    I10 @BASEBOARD_FAB2_LIB.BASEBOARD_FAB2(SCH_1):PAGE199
    12 FM_P12V_HOTSWAP0_EN @BASEBOARD_FAB2_LIB.BASEBOARD_FAB2(SCH_1):FM_P12V_HOTSWAP0_EN    I10 @BASEBOARD_FAB2_LIB.BASEBOARD_FAB2(SCH_1):PAGE199
    33 AGND_HSC @BASEBOARD_FAB2_LIB.BASEBOARD_FAB2(SCH_1):AGND_HSC    I10 @BASEBOARD_FAB2_LIB.BASEBOARD_FAB2(SCH_1):PAGE199
     6 IRQ_HSC_FAULT_R_N @BASEBOARD_FAB2_LIB.BASEBOARD_FAB2(SCH_1):IRQ_HSC_FAULT_R_N    I10 @BASEBOARD_FAB2_LIB.BASEBOARD_FAB2(SCH_1):PAGE199
    24 A_HSC_GATE @BASEBOARD_FAB2_LIB.BASEBOARD_FAB2(SCH_1):A_HSC_GATE    I10 @BASEBOARD_FAB2_LIB.BASEBOARD_FAB2(SCH_1):PAGE199
    22 AGND_HSC @BASEBOARD_FAB2_LIB.BASEBOARD_FAB2(SCH_1):AGND_HSC    I10 @BASEBOARD_FAB2_LIB.BASEBOARD_FAB2(SCH_1):PAGE199
    13 IRQ_SML1_PMBUS_ALERT_R_N @BASEBOARD_FAB2_LIB.BASEBOARD_FAB2(SCH_1):IRQ_SML1_PMBUS_ALERT_R_N    I10 @BASEBOARD_FAB2_LIB.BASEBOARD_FAB2(SCH_1):PAGE199
    14 TP_HSC_ALERT2_N @BASEBOARD_FAB2_LIB.BASEBOARD_FAB2(SCH_1):TP_HSC_ALERT2_N    I10 @BASEBOARD_FAB2_LIB.BASEBOARD_FAB2(SCH_1):PAGE199
    27 A_HSC_HSN @BASEBOARD_FAB2_LIB.BASEBOARD_FAB2(SCH_1):A_HSC_HSN    I10 @BASEBOARD_FAB2_LIB.BASEBOARD_FAB2(SCH_1):PAGE199
    28 A_HSC_HSP @BASEBOARD_FAB2_LIB.BASEBOARD_FAB2(SCH_1):A_HSC_HSP    I10 @BASEBOARD_FAB2_LIB.BASEBOARD_FAB2(SCH_1):PAGE199
     3 A_HSC_ISET @BASEBOARD_FAB2_LIB.BASEBOARD_FAB2(SCH_1):A_HSC_ISET    I10 @BASEBOARD_FAB2_LIB.BASEBOARD_FAB2(SCH_1):PAGE199
     4 A_HSC_ISTART @BASEBOARD_FAB2_LIB.BASEBOARD_FAB2(SCH_1):A_HSC_ISTART    I10 @BASEBOARD_FAB2_LIB.BASEBOARD_FAB2(SCH_1):PAGE199
    10 TP_HSC_MCLK @BASEBOARD_FAB2_LIB.BASEBOARD_FAB2(SCH_1):TP_HSC_MCLK    I10 @BASEBOARD_FAB2_LIB.BASEBOARD_FAB2(SCH_1):PAGE199
    11 TP_HSC_MDAT @BASEBOARD_FAB2_LIB.BASEBOARD_FAB2(SCH_1):TP_HSC_MDAT    I10 @BASEBOARD_FAB2_LIB.BASEBOARD_FAB2(SCH_1):PAGE199
    26 A_HSC_MON @BASEBOARD_FAB2_LIB.BASEBOARD_FAB2(SCH_1):A_HSC_MON    I10 @BASEBOARD_FAB2_LIB.BASEBOARD_FAB2(SCH_1):PAGE199
    29 A_HSC_MOP @BASEBOARD_FAB2_LIB.BASEBOARD_FAB2(SCH_1):A_HSC_MOP    I10 @BASEBOARD_FAB2_LIB.BASEBOARD_FAB2(SCH_1):PAGE199
    32 A_HSC_OV @BASEBOARD_FAB2_LIB.BASEBOARD_FAB2(SCH_1):A_HSC_OV    I10 @BASEBOARD_FAB2_LIB.BASEBOARD_FAB2(SCH_1):PAGE199
    23    GND @BASEBOARD_FAB2_LIB.BASEBOARD_FAB2(SCH_1):GND    I10 @BASEBOARD_FAB2_LIB.BASEBOARD_FAB2(SCH_1):PAGE199
     1 A_HSC_PSET @BASEBOARD_FAB2_LIB.BASEBOARD_FAB2(SCH_1):A_HSC_PSET    I10 @BASEBOARD_FAB2_LIB.BASEBOARD_FAB2(SCH_1):PAGE199
    21 A_HSC_PWGIN @BASEBOARD_FAB2_LIB.BASEBOARD_FAB2(SCH_1):A_HSC_PWGIN    I10 @BASEBOARD_FAB2_LIB.BASEBOARD_FAB2(SCH_1):PAGE199
    18 PWRGD_P12V_R @BASEBOARD_FAB2_LIB.BASEBOARD_FAB2(SCH_1):PWRGD_P12V_R    I10 @BASEBOARD_FAB2_LIB.BASEBOARD_FAB2(SCH_1):PAGE199
    17 PD_HSC_RETRY_N @BASEBOARD_FAB2_LIB.BASEBOARD_FAB2(SCH_1):PD_HSC_RETRY_N    I10 @BASEBOARD_FAB2_LIB.BASEBOARD_FAB2(SCH_1):PAGE199
    16 SMB_3V3SB_HSC_SCL_R @BASEBOARD_FAB2_LIB.BASEBOARD_FAB2(SCH_1):SMB_3V3SB_HSC_SCL_R    I10 @BASEBOARD_FAB2_LIB.BASEBOARD_FAB2(SCH_1):PAGE199
    15 SMB_3V3SB_HSC_SDA_R @BASEBOARD_FAB2_LIB.BASEBOARD_FAB2(SCH_1):SMB_3V3SB_HSC_SDA_R    I10 @BASEBOARD_FAB2_LIB.BASEBOARD_FAB2(SCH_1):PAGE199
     9 TP_HSC_SPISSN @BASEBOARD_FAB2_LIB.BASEBOARD_FAB2(SCH_1):TP_HSC_SPISSN    I10 @BASEBOARD_FAB2_LIB.BASEBOARD_FAB2(SCH_1):PAGE199
    25 A_HSC_TEMP @BASEBOARD_FAB2_LIB.BASEBOARD_FAB2(SCH_1):A_HSC_TEMP    I10 @BASEBOARD_FAB2_LIB.BASEBOARD_FAB2(SCH_1):PAGE199
     5 A_HSC_TIMER @BASEBOARD_FAB2_LIB.BASEBOARD_FAB2(SCH_1):A_HSC_TIMER    I10 @BASEBOARD_FAB2_LIB.BASEBOARD_FAB2(SCH_1):PAGE199
    31 A_HSC_UV @BASEBOARD_FAB2_LIB.BASEBOARD_FAB2(SCH_1):A_HSC_UV    I10 @BASEBOARD_FAB2_LIB.BASEBOARD_FAB2(SCH_1):PAGE199
     2 A_HSC_VCAP @BASEBOARD_FAB2_LIB.BASEBOARD_FAB2(SCH_1):A_HSC_VCAP    I10 @BASEBOARD_FAB2_LIB.BASEBOARD_FAB2(SCH_1):PAGE199
    30 P12V_HSC_VCC @BASEBOARD_FAB2_LIB.BASEBOARD_FAB2(SCH_1):P12V_HSC_VCC    I10 @BASEBOARD_FAB2_LIB.BASEBOARD_FAB2(SCH_1):PAGE199
    20 A_HSC_VOUT @BASEBOARD_FAB2_LIB.BASEBOARD_FAB2(SCH_1):A_HSC_VOUT    I10 @BASEBOARD_FAB2_LIB.BASEBOARD_FAB2(SCH_1):PAGE199

EU1D3 IR354XX_SM-IR35411,IC,H73688-0A
    33 VR_PVCCIN_CPU1_PH3_BOOT_R @BASEBOARD_FAB2_LIB.BASEBOARD_FAB2(SCH_1):VR_PVCCIN_CPU1_PH3_BOOT_R    I27 @BASEBOARD_FAB2_LIB.BASEBOARD_FAB2(SCH_1):PAGE208
    35 P5V_STBY @BASEBOARD_FAB2_LIB.BASEBOARD_FAB2(SCH_1):P5V_STBY    I27 @BASEBOARD_FAB2_LIB.BASEBOARD_FAB2(SCH_1):PAGE208
    41 TP_PVCCIN_CPU1_PH3_GL_1 @BASEBOARD_FAB2_LIB.BASEBOARD_FAB2(SCH_1):TP_PVCCIN_CPU1_PH3_GL_1    I27 @BASEBOARD_FAB2_LIB.BASEBOARD_FAB2(SCH_1):PAGE208
     6 TP_PVCCIN_CPU1_PH3_GL_0 @BASEBOARD_FAB2_LIB.BASEBOARD_FAB2(SCH_1):TP_PVCCIN_CPU1_PH3_GL_0    I27 @BASEBOARD_FAB2_LIB.BASEBOARD_FAB2(SCH_1):PAGE208
    38 ISENSE_PVCCIN_CPU1_PH3_IMON @BASEBOARD_FAB2_LIB.BASEBOARD_FAB2(SCH_1):ISENSE_PVCCIN_CPU1_PH3_IMON    I27 @BASEBOARD_FAB2_LIB.BASEBOARD_FAB2(SCH_1):PAGE208
     2    GND @BASEBOARD_FAB2_LIB.BASEBOARD_FAB2(SCH_1):GND    I27 @BASEBOARD_FAB2_LIB.BASEBOARD_FAB2(SCH_1):PAGE208
    31 NC_PVCCIN_CPU1_PH3_P31 @BASEBOARD_FAB2_LIB.BASEBOARD_FAB2(SCH_1):NC_PVCCIN_CPU1_PH3_P31    I27 @BASEBOARD_FAB2_LIB.BASEBOARD_FAB2(SCH_1):PAGE208
    37 VR_PVCCIN_CPU1_PH3_OCSET @BASEBOARD_FAB2_LIB.BASEBOARD_FAB2(SCH_1):VR_PVCCIN_CPU1_PH3_OCSET    I27 @BASEBOARD_FAB2_LIB.BASEBOARD_FAB2(SCH_1):PAGE208
    40    GND @BASEBOARD_FAB2_LIB.BASEBOARD_FAB2(SCH_1):GND    I27 @BASEBOARD_FAB2_LIB.BASEBOARD_FAB2(SCH_1):PAGE208
     7    GND @BASEBOARD_FAB2_LIB.BASEBOARD_FAB2(SCH_1):GND    I27 @BASEBOARD_FAB2_LIB.BASEBOARD_FAB2(SCH_1):PAGE208
     5    GND @BASEBOARD_FAB2_LIB.BASEBOARD_FAB2(SCH_1):GND    I27 @BASEBOARD_FAB2_LIB.BASEBOARD_FAB2(SCH_1):PAGE208
    32 VR_PVCCIN_CPU1_PH3_PHASE @BASEBOARD_FAB2_LIB.BASEBOARD_FAB2(SCH_1):VR_PVCCIN_CPU1_PH3_PHASE    I27 @BASEBOARD_FAB2_LIB.BASEBOARD_FAB2(SCH_1):PAGE208
    34 VR_PVCCIN_CPU1_PWM3 @BASEBOARD_FAB2_LIB.BASEBOARD_FAB2(SCH_1):VR_PVCCIN_CPU1_PWM3    I27 @BASEBOARD_FAB2_LIB.BASEBOARD_FAB2(SCH_1):PAGE208
    39 VR_PVCCIN_CPU1_AIREF3 @BASEBOARD_FAB2_LIB.BASEBOARD_FAB2(SCH_1):VR_PVCCIN_CPU1_AIREF3    I27 @BASEBOARD_FAB2_LIB.BASEBOARD_FAB2(SCH_1):PAGE208
    10 VR_PVCCIN_CPU1_PHASE3 @BASEBOARD_FAB2_LIB.BASEBOARD_FAB2(SCH_1):VR_PVCCIN_CPU1_PHASE3    I27 @BASEBOARD_FAB2_LIB.BASEBOARD_FAB2(SCH_1):PAGE208
    36 A_TSENSE_PVCCIN_CPU1 @BASEBOARD_FAB2_LIB.BASEBOARD_FAB2(SCH_1):A_TSENSE_PVCCIN_CPU1    I27 @BASEBOARD_FAB2_LIB.BASEBOARD_FAB2(SCH_1):PAGE208
     3 VR_PVCCIN_CPU1_PH3_VCIN @BASEBOARD_FAB2_LIB.BASEBOARD_FAB2(SCH_1):VR_PVCCIN_CPU1_PH3_VCIN    I27 @BASEBOARD_FAB2_LIB.BASEBOARD_FAB2(SCH_1):PAGE208
     4 P5V_STBY @BASEBOARD_FAB2_LIB.BASEBOARD_FAB2(SCH_1):P5V_STBY    I27 @BASEBOARD_FAB2_LIB.BASEBOARD_FAB2(SCH_1):PAGE208
    30 VR_FET_SW_P12V_STBY_PVCCIN_CPU1 @BASEBOARD_FAB2_LIB.BASEBOARD_FAB2(SCH_1):VR_FET_SW_P12V_STBY_PVCCIN_CPU1    I27 @BASEBOARD_FAB2_LIB.BASEBOARD_FAB2(SCH_1):PAGE208
    25 VR_FET_SW_P12V_STBY_PVCCIN_CPU1 @BASEBOARD_FAB2_LIB.BASEBOARD_FAB2(SCH_1):VR_FET_SW_P12V_STBY_PVCCIN_CPU1    I27 @BASEBOARD_FAB2_LIB.BASEBOARD_FAB2(SCH_1):PAGE208
     1 PVCCIN_CPU1 @BASEBOARD_FAB2_LIB.BASEBOARD_FAB2(SCH_1):PVCCIN_CPU1    I27 @BASEBOARD_FAB2_LIB.BASEBOARD_FAB2(SCH_1):PAGE208

EU1D4 IR354XX_SM-IR35411,IC,H73688-0A
    33 VR_PVCCIN_CPU1_PH2_BOOT_R @BASEBOARD_FAB2_LIB.BASEBOARD_FAB2(SCH_1):VR_PVCCIN_CPU1_PH2_BOOT_R    I24 @BASEBOARD_FAB2_LIB.BASEBOARD_FAB2(SCH_1):PAGE207
    35 P5V_STBY @BASEBOARD_FAB2_LIB.BASEBOARD_FAB2(SCH_1):P5V_STBY    I24 @BASEBOARD_FAB2_LIB.BASEBOARD_FAB2(SCH_1):PAGE207
    41 TP_PVCCINC_CPU1_PH2_GL_1 @BASEBOARD_FAB2_LIB.BASEBOARD_FAB2(SCH_1):TP_PVCCINC_CPU1_PH2_GL_1    I24 @BASEBOARD_FAB2_LIB.BASEBOARD_FAB2(SCH_1):PAGE207
     6 TP_PVCCINC_CPU1_PH2_GL_0 @BASEBOARD_FAB2_LIB.BASEBOARD_FAB2(SCH_1):TP_PVCCINC_CPU1_PH2_GL_0    I24 @BASEBOARD_FAB2_LIB.BASEBOARD_FAB2(SCH_1):PAGE207
    38 ISENSE_PVCCIN_CPU1_PH2_IMON @BASEBOARD_FAB2_LIB.BASEBOARD_FAB2(SCH_1):ISENSE_PVCCIN_CPU1_PH2_IMON    I24 @BASEBOARD_FAB2_LIB.BASEBOARD_FAB2(SCH_1):PAGE207
     2    GND @BASEBOARD_FAB2_LIB.BASEBOARD_FAB2(SCH_1):GND    I24 @BASEBOARD_FAB2_LIB.BASEBOARD_FAB2(SCH_1):PAGE207
    31 NC_PVCCIN_CPU1_PH2_P31 @BASEBOARD_FAB2_LIB.BASEBOARD_FAB2(SCH_1):NC_PVCCIN_CPU1_PH2_P31    I24 @BASEBOARD_FAB2_LIB.BASEBOARD_FAB2(SCH_1):PAGE207
    37 VR_PVCCIN_CPU1_PH2_OCSET @BASEBOARD_FAB2_LIB.BASEBOARD_FAB2(SCH_1):VR_PVCCIN_CPU1_PH2_OCSET    I24 @BASEBOARD_FAB2_LIB.BASEBOARD_FAB2(SCH_1):PAGE207
    40    GND @BASEBOARD_FAB2_LIB.BASEBOARD_FAB2(SCH_1):GND    I24 @BASEBOARD_FAB2_LIB.BASEBOARD_FAB2(SCH_1):PAGE207
     7    GND @BASEBOARD_FAB2_LIB.BASEBOARD_FAB2(SCH_1):GND    I24 @BASEBOARD_FAB2_LIB.BASEBOARD_FAB2(SCH_1):PAGE207
     5    GND @BASEBOARD_FAB2_LIB.BASEBOARD_FAB2(SCH_1):GND    I24 @BASEBOARD_FAB2_LIB.BASEBOARD_FAB2(SCH_1):PAGE207
    32 VR_PVCCIN_CPU1_PH2_PHASE @BASEBOARD_FAB2_LIB.BASEBOARD_FAB2(SCH_1):VR_PVCCIN_CPU1_PH2_PHASE    I24 @BASEBOARD_FAB2_LIB.BASEBOARD_FAB2(SCH_1):PAGE207
    34 VR_PVCCIN_CPU1_PWM2 @BASEBOARD_FAB2_LIB.BASEBOARD_FAB2(SCH_1):VR_PVCCIN_CPU1_PWM2    I24 @BASEBOARD_FAB2_LIB.BASEBOARD_FAB2(SCH_1):PAGE207
    39 VR_PVCCIN_CPU1_AIREF2 @BASEBOARD_FAB2_LIB.BASEBOARD_FAB2(SCH_1):VR_PVCCIN_CPU1_AIREF2    I24 @BASEBOARD_FAB2_LIB.BASEBOARD_FAB2(SCH_1):PAGE207
    10 VR_PVCCIN_CPU1_PHASE2 @BASEBOARD_FAB2_LIB.BASEBOARD_FAB2(SCH_1):VR_PVCCIN_CPU1_PHASE2    I24 @BASEBOARD_FAB2_LIB.BASEBOARD_FAB2(SCH_1):PAGE207
    36 A_TSENSE_PVCCIN_CPU1 @BASEBOARD_FAB2_LIB.BASEBOARD_FAB2(SCH_1):A_TSENSE_PVCCIN_CPU1    I24 @BASEBOARD_FAB2_LIB.BASEBOARD_FAB2(SCH_1):PAGE207
     3 VR_PVCCIN_CPU1_PH2_VCIN @BASEBOARD_FAB2_LIB.BASEBOARD_FAB2(SCH_1):VR_PVCCIN_CPU1_PH2_VCIN    I24 @BASEBOARD_FAB2_LIB.BASEBOARD_FAB2(SCH_1):PAGE207
     4 P5V_STBY @BASEBOARD_FAB2_LIB.BASEBOARD_FAB2(SCH_1):P5V_STBY    I24 @BASEBOARD_FAB2_LIB.BASEBOARD_FAB2(SCH_1):PAGE207
    30 VR_FET_SW_P12V_STBY_PVCCIN_CPU1 @BASEBOARD_FAB2_LIB.BASEBOARD_FAB2(SCH_1):VR_FET_SW_P12V_STBY_PVCCIN_CPU1    I24 @BASEBOARD_FAB2_LIB.BASEBOARD_FAB2(SCH_1):PAGE207
    25 VR_FET_SW_P12V_STBY_PVCCIN_CPU1 @BASEBOARD_FAB2_LIB.BASEBOARD_FAB2(SCH_1):VR_FET_SW_P12V_STBY_PVCCIN_CPU1    I24 @BASEBOARD_FAB2_LIB.BASEBOARD_FAB2(SCH_1):PAGE207
     1 PVCCIN_CPU1 @BASEBOARD_FAB2_LIB.BASEBOARD_FAB2(SCH_1):PVCCIN_CPU1    I24 @BASEBOARD_FAB2_LIB.BASEBOARD_FAB2(SCH_1):PAGE207

EU1E1 MOSFETN_1D3S_SOT5-IC,G68777-001
     1 P12V_STBY @BASEBOARD_FAB2_LIB.BASEBOARD_FAB2(SCH_1):P12V_STBY    I59 @BASEBOARD_FAB2_LIB.BASEBOARD_FAB2(SCH_1):PAGE200
     2 P12V_STBY @BASEBOARD_FAB2_LIB.BASEBOARD_FAB2(SCH_1):P12V_STBY    I59 @BASEBOARD_FAB2_LIB.BASEBOARD_FAB2(SCH_1):PAGE200
     3 P12V_STBY @BASEBOARD_FAB2_LIB.BASEBOARD_FAB2(SCH_1):P12V_STBY    I59 @BASEBOARD_FAB2_LIB.BASEBOARD_FAB2(SCH_1):PAGE200
     5 P12V_MB0_SW @BASEBOARD_FAB2_LIB.BASEBOARD_FAB2(SCH_1):P12V_MB0_SW    I59 @BASEBOARD_FAB2_LIB.BASEBOARD_FAB2(SCH_1):PAGE200
     4 A_HSC_GATE3_R @BASEBOARD_FAB2_LIB.BASEBOARD_FAB2(SCH_1):A_HSC_GATE3_R    I59 @BASEBOARD_FAB2_LIB.BASEBOARD_FAB2(SCH_1):PAGE200

EU1E2 IR354XX_SM-IR35411,IC,H73688-0A
    33 VR_PVCCIN_CPU1_PH1_BOOT_R @BASEBOARD_FAB2_LIB.BASEBOARD_FAB2(SCH_1):VR_PVCCIN_CPU1_PH1_BOOT_R    I20 @BASEBOARD_FAB2_LIB.BASEBOARD_FAB2(SCH_1):PAGE207
    35 P5V_STBY @BASEBOARD_FAB2_LIB.BASEBOARD_FAB2(SCH_1):P5V_STBY    I20 @BASEBOARD_FAB2_LIB.BASEBOARD_FAB2(SCH_1):PAGE207
    41 TP_PVCCINC_CPU1_PH1_GL_1 @BASEBOARD_FAB2_LIB.BASEBOARD_FAB2(SCH_1):TP_PVCCINC_CPU1_PH1_GL_1    I20 @BASEBOARD_FAB2_LIB.BASEBOARD_FAB2(SCH_1):PAGE207
     6 TP_PVCCINC_CPU1_PH1_GL_0 @BASEBOARD_FAB2_LIB.BASEBOARD_FAB2(SCH_1):TP_PVCCINC_CPU1_PH1_GL_0    I20 @BASEBOARD_FAB2_LIB.BASEBOARD_FAB2(SCH_1):PAGE207
    38 ISENSE_PVCCIN_CPU1_PH1_IMON @BASEBOARD_FAB2_LIB.BASEBOARD_FAB2(SCH_1):ISENSE_PVCCIN_CPU1_PH1_IMON    I20 @BASEBOARD_FAB2_LIB.BASEBOARD_FAB2(SCH_1):PAGE207
     2    GND @BASEBOARD_FAB2_LIB.BASEBOARD_FAB2(SCH_1):GND    I20 @BASEBOARD_FAB2_LIB.BASEBOARD_FAB2(SCH_1):PAGE207
    31 NC_PVCCIN_CPU1_PH1_P31 @BASEBOARD_FAB2_LIB.BASEBOARD_FAB2(SCH_1):NC_PVCCIN_CPU1_PH1_P31    I20 @BASEBOARD_FAB2_LIB.BASEBOARD_FAB2(SCH_1):PAGE207
    37 VR_PVCCIN_CPU1_PH1_OCSET @BASEBOARD_FAB2_LIB.BASEBOARD_FAB2(SCH_1):VR_PVCCIN_CPU1_PH1_OCSET    I20 @BASEBOARD_FAB2_LIB.BASEBOARD_FAB2(SCH_1):PAGE207
    40    GND @BASEBOARD_FAB2_LIB.BASEBOARD_FAB2(SCH_1):GND    I20 @BASEBOARD_FAB2_LIB.BASEBOARD_FAB2(SCH_1):PAGE207
     7    GND @BASEBOARD_FAB2_LIB.BASEBOARD_FAB2(SCH_1):GND    I20 @BASEBOARD_FAB2_LIB.BASEBOARD_FAB2(SCH_1):PAGE207
     5    GND @BASEBOARD_FAB2_LIB.BASEBOARD_FAB2(SCH_1):GND    I20 @BASEBOARD_FAB2_LIB.BASEBOARD_FAB2(SCH_1):PAGE207
    32 VR_PVCCIN_CPU1_PH1_PHASE @BASEBOARD_FAB2_LIB.BASEBOARD_FAB2(SCH_1):VR_PVCCIN_CPU1_PH1_PHASE    I20 @BASEBOARD_FAB2_LIB.BASEBOARD_FAB2(SCH_1):PAGE207
    34 VR_PVCCIN_CPU1_PWM1 @BASEBOARD_FAB2_LIB.BASEBOARD_FAB2(SCH_1):VR_PVCCIN_CPU1_PWM1    I20 @BASEBOARD_FAB2_LIB.BASEBOARD_FAB2(SCH_1):PAGE207
    39 VR_PVCCIN_CPU1_AIREF1 @BASEBOARD_FAB2_LIB.BASEBOARD_FAB2(SCH_1):VR_PVCCIN_CPU1_AIREF1    I20 @BASEBOARD_FAB2_LIB.BASEBOARD_FAB2(SCH_1):PAGE207
    10 VR_PVCCIN_CPU1_PHASE1 @BASEBOARD_FAB2_LIB.BASEBOARD_FAB2(SCH_1):VR_PVCCIN_CPU1_PHASE1    I20 @BASEBOARD_FAB2_LIB.BASEBOARD_FAB2(SCH_1):PAGE207
    36 A_TSENSE_PVCCIN_CPU1 @BASEBOARD_FAB2_LIB.BASEBOARD_FAB2(SCH_1):A_TSENSE_PVCCIN_CPU1    I20 @BASEBOARD_FAB2_LIB.BASEBOARD_FAB2(SCH_1):PAGE207
     3 VR_PVCCIN_CPU1_PH1_VCIN @BASEBOARD_FAB2_LIB.BASEBOARD_FAB2(SCH_1):VR_PVCCIN_CPU1_PH1_VCIN    I20 @BASEBOARD_FAB2_LIB.BASEBOARD_FAB2(SCH_1):PAGE207
     4 P5V_STBY @BASEBOARD_FAB2_LIB.BASEBOARD_FAB2(SCH_1):P5V_STBY    I20 @BASEBOARD_FAB2_LIB.BASEBOARD_FAB2(SCH_1):PAGE207
    30 VR_FET_SW_P12V_STBY_PVCCIN_CPU1 @BASEBOARD_FAB2_LIB.BASEBOARD_FAB2(SCH_1):VR_FET_SW_P12V_STBY_PVCCIN_CPU1    I20 @BASEBOARD_FAB2_LIB.BASEBOARD_FAB2(SCH_1):PAGE207
    25 VR_FET_SW_P12V_STBY_PVCCIN_CPU1 @BASEBOARD_FAB2_LIB.BASEBOARD_FAB2(SCH_1):VR_FET_SW_P12V_STBY_PVCCIN_CPU1    I20 @BASEBOARD_FAB2_LIB.BASEBOARD_FAB2(SCH_1):PAGE207
     1 PVCCIN_CPU1 @BASEBOARD_FAB2_LIB.BASEBOARD_FAB2(SCH_1):PVCCIN_CPU1    I20 @BASEBOARD_FAB2_LIB.BASEBOARD_FAB2(SCH_1):PAGE207

EU1E3 MOSFETN_1D3S_SOT5-IC,G68777-001
     1 P12V_STBY @BASEBOARD_FAB2_LIB.BASEBOARD_FAB2(SCH_1):P12V_STBY    I54 @BASEBOARD_FAB2_LIB.BASEBOARD_FAB2(SCH_1):PAGE200
     2 P12V_STBY @BASEBOARD_FAB2_LIB.BASEBOARD_FAB2(SCH_1):P12V_STBY    I54 @BASEBOARD_FAB2_LIB.BASEBOARD_FAB2(SCH_1):PAGE200
     3 P12V_STBY @BASEBOARD_FAB2_LIB.BASEBOARD_FAB2(SCH_1):P12V_STBY    I54 @BASEBOARD_FAB2_LIB.BASEBOARD_FAB2(SCH_1):PAGE200
     5 P12V_MB0_SW @BASEBOARD_FAB2_LIB.BASEBOARD_FAB2(SCH_1):P12V_MB0_SW    I54 @BASEBOARD_FAB2_LIB.BASEBOARD_FAB2(SCH_1):PAGE200
     4 A_HSC_GATE1_R @BASEBOARD_FAB2_LIB.BASEBOARD_FAB2(SCH_1):A_HSC_GATE1_R    I54 @BASEBOARD_FAB2_LIB.BASEBOARD_FAB2(SCH_1):PAGE200

EU1F1 IR354XX_SM-IR35411,IC,H73688-0A
    33 VR_PVDDQ_GHJ_PH2_BOOT_R @BASEBOARD_FAB2_LIB.BASEBOARD_FAB2(SCH_1):VR_PVDDQ_GHJ_PH2_BOOT_R   I111 @BASEBOARD_FAB2_LIB.BASEBOARD_FAB2(SCH_1):PAGE224
    35 P5V_STBY @BASEBOARD_FAB2_LIB.BASEBOARD_FAB2(SCH_1):P5V_STBY   I111 @BASEBOARD_FAB2_LIB.BASEBOARD_FAB2(SCH_1):PAGE224
    41 TP_PVDDQ_GHJ_PH2_GL_1 @BASEBOARD_FAB2_LIB.BASEBOARD_FAB2(SCH_1):TP_PVDDQ_GHJ_PH2_GL_1   I111 @BASEBOARD_FAB2_LIB.BASEBOARD_FAB2(SCH_1):PAGE224
     6 TP_PVDDQ_GHJ_PH2_GL_0 @BASEBOARD_FAB2_LIB.BASEBOARD_FAB2(SCH_1):TP_PVDDQ_GHJ_PH2_GL_0   I111 @BASEBOARD_FAB2_LIB.BASEBOARD_FAB2(SCH_1):PAGE224
    38 ISENSE_PVDDQ_GHJ_PH2_IMON @BASEBOARD_FAB2_LIB.BASEBOARD_FAB2(SCH_1):ISENSE_PVDDQ_GHJ_PH2_IMON   I111 @BASEBOARD_FAB2_LIB.BASEBOARD_FAB2(SCH_1):PAGE224
     2    GND @BASEBOARD_FAB2_LIB.BASEBOARD_FAB2(SCH_1):GND   I111 @BASEBOARD_FAB2_LIB.BASEBOARD_FAB2(SCH_1):PAGE224
    31 NC_PVDDQ_GHJ_PH2_P31 @BASEBOARD_FAB2_LIB.BASEBOARD_FAB2(SCH_1):NC_PVDDQ_GHJ_PH2_P31   I111 @BASEBOARD_FAB2_LIB.BASEBOARD_FAB2(SCH_1):PAGE224
    37 VR_PVDDQ_GHJ_PH2_OCSET @BASEBOARD_FAB2_LIB.BASEBOARD_FAB2(SCH_1):VR_PVDDQ_GHJ_PH2_OCSET   I111 @BASEBOARD_FAB2_LIB.BASEBOARD_FAB2(SCH_1):PAGE224
    40    GND @BASEBOARD_FAB2_LIB.BASEBOARD_FAB2(SCH_1):GND   I111 @BASEBOARD_FAB2_LIB.BASEBOARD_FAB2(SCH_1):PAGE224
     7    GND @BASEBOARD_FAB2_LIB.BASEBOARD_FAB2(SCH_1):GND   I111 @BASEBOARD_FAB2_LIB.BASEBOARD_FAB2(SCH_1):PAGE224
     5    GND @BASEBOARD_FAB2_LIB.BASEBOARD_FAB2(SCH_1):GND   I111 @BASEBOARD_FAB2_LIB.BASEBOARD_FAB2(SCH_1):PAGE224
    32 VR_PVDDQ_GHJ_PH2_PHASE @BASEBOARD_FAB2_LIB.BASEBOARD_FAB2(SCH_1):VR_PVDDQ_GHJ_PH2_PHASE   I111 @BASEBOARD_FAB2_LIB.BASEBOARD_FAB2(SCH_1):PAGE224
    34 VR_PVDDQ_GHJ_PWM2 @BASEBOARD_FAB2_LIB.BASEBOARD_FAB2(SCH_1):VR_PVDDQ_GHJ_PWM2   I111 @BASEBOARD_FAB2_LIB.BASEBOARD_FAB2(SCH_1):PAGE224
    39 VR_PVDDQ_GHJ_AIREF2 @BASEBOARD_FAB2_LIB.BASEBOARD_FAB2(SCH_1):VR_PVDDQ_GHJ_AIREF2   I111 @BASEBOARD_FAB2_LIB.BASEBOARD_FAB2(SCH_1):PAGE224
    10 VR_PVDDQ_GHJ_PH2_SW @BASEBOARD_FAB2_LIB.BASEBOARD_FAB2(SCH_1):VR_PVDDQ_GHJ_PH2_SW   I111 @BASEBOARD_FAB2_LIB.BASEBOARD_FAB2(SCH_1):PAGE224
    36 A_TSENSE_PVDDQ_GHJ @BASEBOARD_FAB2_LIB.BASEBOARD_FAB2(SCH_1):A_TSENSE_PVDDQ_GHJ   I111 @BASEBOARD_FAB2_LIB.BASEBOARD_FAB2(SCH_1):PAGE224
     3 VR_PVDDQ_GHJ_PH2_VCIN @BASEBOARD_FAB2_LIB.BASEBOARD_FAB2(SCH_1):VR_PVDDQ_GHJ_PH2_VCIN   I111 @BASEBOARD_FAB2_LIB.BASEBOARD_FAB2(SCH_1):PAGE224
     4 P5V_STBY @BASEBOARD_FAB2_LIB.BASEBOARD_FAB2(SCH_1):P5V_STBY   I111 @BASEBOARD_FAB2_LIB.BASEBOARD_FAB2(SCH_1):PAGE224
    30 VR_FET_SW_P12V_STBY_PVDDQ_GHJ @BASEBOARD_FAB2_LIB.BASEBOARD_FAB2(SCH_1):VR_FET_SW_P12V_STBY_PVDDQ_GHJ   I111 @BASEBOARD_FAB2_LIB.BASEBOARD_FAB2(SCH_1):PAGE224
    25 VR_FET_SW_P12V_STBY_PVDDQ_GHJ @BASEBOARD_FAB2_LIB.BASEBOARD_FAB2(SCH_1):VR_FET_SW_P12V_STBY_PVDDQ_GHJ   I111 @BASEBOARD_FAB2_LIB.BASEBOARD_FAB2(SCH_1):PAGE224
     1 PVDDQ_GHJ @BASEBOARD_FAB2_LIB.BASEBOARD_FAB2(SCH_1):PVDDQ_GHJ   I111 @BASEBOARD_FAB2_LIB.BASEBOARD_FAB2(SCH_1):PAGE224

EU1G1 IR354XX_SM-IR35411,IC,H73688-0A
    33 VR_PVDDQ_GHJ_PH1_BOOT_R @BASEBOARD_FAB2_LIB.BASEBOARD_FAB2(SCH_1):VR_PVDDQ_GHJ_PH1_BOOT_R   I110 @BASEBOARD_FAB2_LIB.BASEBOARD_FAB2(SCH_1):PAGE224
    35 P5V_STBY @BASEBOARD_FAB2_LIB.BASEBOARD_FAB2(SCH_1):P5V_STBY   I110 @BASEBOARD_FAB2_LIB.BASEBOARD_FAB2(SCH_1):PAGE224
    41 TP_PVDDQ_GHJ_PH1_GL_1 @BASEBOARD_FAB2_LIB.BASEBOARD_FAB2(SCH_1):TP_PVDDQ_GHJ_PH1_GL_1   I110 @BASEBOARD_FAB2_LIB.BASEBOARD_FAB2(SCH_1):PAGE224
     6 TP_PVDDQ_GHJ_PH1_GL_0 @BASEBOARD_FAB2_LIB.BASEBOARD_FAB2(SCH_1):TP_PVDDQ_GHJ_PH1_GL_0   I110 @BASEBOARD_FAB2_LIB.BASEBOARD_FAB2(SCH_1):PAGE224
    38 ISENSE_PVDDQ_GHJ_PH1_IMON @BASEBOARD_FAB2_LIB.BASEBOARD_FAB2(SCH_1):ISENSE_PVDDQ_GHJ_PH1_IMON   I110 @BASEBOARD_FAB2_LIB.BASEBOARD_FAB2(SCH_1):PAGE224
     2    GND @BASEBOARD_FAB2_LIB.BASEBOARD_FAB2(SCH_1):GND   I110 @BASEBOARD_FAB2_LIB.BASEBOARD_FAB2(SCH_1):PAGE224
    31 NC_PVDDQ_GHJ_PH1_P31 @BASEBOARD_FAB2_LIB.BASEBOARD_FAB2(SCH_1):NC_PVDDQ_GHJ_PH1_P31   I110 @BASEBOARD_FAB2_LIB.BASEBOARD_FAB2(SCH_1):PAGE224
    37 VR_PVDDQ_GHJ_PH1_OCSET @BASEBOARD_FAB2_LIB.BASEBOARD_FAB2(SCH_1):VR_PVDDQ_GHJ_PH1_OCSET   I110 @BASEBOARD_FAB2_LIB.BASEBOARD_FAB2(SCH_1):PAGE224
    40    GND @BASEBOARD_FAB2_LIB.BASEBOARD_FAB2(SCH_1):GND   I110 @BASEBOARD_FAB2_LIB.BASEBOARD_FAB2(SCH_1):PAGE224
     7    GND @BASEBOARD_FAB2_LIB.BASEBOARD_FAB2(SCH_1):GND   I110 @BASEBOARD_FAB2_LIB.BASEBOARD_FAB2(SCH_1):PAGE224
     5    GND @BASEBOARD_FAB2_LIB.BASEBOARD_FAB2(SCH_1):GND   I110 @BASEBOARD_FAB2_LIB.BASEBOARD_FAB2(SCH_1):PAGE224
    32 VR_PVDDQ_GHJ_PH1_PHASE @BASEBOARD_FAB2_LIB.BASEBOARD_FAB2(SCH_1):VR_PVDDQ_GHJ_PH1_PHASE   I110 @BASEBOARD_FAB2_LIB.BASEBOARD_FAB2(SCH_1):PAGE224
    34 VR_PVDDQ_GHJ_PWM1 @BASEBOARD_FAB2_LIB.BASEBOARD_FAB2(SCH_1):VR_PVDDQ_GHJ_PWM1   I110 @BASEBOARD_FAB2_LIB.BASEBOARD_FAB2(SCH_1):PAGE224
    39 VR_PVDDQ_GHJ_AIREF1 @BASEBOARD_FAB2_LIB.BASEBOARD_FAB2(SCH_1):VR_PVDDQ_GHJ_AIREF1   I110 @BASEBOARD_FAB2_LIB.BASEBOARD_FAB2(SCH_1):PAGE224
    10 VR_PVDDQ_GHJ_PH1_SW @BASEBOARD_FAB2_LIB.BASEBOARD_FAB2(SCH_1):VR_PVDDQ_GHJ_PH1_SW   I110 @BASEBOARD_FAB2_LIB.BASEBOARD_FAB2(SCH_1):PAGE224
    36 A_TSENSE_PVDDQ_GHJ @BASEBOARD_FAB2_LIB.BASEBOARD_FAB2(SCH_1):A_TSENSE_PVDDQ_GHJ   I110 @BASEBOARD_FAB2_LIB.BASEBOARD_FAB2(SCH_1):PAGE224
     3 VR_PVDDQ_GHJ_PH1_VCIN @BASEBOARD_FAB2_LIB.BASEBOARD_FAB2(SCH_1):VR_PVDDQ_GHJ_PH1_VCIN   I110 @BASEBOARD_FAB2_LIB.BASEBOARD_FAB2(SCH_1):PAGE224
     4 P5V_STBY @BASEBOARD_FAB2_LIB.BASEBOARD_FAB2(SCH_1):P5V_STBY   I110 @BASEBOARD_FAB2_LIB.BASEBOARD_FAB2(SCH_1):PAGE224
    30 VR_FET_SW_P12V_STBY_PVDDQ_GHJ @BASEBOARD_FAB2_LIB.BASEBOARD_FAB2(SCH_1):VR_FET_SW_P12V_STBY_PVDDQ_GHJ   I110 @BASEBOARD_FAB2_LIB.BASEBOARD_FAB2(SCH_1):PAGE224
    25 VR_FET_SW_P12V_STBY_PVDDQ_GHJ @BASEBOARD_FAB2_LIB.BASEBOARD_FAB2(SCH_1):VR_FET_SW_P12V_STBY_PVDDQ_GHJ   I110 @BASEBOARD_FAB2_LIB.BASEBOARD_FAB2(SCH_1):PAGE224
     1 PVDDQ_GHJ @BASEBOARD_FAB2_LIB.BASEBOARD_FAB2(SCH_1):PVDDQ_GHJ   I110 @BASEBOARD_FAB2_LIB.BASEBOARD_FAB2(SCH_1):PAGE224

EU1G2 PXM1310B_QFN-IC,H89186-001
     1 TP_PVDDQ_GHJ_BPWM1 @BASEBOARD_FAB2_LIB.BASEBOARD_FAB2(SCH_1):TP_PVDDQ_GHJ_BPWM1    I90 @BASEBOARD_FAB2_LIB.BASEBOARD_FAB2(SCH_1):PAGE223
     2 NC_PVDDQ_GHJ_DNC0 @BASEBOARD_FAB2_LIB.BASEBOARD_FAB2(SCH_1):NC_PVDDQ_GHJ_DNC0    I90 @BASEBOARD_FAB2_LIB.BASEBOARD_FAB2(SCH_1):PAGE223
     3 TP_PVDDQ_GHJ_PWM3 @BASEBOARD_FAB2_LIB.BASEBOARD_FAB2(SCH_1):TP_PVDDQ_GHJ_PWM3    I90 @BASEBOARD_FAB2_LIB.BASEBOARD_FAB2(SCH_1):PAGE223
     4 VR_PVDDQ_GHJ_PWM2 @BASEBOARD_FAB2_LIB.BASEBOARD_FAB2(SCH_1):VR_PVDDQ_GHJ_PWM2    I90 @BASEBOARD_FAB2_LIB.BASEBOARD_FAB2(SCH_1):PAGE223
     5 VR_PVDDQ_GHJ_PWM1 @BASEBOARD_FAB2_LIB.BASEBOARD_FAB2(SCH_1):VR_PVDDQ_GHJ_PWM1    I90 @BASEBOARD_FAB2_LIB.BASEBOARD_FAB2(SCH_1):PAGE223
     6 SMB_VR_SDA_VDDQ_GHJ @BASEBOARD_FAB2_LIB.BASEBOARD_FAB2(SCH_1):SMB_VR_SDA_VDDQ_GHJ    I90 @BASEBOARD_FAB2_LIB.BASEBOARD_FAB2(SCH_1):PAGE223
     7 SMB_VR_SCL_VDDQ_GHJ @BASEBOARD_FAB2_LIB.BASEBOARD_FAB2(SCH_1):SMB_VR_SCL_VDDQ_GHJ    I90 @BASEBOARD_FAB2_LIB.BASEBOARD_FAB2(SCH_1):PAGE223
     8 TP_PVDDQ_GHJ_RESET_N @BASEBOARD_FAB2_LIB.BASEBOARD_FAB2(SCH_1):TP_PVDDQ_GHJ_RESET_N    I90 @BASEBOARD_FAB2_LIB.BASEBOARD_FAB2(SCH_1):PAGE223
     9 PWRGD_PVDDQ_GHJ_R @BASEBOARD_FAB2_LIB.BASEBOARD_FAB2(SCH_1):PWRGD_PVDDQ_GHJ_R    I90 @BASEBOARD_FAB2_LIB.BASEBOARD_FAB2(SCH_1):PAGE223
    10 VR_PVDDQ_GHJ_VREN @BASEBOARD_FAB2_LIB.BASEBOARD_FAB2(SCH_1):VR_PVDDQ_GHJ_VREN    I90 @BASEBOARD_FAB2_LIB.BASEBOARD_FAB2(SCH_1):PAGE223
    11 IRQ_PVDDQ_GHJ_VRHOT_LVT3_R_N @BASEBOARD_FAB2_LIB.BASEBOARD_FAB2(SCH_1):IRQ_PVDDQ_GHJ_VRHOT_LVT3_R_N    I90 @BASEBOARD_FAB2_LIB.BASEBOARD_FAB2(SCH_1):PAGE223
    12 NC_PVDDQ_GHJ_PINALRT_N @BASEBOARD_FAB2_LIB.BASEBOARD_FAB2(SCH_1):NC_PVDDQ_GHJ_PINALRT_N    I90 @BASEBOARD_FAB2_LIB.BASEBOARD_FAB2(SCH_1):PAGE223
    13 PU_VR_PVDDQ_GHJ_FAULT1 @BASEBOARD_FAB2_LIB.BASEBOARD_FAB2(SCH_1):PU_VR_PVDDQ_GHJ_FAULT1    I90 @BASEBOARD_FAB2_LIB.BASEBOARD_FAB2(SCH_1):PAGE223
    14 TP_PVDDQ_GHJ_MP1 @BASEBOARD_FAB2_LIB.BASEBOARD_FAB2(SCH_1):TP_PVDDQ_GHJ_MP1    I90 @BASEBOARD_FAB2_LIB.BASEBOARD_FAB2(SCH_1):PAGE223
    15 SVID_CLK_PVDDQ_GHJ @BASEBOARD_FAB2_LIB.BASEBOARD_FAB2(SCH_1):SVID_CLK_PVDDQ_GHJ    I90 @BASEBOARD_FAB2_LIB.BASEBOARD_FAB2(SCH_1):PAGE223
    16 SVID_VDIO_PVDDQ_GHJ @BASEBOARD_FAB2_LIB.BASEBOARD_FAB2(SCH_1):SVID_VDIO_PVDDQ_GHJ    I90 @BASEBOARD_FAB2_LIB.BASEBOARD_FAB2(SCH_1):PAGE223
    17 SVID_ALERT_PVDDQ_GHJ @BASEBOARD_FAB2_LIB.BASEBOARD_FAB2(SCH_1):SVID_ALERT_PVDDQ_GHJ    I90 @BASEBOARD_FAB2_LIB.BASEBOARD_FAB2(SCH_1):PAGE223
    18 TP_PVDDQ_GHJ_MP2 @BASEBOARD_FAB2_LIB.BASEBOARD_FAB2(SCH_1):TP_PVDDQ_GHJ_MP2    I90 @BASEBOARD_FAB2_LIB.BASEBOARD_FAB2(SCH_1):PAGE223
    19 VR_PVDDQ_GHJ_AVSP @BASEBOARD_FAB2_LIB.BASEBOARD_FAB2(SCH_1):VR_PVDDQ_GHJ_AVSP    I90 @BASEBOARD_FAB2_LIB.BASEBOARD_FAB2(SCH_1):PAGE223
    20 VSENSE_PVDDQ_GHJ_N @BASEBOARD_FAB2_LIB.BASEBOARD_FAB2(SCH_1):VSENSE_PVDDQ_GHJ_N    I90 @BASEBOARD_FAB2_LIB.BASEBOARD_FAB2(SCH_1):PAGE223
    21 VR_PVDDQ_GHJ_AIREF1 @BASEBOARD_FAB2_LIB.BASEBOARD_FAB2(SCH_1):VR_PVDDQ_GHJ_AIREF1    I90 @BASEBOARD_FAB2_LIB.BASEBOARD_FAB2(SCH_1):PAGE223
    22 ISENSE_PVDDQ_GHJ_PH1_IMON @BASEBOARD_FAB2_LIB.BASEBOARD_FAB2(SCH_1):ISENSE_PVDDQ_GHJ_PH1_IMON    I90 @BASEBOARD_FAB2_LIB.BASEBOARD_FAB2(SCH_1):PAGE223
    23 VR_PVDDQ_GHJ_AIREF2 @BASEBOARD_FAB2_LIB.BASEBOARD_FAB2(SCH_1):VR_PVDDQ_GHJ_AIREF2    I90 @BASEBOARD_FAB2_LIB.BASEBOARD_FAB2(SCH_1):PAGE223
    24 ISENSE_PVDDQ_GHJ_PH2_IMON @BASEBOARD_FAB2_LIB.BASEBOARD_FAB2(SCH_1):ISENSE_PVDDQ_GHJ_PH2_IMON    I90 @BASEBOARD_FAB2_LIB.BASEBOARD_FAB2(SCH_1):PAGE223
    25 TP_PVDDQ_GHJ_PH3_IMON_REF @BASEBOARD_FAB2_LIB.BASEBOARD_FAB2(SCH_1):TP_PVDDQ_GHJ_PH3_IMON_REF    I90 @BASEBOARD_FAB2_LIB.BASEBOARD_FAB2(SCH_1):PAGE223
    26 TP_PVDDQ_GHJ_PH3_IMON @BASEBOARD_FAB2_LIB.BASEBOARD_FAB2(SCH_1):TP_PVDDQ_GHJ_PH3_IMON    I90 @BASEBOARD_FAB2_LIB.BASEBOARD_FAB2(SCH_1):PAGE223
    27    GND @BASEBOARD_FAB2_LIB.BASEBOARD_FAB2(SCH_1):GND    I90 @BASEBOARD_FAB2_LIB.BASEBOARD_FAB2(SCH_1):PAGE223
    28 NC_PVDDQ_GHJ_DNC1 @BASEBOARD_FAB2_LIB.BASEBOARD_FAB2(SCH_1):NC_PVDDQ_GHJ_DNC1    I90 @BASEBOARD_FAB2_LIB.BASEBOARD_FAB2(SCH_1):PAGE223
    29 TP_PVDDQ_GHJ_BVSEN @BASEBOARD_FAB2_LIB.BASEBOARD_FAB2(SCH_1):TP_PVDDQ_GHJ_BVSEN    I90 @BASEBOARD_FAB2_LIB.BASEBOARD_FAB2(SCH_1):PAGE223
    30 TP_PVDDQ_GHJ_BVREF @BASEBOARD_FAB2_LIB.BASEBOARD_FAB2(SCH_1):TP_PVDDQ_GHJ_BVREF    I90 @BASEBOARD_FAB2_LIB.BASEBOARD_FAB2(SCH_1):PAGE223
    31 TP_PVDDQ_GHJ_BREF1 @BASEBOARD_FAB2_LIB.BASEBOARD_FAB2(SCH_1):TP_PVDDQ_GHJ_BREF1    I90 @BASEBOARD_FAB2_LIB.BASEBOARD_FAB2(SCH_1):PAGE223
    32    GND @BASEBOARD_FAB2_LIB.BASEBOARD_FAB2(SCH_1):GND    I90 @BASEBOARD_FAB2_LIB.BASEBOARD_FAB2(SCH_1):PAGE223
    33 VR_PVDDQ_GHJ_XADDR2 @BASEBOARD_FAB2_LIB.BASEBOARD_FAB2(SCH_1):VR_PVDDQ_GHJ_XADDR2    I90 @BASEBOARD_FAB2_LIB.BASEBOARD_FAB2(SCH_1):PAGE223
    34 TP_PVDDQ_GHJ_BTSEN @BASEBOARD_FAB2_LIB.BASEBOARD_FAB2(SCH_1):TP_PVDDQ_GHJ_BTSEN    I90 @BASEBOARD_FAB2_LIB.BASEBOARD_FAB2(SCH_1):PAGE223
    35 A_TSENSE_PVDDQ_GHJ @BASEBOARD_FAB2_LIB.BASEBOARD_FAB2(SCH_1):A_TSENSE_PVDDQ_GHJ    I90 @BASEBOARD_FAB2_LIB.BASEBOARD_FAB2(SCH_1):PAGE223
    36 VR_PVDDQ_GHJ_XADDR1 @BASEBOARD_FAB2_LIB.BASEBOARD_FAB2(SCH_1):VR_PVDDQ_GHJ_XADDR1    I90 @BASEBOARD_FAB2_LIB.BASEBOARD_FAB2(SCH_1):PAGE223
    37 VR_PVDDQ_GHJ_VINSEN @BASEBOARD_FAB2_LIB.BASEBOARD_FAB2(SCH_1):VR_PVDDQ_GHJ_VINSEN    I90 @BASEBOARD_FAB2_LIB.BASEBOARD_FAB2(SCH_1):PAGE223
    38 VR_PVDDQ_GHJ_AIINSEN @BASEBOARD_FAB2_LIB.BASEBOARD_FAB2(SCH_1):VR_PVDDQ_GHJ_AIINSEN    I90 @BASEBOARD_FAB2_LIB.BASEBOARD_FAB2(SCH_1):PAGE223
    39 VR_PVDDQ_GHJ_VDD @BASEBOARD_FAB2_LIB.BASEBOARD_FAB2(SCH_1):VR_PVDDQ_GHJ_VDD    I90 @BASEBOARD_FAB2_LIB.BASEBOARD_FAB2(SCH_1):PAGE223
    40 VR_PVDDQ_GHJ_VD12 @BASEBOARD_FAB2_LIB.BASEBOARD_FAB2(SCH_1):VR_PVDDQ_GHJ_VD12    I90 @BASEBOARD_FAB2_LIB.BASEBOARD_FAB2(SCH_1):PAGE223
    41    GND @BASEBOARD_FAB2_LIB.BASEBOARD_FAB2(SCH_1):GND    I90 @BASEBOARD_FAB2_LIB.BASEBOARD_FAB2(SCH_1):PAGE223

EU2T1 SLG55021_SM-IC,G56246-001
     4    GND @BASEBOARD_FAB2_LIB.BASEBOARD_FAB2(SCH_1):GND     I1 @BASEBOARD_FAB2_LIB.BASEBOARD_FAB2(SCH_1):PAGE198
     9    GND @BASEBOARD_FAB2_LIB.BASEBOARD_FAB2(SCH_1):GND     I1 @BASEBOARD_FAB2_LIB.BASEBOARD_FAB2(SCH_1):PAGE198
     1 P5V_STBY @BASEBOARD_FAB2_LIB.BASEBOARD_FAB2(SCH_1):P5V_STBY     I1 @BASEBOARD_FAB2_LIB.BASEBOARD_FAB2(SCH_1):PAGE198
     2 FM_P3V3_CPLD_EN @BASEBOARD_FAB2_LIB.BASEBOARD_FAB2(SCH_1):FM_P3V3_CPLD_EN     I1 @BASEBOARD_FAB2_LIB.BASEBOARD_FAB2(SCH_1):PAGE198
     3 P5V_STBY @BASEBOARD_FAB2_LIB.BASEBOARD_FAB2(SCH_1):P5V_STBY     I1 @BASEBOARD_FAB2_LIB.BASEBOARD_FAB2(SCH_1):PAGE198
     5 P3V3_STBY @BASEBOARD_FAB2_LIB.BASEBOARD_FAB2(SCH_1):P3V3_STBY     I1 @BASEBOARD_FAB2_LIB.BASEBOARD_FAB2(SCH_1):PAGE198
     6   P3V3 @BASEBOARD_FAB2_LIB.BASEBOARD_FAB2(SCH_1):P3V3     I1 @BASEBOARD_FAB2_LIB.BASEBOARD_FAB2(SCH_1):PAGE198
     7 P3V3_SWITCH_G @BASEBOARD_FAB2_LIB.BASEBOARD_FAB2(SCH_1):P3V3_SWITCH_G     I1 @BASEBOARD_FAB2_LIB.BASEBOARD_FAB2(SCH_1):PAGE198
     8 TP_SLG55021_P3V3_8 @BASEBOARD_FAB2_LIB.BASEBOARD_FAB2(SCH_1):TP_SLG55021_P3V3_8     I1 @BASEBOARD_FAB2_LIB.BASEBOARD_FAB2(SCH_1):PAGE198

EU3P1 PXE1110B_QFN-IC,H89187-001
     1 NC_PVCCIO_CPU0_DNC0 @BASEBOARD_FAB2_LIB.BASEBOARD_FAB2(SCH_1):NC_PVCCIO_CPU0_DNC0    I93 @BASEBOARD_FAB2_LIB.BASEBOARD_FAB2(SCH_1):PAGE211
     2 NC_PVCCIO_CPU0_DNC1 @BASEBOARD_FAB2_LIB.BASEBOARD_FAB2(SCH_1):NC_PVCCIO_CPU0_DNC1    I93 @BASEBOARD_FAB2_LIB.BASEBOARD_FAB2(SCH_1):PAGE211
     3 TP_PVCCIO_CPU0_BPWM1 @BASEBOARD_FAB2_LIB.BASEBOARD_FAB2(SCH_1):TP_PVCCIO_CPU0_BPWM1    I93 @BASEBOARD_FAB2_LIB.BASEBOARD_FAB2(SCH_1):PAGE211
     4 NC_PVCCIO_CPU0_DNC2 @BASEBOARD_FAB2_LIB.BASEBOARD_FAB2(SCH_1):NC_PVCCIO_CPU0_DNC2    I93 @BASEBOARD_FAB2_LIB.BASEBOARD_FAB2(SCH_1):PAGE211
     5 VR_PVCCIO_CPU0_PWM1 @BASEBOARD_FAB2_LIB.BASEBOARD_FAB2(SCH_1):VR_PVCCIO_CPU0_PWM1    I93 @BASEBOARD_FAB2_LIB.BASEBOARD_FAB2(SCH_1):PAGE211
     6 SMB_VR_SDA_PVCCIO_CPU0 @BASEBOARD_FAB2_LIB.BASEBOARD_FAB2(SCH_1):SMB_VR_SDA_PVCCIO_CPU0    I93 @BASEBOARD_FAB2_LIB.BASEBOARD_FAB2(SCH_1):PAGE211
     7 SMB_VR_SCL_PVCCIO_CPU0 @BASEBOARD_FAB2_LIB.BASEBOARD_FAB2(SCH_1):SMB_VR_SCL_PVCCIO_CPU0    I93 @BASEBOARD_FAB2_LIB.BASEBOARD_FAB2(SCH_1):PAGE211
     8 TP_PVCCIO_CPU0_RESET_N @BASEBOARD_FAB2_LIB.BASEBOARD_FAB2(SCH_1):TP_PVCCIO_CPU0_RESET_N    I93 @BASEBOARD_FAB2_LIB.BASEBOARD_FAB2(SCH_1):PAGE211
     9 PWRGD_PVCCIO_CPU0_R @BASEBOARD_FAB2_LIB.BASEBOARD_FAB2(SCH_1):PWRGD_PVCCIO_CPU0_R    I93 @BASEBOARD_FAB2_LIB.BASEBOARD_FAB2(SCH_1):PAGE211
    10 VR_PVCCIO_CPU0_EN @BASEBOARD_FAB2_LIB.BASEBOARD_FAB2(SCH_1):VR_PVCCIO_CPU0_EN    I93 @BASEBOARD_FAB2_LIB.BASEBOARD_FAB2(SCH_1):PAGE211
    11 IRQ_PVCCIO_CPU0_VRHOT_N @BASEBOARD_FAB2_LIB.BASEBOARD_FAB2(SCH_1):IRQ_PVCCIO_CPU0_VRHOT_N    I93 @BASEBOARD_FAB2_LIB.BASEBOARD_FAB2(SCH_1):PAGE211
    12 TP_PVCCIO_CPU0_PINALRT_N @BASEBOARD_FAB2_LIB.BASEBOARD_FAB2(SCH_1):TP_PVCCIO_CPU0_PINALRT_N    I93 @BASEBOARD_FAB2_LIB.BASEBOARD_FAB2(SCH_1):PAGE211
    13 TP_VR_PVCCIO_CPU0_MP0 @BASEBOARD_FAB2_LIB.BASEBOARD_FAB2(SCH_1):TP_VR_PVCCIO_CPU0_MP0    I93 @BASEBOARD_FAB2_LIB.BASEBOARD_FAB2(SCH_1):PAGE211
    14 TP_VR_PVCCIO_CPU0_MP1 @BASEBOARD_FAB2_LIB.BASEBOARD_FAB2(SCH_1):TP_VR_PVCCIO_CPU0_MP1    I93 @BASEBOARD_FAB2_LIB.BASEBOARD_FAB2(SCH_1):PAGE211
    15 SVID_CLK_PVCCIO_CPU0 @BASEBOARD_FAB2_LIB.BASEBOARD_FAB2(SCH_1):SVID_CLK_PVCCIO_CPU0    I93 @BASEBOARD_FAB2_LIB.BASEBOARD_FAB2(SCH_1):PAGE211
    16 SVID_VDIO_PVCCIO_CPU0 @BASEBOARD_FAB2_LIB.BASEBOARD_FAB2(SCH_1):SVID_VDIO_PVCCIO_CPU0    I93 @BASEBOARD_FAB2_LIB.BASEBOARD_FAB2(SCH_1):PAGE211
    17 SVID_ALERT_PVCCIO_CPU0 @BASEBOARD_FAB2_LIB.BASEBOARD_FAB2(SCH_1):SVID_ALERT_PVCCIO_CPU0    I93 @BASEBOARD_FAB2_LIB.BASEBOARD_FAB2(SCH_1):PAGE211
    18 TP_VR_PVCCIO_CPU0_MP2 @BASEBOARD_FAB2_LIB.BASEBOARD_FAB2(SCH_1):TP_VR_PVCCIO_CPU0_MP2    I93 @BASEBOARD_FAB2_LIB.BASEBOARD_FAB2(SCH_1):PAGE211
    19 VR_PVCCIO_CPU0_AVSP @BASEBOARD_FAB2_LIB.BASEBOARD_FAB2(SCH_1):VR_PVCCIO_CPU0_AVSP    I93 @BASEBOARD_FAB2_LIB.BASEBOARD_FAB2(SCH_1):PAGE211
    20 VSENSE_PVCCIO_CPU0_AVSN @BASEBOARD_FAB2_LIB.BASEBOARD_FAB2(SCH_1):VSENSE_PVCCIO_CPU0_AVSN    I93 @BASEBOARD_FAB2_LIB.BASEBOARD_FAB2(SCH_1):PAGE211
    21 VR_PVCCIO_CPU0_AIREF1 @BASEBOARD_FAB2_LIB.BASEBOARD_FAB2(SCH_1):VR_PVCCIO_CPU0_AIREF1    I93 @BASEBOARD_FAB2_LIB.BASEBOARD_FAB2(SCH_1):PAGE211
    22 ISENSE_PVCCIO_CPU0_PH1_IMON @BASEBOARD_FAB2_LIB.BASEBOARD_FAB2(SCH_1):ISENSE_PVCCIO_CPU0_PH1_IMON    I93 @BASEBOARD_FAB2_LIB.BASEBOARD_FAB2(SCH_1):PAGE211
    23    GND @BASEBOARD_FAB2_LIB.BASEBOARD_FAB2(SCH_1):GND    I93 @BASEBOARD_FAB2_LIB.BASEBOARD_FAB2(SCH_1):PAGE211
    24 NC_PVCCIO_CPU0_DNC3 @BASEBOARD_FAB2_LIB.BASEBOARD_FAB2(SCH_1):NC_PVCCIO_CPU0_DNC3    I93 @BASEBOARD_FAB2_LIB.BASEBOARD_FAB2(SCH_1):PAGE211
    25 TP_PVCCIO_CPU0_BIREF1 @BASEBOARD_FAB2_LIB.BASEBOARD_FAB2(SCH_1):TP_PVCCIO_CPU0_BIREF1    I93 @BASEBOARD_FAB2_LIB.BASEBOARD_FAB2(SCH_1):PAGE211
    26    GND @BASEBOARD_FAB2_LIB.BASEBOARD_FAB2(SCH_1):GND    I93 @BASEBOARD_FAB2_LIB.BASEBOARD_FAB2(SCH_1):PAGE211
    27    GND @BASEBOARD_FAB2_LIB.BASEBOARD_FAB2(SCH_1):GND    I93 @BASEBOARD_FAB2_LIB.BASEBOARD_FAB2(SCH_1):PAGE211
    28 NC_PVCCIO_CPU0_DNC4 @BASEBOARD_FAB2_LIB.BASEBOARD_FAB2(SCH_1):NC_PVCCIO_CPU0_DNC4    I93 @BASEBOARD_FAB2_LIB.BASEBOARD_FAB2(SCH_1):PAGE211
    29 TP_PVCCIO_CPU0_BVSEN @BASEBOARD_FAB2_LIB.BASEBOARD_FAB2(SCH_1):TP_PVCCIO_CPU0_BVSEN    I93 @BASEBOARD_FAB2_LIB.BASEBOARD_FAB2(SCH_1):PAGE211
    30 TP_PVCCIO_CPU0_BVREF @BASEBOARD_FAB2_LIB.BASEBOARD_FAB2(SCH_1):TP_PVCCIO_CPU0_BVREF    I93 @BASEBOARD_FAB2_LIB.BASEBOARD_FAB2(SCH_1):PAGE211
    31 TP_VR_PVCCIO_CPU0_MP3 @BASEBOARD_FAB2_LIB.BASEBOARD_FAB2(SCH_1):TP_VR_PVCCIO_CPU0_MP3    I93 @BASEBOARD_FAB2_LIB.BASEBOARD_FAB2(SCH_1):PAGE211
    32 PU_VR_PVCCIO_CPU0_FAULT1 @BASEBOARD_FAB2_LIB.BASEBOARD_FAB2(SCH_1):PU_VR_PVCCIO_CPU0_FAULT1    I93 @BASEBOARD_FAB2_LIB.BASEBOARD_FAB2(SCH_1):PAGE211
    33 VR_PVCCIO_CPU0_XADDR2 @BASEBOARD_FAB2_LIB.BASEBOARD_FAB2(SCH_1):VR_PVCCIO_CPU0_XADDR2    I93 @BASEBOARD_FAB2_LIB.BASEBOARD_FAB2(SCH_1):PAGE211
    34 TP_PVCCIO_CPU0_BTSEN @BASEBOARD_FAB2_LIB.BASEBOARD_FAB2(SCH_1):TP_PVCCIO_CPU0_BTSEN    I93 @BASEBOARD_FAB2_LIB.BASEBOARD_FAB2(SCH_1):PAGE211
    35 A_TSENSE_PVCCIO_CPU0 @BASEBOARD_FAB2_LIB.BASEBOARD_FAB2(SCH_1):A_TSENSE_PVCCIO_CPU0    I93 @BASEBOARD_FAB2_LIB.BASEBOARD_FAB2(SCH_1):PAGE211
    36 VR_PVCCIO_CPU0_XADDR1 @BASEBOARD_FAB2_LIB.BASEBOARD_FAB2(SCH_1):VR_PVCCIO_CPU0_XADDR1    I93 @BASEBOARD_FAB2_LIB.BASEBOARD_FAB2(SCH_1):PAGE211
    37 VR_PVCCIO_CPU0_VINSEN @BASEBOARD_FAB2_LIB.BASEBOARD_FAB2(SCH_1):VR_PVCCIO_CPU0_VINSEN    I93 @BASEBOARD_FAB2_LIB.BASEBOARD_FAB2(SCH_1):PAGE211
    38 TP_VR_PVCCIO_CPU0_AIINSEN @BASEBOARD_FAB2_LIB.BASEBOARD_FAB2(SCH_1):TP_VR_PVCCIO_CPU0_AIINSEN    I93 @BASEBOARD_FAB2_LIB.BASEBOARD_FAB2(SCH_1):PAGE211
    39 VR_PVCCIO_CPU0_VDD @BASEBOARD_FAB2_LIB.BASEBOARD_FAB2(SCH_1):VR_PVCCIO_CPU0_VDD    I93 @BASEBOARD_FAB2_LIB.BASEBOARD_FAB2(SCH_1):PAGE211
    40 VR_PVCCIO_CPU0_VD12 @BASEBOARD_FAB2_LIB.BASEBOARD_FAB2(SCH_1):VR_PVCCIO_CPU0_VD12    I93 @BASEBOARD_FAB2_LIB.BASEBOARD_FAB2(SCH_1):PAGE211
    41    GND @BASEBOARD_FAB2_LIB.BASEBOARD_FAB2(SCH_1):GND    I93 @BASEBOARD_FAB2_LIB.BASEBOARD_FAB2(SCH_1):PAGE211

EU4A1 MIC5166_DFN-IC,H55101-001
     7 FM_PVTT_DEF_EN_R @BASEBOARD_FAB2_LIB.BASEBOARD_FAB2(SCH_1):FM_PVTT_DEF_EN_R    I31 @BASEBOARD_FAB2_LIB.BASEBOARD_FAB2(SCH_1):PAGE222
    10 PVDDQ_DEF @BASEBOARD_FAB2_LIB.BASEBOARD_FAB2(SCH_1):PVDDQ_DEF    I31 @BASEBOARD_FAB2_LIB.BASEBOARD_FAB2(SCH_1):PAGE222
     1 VR_PVTT_DEF_VREF @BASEBOARD_FAB2_LIB.BASEBOARD_FAB2(SCH_1):VR_PVTT_DEF_VREF    I31 @BASEBOARD_FAB2_LIB.BASEBOARD_FAB2(SCH_1):PAGE222
     2 VR_PVTT_DEF_BIAS @BASEBOARD_FAB2_LIB.BASEBOARD_FAB2(SCH_1):VR_PVTT_DEF_BIAS    I31 @BASEBOARD_FAB2_LIB.BASEBOARD_FAB2(SCH_1):PAGE222
     3    GND @BASEBOARD_FAB2_LIB.BASEBOARD_FAB2(SCH_1):GND    I31 @BASEBOARD_FAB2_LIB.BASEBOARD_FAB2(SCH_1):PAGE222
     5 PWRGD_PVTT_DEF_CPU0_R @BASEBOARD_FAB2_LIB.BASEBOARD_FAB2(SCH_1):PWRGD_PVTT_DEF_CPU0_R    I31 @BASEBOARD_FAB2_LIB.BASEBOARD_FAB2(SCH_1):PAGE222
     4 VSENSE_PVDDQ_DEF_VTT @BASEBOARD_FAB2_LIB.BASEBOARD_FAB2(SCH_1):VSENSE_PVDDQ_DEF_VTT    I31 @BASEBOARD_FAB2_LIB.BASEBOARD_FAB2(SCH_1):PAGE222
     6 VR_PVTT_DEF_SNS @BASEBOARD_FAB2_LIB.BASEBOARD_FAB2(SCH_1):VR_PVTT_DEF_SNS    I31 @BASEBOARD_FAB2_LIB.BASEBOARD_FAB2(SCH_1):PAGE222
     8    GND @BASEBOARD_FAB2_LIB.BASEBOARD_FAB2(SCH_1):GND    I31 @BASEBOARD_FAB2_LIB.BASEBOARD_FAB2(SCH_1):PAGE222
     9 PVTT_DEF @BASEBOARD_FAB2_LIB.BASEBOARD_FAB2(SCH_1):PVTT_DEF    I31 @BASEBOARD_FAB2_LIB.BASEBOARD_FAB2(SCH_1):PAGE222
    11    GND @BASEBOARD_FAB2_LIB.BASEBOARD_FAB2(SCH_1):GND    I31 @BASEBOARD_FAB2_LIB.BASEBOARD_FAB2(SCH_1):PAGE222

EU4A2 MIC5166_DFN-IC,H55101-001
     7 FM_PVTT_KLM_EN_R @BASEBOARD_FAB2_LIB.BASEBOARD_FAB2(SCH_1):FM_PVTT_KLM_EN_R    I31 @BASEBOARD_FAB2_LIB.BASEBOARD_FAB2(SCH_1):PAGE230
    10 PVDDQ_KLM @BASEBOARD_FAB2_LIB.BASEBOARD_FAB2(SCH_1):PVDDQ_KLM    I31 @BASEBOARD_FAB2_LIB.BASEBOARD_FAB2(SCH_1):PAGE230
     1 VR_PVTT_KLM_VREF @BASEBOARD_FAB2_LIB.BASEBOARD_FAB2(SCH_1):VR_PVTT_KLM_VREF    I31 @BASEBOARD_FAB2_LIB.BASEBOARD_FAB2(SCH_1):PAGE230
     2 VR_PVTT_KLM_BIAS @BASEBOARD_FAB2_LIB.BASEBOARD_FAB2(SCH_1):VR_PVTT_KLM_BIAS    I31 @BASEBOARD_FAB2_LIB.BASEBOARD_FAB2(SCH_1):PAGE230
     3    GND @BASEBOARD_FAB2_LIB.BASEBOARD_FAB2(SCH_1):GND    I31 @BASEBOARD_FAB2_LIB.BASEBOARD_FAB2(SCH_1):PAGE230
     5 PWRGD_PVTT_KLM_CPU1_R @BASEBOARD_FAB2_LIB.BASEBOARD_FAB2(SCH_1):PWRGD_PVTT_KLM_CPU1_R    I31 @BASEBOARD_FAB2_LIB.BASEBOARD_FAB2(SCH_1):PAGE230
     4 VSENSE_PVDDQ_KLM_VTT @BASEBOARD_FAB2_LIB.BASEBOARD_FAB2(SCH_1):VSENSE_PVDDQ_KLM_VTT    I31 @BASEBOARD_FAB2_LIB.BASEBOARD_FAB2(SCH_1):PAGE230
     6 VR_PVTT_KLM_SNS @BASEBOARD_FAB2_LIB.BASEBOARD_FAB2(SCH_1):VR_PVTT_KLM_SNS    I31 @BASEBOARD_FAB2_LIB.BASEBOARD_FAB2(SCH_1):PAGE230
     8    GND @BASEBOARD_FAB2_LIB.BASEBOARD_FAB2(SCH_1):GND    I31 @BASEBOARD_FAB2_LIB.BASEBOARD_FAB2(SCH_1):PAGE230
     9 PVTT_KLM @BASEBOARD_FAB2_LIB.BASEBOARD_FAB2(SCH_1):PVTT_KLM    I31 @BASEBOARD_FAB2_LIB.BASEBOARD_FAB2(SCH_1):PAGE230
    11    GND @BASEBOARD_FAB2_LIB.BASEBOARD_FAB2(SCH_1):GND    I31 @BASEBOARD_FAB2_LIB.BASEBOARD_FAB2(SCH_1):PAGE230

EU4A3 NCP3232L_SM-IC,H86355-001
     5 AGND_PVPP_KLM @BASEBOARD_FAB2_LIB.BASEBOARD_FAB2(SCH_1):AGND_PVPP_KLM   I184 @BASEBOARD_FAB2_LIB.BASEBOARD_FAB2(SCH_1):PAGE234
    36 VR_PVPP_KLM_BOOT @BASEBOARD_FAB2_LIB.BASEBOARD_FAB2(SCH_1):VR_PVPP_KLM_BOOT   I184 @BASEBOARD_FAB2_LIB.BASEBOARD_FAB2(SCH_1):PAGE234
     3 VR_COMP_PVPP_KLM_3 @BASEBOARD_FAB2_LIB.BASEBOARD_FAB2(SCH_1):VR_COMP_PVPP_KLM_3   I184 @BASEBOARD_FAB2_LIB.BASEBOARD_FAB2(SCH_1):PAGE234
    40 FM_PVPP_PVDDQ_CPU1_EN_KLM @BASEBOARD_FAB2_LIB.BASEBOARD_FAB2(SCH_1):FM_PVPP_PVDDQ_CPU1_EN_KLM   I184 @BASEBOARD_FAB2_LIB.BASEBOARD_FAB2(SCH_1):PAGE234
     2 VR_FB_PVPP_KLM @BASEBOARD_FAB2_LIB.BASEBOARD_FAB2(SCH_1):VR_FB_PVPP_KLM   I184 @BASEBOARD_FAB2_LIB.BASEBOARD_FAB2(SCH_1):PAGE234
    41    GND @BASEBOARD_FAB2_LIB.BASEBOARD_FAB2(SCH_1):GND   I184 @BASEBOARD_FAB2_LIB.BASEBOARD_FAB2(SCH_1):PAGE234
     4 VR_PVPP_KLM_ISET @BASEBOARD_FAB2_LIB.BASEBOARD_FAB2(SCH_1):VR_PVPP_KLM_ISET   I184 @BASEBOARD_FAB2_LIB.BASEBOARD_FAB2(SCH_1):PAGE234
     6 AGND_PVPP_KLM @BASEBOARD_FAB2_LIB.BASEBOARD_FAB2(SCH_1):AGND_PVPP_KLM   I184 @BASEBOARD_FAB2_LIB.BASEBOARD_FAB2(SCH_1):PAGE234
     7 PWRGD_PVPP_KLM_R @BASEBOARD_FAB2_LIB.BASEBOARD_FAB2(SCH_1):PWRGD_PVPP_KLM_R   I184 @BASEBOARD_FAB2_LIB.BASEBOARD_FAB2(SCH_1):PAGE234
    37    GND @BASEBOARD_FAB2_LIB.BASEBOARD_FAB2(SCH_1):GND   I184 @BASEBOARD_FAB2_LIB.BASEBOARD_FAB2(SCH_1):PAGE234
    28    GND @BASEBOARD_FAB2_LIB.BASEBOARD_FAB2(SCH_1):GND   I184 @BASEBOARD_FAB2_LIB.BASEBOARD_FAB2(SCH_1):PAGE234
    27    GND @BASEBOARD_FAB2_LIB.BASEBOARD_FAB2(SCH_1):GND   I184 @BASEBOARD_FAB2_LIB.BASEBOARD_FAB2(SCH_1):PAGE234
    26    GND @BASEBOARD_FAB2_LIB.BASEBOARD_FAB2(SCH_1):GND   I184 @BASEBOARD_FAB2_LIB.BASEBOARD_FAB2(SCH_1):PAGE234
    25    GND @BASEBOARD_FAB2_LIB.BASEBOARD_FAB2(SCH_1):GND   I184 @BASEBOARD_FAB2_LIB.BASEBOARD_FAB2(SCH_1):PAGE234
    24    GND @BASEBOARD_FAB2_LIB.BASEBOARD_FAB2(SCH_1):GND   I184 @BASEBOARD_FAB2_LIB.BASEBOARD_FAB2(SCH_1):PAGE234
    23    GND @BASEBOARD_FAB2_LIB.BASEBOARD_FAB2(SCH_1):GND   I184 @BASEBOARD_FAB2_LIB.BASEBOARD_FAB2(SCH_1):PAGE234
    22    GND @BASEBOARD_FAB2_LIB.BASEBOARD_FAB2(SCH_1):GND   I184 @BASEBOARD_FAB2_LIB.BASEBOARD_FAB2(SCH_1):PAGE234
    21    GND @BASEBOARD_FAB2_LIB.BASEBOARD_FAB2(SCH_1):GND   I184 @BASEBOARD_FAB2_LIB.BASEBOARD_FAB2(SCH_1):PAGE234
    20    GND @BASEBOARD_FAB2_LIB.BASEBOARD_FAB2(SCH_1):GND   I184 @BASEBOARD_FAB2_LIB.BASEBOARD_FAB2(SCH_1):PAGE234
    19    GND @BASEBOARD_FAB2_LIB.BASEBOARD_FAB2(SCH_1):GND   I184 @BASEBOARD_FAB2_LIB.BASEBOARD_FAB2(SCH_1):PAGE234
    18    GND @BASEBOARD_FAB2_LIB.BASEBOARD_FAB2(SCH_1):GND   I184 @BASEBOARD_FAB2_LIB.BASEBOARD_FAB2(SCH_1):PAGE234
    17    GND @BASEBOARD_FAB2_LIB.BASEBOARD_FAB2(SCH_1):GND   I184 @BASEBOARD_FAB2_LIB.BASEBOARD_FAB2(SCH_1):PAGE234
    16    GND @BASEBOARD_FAB2_LIB.BASEBOARD_FAB2(SCH_1):GND   I184 @BASEBOARD_FAB2_LIB.BASEBOARD_FAB2(SCH_1):PAGE234
     1 VR_PVPP_KLM_SS @BASEBOARD_FAB2_LIB.BASEBOARD_FAB2(SCH_1):VR_PVPP_KLM_SS   I184 @BASEBOARD_FAB2_LIB.BASEBOARD_FAB2(SCH_1):PAGE234
    38 VR_VB_PVPP_KLM @BASEBOARD_FAB2_LIB.BASEBOARD_FAB2(SCH_1):VR_VB_PVPP_KLM   I184 @BASEBOARD_FAB2_LIB.BASEBOARD_FAB2(SCH_1):PAGE234
    39 VR_FET_SW_P12V_STBY_PVPP_KLM @BASEBOARD_FAB2_LIB.BASEBOARD_FAB2(SCH_1):VR_FET_SW_P12V_STBY_PVPP_KLM   I184 @BASEBOARD_FAB2_LIB.BASEBOARD_FAB2(SCH_1):PAGE234
    42 VR_FET_SW_P12V_STBY_PVPP_KLM @BASEBOARD_FAB2_LIB.BASEBOARD_FAB2(SCH_1):VR_FET_SW_P12V_STBY_PVPP_KLM   I184 @BASEBOARD_FAB2_LIB.BASEBOARD_FAB2(SCH_1):PAGE234
    14 VR_FET_SW_P12V_STBY_PVPP_KLM @BASEBOARD_FAB2_LIB.BASEBOARD_FAB2(SCH_1):VR_FET_SW_P12V_STBY_PVPP_KLM   I184 @BASEBOARD_FAB2_LIB.BASEBOARD_FAB2(SCH_1):PAGE234
    13 VR_FET_SW_P12V_STBY_PVPP_KLM @BASEBOARD_FAB2_LIB.BASEBOARD_FAB2(SCH_1):VR_FET_SW_P12V_STBY_PVPP_KLM   I184 @BASEBOARD_FAB2_LIB.BASEBOARD_FAB2(SCH_1):PAGE234
    12 VR_FET_SW_P12V_STBY_PVPP_KLM @BASEBOARD_FAB2_LIB.BASEBOARD_FAB2(SCH_1):VR_FET_SW_P12V_STBY_PVPP_KLM   I184 @BASEBOARD_FAB2_LIB.BASEBOARD_FAB2(SCH_1):PAGE234
    11 VR_FET_SW_P12V_STBY_PVPP_KLM @BASEBOARD_FAB2_LIB.BASEBOARD_FAB2(SCH_1):VR_FET_SW_P12V_STBY_PVPP_KLM   I184 @BASEBOARD_FAB2_LIB.BASEBOARD_FAB2(SCH_1):PAGE234
    10 VR_FET_SW_P12V_STBY_PVPP_KLM @BASEBOARD_FAB2_LIB.BASEBOARD_FAB2(SCH_1):VR_FET_SW_P12V_STBY_PVPP_KLM   I184 @BASEBOARD_FAB2_LIB.BASEBOARD_FAB2(SCH_1):PAGE234
     9 VR_FET_SW_P12V_STBY_PVPP_KLM @BASEBOARD_FAB2_LIB.BASEBOARD_FAB2(SCH_1):VR_FET_SW_P12V_STBY_PVPP_KLM   I184 @BASEBOARD_FAB2_LIB.BASEBOARD_FAB2(SCH_1):PAGE234
     8 VR_FET_SW_P12V_STBY_PVPP_KLM @BASEBOARD_FAB2_LIB.BASEBOARD_FAB2(SCH_1):VR_FET_SW_P12V_STBY_PVPP_KLM   I184 @BASEBOARD_FAB2_LIB.BASEBOARD_FAB2(SCH_1):PAGE234
    35 VR_PVPP_KLM_PHASE @BASEBOARD_FAB2_LIB.BASEBOARD_FAB2(SCH_1):VR_PVPP_KLM_PHASE   I184 @BASEBOARD_FAB2_LIB.BASEBOARD_FAB2(SCH_1):PAGE234
    43 VR_PVPP_KLM_PHASE @BASEBOARD_FAB2_LIB.BASEBOARD_FAB2(SCH_1):VR_PVPP_KLM_PHASE   I184 @BASEBOARD_FAB2_LIB.BASEBOARD_FAB2(SCH_1):PAGE234
    34 VR_PVPP_KLM_PHASE @BASEBOARD_FAB2_LIB.BASEBOARD_FAB2(SCH_1):VR_PVPP_KLM_PHASE   I184 @BASEBOARD_FAB2_LIB.BASEBOARD_FAB2(SCH_1):PAGE234
    33 VR_PVPP_KLM_PHASE @BASEBOARD_FAB2_LIB.BASEBOARD_FAB2(SCH_1):VR_PVPP_KLM_PHASE   I184 @BASEBOARD_FAB2_LIB.BASEBOARD_FAB2(SCH_1):PAGE234
    32 VR_PVPP_KLM_PHASE @BASEBOARD_FAB2_LIB.BASEBOARD_FAB2(SCH_1):VR_PVPP_KLM_PHASE   I184 @BASEBOARD_FAB2_LIB.BASEBOARD_FAB2(SCH_1):PAGE234
    31 VR_PVPP_KLM_PHASE @BASEBOARD_FAB2_LIB.BASEBOARD_FAB2(SCH_1):VR_PVPP_KLM_PHASE   I184 @BASEBOARD_FAB2_LIB.BASEBOARD_FAB2(SCH_1):PAGE234
    30 VR_PVPP_KLM_PHASE @BASEBOARD_FAB2_LIB.BASEBOARD_FAB2(SCH_1):VR_PVPP_KLM_PHASE   I184 @BASEBOARD_FAB2_LIB.BASEBOARD_FAB2(SCH_1):PAGE234
    29 VR_PVPP_KLM_PHASE @BASEBOARD_FAB2_LIB.BASEBOARD_FAB2(SCH_1):VR_PVPP_KLM_PHASE   I184 @BASEBOARD_FAB2_LIB.BASEBOARD_FAB2(SCH_1):PAGE234
    15 VR_PVPP_KLM_PHASE @BASEBOARD_FAB2_LIB.BASEBOARD_FAB2(SCH_1):VR_PVPP_KLM_PHASE   I184 @BASEBOARD_FAB2_LIB.BASEBOARD_FAB2(SCH_1):PAGE234

EU4C1 IR354XX_SM-IR35412,IC,H73684-0A
    33 VR_PVSA_CPU0_BOOT_R @BASEBOARD_FAB2_LIB.BASEBOARD_FAB2(SCH_1):VR_PVSA_CPU0_BOOT_R    I46 @BASEBOARD_FAB2_LIB.BASEBOARD_FAB2(SCH_1):PAGE205
    35 P5V_STBY @BASEBOARD_FAB2_LIB.BASEBOARD_FAB2(SCH_1):P5V_STBY    I46 @BASEBOARD_FAB2_LIB.BASEBOARD_FAB2(SCH_1):PAGE205
    41 TP_PVSA_CPU0_GL_1 @BASEBOARD_FAB2_LIB.BASEBOARD_FAB2(SCH_1):TP_PVSA_CPU0_GL_1    I46 @BASEBOARD_FAB2_LIB.BASEBOARD_FAB2(SCH_1):PAGE205
     6 TP_PVSA_CPU0_GL_0 @BASEBOARD_FAB2_LIB.BASEBOARD_FAB2(SCH_1):TP_PVSA_CPU0_GL_0    I46 @BASEBOARD_FAB2_LIB.BASEBOARD_FAB2(SCH_1):PAGE205
    38 ISENSE_PVSA_CPU0_IMON @BASEBOARD_FAB2_LIB.BASEBOARD_FAB2(SCH_1):ISENSE_PVSA_CPU0_IMON    I46 @BASEBOARD_FAB2_LIB.BASEBOARD_FAB2(SCH_1):PAGE205
     2    GND @BASEBOARD_FAB2_LIB.BASEBOARD_FAB2(SCH_1):GND    I46 @BASEBOARD_FAB2_LIB.BASEBOARD_FAB2(SCH_1):PAGE205
    31 NC_PVSA_CPU0_P31 @BASEBOARD_FAB2_LIB.BASEBOARD_FAB2(SCH_1):NC_PVSA_CPU0_P31    I46 @BASEBOARD_FAB2_LIB.BASEBOARD_FAB2(SCH_1):PAGE205
    37 VR_PVSA_CPU0_OCSET @BASEBOARD_FAB2_LIB.BASEBOARD_FAB2(SCH_1):VR_PVSA_CPU0_OCSET    I46 @BASEBOARD_FAB2_LIB.BASEBOARD_FAB2(SCH_1):PAGE205
    40    GND @BASEBOARD_FAB2_LIB.BASEBOARD_FAB2(SCH_1):GND    I46 @BASEBOARD_FAB2_LIB.BASEBOARD_FAB2(SCH_1):PAGE205
     7    GND @BASEBOARD_FAB2_LIB.BASEBOARD_FAB2(SCH_1):GND    I46 @BASEBOARD_FAB2_LIB.BASEBOARD_FAB2(SCH_1):PAGE205
     5    GND @BASEBOARD_FAB2_LIB.BASEBOARD_FAB2(SCH_1):GND    I46 @BASEBOARD_FAB2_LIB.BASEBOARD_FAB2(SCH_1):PAGE205
    32 VR_PVSA_CPU0_PHASE @BASEBOARD_FAB2_LIB.BASEBOARD_FAB2(SCH_1):VR_PVSA_CPU0_PHASE    I46 @BASEBOARD_FAB2_LIB.BASEBOARD_FAB2(SCH_1):PAGE205
    34 VR_PVSA_CPU0_PWM @BASEBOARD_FAB2_LIB.BASEBOARD_FAB2(SCH_1):VR_PVSA_CPU0_PWM    I46 @BASEBOARD_FAB2_LIB.BASEBOARD_FAB2(SCH_1):PAGE205
    39 VR_PVSA_CPU0_BIREF1 @BASEBOARD_FAB2_LIB.BASEBOARD_FAB2(SCH_1):VR_PVSA_CPU0_BIREF1    I46 @BASEBOARD_FAB2_LIB.BASEBOARD_FAB2(SCH_1):PAGE205
    10 VR_PVSA_CPU0_PHASE_SW @BASEBOARD_FAB2_LIB.BASEBOARD_FAB2(SCH_1):VR_PVSA_CPU0_PHASE_SW    I46 @BASEBOARD_FAB2_LIB.BASEBOARD_FAB2(SCH_1):PAGE205
    36 A_TSENSE_PVSA_CPU0 @BASEBOARD_FAB2_LIB.BASEBOARD_FAB2(SCH_1):A_TSENSE_PVSA_CPU0    I46 @BASEBOARD_FAB2_LIB.BASEBOARD_FAB2(SCH_1):PAGE205
     3 VR_PVSA_CPU0_VCIN @BASEBOARD_FAB2_LIB.BASEBOARD_FAB2(SCH_1):VR_PVSA_CPU0_VCIN    I46 @BASEBOARD_FAB2_LIB.BASEBOARD_FAB2(SCH_1):PAGE205
     4 P5V_STBY @BASEBOARD_FAB2_LIB.BASEBOARD_FAB2(SCH_1):P5V_STBY    I46 @BASEBOARD_FAB2_LIB.BASEBOARD_FAB2(SCH_1):PAGE205
    30 VR_FET_SW_P12V_STBY_PVCCIN_CPU0 @BASEBOARD_FAB2_LIB.BASEBOARD_FAB2(SCH_1):VR_FET_SW_P12V_STBY_PVCCIN_CPU0    I46 @BASEBOARD_FAB2_LIB.BASEBOARD_FAB2(SCH_1):PAGE205
    25 VR_FET_SW_P12V_STBY_PVCCIN_CPU0 @BASEBOARD_FAB2_LIB.BASEBOARD_FAB2(SCH_1):VR_FET_SW_P12V_STBY_PVCCIN_CPU0    I46 @BASEBOARD_FAB2_LIB.BASEBOARD_FAB2(SCH_1):PAGE205
     1 PVSA_CPU0 @BASEBOARD_FAB2_LIB.BASEBOARD_FAB2(SCH_1):PVSA_CPU0    I46 @BASEBOARD_FAB2_LIB.BASEBOARD_FAB2(SCH_1):PAGE205

EU4C2 IR354XX_SM-IR35411,IC,H73688-0A
    33 VR_PVCCIN_CPU0_PH5_BOOT_R @BASEBOARD_FAB2_LIB.BASEBOARD_FAB2(SCH_1):VR_PVCCIN_CPU0_PH5_BOOT_R    I71 @BASEBOARD_FAB2_LIB.BASEBOARD_FAB2(SCH_1):PAGE204
    35 P5V_STBY @BASEBOARD_FAB2_LIB.BASEBOARD_FAB2(SCH_1):P5V_STBY    I71 @BASEBOARD_FAB2_LIB.BASEBOARD_FAB2(SCH_1):PAGE204
    41 TP_PVCCIN_CPU0_PH5_GL_1 @BASEBOARD_FAB2_LIB.BASEBOARD_FAB2(SCH_1):TP_PVCCIN_CPU0_PH5_GL_1    I71 @BASEBOARD_FAB2_LIB.BASEBOARD_FAB2(SCH_1):PAGE204
     6 TP_PVCCIN_CPU0_PH5_GL_0 @BASEBOARD_FAB2_LIB.BASEBOARD_FAB2(SCH_1):TP_PVCCIN_CPU0_PH5_GL_0    I71 @BASEBOARD_FAB2_LIB.BASEBOARD_FAB2(SCH_1):PAGE204
    38 ISENSE_PVCCIN_CPU0_PH5_IMON @BASEBOARD_FAB2_LIB.BASEBOARD_FAB2(SCH_1):ISENSE_PVCCIN_CPU0_PH5_IMON    I71 @BASEBOARD_FAB2_LIB.BASEBOARD_FAB2(SCH_1):PAGE204
     2    GND @BASEBOARD_FAB2_LIB.BASEBOARD_FAB2(SCH_1):GND    I71 @BASEBOARD_FAB2_LIB.BASEBOARD_FAB2(SCH_1):PAGE204
    31 NC_PVCCIN_CPU0_PH5_P31 @BASEBOARD_FAB2_LIB.BASEBOARD_FAB2(SCH_1):NC_PVCCIN_CPU0_PH5_P31    I71 @BASEBOARD_FAB2_LIB.BASEBOARD_FAB2(SCH_1):PAGE204
    37 VR_PVCCIN_CPU0_PH5_OCSET @BASEBOARD_FAB2_LIB.BASEBOARD_FAB2(SCH_1):VR_PVCCIN_CPU0_PH5_OCSET    I71 @BASEBOARD_FAB2_LIB.BASEBOARD_FAB2(SCH_1):PAGE204
    40    GND @BASEBOARD_FAB2_LIB.BASEBOARD_FAB2(SCH_1):GND    I71 @BASEBOARD_FAB2_LIB.BASEBOARD_FAB2(SCH_1):PAGE204
     7    GND @BASEBOARD_FAB2_LIB.BASEBOARD_FAB2(SCH_1):GND    I71 @BASEBOARD_FAB2_LIB.BASEBOARD_FAB2(SCH_1):PAGE204
     5    GND @BASEBOARD_FAB2_LIB.BASEBOARD_FAB2(SCH_1):GND    I71 @BASEBOARD_FAB2_LIB.BASEBOARD_FAB2(SCH_1):PAGE204
    32 VR_PVCCIN_CPU0_PH5_PHASE @BASEBOARD_FAB2_LIB.BASEBOARD_FAB2(SCH_1):VR_PVCCIN_CPU0_PH5_PHASE    I71 @BASEBOARD_FAB2_LIB.BASEBOARD_FAB2(SCH_1):PAGE204
    34 VR_PVCCIN_CPU0_PWM5 @BASEBOARD_FAB2_LIB.BASEBOARD_FAB2(SCH_1):VR_PVCCIN_CPU0_PWM5    I71 @BASEBOARD_FAB2_LIB.BASEBOARD_FAB2(SCH_1):PAGE204
    39 VR_PVCCIN_CPU0_AIREF5 @BASEBOARD_FAB2_LIB.BASEBOARD_FAB2(SCH_1):VR_PVCCIN_CPU0_AIREF5    I71 @BASEBOARD_FAB2_LIB.BASEBOARD_FAB2(SCH_1):PAGE204
    10 VR_PVCCIN_CPU0_PHASE5 @BASEBOARD_FAB2_LIB.BASEBOARD_FAB2(SCH_1):VR_PVCCIN_CPU0_PHASE5    I71 @BASEBOARD_FAB2_LIB.BASEBOARD_FAB2(SCH_1):PAGE204
    36 A_TSENSE_PVCCIN_CPU0 @BASEBOARD_FAB2_LIB.BASEBOARD_FAB2(SCH_1):A_TSENSE_PVCCIN_CPU0    I71 @BASEBOARD_FAB2_LIB.BASEBOARD_FAB2(SCH_1):PAGE204
     3 VR_PVCCIN_CPU0_PH5_VCIN @BASEBOARD_FAB2_LIB.BASEBOARD_FAB2(SCH_1):VR_PVCCIN_CPU0_PH5_VCIN    I71 @BASEBOARD_FAB2_LIB.BASEBOARD_FAB2(SCH_1):PAGE204
     4 P5V_STBY @BASEBOARD_FAB2_LIB.BASEBOARD_FAB2(SCH_1):P5V_STBY    I71 @BASEBOARD_FAB2_LIB.BASEBOARD_FAB2(SCH_1):PAGE204
    30 VR_FET_SW_P12V_STBY_PVCCIN_CPU0 @BASEBOARD_FAB2_LIB.BASEBOARD_FAB2(SCH_1):VR_FET_SW_P12V_STBY_PVCCIN_CPU0    I71 @BASEBOARD_FAB2_LIB.BASEBOARD_FAB2(SCH_1):PAGE204
    25 VR_FET_SW_P12V_STBY_PVCCIN_CPU0 @BASEBOARD_FAB2_LIB.BASEBOARD_FAB2(SCH_1):VR_FET_SW_P12V_STBY_PVCCIN_CPU0    I71 @BASEBOARD_FAB2_LIB.BASEBOARD_FAB2(SCH_1):PAGE204
     1 PVCCIN_CPU0 @BASEBOARD_FAB2_LIB.BASEBOARD_FAB2(SCH_1):PVCCIN_CPU0    I71 @BASEBOARD_FAB2_LIB.BASEBOARD_FAB2(SCH_1):PAGE204

EU4D1 IR354XX_SM-IR35411,IC,H73688-0A
    33 VR_PVCCIN_CPU0_PH4_BOOT_R @BASEBOARD_FAB2_LIB.BASEBOARD_FAB2(SCH_1):VR_PVCCIN_CPU0_PH4_BOOT_R    I71 @BASEBOARD_FAB2_LIB.BASEBOARD_FAB2(SCH_1):PAGE203
    35 P5V_STBY @BASEBOARD_FAB2_LIB.BASEBOARD_FAB2(SCH_1):P5V_STBY    I71 @BASEBOARD_FAB2_LIB.BASEBOARD_FAB2(SCH_1):PAGE203
    41 TP_PVCCIN_CPU0_PH4_GL_1 @BASEBOARD_FAB2_LIB.BASEBOARD_FAB2(SCH_1):TP_PVCCIN_CPU0_PH4_GL_1    I71 @BASEBOARD_FAB2_LIB.BASEBOARD_FAB2(SCH_1):PAGE203
     6 TP_PVCCIN_CPU0_PH4_GL_0 @BASEBOARD_FAB2_LIB.BASEBOARD_FAB2(SCH_1):TP_PVCCIN_CPU0_PH4_GL_0    I71 @BASEBOARD_FAB2_LIB.BASEBOARD_FAB2(SCH_1):PAGE203
    38 ISENSE_PVCCIN_CPU0_PH4_IMON @BASEBOARD_FAB2_LIB.BASEBOARD_FAB2(SCH_1):ISENSE_PVCCIN_CPU0_PH4_IMON    I71 @BASEBOARD_FAB2_LIB.BASEBOARD_FAB2(SCH_1):PAGE203
     2    GND @BASEBOARD_FAB2_LIB.BASEBOARD_FAB2(SCH_1):GND    I71 @BASEBOARD_FAB2_LIB.BASEBOARD_FAB2(SCH_1):PAGE203
    31 NC_PVCCIN_CPU0_PH4_P31 @BASEBOARD_FAB2_LIB.BASEBOARD_FAB2(SCH_1):NC_PVCCIN_CPU0_PH4_P31    I71 @BASEBOARD_FAB2_LIB.BASEBOARD_FAB2(SCH_1):PAGE203
    37 VR_PVCCIN_CPU0_PH4_OCSET @BASEBOARD_FAB2_LIB.BASEBOARD_FAB2(SCH_1):VR_PVCCIN_CPU0_PH4_OCSET    I71 @BASEBOARD_FAB2_LIB.BASEBOARD_FAB2(SCH_1):PAGE203
    40    GND @BASEBOARD_FAB2_LIB.BASEBOARD_FAB2(SCH_1):GND    I71 @BASEBOARD_FAB2_LIB.BASEBOARD_FAB2(SCH_1):PAGE203
     7    GND @BASEBOARD_FAB2_LIB.BASEBOARD_FAB2(SCH_1):GND    I71 @BASEBOARD_FAB2_LIB.BASEBOARD_FAB2(SCH_1):PAGE203
     5    GND @BASEBOARD_FAB2_LIB.BASEBOARD_FAB2(SCH_1):GND    I71 @BASEBOARD_FAB2_LIB.BASEBOARD_FAB2(SCH_1):PAGE203
    32 VR_PVCCIN_CPU0_PH4_PHASE @BASEBOARD_FAB2_LIB.BASEBOARD_FAB2(SCH_1):VR_PVCCIN_CPU0_PH4_PHASE    I71 @BASEBOARD_FAB2_LIB.BASEBOARD_FAB2(SCH_1):PAGE203
    34 VR_PVCCIN_CPU0_PWM4 @BASEBOARD_FAB2_LIB.BASEBOARD_FAB2(SCH_1):VR_PVCCIN_CPU0_PWM4    I71 @BASEBOARD_FAB2_LIB.BASEBOARD_FAB2(SCH_1):PAGE203
    39 VR_PVCCIN_CPU0_AIREF4 @BASEBOARD_FAB2_LIB.BASEBOARD_FAB2(SCH_1):VR_PVCCIN_CPU0_AIREF4    I71 @BASEBOARD_FAB2_LIB.BASEBOARD_FAB2(SCH_1):PAGE203
    10 VR_PVCCIN_CPU0_PHASE4 @BASEBOARD_FAB2_LIB.BASEBOARD_FAB2(SCH_1):VR_PVCCIN_CPU0_PHASE4    I71 @BASEBOARD_FAB2_LIB.BASEBOARD_FAB2(SCH_1):PAGE203
    36 A_TSENSE_PVCCIN_CPU0 @BASEBOARD_FAB2_LIB.BASEBOARD_FAB2(SCH_1):A_TSENSE_PVCCIN_CPU0    I71 @BASEBOARD_FAB2_LIB.BASEBOARD_FAB2(SCH_1):PAGE203
     3 VR_PVCCIN_CPU0_PH4_VCIN @BASEBOARD_FAB2_LIB.BASEBOARD_FAB2(SCH_1):VR_PVCCIN_CPU0_PH4_VCIN    I71 @BASEBOARD_FAB2_LIB.BASEBOARD_FAB2(SCH_1):PAGE203
     4 P5V_STBY @BASEBOARD_FAB2_LIB.BASEBOARD_FAB2(SCH_1):P5V_STBY    I71 @BASEBOARD_FAB2_LIB.BASEBOARD_FAB2(SCH_1):PAGE203
    30 VR_FET_SW_P12V_STBY_PVCCIN_CPU0 @BASEBOARD_FAB2_LIB.BASEBOARD_FAB2(SCH_1):VR_FET_SW_P12V_STBY_PVCCIN_CPU0    I71 @BASEBOARD_FAB2_LIB.BASEBOARD_FAB2(SCH_1):PAGE203
    25 VR_FET_SW_P12V_STBY_PVCCIN_CPU0 @BASEBOARD_FAB2_LIB.BASEBOARD_FAB2(SCH_1):VR_FET_SW_P12V_STBY_PVCCIN_CPU0    I71 @BASEBOARD_FAB2_LIB.BASEBOARD_FAB2(SCH_1):PAGE203
     1 PVCCIN_CPU0 @BASEBOARD_FAB2_LIB.BASEBOARD_FAB2(SCH_1):PVCCIN_CPU0    I71 @BASEBOARD_FAB2_LIB.BASEBOARD_FAB2(SCH_1):PAGE203

EU4D2 NB3W1200L_LCC-IC,H13585-001
     1 P3V3_DB1200_A @BASEBOARD_FAB2_LIB.BASEBOARD_FAB2(SCH_1):P3V3_DB1200_A     I1 @BASEBOARD_FAB2_LIB.BASEBOARD_FAB2(SCH_1):PAGE102
     2    GND @BASEBOARD_FAB2_LIB.BASEBOARD_FAB2(SCH_1):GND     I1 @BASEBOARD_FAB2_LIB.BASEBOARD_FAB2(SCH_1):PAGE102
     3 NC_DB1200ZL<0> @BASEBOARD_FAB2_LIB.BASEBOARD_FAB2(SCH_1):NC_DB1200ZL(0)     I1 @BASEBOARD_FAB2_LIB.BASEBOARD_FAB2(SCH_1):PAGE102
     4 FM_100M_N @BASEBOARD_FAB2_LIB.BASEBOARD_FAB2(SCH_1):FM_100M_N     I1 @BASEBOARD_FAB2_LIB.BASEBOARD_FAB2(SCH_1):PAGE102
     5 FM_HBW_BYPASS_LOWBW_N @BASEBOARD_FAB2_LIB.BASEBOARD_FAB2(SCH_1):FM_HBW_BYPASS_LOWBW_N     I1 @BASEBOARD_FAB2_LIB.BASEBOARD_FAB2(SCH_1):PAGE102
     6 FM_DB1200_PWRGD @BASEBOARD_FAB2_LIB.BASEBOARD_FAB2(SCH_1):FM_DB1200_PWRGD     I1 @BASEBOARD_FAB2_LIB.BASEBOARD_FAB2(SCH_1):PAGE102
     7    GND @BASEBOARD_FAB2_LIB.BASEBOARD_FAB2(SCH_1):GND     I1 @BASEBOARD_FAB2_LIB.BASEBOARD_FAB2(SCH_1):PAGE102
     8 P3V3_DB1200_R @BASEBOARD_FAB2_LIB.BASEBOARD_FAB2(SCH_1):P3V3_DB1200_R     I1 @BASEBOARD_FAB2_LIB.BASEBOARD_FAB2(SCH_1):PAGE102
     9 CLK_100M_DB1200_DP @BASEBOARD_FAB2_LIB.BASEBOARD_FAB2(SCH_1):CLK_100M_DB1200_DP     I1 @BASEBOARD_FAB2_LIB.BASEBOARD_FAB2(SCH_1):PAGE102
    10 CLK_100M_DB1200_DN @BASEBOARD_FAB2_LIB.BASEBOARD_FAB2(SCH_1):CLK_100M_DB1200_DN     I1 @BASEBOARD_FAB2_LIB.BASEBOARD_FAB2(SCH_1):PAGE102
    11 FM_DB1200_SMB_SA0 @BASEBOARD_FAB2_LIB.BASEBOARD_FAB2(SCH_1):FM_DB1200_SMB_SA0     I1 @BASEBOARD_FAB2_LIB.BASEBOARD_FAB2(SCH_1):PAGE102
    12 SMB_HOST_STBY_LVC3_SDA_R2 @BASEBOARD_FAB2_LIB.BASEBOARD_FAB2(SCH_1):SMB_HOST_STBY_LVC3_SDA_R2     I1 @BASEBOARD_FAB2_LIB.BASEBOARD_FAB2(SCH_1):PAGE102
    13 SMB_HOST_STBY_LVC3_SCL_R2 @BASEBOARD_FAB2_LIB.BASEBOARD_FAB2(SCH_1):SMB_HOST_STBY_LVC3_SCL_R2     I1 @BASEBOARD_FAB2_LIB.BASEBOARD_FAB2(SCH_1):PAGE102
    14 FM_DB1200_SMB_SA1 @BASEBOARD_FAB2_LIB.BASEBOARD_FAB2(SCH_1):FM_DB1200_SMB_SA1     I1 @BASEBOARD_FAB2_LIB.BASEBOARD_FAB2(SCH_1):PAGE102
    15 NC_DB1200ZL<2> @BASEBOARD_FAB2_LIB.BASEBOARD_FAB2(SCH_1):NC_DB1200ZL(2)     I1 @BASEBOARD_FAB2_LIB.BASEBOARD_FAB2(SCH_1):PAGE102
    16 NC_DB1200ZL<1> @BASEBOARD_FAB2_LIB.BASEBOARD_FAB2(SCH_1):NC_DB1200ZL(1)     I1 @BASEBOARD_FAB2_LIB.BASEBOARD_FAB2(SCH_1):PAGE102
    17 CLK_100M_CPU0_BCLK0_R_DP @BASEBOARD_FAB2_LIB.BASEBOARD_FAB2(SCH_1):CLK_100M_CPU0_BCLK0_R_DP     I1 @BASEBOARD_FAB2_LIB.BASEBOARD_FAB2(SCH_1):PAGE102
    18 CLK_100M_CPU0_BCLK0_R_DN @BASEBOARD_FAB2_LIB.BASEBOARD_FAB2(SCH_1):CLK_100M_CPU0_BCLK0_R_DN     I1 @BASEBOARD_FAB2_LIB.BASEBOARD_FAB2(SCH_1):PAGE102
    19 FM_DB1200ZL_BCLKS_EN_N @BASEBOARD_FAB2_LIB.BASEBOARD_FAB2(SCH_1):FM_DB1200ZL_BCLKS_EN_N     I1 @BASEBOARD_FAB2_LIB.BASEBOARD_FAB2(SCH_1):PAGE102
    20 FM_DB1200ZL_BCLKS_EN_N @BASEBOARD_FAB2_LIB.BASEBOARD_FAB2(SCH_1):FM_DB1200ZL_BCLKS_EN_N     I1 @BASEBOARD_FAB2_LIB.BASEBOARD_FAB2(SCH_1):PAGE102
    21 CLK_100M_CPU0_BCLK1_R_DP @BASEBOARD_FAB2_LIB.BASEBOARD_FAB2(SCH_1):CLK_100M_CPU0_BCLK1_R_DP     I1 @BASEBOARD_FAB2_LIB.BASEBOARD_FAB2(SCH_1):PAGE102
    22 CLK_100M_CPU0_BCLK1_R_DN @BASEBOARD_FAB2_LIB.BASEBOARD_FAB2(SCH_1):CLK_100M_CPU0_BCLK1_R_DN     I1 @BASEBOARD_FAB2_LIB.BASEBOARD_FAB2(SCH_1):PAGE102
    23    GND @BASEBOARD_FAB2_LIB.BASEBOARD_FAB2(SCH_1):GND     I1 @BASEBOARD_FAB2_LIB.BASEBOARD_FAB2(SCH_1):PAGE102
    24 P3V3_DB1200 @BASEBOARD_FAB2_LIB.BASEBOARD_FAB2(SCH_1):P3V3_DB1200     I1 @BASEBOARD_FAB2_LIB.BASEBOARD_FAB2(SCH_1):PAGE102
    25 P3V3_DB1200 @BASEBOARD_FAB2_LIB.BASEBOARD_FAB2(SCH_1):P3V3_DB1200     I1 @BASEBOARD_FAB2_LIB.BASEBOARD_FAB2(SCH_1):PAGE102
    26 CLK_100M_CPU0_BCLK2_R_DP @BASEBOARD_FAB2_LIB.BASEBOARD_FAB2(SCH_1):CLK_100M_CPU0_BCLK2_R_DP     I1 @BASEBOARD_FAB2_LIB.BASEBOARD_FAB2(SCH_1):PAGE102
    27 CLK_100M_CPU0_BCLK2_R_DN @BASEBOARD_FAB2_LIB.BASEBOARD_FAB2(SCH_1):CLK_100M_CPU0_BCLK2_R_DN     I1 @BASEBOARD_FAB2_LIB.BASEBOARD_FAB2(SCH_1):PAGE102
    28 FM_DB1200ZL_BCLKS_EN_N @BASEBOARD_FAB2_LIB.BASEBOARD_FAB2(SCH_1):FM_DB1200ZL_BCLKS_EN_N     I1 @BASEBOARD_FAB2_LIB.BASEBOARD_FAB2(SCH_1):PAGE102
    29 FM_CPU0_MCP_CLK_EN_N @BASEBOARD_FAB2_LIB.BASEBOARD_FAB2(SCH_1):FM_CPU0_MCP_CLK_EN_N     I1 @BASEBOARD_FAB2_LIB.BASEBOARD_FAB2(SCH_1):PAGE102
    30 CLK_100M_CPU0_PE_REFCLK_R_DP @BASEBOARD_FAB2_LIB.BASEBOARD_FAB2(SCH_1):CLK_100M_CPU0_PE_REFCLK_R_DP     I1 @BASEBOARD_FAB2_LIB.BASEBOARD_FAB2(SCH_1):PAGE102
    31 CLK_100M_CPU0_PE_REFCLK_R_DN @BASEBOARD_FAB2_LIB.BASEBOARD_FAB2(SCH_1):CLK_100M_CPU0_PE_REFCLK_R_DN     I1 @BASEBOARD_FAB2_LIB.BASEBOARD_FAB2(SCH_1):PAGE102
    32 P3V3_DB1200 @BASEBOARD_FAB2_LIB.BASEBOARD_FAB2(SCH_1):P3V3_DB1200     I1 @BASEBOARD_FAB2_LIB.BASEBOARD_FAB2(SCH_1):PAGE102
    33    GND @BASEBOARD_FAB2_LIB.BASEBOARD_FAB2(SCH_1):GND     I1 @BASEBOARD_FAB2_LIB.BASEBOARD_FAB2(SCH_1):PAGE102
    34 CLK_100M_CPU0_RC_REFCLK0_R_DP @BASEBOARD_FAB2_LIB.BASEBOARD_FAB2(SCH_1):CLK_100M_CPU0_RC_REFCLK0_R_DP     I1 @BASEBOARD_FAB2_LIB.BASEBOARD_FAB2(SCH_1):PAGE102
    35 CLK_100M_CPU0_RC_REFCLK0_R_DN @BASEBOARD_FAB2_LIB.BASEBOARD_FAB2(SCH_1):CLK_100M_CPU0_RC_REFCLK0_R_DN     I1 @BASEBOARD_FAB2_LIB.BASEBOARD_FAB2(SCH_1):PAGE102
    36 FM_CPU0_MCP_CLK_EN_N @BASEBOARD_FAB2_LIB.BASEBOARD_FAB2(SCH_1):FM_CPU0_MCP_CLK_EN_N     I1 @BASEBOARD_FAB2_LIB.BASEBOARD_FAB2(SCH_1):PAGE102
    37 FM_CPU0_MCP_CLK_EN_N @BASEBOARD_FAB2_LIB.BASEBOARD_FAB2(SCH_1):FM_CPU0_MCP_CLK_EN_N     I1 @BASEBOARD_FAB2_LIB.BASEBOARD_FAB2(SCH_1):PAGE102
    38 CLK_100M_CPU0_RC_REFCLK1_R_DP @BASEBOARD_FAB2_LIB.BASEBOARD_FAB2(SCH_1):CLK_100M_CPU0_RC_REFCLK1_R_DP     I1 @BASEBOARD_FAB2_LIB.BASEBOARD_FAB2(SCH_1):PAGE102
    39 CLK_100M_CPU0_RC_REFCLK1_R_DN @BASEBOARD_FAB2_LIB.BASEBOARD_FAB2(SCH_1):CLK_100M_CPU0_RC_REFCLK1_R_DN     I1 @BASEBOARD_FAB2_LIB.BASEBOARD_FAB2(SCH_1):PAGE102
    40 P3V3_DB1200 @BASEBOARD_FAB2_LIB.BASEBOARD_FAB2(SCH_1):P3V3_DB1200     I1 @BASEBOARD_FAB2_LIB.BASEBOARD_FAB2(SCH_1):PAGE102
    41    GND @BASEBOARD_FAB2_LIB.BASEBOARD_FAB2(SCH_1):GND     I1 @BASEBOARD_FAB2_LIB.BASEBOARD_FAB2(SCH_1):PAGE102
    42 CLK_100M_CPU1_BCLK0_R_DP @BASEBOARD_FAB2_LIB.BASEBOARD_FAB2(SCH_1):CLK_100M_CPU1_BCLK0_R_DP     I1 @BASEBOARD_FAB2_LIB.BASEBOARD_FAB2(SCH_1):PAGE102
    43 CLK_100M_CPU1_BCLK0_R_DN @BASEBOARD_FAB2_LIB.BASEBOARD_FAB2(SCH_1):CLK_100M_CPU1_BCLK0_R_DN     I1 @BASEBOARD_FAB2_LIB.BASEBOARD_FAB2(SCH_1):PAGE102
    44 FM_DB1200ZL_BCLKS_EN_N @BASEBOARD_FAB2_LIB.BASEBOARD_FAB2(SCH_1):FM_DB1200ZL_BCLKS_EN_N     I1 @BASEBOARD_FAB2_LIB.BASEBOARD_FAB2(SCH_1):PAGE102
    45 FM_DB1200ZL_BCLKS_EN_N @BASEBOARD_FAB2_LIB.BASEBOARD_FAB2(SCH_1):FM_DB1200ZL_BCLKS_EN_N     I1 @BASEBOARD_FAB2_LIB.BASEBOARD_FAB2(SCH_1):PAGE102
    46 CLK_100M_CPU1_BCLK1_R_DP @BASEBOARD_FAB2_LIB.BASEBOARD_FAB2(SCH_1):CLK_100M_CPU1_BCLK1_R_DP     I1 @BASEBOARD_FAB2_LIB.BASEBOARD_FAB2(SCH_1):PAGE102
    47 CLK_100M_CPU1_BCLK1_R_DN @BASEBOARD_FAB2_LIB.BASEBOARD_FAB2(SCH_1):CLK_100M_CPU1_BCLK1_R_DN     I1 @BASEBOARD_FAB2_LIB.BASEBOARD_FAB2(SCH_1):PAGE102
    48    GND @BASEBOARD_FAB2_LIB.BASEBOARD_FAB2(SCH_1):GND     I1 @BASEBOARD_FAB2_LIB.BASEBOARD_FAB2(SCH_1):PAGE102
    49 P3V3_DB1200 @BASEBOARD_FAB2_LIB.BASEBOARD_FAB2(SCH_1):P3V3_DB1200     I1 @BASEBOARD_FAB2_LIB.BASEBOARD_FAB2(SCH_1):PAGE102
    50 CLK_100M_CPU1_BCLK2_R_DP @BASEBOARD_FAB2_LIB.BASEBOARD_FAB2(SCH_1):CLK_100M_CPU1_BCLK2_R_DP     I1 @BASEBOARD_FAB2_LIB.BASEBOARD_FAB2(SCH_1):PAGE102
    51 CLK_100M_CPU1_BCLK2_R_DN @BASEBOARD_FAB2_LIB.BASEBOARD_FAB2(SCH_1):CLK_100M_CPU1_BCLK2_R_DN     I1 @BASEBOARD_FAB2_LIB.BASEBOARD_FAB2(SCH_1):PAGE102
    52 FM_DB1200ZL_BCLKS_EN_N @BASEBOARD_FAB2_LIB.BASEBOARD_FAB2(SCH_1):FM_DB1200ZL_BCLKS_EN_N     I1 @BASEBOARD_FAB2_LIB.BASEBOARD_FAB2(SCH_1):PAGE102
    53 FM_CPU1_MCP_CLK_EN_N @BASEBOARD_FAB2_LIB.BASEBOARD_FAB2(SCH_1):FM_CPU1_MCP_CLK_EN_N     I1 @BASEBOARD_FAB2_LIB.BASEBOARD_FAB2(SCH_1):PAGE102
    54 CLK_100M_CPU1_PE_REFCLK_R_DP @BASEBOARD_FAB2_LIB.BASEBOARD_FAB2(SCH_1):CLK_100M_CPU1_PE_REFCLK_R_DP     I1 @BASEBOARD_FAB2_LIB.BASEBOARD_FAB2(SCH_1):PAGE102
    55 CLK_100M_CPU1_PE_REFCLK_R_DN @BASEBOARD_FAB2_LIB.BASEBOARD_FAB2(SCH_1):CLK_100M_CPU1_PE_REFCLK_R_DN     I1 @BASEBOARD_FAB2_LIB.BASEBOARD_FAB2(SCH_1):PAGE102
    56 P3V3_DB1200 @BASEBOARD_FAB2_LIB.BASEBOARD_FAB2(SCH_1):P3V3_DB1200     I1 @BASEBOARD_FAB2_LIB.BASEBOARD_FAB2(SCH_1):PAGE102
    57 P3V3_DB1200 @BASEBOARD_FAB2_LIB.BASEBOARD_FAB2(SCH_1):P3V3_DB1200     I1 @BASEBOARD_FAB2_LIB.BASEBOARD_FAB2(SCH_1):PAGE102
    58    GND @BASEBOARD_FAB2_LIB.BASEBOARD_FAB2(SCH_1):GND     I1 @BASEBOARD_FAB2_LIB.BASEBOARD_FAB2(SCH_1):PAGE102
    59 CLK_100M_CPU1_RC_REFCLK0_R_DP @BASEBOARD_FAB2_LIB.BASEBOARD_FAB2(SCH_1):CLK_100M_CPU1_RC_REFCLK0_R_DP     I1 @BASEBOARD_FAB2_LIB.BASEBOARD_FAB2(SCH_1):PAGE102
    60 CLK_100M_CPU1_RC_REFCLK0_R_DN @BASEBOARD_FAB2_LIB.BASEBOARD_FAB2(SCH_1):CLK_100M_CPU1_RC_REFCLK0_R_DN     I1 @BASEBOARD_FAB2_LIB.BASEBOARD_FAB2(SCH_1):PAGE102
    61 FM_CPU1_MCP_CLK_EN_N @BASEBOARD_FAB2_LIB.BASEBOARD_FAB2(SCH_1):FM_CPU1_MCP_CLK_EN_N     I1 @BASEBOARD_FAB2_LIB.BASEBOARD_FAB2(SCH_1):PAGE102
    62 FM_CPU1_MCP_CLK_EN_N @BASEBOARD_FAB2_LIB.BASEBOARD_FAB2(SCH_1):FM_CPU1_MCP_CLK_EN_N     I1 @BASEBOARD_FAB2_LIB.BASEBOARD_FAB2(SCH_1):PAGE102
    63 CLK_100M_CPU1_RC_REFCLK1_R_DP @BASEBOARD_FAB2_LIB.BASEBOARD_FAB2(SCH_1):CLK_100M_CPU1_RC_REFCLK1_R_DP     I1 @BASEBOARD_FAB2_LIB.BASEBOARD_FAB2(SCH_1):PAGE102
    64 CLK_100M_CPU1_RC_REFCLK1_R_DN @BASEBOARD_FAB2_LIB.BASEBOARD_FAB2(SCH_1):CLK_100M_CPU1_RC_REFCLK1_R_DN     I1 @BASEBOARD_FAB2_LIB.BASEBOARD_FAB2(SCH_1):PAGE102
    65    GND @BASEBOARD_FAB2_LIB.BASEBOARD_FAB2(SCH_1):GND     I1 @BASEBOARD_FAB2_LIB.BASEBOARD_FAB2(SCH_1):PAGE102

EU4D3 IR354XX_SM-IR35411,IC,H73688-0A
    33 VR_PVCCIN_CPU0_PH3_BOOT_R @BASEBOARD_FAB2_LIB.BASEBOARD_FAB2(SCH_1):VR_PVCCIN_CPU0_PH3_BOOT_R    I70 @BASEBOARD_FAB2_LIB.BASEBOARD_FAB2(SCH_1):PAGE203
    35 P5V_STBY @BASEBOARD_FAB2_LIB.BASEBOARD_FAB2(SCH_1):P5V_STBY    I70 @BASEBOARD_FAB2_LIB.BASEBOARD_FAB2(SCH_1):PAGE203
    41 TP_PVCCIN_CPU0_PH3_GL_1 @BASEBOARD_FAB2_LIB.BASEBOARD_FAB2(SCH_1):TP_PVCCIN_CPU0_PH3_GL_1    I70 @BASEBOARD_FAB2_LIB.BASEBOARD_FAB2(SCH_1):PAGE203
     6 TP_PVCCIN_CPU0_PH3_GL_0 @BASEBOARD_FAB2_LIB.BASEBOARD_FAB2(SCH_1):TP_PVCCIN_CPU0_PH3_GL_0    I70 @BASEBOARD_FAB2_LIB.BASEBOARD_FAB2(SCH_1):PAGE203
    38 ISENSE_PVCCIN_CPU0_PH3_IMON @BASEBOARD_FAB2_LIB.BASEBOARD_FAB2(SCH_1):ISENSE_PVCCIN_CPU0_PH3_IMON    I70 @BASEBOARD_FAB2_LIB.BASEBOARD_FAB2(SCH_1):PAGE203
     2    GND @BASEBOARD_FAB2_LIB.BASEBOARD_FAB2(SCH_1):GND    I70 @BASEBOARD_FAB2_LIB.BASEBOARD_FAB2(SCH_1):PAGE203
    31 NC_PVCCIN_CPU0_PH3_P31 @BASEBOARD_FAB2_LIB.BASEBOARD_FAB2(SCH_1):NC_PVCCIN_CPU0_PH3_P31    I70 @BASEBOARD_FAB2_LIB.BASEBOARD_FAB2(SCH_1):PAGE203
    37 VR_PVCCIN_CPU0_PH3_OCSET @BASEBOARD_FAB2_LIB.BASEBOARD_FAB2(SCH_1):VR_PVCCIN_CPU0_PH3_OCSET    I70 @BASEBOARD_FAB2_LIB.BASEBOARD_FAB2(SCH_1):PAGE203
    40    GND @BASEBOARD_FAB2_LIB.BASEBOARD_FAB2(SCH_1):GND    I70 @BASEBOARD_FAB2_LIB.BASEBOARD_FAB2(SCH_1):PAGE203
     7    GND @BASEBOARD_FAB2_LIB.BASEBOARD_FAB2(SCH_1):GND    I70 @BASEBOARD_FAB2_LIB.BASEBOARD_FAB2(SCH_1):PAGE203
     5    GND @BASEBOARD_FAB2_LIB.BASEBOARD_FAB2(SCH_1):GND    I70 @BASEBOARD_FAB2_LIB.BASEBOARD_FAB2(SCH_1):PAGE203
    32 VR_PVCCIN_CPU0_PH3_PHASE @BASEBOARD_FAB2_LIB.BASEBOARD_FAB2(SCH_1):VR_PVCCIN_CPU0_PH3_PHASE    I70 @BASEBOARD_FAB2_LIB.BASEBOARD_FAB2(SCH_1):PAGE203
    34 VR_PVCCIN_CPU0_PWM3 @BASEBOARD_FAB2_LIB.BASEBOARD_FAB2(SCH_1):VR_PVCCIN_CPU0_PWM3    I70 @BASEBOARD_FAB2_LIB.BASEBOARD_FAB2(SCH_1):PAGE203
    39 VR_PVCCIN_CPU0_AIREF3 @BASEBOARD_FAB2_LIB.BASEBOARD_FAB2(SCH_1):VR_PVCCIN_CPU0_AIREF3    I70 @BASEBOARD_FAB2_LIB.BASEBOARD_FAB2(SCH_1):PAGE203
    10 VR_PVCCIN_CPU0_PHASE3 @BASEBOARD_FAB2_LIB.BASEBOARD_FAB2(SCH_1):VR_PVCCIN_CPU0_PHASE3    I70 @BASEBOARD_FAB2_LIB.BASEBOARD_FAB2(SCH_1):PAGE203
    36 A_TSENSE_PVCCIN_CPU0 @BASEBOARD_FAB2_LIB.BASEBOARD_FAB2(SCH_1):A_TSENSE_PVCCIN_CPU0    I70 @BASEBOARD_FAB2_LIB.BASEBOARD_FAB2(SCH_1):PAGE203
     3 VR_PVCCIN_CPU0_PH3_VCIN @BASEBOARD_FAB2_LIB.BASEBOARD_FAB2(SCH_1):VR_PVCCIN_CPU0_PH3_VCIN    I70 @BASEBOARD_FAB2_LIB.BASEBOARD_FAB2(SCH_1):PAGE203
     4 P5V_STBY @BASEBOARD_FAB2_LIB.BASEBOARD_FAB2(SCH_1):P5V_STBY    I70 @BASEBOARD_FAB2_LIB.BASEBOARD_FAB2(SCH_1):PAGE203
    30 VR_FET_SW_P12V_STBY_PVCCIN_CPU0 @BASEBOARD_FAB2_LIB.BASEBOARD_FAB2(SCH_1):VR_FET_SW_P12V_STBY_PVCCIN_CPU0    I70 @BASEBOARD_FAB2_LIB.BASEBOARD_FAB2(SCH_1):PAGE203
    25 VR_FET_SW_P12V_STBY_PVCCIN_CPU0 @BASEBOARD_FAB2_LIB.BASEBOARD_FAB2(SCH_1):VR_FET_SW_P12V_STBY_PVCCIN_CPU0    I70 @BASEBOARD_FAB2_LIB.BASEBOARD_FAB2(SCH_1):PAGE203
     1 PVCCIN_CPU0 @BASEBOARD_FAB2_LIB.BASEBOARD_FAB2(SCH_1):PVCCIN_CPU0    I70 @BASEBOARD_FAB2_LIB.BASEBOARD_FAB2(SCH_1):PAGE203

EU4D4 PXE1610B_QFN-IC,H79206-001
     1 VR_PVSA_CPU0_PWM @BASEBOARD_FAB2_LIB.BASEBOARD_FAB2(SCH_1):VR_PVSA_CPU0_PWM   I155 @BASEBOARD_FAB2_LIB.BASEBOARD_FAB2(SCH_1):PAGE201
     2 TP_PVCCIN_CPU0_APWM6 @BASEBOARD_FAB2_LIB.BASEBOARD_FAB2(SCH_1):TP_PVCCIN_CPU0_APWM6   I155 @BASEBOARD_FAB2_LIB.BASEBOARD_FAB2(SCH_1):PAGE201
     3 VR_PVCCIN_CPU0_PWM5 @BASEBOARD_FAB2_LIB.BASEBOARD_FAB2(SCH_1):VR_PVCCIN_CPU0_PWM5   I155 @BASEBOARD_FAB2_LIB.BASEBOARD_FAB2(SCH_1):PAGE201
     4 VR_PVCCIN_CPU0_PWM4 @BASEBOARD_FAB2_LIB.BASEBOARD_FAB2(SCH_1):VR_PVCCIN_CPU0_PWM4   I155 @BASEBOARD_FAB2_LIB.BASEBOARD_FAB2(SCH_1):PAGE201
     5 VR_PVCCIN_CPU0_PWM3 @BASEBOARD_FAB2_LIB.BASEBOARD_FAB2(SCH_1):VR_PVCCIN_CPU0_PWM3   I155 @BASEBOARD_FAB2_LIB.BASEBOARD_FAB2(SCH_1):PAGE201
     6 VR_PVCCIN_CPU0_PWM2 @BASEBOARD_FAB2_LIB.BASEBOARD_FAB2(SCH_1):VR_PVCCIN_CPU0_PWM2   I155 @BASEBOARD_FAB2_LIB.BASEBOARD_FAB2(SCH_1):PAGE201
     7 VR_PVCCIN_CPU0_PWM1 @BASEBOARD_FAB2_LIB.BASEBOARD_FAB2(SCH_1):VR_PVCCIN_CPU0_PWM1   I155 @BASEBOARD_FAB2_LIB.BASEBOARD_FAB2(SCH_1):PAGE201
     8 SMB_VR_SDA_R @BASEBOARD_FAB2_LIB.BASEBOARD_FAB2(SCH_1):SMB_VR_SDA_R   I155 @BASEBOARD_FAB2_LIB.BASEBOARD_FAB2(SCH_1):PAGE201
     9 SMB_VR_SCL_R @BASEBOARD_FAB2_LIB.BASEBOARD_FAB2(SCH_1):SMB_VR_SCL_R   I155 @BASEBOARD_FAB2_LIB.BASEBOARD_FAB2(SCH_1):PAGE201
    10 TP_PVCCIN_CPU0_RESET @BASEBOARD_FAB2_LIB.BASEBOARD_FAB2(SCH_1):TP_PVCCIN_CPU0_RESET   I155 @BASEBOARD_FAB2_LIB.BASEBOARD_FAB2(SCH_1):PAGE201
    11 VR_VRRDY_PVCCIN_CPU0 @BASEBOARD_FAB2_LIB.BASEBOARD_FAB2(SCH_1):VR_VRRDY_PVCCIN_CPU0   I155 @BASEBOARD_FAB2_LIB.BASEBOARD_FAB2(SCH_1):PAGE201
    12 VR_PVCCIN_CPU0_VREN @BASEBOARD_FAB2_LIB.BASEBOARD_FAB2(SCH_1):VR_PVCCIN_CPU0_VREN   I155 @BASEBOARD_FAB2_LIB.BASEBOARD_FAB2(SCH_1):PAGE201
    13 IRQ_PVCCIN_CPU0_VRHOT_LVC3_R_N @BASEBOARD_FAB2_LIB.BASEBOARD_FAB2(SCH_1):IRQ_PVCCIN_CPU0_VRHOT_LVC3_R_N   I155 @BASEBOARD_FAB2_LIB.BASEBOARD_FAB2(SCH_1):PAGE201
    14 FM_PVCCIN_CPU0_PWR_IN_ALERT_N @BASEBOARD_FAB2_LIB.BASEBOARD_FAB2(SCH_1):FM_PVCCIN_CPU0_PWR_IN_ALERT_N   I155 @BASEBOARD_FAB2_LIB.BASEBOARD_FAB2(SCH_1):PAGE201
    15 PWRGD_PVSA_CPU0_R @BASEBOARD_FAB2_LIB.BASEBOARD_FAB2(SCH_1):PWRGD_PVSA_CPU0_R   I155 @BASEBOARD_FAB2_LIB.BASEBOARD_FAB2(SCH_1):PAGE201
    16 TP_PVCCIN_CPU0_GP1 @BASEBOARD_FAB2_LIB.BASEBOARD_FAB2(SCH_1):TP_PVCCIN_CPU0_GP1   I155 @BASEBOARD_FAB2_LIB.BASEBOARD_FAB2(SCH_1):PAGE201
    17 SVID_VCLK_PVCCIN_CPU0 @BASEBOARD_FAB2_LIB.BASEBOARD_FAB2(SCH_1):SVID_VCLK_PVCCIN_CPU0   I155 @BASEBOARD_FAB2_LIB.BASEBOARD_FAB2(SCH_1):PAGE201
    18 SVID_VDIO_PVCCIN_CPU0 @BASEBOARD_FAB2_LIB.BASEBOARD_FAB2(SCH_1):SVID_VDIO_PVCCIN_CPU0   I155 @BASEBOARD_FAB2_LIB.BASEBOARD_FAB2(SCH_1):PAGE201
    19 SVID_VALERT_VCCIN_CPU0 @BASEBOARD_FAB2_LIB.BASEBOARD_FAB2(SCH_1):SVID_VALERT_VCCIN_CPU0   I155 @BASEBOARD_FAB2_LIB.BASEBOARD_FAB2(SCH_1):PAGE201
    20 PU_VR_PVCCIN_CPU0_FLT1_SMBALT_N @BASEBOARD_FAB2_LIB.BASEBOARD_FAB2(SCH_1):PU_VR_PVCCIN_CPU0_FLT1_SMBALT_N_IMON   I155 @BASEBOARD_FAB2_LIB.BASEBOARD_FAB2(SCH_1):PAGE201
    21 VSENSE_PVCCIN_CPU0_AVSP @BASEBOARD_FAB2_LIB.BASEBOARD_FAB2(SCH_1):VSENSE_PVCCIN_CPU0_AVSP   I155 @BASEBOARD_FAB2_LIB.BASEBOARD_FAB2(SCH_1):PAGE201
    22 VSENSE_PVCCIN_CPU0_N @BASEBOARD_FAB2_LIB.BASEBOARD_FAB2(SCH_1):VSENSE_PVCCIN_CPU0_N   I155 @BASEBOARD_FAB2_LIB.BASEBOARD_FAB2(SCH_1):PAGE201
    23 VR_PVCCIN_CPU0_AIREF1 @BASEBOARD_FAB2_LIB.BASEBOARD_FAB2(SCH_1):VR_PVCCIN_CPU0_AIREF1   I155 @BASEBOARD_FAB2_LIB.BASEBOARD_FAB2(SCH_1):PAGE201
    24 ISENSE_PVCCIN_CPU0_PH1_IMON @BASEBOARD_FAB2_LIB.BASEBOARD_FAB2(SCH_1):ISENSE_PVCCIN_CPU0_PH1_IMON   I155 @BASEBOARD_FAB2_LIB.BASEBOARD_FAB2(SCH_1):PAGE201
    25 VR_PVCCIN_CPU0_AIREF2 @BASEBOARD_FAB2_LIB.BASEBOARD_FAB2(SCH_1):VR_PVCCIN_CPU0_AIREF2   I155 @BASEBOARD_FAB2_LIB.BASEBOARD_FAB2(SCH_1):PAGE201
    26 ISENSE_PVCCIN_CPU0_PH2_IMON @BASEBOARD_FAB2_LIB.BASEBOARD_FAB2(SCH_1):ISENSE_PVCCIN_CPU0_PH2_IMON   I155 @BASEBOARD_FAB2_LIB.BASEBOARD_FAB2(SCH_1):PAGE201
    27 VR_PVCCIN_CPU0_AIREF3 @BASEBOARD_FAB2_LIB.BASEBOARD_FAB2(SCH_1):VR_PVCCIN_CPU0_AIREF3   I155 @BASEBOARD_FAB2_LIB.BASEBOARD_FAB2(SCH_1):PAGE201
    28 ISENSE_PVCCIN_CPU0_PH3_IMON @BASEBOARD_FAB2_LIB.BASEBOARD_FAB2(SCH_1):ISENSE_PVCCIN_CPU0_PH3_IMON   I155 @BASEBOARD_FAB2_LIB.BASEBOARD_FAB2(SCH_1):PAGE201
    29 VR_PVCCIN_CPU0_AIREF4 @BASEBOARD_FAB2_LIB.BASEBOARD_FAB2(SCH_1):VR_PVCCIN_CPU0_AIREF4   I155 @BASEBOARD_FAB2_LIB.BASEBOARD_FAB2(SCH_1):PAGE201
    30 ISENSE_PVCCIN_CPU0_PH4_IMON @BASEBOARD_FAB2_LIB.BASEBOARD_FAB2(SCH_1):ISENSE_PVCCIN_CPU0_PH4_IMON   I155 @BASEBOARD_FAB2_LIB.BASEBOARD_FAB2(SCH_1):PAGE201
    31 VR_PVCCIN_CPU0_AIREF5 @BASEBOARD_FAB2_LIB.BASEBOARD_FAB2(SCH_1):VR_PVCCIN_CPU0_AIREF5   I155 @BASEBOARD_FAB2_LIB.BASEBOARD_FAB2(SCH_1):PAGE201
    32 ISENSE_PVCCIN_CPU0_PH5_IMON @BASEBOARD_FAB2_LIB.BASEBOARD_FAB2(SCH_1):ISENSE_PVCCIN_CPU0_PH5_IMON   I155 @BASEBOARD_FAB2_LIB.BASEBOARD_FAB2(SCH_1):PAGE201
    33 TP_PVCCIN_CPU0_AIREF6 @BASEBOARD_FAB2_LIB.BASEBOARD_FAB2(SCH_1):TP_PVCCIN_CPU0_AIREF6   I155 @BASEBOARD_FAB2_LIB.BASEBOARD_FAB2(SCH_1):PAGE201
    34 TP_PVCCIN_CPU0_AISEN6 @BASEBOARD_FAB2_LIB.BASEBOARD_FAB2(SCH_1):TP_PVCCIN_CPU0_AISEN6   I155 @BASEBOARD_FAB2_LIB.BASEBOARD_FAB2(SCH_1):PAGE201
    35 VSENSE_PVSA_CPU0_BVSP @BASEBOARD_FAB2_LIB.BASEBOARD_FAB2(SCH_1):VSENSE_PVSA_CPU0_BVSP   I155 @BASEBOARD_FAB2_LIB.BASEBOARD_FAB2(SCH_1):PAGE201
    36 VSENSE_PVSA_CPU0_N @BASEBOARD_FAB2_LIB.BASEBOARD_FAB2(SCH_1):VSENSE_PVSA_CPU0_N   I155 @BASEBOARD_FAB2_LIB.BASEBOARD_FAB2(SCH_1):PAGE201
    37 VR_PVSA_CPU0_BIREF1 @BASEBOARD_FAB2_LIB.BASEBOARD_FAB2(SCH_1):VR_PVSA_CPU0_BIREF1   I155 @BASEBOARD_FAB2_LIB.BASEBOARD_FAB2(SCH_1):PAGE201
    38 ISENSE_PVSA_CPU0_IMON @BASEBOARD_FAB2_LIB.BASEBOARD_FAB2(SCH_1):ISENSE_PVSA_CPU0_IMON   I155 @BASEBOARD_FAB2_LIB.BASEBOARD_FAB2(SCH_1):PAGE201
    39 PU_VR_PVCCIN_CPU0_IMON @BASEBOARD_FAB2_LIB.BASEBOARD_FAB2(SCH_1):PU_VR_PVCCIN_CPU0_IMON   I155 @BASEBOARD_FAB2_LIB.BASEBOARD_FAB2(SCH_1):PAGE201
    40 TP_PVCCIN_CPU0_FAULT1_20 @BASEBOARD_FAB2_LIB.BASEBOARD_FAB2(SCH_1):TP_PVCCIN_CPU0_FAULT1_20   I155 @BASEBOARD_FAB2_LIB.BASEBOARD_FAB2(SCH_1):PAGE201
    41 VR_PVCCIN_CPU0_XADDR2 @BASEBOARD_FAB2_LIB.BASEBOARD_FAB2(SCH_1):VR_PVCCIN_CPU0_XADDR2   I155 @BASEBOARD_FAB2_LIB.BASEBOARD_FAB2(SCH_1):PAGE201
    42 A_TSENSE_PVSA_CPU0 @BASEBOARD_FAB2_LIB.BASEBOARD_FAB2(SCH_1):A_TSENSE_PVSA_CPU0   I155 @BASEBOARD_FAB2_LIB.BASEBOARD_FAB2(SCH_1):PAGE201
    43 A_TSENSE_PVCCIN_CPU0 @BASEBOARD_FAB2_LIB.BASEBOARD_FAB2(SCH_1):A_TSENSE_PVCCIN_CPU0   I155 @BASEBOARD_FAB2_LIB.BASEBOARD_FAB2(SCH_1):PAGE201
    44 VR_PVCCIN_CPU0_XADDR1 @BASEBOARD_FAB2_LIB.BASEBOARD_FAB2(SCH_1):VR_PVCCIN_CPU0_XADDR1   I155 @BASEBOARD_FAB2_LIB.BASEBOARD_FAB2(SCH_1):PAGE201
    45 VR_PVCCIN_CPU0_AVINSEN @BASEBOARD_FAB2_LIB.BASEBOARD_FAB2(SCH_1):VR_PVCCIN_CPU0_AVINSEN   I155 @BASEBOARD_FAB2_LIB.BASEBOARD_FAB2(SCH_1):PAGE201
    46 PVCCIN_PVSA_CPU0_IINSEN @BASEBOARD_FAB2_LIB.BASEBOARD_FAB2(SCH_1):PVCCIN_PVSA_CPU0_IINSEN   I155 @BASEBOARD_FAB2_LIB.BASEBOARD_FAB2(SCH_1):PAGE201
    47 VR_PVCCIN_CPU0_VDD @BASEBOARD_FAB2_LIB.BASEBOARD_FAB2(SCH_1):VR_PVCCIN_CPU0_VDD   I155 @BASEBOARD_FAB2_LIB.BASEBOARD_FAB2(SCH_1):PAGE201
    48 VR_PVCCIN_CPU0_VD12 @BASEBOARD_FAB2_LIB.BASEBOARD_FAB2(SCH_1):VR_PVCCIN_CPU0_VD12   I155 @BASEBOARD_FAB2_LIB.BASEBOARD_FAB2(SCH_1):PAGE201
    49    GND @BASEBOARD_FAB2_LIB.BASEBOARD_FAB2(SCH_1):GND   I155 @BASEBOARD_FAB2_LIB.BASEBOARD_FAB2(SCH_1):PAGE201

EU4D5 PXE1110B_QFN-IC,H89187-001
     1 NC_PVCCIO_CPU1_DNC0 @BASEBOARD_FAB2_LIB.BASEBOARD_FAB2(SCH_1):NC_PVCCIO_CPU1_DNC0    I96 @BASEBOARD_FAB2_LIB.BASEBOARD_FAB2(SCH_1):PAGE213
     2 NC_PVCCIO_CPU1_DNC1 @BASEBOARD_FAB2_LIB.BASEBOARD_FAB2(SCH_1):NC_PVCCIO_CPU1_DNC1    I96 @BASEBOARD_FAB2_LIB.BASEBOARD_FAB2(SCH_1):PAGE213
     3 TP_PVCCIO_CPU1_BPWM1 @BASEBOARD_FAB2_LIB.BASEBOARD_FAB2(SCH_1):TP_PVCCIO_CPU1_BPWM1    I96 @BASEBOARD_FAB2_LIB.BASEBOARD_FAB2(SCH_1):PAGE213
     4 NC_PVCCIO_CPU1_DNC2 @BASEBOARD_FAB2_LIB.BASEBOARD_FAB2(SCH_1):NC_PVCCIO_CPU1_DNC2    I96 @BASEBOARD_FAB2_LIB.BASEBOARD_FAB2(SCH_1):PAGE213
     5 VR_PVCCIO_CPU1_PWM1 @BASEBOARD_FAB2_LIB.BASEBOARD_FAB2(SCH_1):VR_PVCCIO_CPU1_PWM1    I96 @BASEBOARD_FAB2_LIB.BASEBOARD_FAB2(SCH_1):PAGE213
     6 SMB_VR_SDA_PVCCIO_CPU1 @BASEBOARD_FAB2_LIB.BASEBOARD_FAB2(SCH_1):SMB_VR_SDA_PVCCIO_CPU1    I96 @BASEBOARD_FAB2_LIB.BASEBOARD_FAB2(SCH_1):PAGE213
     7 SMB_VR_SCL_PVCCIO_CPU1 @BASEBOARD_FAB2_LIB.BASEBOARD_FAB2(SCH_1):SMB_VR_SCL_PVCCIO_CPU1    I96 @BASEBOARD_FAB2_LIB.BASEBOARD_FAB2(SCH_1):PAGE213
     8 TP_PVCCIO_CPU1_RESET_N @BASEBOARD_FAB2_LIB.BASEBOARD_FAB2(SCH_1):TP_PVCCIO_CPU1_RESET_N    I96 @BASEBOARD_FAB2_LIB.BASEBOARD_FAB2(SCH_1):PAGE213
     9 PWRGD_PVCCIO_CPU1_R @BASEBOARD_FAB2_LIB.BASEBOARD_FAB2(SCH_1):PWRGD_PVCCIO_CPU1_R    I96 @BASEBOARD_FAB2_LIB.BASEBOARD_FAB2(SCH_1):PAGE213
    10 VR_PVCCIO_CPU1_EN @BASEBOARD_FAB2_LIB.BASEBOARD_FAB2(SCH_1):VR_PVCCIO_CPU1_EN    I96 @BASEBOARD_FAB2_LIB.BASEBOARD_FAB2(SCH_1):PAGE213
    11 IRQ_PVCCIO_CPU1_VRHOT_N @BASEBOARD_FAB2_LIB.BASEBOARD_FAB2(SCH_1):IRQ_PVCCIO_CPU1_VRHOT_N    I96 @BASEBOARD_FAB2_LIB.BASEBOARD_FAB2(SCH_1):PAGE213
    12 TP_PVCCIO_CPU1_PINALRT_N @BASEBOARD_FAB2_LIB.BASEBOARD_FAB2(SCH_1):TP_PVCCIO_CPU1_PINALRT_N    I96 @BASEBOARD_FAB2_LIB.BASEBOARD_FAB2(SCH_1):PAGE213
    13 TP_VR_PVCCIO_CPU1_MP0 @BASEBOARD_FAB2_LIB.BASEBOARD_FAB2(SCH_1):TP_VR_PVCCIO_CPU1_MP0    I96 @BASEBOARD_FAB2_LIB.BASEBOARD_FAB2(SCH_1):PAGE213
    14 TP_VR_PVCCIO_CPU1_MP1 @BASEBOARD_FAB2_LIB.BASEBOARD_FAB2(SCH_1):TP_VR_PVCCIO_CPU1_MP1    I96 @BASEBOARD_FAB2_LIB.BASEBOARD_FAB2(SCH_1):PAGE213
    15 SVID_CLK_PVCCIO_CPU1 @BASEBOARD_FAB2_LIB.BASEBOARD_FAB2(SCH_1):SVID_CLK_PVCCIO_CPU1    I96 @BASEBOARD_FAB2_LIB.BASEBOARD_FAB2(SCH_1):PAGE213
    16 SVID_VDIO_PVCCIO_CPU1 @BASEBOARD_FAB2_LIB.BASEBOARD_FAB2(SCH_1):SVID_VDIO_PVCCIO_CPU1    I96 @BASEBOARD_FAB2_LIB.BASEBOARD_FAB2(SCH_1):PAGE213
    17 SVID_ALERT_PVCCIO_CPU1 @BASEBOARD_FAB2_LIB.BASEBOARD_FAB2(SCH_1):SVID_ALERT_PVCCIO_CPU1    I96 @BASEBOARD_FAB2_LIB.BASEBOARD_FAB2(SCH_1):PAGE213
    18 TP_VR_PVCCIO_CPU1_MP2 @BASEBOARD_FAB2_LIB.BASEBOARD_FAB2(SCH_1):TP_VR_PVCCIO_CPU1_MP2    I96 @BASEBOARD_FAB2_LIB.BASEBOARD_FAB2(SCH_1):PAGE213
    19 VR_PVCCIO_CPU1_AVSP @BASEBOARD_FAB2_LIB.BASEBOARD_FAB2(SCH_1):VR_PVCCIO_CPU1_AVSP    I96 @BASEBOARD_FAB2_LIB.BASEBOARD_FAB2(SCH_1):PAGE213
    20 VSENSE_PVCCIO_CPU1_AVSN @BASEBOARD_FAB2_LIB.BASEBOARD_FAB2(SCH_1):VSENSE_PVCCIO_CPU1_AVSN    I96 @BASEBOARD_FAB2_LIB.BASEBOARD_FAB2(SCH_1):PAGE213
    21 VR_PVCCIO_CPU1_AIREF1 @BASEBOARD_FAB2_LIB.BASEBOARD_FAB2(SCH_1):VR_PVCCIO_CPU1_AIREF1    I96 @BASEBOARD_FAB2_LIB.BASEBOARD_FAB2(SCH_1):PAGE213
    22 ISENSE_PVCCIO_CPU1_PH1_IMON @BASEBOARD_FAB2_LIB.BASEBOARD_FAB2(SCH_1):ISENSE_PVCCIO_CPU1_PH1_IMON    I96 @BASEBOARD_FAB2_LIB.BASEBOARD_FAB2(SCH_1):PAGE213
    23    GND @BASEBOARD_FAB2_LIB.BASEBOARD_FAB2(SCH_1):GND    I96 @BASEBOARD_FAB2_LIB.BASEBOARD_FAB2(SCH_1):PAGE213
    24 NC_PVCCIO_CPU1_DNC3 @BASEBOARD_FAB2_LIB.BASEBOARD_FAB2(SCH_1):NC_PVCCIO_CPU1_DNC3    I96 @BASEBOARD_FAB2_LIB.BASEBOARD_FAB2(SCH_1):PAGE213
    25 TP_PVCCIO_CPU1_BIREF1 @BASEBOARD_FAB2_LIB.BASEBOARD_FAB2(SCH_1):TP_PVCCIO_CPU1_BIREF1    I96 @BASEBOARD_FAB2_LIB.BASEBOARD_FAB2(SCH_1):PAGE213
    26    GND @BASEBOARD_FAB2_LIB.BASEBOARD_FAB2(SCH_1):GND    I96 @BASEBOARD_FAB2_LIB.BASEBOARD_FAB2(SCH_1):PAGE213
    27    GND @BASEBOARD_FAB2_LIB.BASEBOARD_FAB2(SCH_1):GND    I96 @BASEBOARD_FAB2_LIB.BASEBOARD_FAB2(SCH_1):PAGE213
    28 NC_PVCCIO_CPU1_DNC4 @BASEBOARD_FAB2_LIB.BASEBOARD_FAB2(SCH_1):NC_PVCCIO_CPU1_DNC4    I96 @BASEBOARD_FAB2_LIB.BASEBOARD_FAB2(SCH_1):PAGE213
    29 TP_PVCCIO_CPU1_BVSEN @BASEBOARD_FAB2_LIB.BASEBOARD_FAB2(SCH_1):TP_PVCCIO_CPU1_BVSEN    I96 @BASEBOARD_FAB2_LIB.BASEBOARD_FAB2(SCH_1):PAGE213
    30 TP_PVCCIO_CPU1_BVREF @BASEBOARD_FAB2_LIB.BASEBOARD_FAB2(SCH_1):TP_PVCCIO_CPU1_BVREF    I96 @BASEBOARD_FAB2_LIB.BASEBOARD_FAB2(SCH_1):PAGE213
    31 TP_VR_PVCCIO_CPU1_MP3 @BASEBOARD_FAB2_LIB.BASEBOARD_FAB2(SCH_1):TP_VR_PVCCIO_CPU1_MP3    I96 @BASEBOARD_FAB2_LIB.BASEBOARD_FAB2(SCH_1):PAGE213
    32 PU_VR_PVCCIO_CPU1_FAULT1 @BASEBOARD_FAB2_LIB.BASEBOARD_FAB2(SCH_1):PU_VR_PVCCIO_CPU1_FAULT1    I96 @BASEBOARD_FAB2_LIB.BASEBOARD_FAB2(SCH_1):PAGE213
    33 VR_PVCCIO_CPU1_XADDR2 @BASEBOARD_FAB2_LIB.BASEBOARD_FAB2(SCH_1):VR_PVCCIO_CPU1_XADDR2    I96 @BASEBOARD_FAB2_LIB.BASEBOARD_FAB2(SCH_1):PAGE213
    34 TP_PVCCIO_CPU1_BTSEN @BASEBOARD_FAB2_LIB.BASEBOARD_FAB2(SCH_1):TP_PVCCIO_CPU1_BTSEN    I96 @BASEBOARD_FAB2_LIB.BASEBOARD_FAB2(SCH_1):PAGE213
    35 A_TSENSE_PVCCIO_CPU1 @BASEBOARD_FAB2_LIB.BASEBOARD_FAB2(SCH_1):A_TSENSE_PVCCIO_CPU1    I96 @BASEBOARD_FAB2_LIB.BASEBOARD_FAB2(SCH_1):PAGE213
    36 VR_PVCCIO_CPU1_XADDR1 @BASEBOARD_FAB2_LIB.BASEBOARD_FAB2(SCH_1):VR_PVCCIO_CPU1_XADDR1    I96 @BASEBOARD_FAB2_LIB.BASEBOARD_FAB2(SCH_1):PAGE213
    37 VR_PVCCIO_CPU1_VINSEN @BASEBOARD_FAB2_LIB.BASEBOARD_FAB2(SCH_1):VR_PVCCIO_CPU1_VINSEN    I96 @BASEBOARD_FAB2_LIB.BASEBOARD_FAB2(SCH_1):PAGE213
    38 TP_VR_PVCCIO_CPU1_AIINSEN @BASEBOARD_FAB2_LIB.BASEBOARD_FAB2(SCH_1):TP_VR_PVCCIO_CPU1_AIINSEN    I96 @BASEBOARD_FAB2_LIB.BASEBOARD_FAB2(SCH_1):PAGE213
    39 VR_PVCCIO_CPU1_VDD @BASEBOARD_FAB2_LIB.BASEBOARD_FAB2(SCH_1):VR_PVCCIO_CPU1_VDD    I96 @BASEBOARD_FAB2_LIB.BASEBOARD_FAB2(SCH_1):PAGE213
    40 VR_PVCCIO_CPU1_VD12 @BASEBOARD_FAB2_LIB.BASEBOARD_FAB2(SCH_1):VR_PVCCIO_CPU1_VD12    I96 @BASEBOARD_FAB2_LIB.BASEBOARD_FAB2(SCH_1):PAGE213
    41    GND @BASEBOARD_FAB2_LIB.BASEBOARD_FAB2(SCH_1):GND    I96 @BASEBOARD_FAB2_LIB.BASEBOARD_FAB2(SCH_1):PAGE213

EU4D6 IR354XX_SM-IR35411,IC,H73688-0A
    33 VR_PVCCIN_CPU0_PH2_BOOT_R @BASEBOARD_FAB2_LIB.BASEBOARD_FAB2(SCH_1):VR_PVCCIN_CPU0_PH2_BOOT_R    I64 @BASEBOARD_FAB2_LIB.BASEBOARD_FAB2(SCH_1):PAGE202
    35 P5V_STBY @BASEBOARD_FAB2_LIB.BASEBOARD_FAB2(SCH_1):P5V_STBY    I64 @BASEBOARD_FAB2_LIB.BASEBOARD_FAB2(SCH_1):PAGE202
    41 TP_PVCCIN_CPU0_PH2_GL_1 @BASEBOARD_FAB2_LIB.BASEBOARD_FAB2(SCH_1):TP_PVCCIN_CPU0_PH2_GL_1    I64 @BASEBOARD_FAB2_LIB.BASEBOARD_FAB2(SCH_1):PAGE202
     6 TP_PVCCIN_CPU0_PH2_GL_0 @BASEBOARD_FAB2_LIB.BASEBOARD_FAB2(SCH_1):TP_PVCCIN_CPU0_PH2_GL_0    I64 @BASEBOARD_FAB2_LIB.BASEBOARD_FAB2(SCH_1):PAGE202
    38 ISENSE_PVCCIN_CPU0_PH2_IMON @BASEBOARD_FAB2_LIB.BASEBOARD_FAB2(SCH_1):ISENSE_PVCCIN_CPU0_PH2_IMON    I64 @BASEBOARD_FAB2_LIB.BASEBOARD_FAB2(SCH_1):PAGE202
     2    GND @BASEBOARD_FAB2_LIB.BASEBOARD_FAB2(SCH_1):GND    I64 @BASEBOARD_FAB2_LIB.BASEBOARD_FAB2(SCH_1):PAGE202
    31 NC_PVCCIN_CPU0_PH2_P31 @BASEBOARD_FAB2_LIB.BASEBOARD_FAB2(SCH_1):NC_PVCCIN_CPU0_PH2_P31    I64 @BASEBOARD_FAB2_LIB.BASEBOARD_FAB2(SCH_1):PAGE202
    37 VR_PVCCIN_CPU0_PH2_OCSET @BASEBOARD_FAB2_LIB.BASEBOARD_FAB2(SCH_1):VR_PVCCIN_CPU0_PH2_OCSET    I64 @BASEBOARD_FAB2_LIB.BASEBOARD_FAB2(SCH_1):PAGE202
    40    GND @BASEBOARD_FAB2_LIB.BASEBOARD_FAB2(SCH_1):GND    I64 @BASEBOARD_FAB2_LIB.BASEBOARD_FAB2(SCH_1):PAGE202
     7    GND @BASEBOARD_FAB2_LIB.BASEBOARD_FAB2(SCH_1):GND    I64 @BASEBOARD_FAB2_LIB.BASEBOARD_FAB2(SCH_1):PAGE202
     5    GND @BASEBOARD_FAB2_LIB.BASEBOARD_FAB2(SCH_1):GND    I64 @BASEBOARD_FAB2_LIB.BASEBOARD_FAB2(SCH_1):PAGE202
    32 VR_PVCCIN_CPU0_PH2_PHASE @BASEBOARD_FAB2_LIB.BASEBOARD_FAB2(SCH_1):VR_PVCCIN_CPU0_PH2_PHASE    I64 @BASEBOARD_FAB2_LIB.BASEBOARD_FAB2(SCH_1):PAGE202
    34 VR_PVCCIN_CPU0_PWM2 @BASEBOARD_FAB2_LIB.BASEBOARD_FAB2(SCH_1):VR_PVCCIN_CPU0_PWM2    I64 @BASEBOARD_FAB2_LIB.BASEBOARD_FAB2(SCH_1):PAGE202
    39 VR_PVCCIN_CPU0_AIREF2 @BASEBOARD_FAB2_LIB.BASEBOARD_FAB2(SCH_1):VR_PVCCIN_CPU0_AIREF2    I64 @BASEBOARD_FAB2_LIB.BASEBOARD_FAB2(SCH_1):PAGE202
    10 VR_PVCCIN_CPU0_PHASE2 @BASEBOARD_FAB2_LIB.BASEBOARD_FAB2(SCH_1):VR_PVCCIN_CPU0_PHASE2    I64 @BASEBOARD_FAB2_LIB.BASEBOARD_FAB2(SCH_1):PAGE202
    36 A_TSENSE_PVCCIN_CPU0 @BASEBOARD_FAB2_LIB.BASEBOARD_FAB2(SCH_1):A_TSENSE_PVCCIN_CPU0    I64 @BASEBOARD_FAB2_LIB.BASEBOARD_FAB2(SCH_1):PAGE202
     3 VR_PVCCIN_CPU0_PH2_VCIN @BASEBOARD_FAB2_LIB.BASEBOARD_FAB2(SCH_1):VR_PVCCIN_CPU0_PH2_VCIN    I64 @BASEBOARD_FAB2_LIB.BASEBOARD_FAB2(SCH_1):PAGE202
     4 P5V_STBY @BASEBOARD_FAB2_LIB.BASEBOARD_FAB2(SCH_1):P5V_STBY    I64 @BASEBOARD_FAB2_LIB.BASEBOARD_FAB2(SCH_1):PAGE202
    30 VR_FET_SW_P12V_STBY_PVCCIN_CPU0 @BASEBOARD_FAB2_LIB.BASEBOARD_FAB2(SCH_1):VR_FET_SW_P12V_STBY_PVCCIN_CPU0    I64 @BASEBOARD_FAB2_LIB.BASEBOARD_FAB2(SCH_1):PAGE202
    25 VR_FET_SW_P12V_STBY_PVCCIN_CPU0 @BASEBOARD_FAB2_LIB.BASEBOARD_FAB2(SCH_1):VR_FET_SW_P12V_STBY_PVCCIN_CPU0    I64 @BASEBOARD_FAB2_LIB.BASEBOARD_FAB2(SCH_1):PAGE202
     1 PVCCIN_CPU0 @BASEBOARD_FAB2_LIB.BASEBOARD_FAB2(SCH_1):PVCCIN_CPU0    I64 @BASEBOARD_FAB2_LIB.BASEBOARD_FAB2(SCH_1):PAGE202

EU4E1 IR354XX_SM-IR35411,IC,H73688-0A
    33 VR_PVCCIN_CPU0_PH1_BOOT_R @BASEBOARD_FAB2_LIB.BASEBOARD_FAB2(SCH_1):VR_PVCCIN_CPU0_PH1_BOOT_R    I63 @BASEBOARD_FAB2_LIB.BASEBOARD_FAB2(SCH_1):PAGE202
    35 P5V_STBY @BASEBOARD_FAB2_LIB.BASEBOARD_FAB2(SCH_1):P5V_STBY    I63 @BASEBOARD_FAB2_LIB.BASEBOARD_FAB2(SCH_1):PAGE202
    41 TP_PVCCIN_CPU0_PH1_GL_1 @BASEBOARD_FAB2_LIB.BASEBOARD_FAB2(SCH_1):TP_PVCCIN_CPU0_PH1_GL_1    I63 @BASEBOARD_FAB2_LIB.BASEBOARD_FAB2(SCH_1):PAGE202
     6 TP_PVCCIN_CPU0_PH1_GL_0 @BASEBOARD_FAB2_LIB.BASEBOARD_FAB2(SCH_1):TP_PVCCIN_CPU0_PH1_GL_0    I63 @BASEBOARD_FAB2_LIB.BASEBOARD_FAB2(SCH_1):PAGE202
    38 ISENSE_PVCCIN_CPU0_PH1_IMON @BASEBOARD_FAB2_LIB.BASEBOARD_FAB2(SCH_1):ISENSE_PVCCIN_CPU0_PH1_IMON    I63 @BASEBOARD_FAB2_LIB.BASEBOARD_FAB2(SCH_1):PAGE202
     2    GND @BASEBOARD_FAB2_LIB.BASEBOARD_FAB2(SCH_1):GND    I63 @BASEBOARD_FAB2_LIB.BASEBOARD_FAB2(SCH_1):PAGE202
    31 NC_PVCCIN_CPU0_PH1_P31 @BASEBOARD_FAB2_LIB.BASEBOARD_FAB2(SCH_1):NC_PVCCIN_CPU0_PH1_P31    I63 @BASEBOARD_FAB2_LIB.BASEBOARD_FAB2(SCH_1):PAGE202
    37 VR_PVCCIN_CPU0_PH1_OCSET @BASEBOARD_FAB2_LIB.BASEBOARD_FAB2(SCH_1):VR_PVCCIN_CPU0_PH1_OCSET    I63 @BASEBOARD_FAB2_LIB.BASEBOARD_FAB2(SCH_1):PAGE202
    40    GND @BASEBOARD_FAB2_LIB.BASEBOARD_FAB2(SCH_1):GND    I63 @BASEBOARD_FAB2_LIB.BASEBOARD_FAB2(SCH_1):PAGE202
     7    GND @BASEBOARD_FAB2_LIB.BASEBOARD_FAB2(SCH_1):GND    I63 @BASEBOARD_FAB2_LIB.BASEBOARD_FAB2(SCH_1):PAGE202
     5    GND @BASEBOARD_FAB2_LIB.BASEBOARD_FAB2(SCH_1):GND    I63 @BASEBOARD_FAB2_LIB.BASEBOARD_FAB2(SCH_1):PAGE202
    32 VR_PVCCIN_CPU0_PH1_PHASE @BASEBOARD_FAB2_LIB.BASEBOARD_FAB2(SCH_1):VR_PVCCIN_CPU0_PH1_PHASE    I63 @BASEBOARD_FAB2_LIB.BASEBOARD_FAB2(SCH_1):PAGE202
    34 VR_PVCCIN_CPU0_PWM1 @BASEBOARD_FAB2_LIB.BASEBOARD_FAB2(SCH_1):VR_PVCCIN_CPU0_PWM1    I63 @BASEBOARD_FAB2_LIB.BASEBOARD_FAB2(SCH_1):PAGE202
    39 VR_PVCCIN_CPU0_AIREF1 @BASEBOARD_FAB2_LIB.BASEBOARD_FAB2(SCH_1):VR_PVCCIN_CPU0_AIREF1    I63 @BASEBOARD_FAB2_LIB.BASEBOARD_FAB2(SCH_1):PAGE202
    10 VR_PVCCIN_CPU0_PHASE1 @BASEBOARD_FAB2_LIB.BASEBOARD_FAB2(SCH_1):VR_PVCCIN_CPU0_PHASE1    I63 @BASEBOARD_FAB2_LIB.BASEBOARD_FAB2(SCH_1):PAGE202
    36 A_TSENSE_PVCCIN_CPU0 @BASEBOARD_FAB2_LIB.BASEBOARD_FAB2(SCH_1):A_TSENSE_PVCCIN_CPU0    I63 @BASEBOARD_FAB2_LIB.BASEBOARD_FAB2(SCH_1):PAGE202
     3 VR_PVCCIN_CPU0_PH1_VCIN @BASEBOARD_FAB2_LIB.BASEBOARD_FAB2(SCH_1):VR_PVCCIN_CPU0_PH1_VCIN    I63 @BASEBOARD_FAB2_LIB.BASEBOARD_FAB2(SCH_1):PAGE202
     4 P5V_STBY @BASEBOARD_FAB2_LIB.BASEBOARD_FAB2(SCH_1):P5V_STBY    I63 @BASEBOARD_FAB2_LIB.BASEBOARD_FAB2(SCH_1):PAGE202
    30 VR_FET_SW_P12V_STBY_PVCCIN_CPU0 @BASEBOARD_FAB2_LIB.BASEBOARD_FAB2(SCH_1):VR_FET_SW_P12V_STBY_PVCCIN_CPU0    I63 @BASEBOARD_FAB2_LIB.BASEBOARD_FAB2(SCH_1):PAGE202
    25 VR_FET_SW_P12V_STBY_PVCCIN_CPU0 @BASEBOARD_FAB2_LIB.BASEBOARD_FAB2(SCH_1):VR_FET_SW_P12V_STBY_PVCCIN_CPU0    I63 @BASEBOARD_FAB2_LIB.BASEBOARD_FAB2(SCH_1):PAGE202
     1 PVCCIN_CPU0 @BASEBOARD_FAB2_LIB.BASEBOARD_FAB2(SCH_1):PVCCIN_CPU0    I63 @BASEBOARD_FAB2_LIB.BASEBOARD_FAB2(SCH_1):PAGE202

EU4E2 IR354XX_SM-IR35412,IC,H73684-0A
    33 VR_PVCCIO_CPU1_PH1_BOOT_R @BASEBOARD_FAB2_LIB.BASEBOARD_FAB2(SCH_1):VR_PVCCIO_CPU1_PH1_BOOT_R   I126 @BASEBOARD_FAB2_LIB.BASEBOARD_FAB2(SCH_1):PAGE214
    35 P5V_STBY @BASEBOARD_FAB2_LIB.BASEBOARD_FAB2(SCH_1):P5V_STBY   I126 @BASEBOARD_FAB2_LIB.BASEBOARD_FAB2(SCH_1):PAGE214
    41 TP_PVCCIO_CPU1_GL_1 @BASEBOARD_FAB2_LIB.BASEBOARD_FAB2(SCH_1):TP_PVCCIO_CPU1_GL_1   I126 @BASEBOARD_FAB2_LIB.BASEBOARD_FAB2(SCH_1):PAGE214
     6 TP_PVCCIO_CPU1_GL_0 @BASEBOARD_FAB2_LIB.BASEBOARD_FAB2(SCH_1):TP_PVCCIO_CPU1_GL_0   I126 @BASEBOARD_FAB2_LIB.BASEBOARD_FAB2(SCH_1):PAGE214
    38 ISENSE_PVCCIO_CPU1_PH1_IMON @BASEBOARD_FAB2_LIB.BASEBOARD_FAB2(SCH_1):ISENSE_PVCCIO_CPU1_PH1_IMON   I126 @BASEBOARD_FAB2_LIB.BASEBOARD_FAB2(SCH_1):PAGE214
     2    GND @BASEBOARD_FAB2_LIB.BASEBOARD_FAB2(SCH_1):GND   I126 @BASEBOARD_FAB2_LIB.BASEBOARD_FAB2(SCH_1):PAGE214
    31 NC_PVCCIO_CPU1_PH1_P31 @BASEBOARD_FAB2_LIB.BASEBOARD_FAB2(SCH_1):NC_PVCCIO_CPU1_PH1_P31   I126 @BASEBOARD_FAB2_LIB.BASEBOARD_FAB2(SCH_1):PAGE214
    37 VR_PVCCIO_CPU1_OCSET @BASEBOARD_FAB2_LIB.BASEBOARD_FAB2(SCH_1):VR_PVCCIO_CPU1_OCSET   I126 @BASEBOARD_FAB2_LIB.BASEBOARD_FAB2(SCH_1):PAGE214
    40    GND @BASEBOARD_FAB2_LIB.BASEBOARD_FAB2(SCH_1):GND   I126 @BASEBOARD_FAB2_LIB.BASEBOARD_FAB2(SCH_1):PAGE214
     7    GND @BASEBOARD_FAB2_LIB.BASEBOARD_FAB2(SCH_1):GND   I126 @BASEBOARD_FAB2_LIB.BASEBOARD_FAB2(SCH_1):PAGE214
     5    GND @BASEBOARD_FAB2_LIB.BASEBOARD_FAB2(SCH_1):GND   I126 @BASEBOARD_FAB2_LIB.BASEBOARD_FAB2(SCH_1):PAGE214
    32 VR_PVCCIO_CPU1_PH1_PHASE @BASEBOARD_FAB2_LIB.BASEBOARD_FAB2(SCH_1):VR_PVCCIO_CPU1_PH1_PHASE   I126 @BASEBOARD_FAB2_LIB.BASEBOARD_FAB2(SCH_1):PAGE214
    34 VR_PVCCIO_CPU1_PWM1 @BASEBOARD_FAB2_LIB.BASEBOARD_FAB2(SCH_1):VR_PVCCIO_CPU1_PWM1   I126 @BASEBOARD_FAB2_LIB.BASEBOARD_FAB2(SCH_1):PAGE214
    39 VR_PVCCIO_CPU1_AIREF1 @BASEBOARD_FAB2_LIB.BASEBOARD_FAB2(SCH_1):VR_PVCCIO_CPU1_AIREF1   I126 @BASEBOARD_FAB2_LIB.BASEBOARD_FAB2(SCH_1):PAGE214
    10 VR_PVCCIO_CPU1_PH1_SW @BASEBOARD_FAB2_LIB.BASEBOARD_FAB2(SCH_1):VR_PVCCIO_CPU1_PH1_SW   I126 @BASEBOARD_FAB2_LIB.BASEBOARD_FAB2(SCH_1):PAGE214
    36 A_TSENSE_PVCCIO_CPU1 @BASEBOARD_FAB2_LIB.BASEBOARD_FAB2(SCH_1):A_TSENSE_PVCCIO_CPU1   I126 @BASEBOARD_FAB2_LIB.BASEBOARD_FAB2(SCH_1):PAGE214
     3 VR_PVCCIO_CPU1_PH1_VCIN @BASEBOARD_FAB2_LIB.BASEBOARD_FAB2(SCH_1):VR_PVCCIO_CPU1_PH1_VCIN   I126 @BASEBOARD_FAB2_LIB.BASEBOARD_FAB2(SCH_1):PAGE214
     4 P5V_STBY @BASEBOARD_FAB2_LIB.BASEBOARD_FAB2(SCH_1):P5V_STBY   I126 @BASEBOARD_FAB2_LIB.BASEBOARD_FAB2(SCH_1):PAGE214
    30 VR_FET_SW_P12V_STBY_PVCCIN_CPU0 @BASEBOARD_FAB2_LIB.BASEBOARD_FAB2(SCH_1):VR_FET_SW_P12V_STBY_PVCCIN_CPU0   I126 @BASEBOARD_FAB2_LIB.BASEBOARD_FAB2(SCH_1):PAGE214
    25 VR_FET_SW_P12V_STBY_PVCCIN_CPU0 @BASEBOARD_FAB2_LIB.BASEBOARD_FAB2(SCH_1):VR_FET_SW_P12V_STBY_PVCCIN_CPU0   I126 @BASEBOARD_FAB2_LIB.BASEBOARD_FAB2(SCH_1):PAGE214
     1 PVCCIO_CPU1 @BASEBOARD_FAB2_LIB.BASEBOARD_FAB2(SCH_1):PVCCIO_CPU1   I126 @BASEBOARD_FAB2_LIB.BASEBOARD_FAB2(SCH_1):PAGE214

EU4G1 NCP3232L_SM-IC,H86355-001
     5 AGND_PVPP_GHJ @BASEBOARD_FAB2_LIB.BASEBOARD_FAB2(SCH_1):AGND_PVPP_GHJ   I225 @BASEBOARD_FAB2_LIB.BASEBOARD_FAB2(SCH_1):PAGE233
    36 VR_PVPP_GHJ_BOOT @BASEBOARD_FAB2_LIB.BASEBOARD_FAB2(SCH_1):VR_PVPP_GHJ_BOOT   I225 @BASEBOARD_FAB2_LIB.BASEBOARD_FAB2(SCH_1):PAGE233
     3 VR_COMP_PVPP_GHJ_3 @BASEBOARD_FAB2_LIB.BASEBOARD_FAB2(SCH_1):VR_COMP_PVPP_GHJ_3   I225 @BASEBOARD_FAB2_LIB.BASEBOARD_FAB2(SCH_1):PAGE233
    40 FM_PVPP_PVDDQ_CPU1_EN_GHJ @BASEBOARD_FAB2_LIB.BASEBOARD_FAB2(SCH_1):FM_PVPP_PVDDQ_CPU1_EN_GHJ   I225 @BASEBOARD_FAB2_LIB.BASEBOARD_FAB2(SCH_1):PAGE233
     2 VR_FB_PVPP_GHJ @BASEBOARD_FAB2_LIB.BASEBOARD_FAB2(SCH_1):VR_FB_PVPP_GHJ   I225 @BASEBOARD_FAB2_LIB.BASEBOARD_FAB2(SCH_1):PAGE233
    41    GND @BASEBOARD_FAB2_LIB.BASEBOARD_FAB2(SCH_1):GND   I225 @BASEBOARD_FAB2_LIB.BASEBOARD_FAB2(SCH_1):PAGE233
     4 VR_PVPP_GHJ_ISET @BASEBOARD_FAB2_LIB.BASEBOARD_FAB2(SCH_1):VR_PVPP_GHJ_ISET   I225 @BASEBOARD_FAB2_LIB.BASEBOARD_FAB2(SCH_1):PAGE233
     6 AGND_PVPP_GHJ @BASEBOARD_FAB2_LIB.BASEBOARD_FAB2(SCH_1):AGND_PVPP_GHJ   I225 @BASEBOARD_FAB2_LIB.BASEBOARD_FAB2(SCH_1):PAGE233
     7 PWRGD_PVPP_GHJ_R @BASEBOARD_FAB2_LIB.BASEBOARD_FAB2(SCH_1):PWRGD_PVPP_GHJ_R   I225 @BASEBOARD_FAB2_LIB.BASEBOARD_FAB2(SCH_1):PAGE233
    37    GND @BASEBOARD_FAB2_LIB.BASEBOARD_FAB2(SCH_1):GND   I225 @BASEBOARD_FAB2_LIB.BASEBOARD_FAB2(SCH_1):PAGE233
    28    GND @BASEBOARD_FAB2_LIB.BASEBOARD_FAB2(SCH_1):GND   I225 @BASEBOARD_FAB2_LIB.BASEBOARD_FAB2(SCH_1):PAGE233
    27    GND @BASEBOARD_FAB2_LIB.BASEBOARD_FAB2(SCH_1):GND   I225 @BASEBOARD_FAB2_LIB.BASEBOARD_FAB2(SCH_1):PAGE233
    26    GND @BASEBOARD_FAB2_LIB.BASEBOARD_FAB2(SCH_1):GND   I225 @BASEBOARD_FAB2_LIB.BASEBOARD_FAB2(SCH_1):PAGE233
    25    GND @BASEBOARD_FAB2_LIB.BASEBOARD_FAB2(SCH_1):GND   I225 @BASEBOARD_FAB2_LIB.BASEBOARD_FAB2(SCH_1):PAGE233
    24    GND @BASEBOARD_FAB2_LIB.BASEBOARD_FAB2(SCH_1):GND   I225 @BASEBOARD_FAB2_LIB.BASEBOARD_FAB2(SCH_1):PAGE233
    23    GND @BASEBOARD_FAB2_LIB.BASEBOARD_FAB2(SCH_1):GND   I225 @BASEBOARD_FAB2_LIB.BASEBOARD_FAB2(SCH_1):PAGE233
    22    GND @BASEBOARD_FAB2_LIB.BASEBOARD_FAB2(SCH_1):GND   I225 @BASEBOARD_FAB2_LIB.BASEBOARD_FAB2(SCH_1):PAGE233
    21    GND @BASEBOARD_FAB2_LIB.BASEBOARD_FAB2(SCH_1):GND   I225 @BASEBOARD_FAB2_LIB.BASEBOARD_FAB2(SCH_1):PAGE233
    20    GND @BASEBOARD_FAB2_LIB.BASEBOARD_FAB2(SCH_1):GND   I225 @BASEBOARD_FAB2_LIB.BASEBOARD_FAB2(SCH_1):PAGE233
    19    GND @BASEBOARD_FAB2_LIB.BASEBOARD_FAB2(SCH_1):GND   I225 @BASEBOARD_FAB2_LIB.BASEBOARD_FAB2(SCH_1):PAGE233
    18    GND @BASEBOARD_FAB2_LIB.BASEBOARD_FAB2(SCH_1):GND   I225 @BASEBOARD_FAB2_LIB.BASEBOARD_FAB2(SCH_1):PAGE233
    17    GND @BASEBOARD_FAB2_LIB.BASEBOARD_FAB2(SCH_1):GND   I225 @BASEBOARD_FAB2_LIB.BASEBOARD_FAB2(SCH_1):PAGE233
    16    GND @BASEBOARD_FAB2_LIB.BASEBOARD_FAB2(SCH_1):GND   I225 @BASEBOARD_FAB2_LIB.BASEBOARD_FAB2(SCH_1):PAGE233
     1 VR_PVPP_GHJ_SS @BASEBOARD_FAB2_LIB.BASEBOARD_FAB2(SCH_1):VR_PVPP_GHJ_SS   I225 @BASEBOARD_FAB2_LIB.BASEBOARD_FAB2(SCH_1):PAGE233
    38 VR_VB_PVPP_GHJ @BASEBOARD_FAB2_LIB.BASEBOARD_FAB2(SCH_1):VR_VB_PVPP_GHJ   I225 @BASEBOARD_FAB2_LIB.BASEBOARD_FAB2(SCH_1):PAGE233
    39 VR_FET_SW_P12V_STBY_PVPP_GHJ @BASEBOARD_FAB2_LIB.BASEBOARD_FAB2(SCH_1):VR_FET_SW_P12V_STBY_PVPP_GHJ   I225 @BASEBOARD_FAB2_LIB.BASEBOARD_FAB2(SCH_1):PAGE233
    42 VR_FET_SW_P12V_STBY_PVPP_GHJ @BASEBOARD_FAB2_LIB.BASEBOARD_FAB2(SCH_1):VR_FET_SW_P12V_STBY_PVPP_GHJ   I225 @BASEBOARD_FAB2_LIB.BASEBOARD_FAB2(SCH_1):PAGE233
    14 VR_FET_SW_P12V_STBY_PVPP_GHJ @BASEBOARD_FAB2_LIB.BASEBOARD_FAB2(SCH_1):VR_FET_SW_P12V_STBY_PVPP_GHJ   I225 @BASEBOARD_FAB2_LIB.BASEBOARD_FAB2(SCH_1):PAGE233
    13 VR_FET_SW_P12V_STBY_PVPP_GHJ @BASEBOARD_FAB2_LIB.BASEBOARD_FAB2(SCH_1):VR_FET_SW_P12V_STBY_PVPP_GHJ   I225 @BASEBOARD_FAB2_LIB.BASEBOARD_FAB2(SCH_1):PAGE233
    12 VR_FET_SW_P12V_STBY_PVPP_GHJ @BASEBOARD_FAB2_LIB.BASEBOARD_FAB2(SCH_1):VR_FET_SW_P12V_STBY_PVPP_GHJ   I225 @BASEBOARD_FAB2_LIB.BASEBOARD_FAB2(SCH_1):PAGE233
    11 VR_FET_SW_P12V_STBY_PVPP_GHJ @BASEBOARD_FAB2_LIB.BASEBOARD_FAB2(SCH_1):VR_FET_SW_P12V_STBY_PVPP_GHJ   I225 @BASEBOARD_FAB2_LIB.BASEBOARD_FAB2(SCH_1):PAGE233
    10 VR_FET_SW_P12V_STBY_PVPP_GHJ @BASEBOARD_FAB2_LIB.BASEBOARD_FAB2(SCH_1):VR_FET_SW_P12V_STBY_PVPP_GHJ   I225 @BASEBOARD_FAB2_LIB.BASEBOARD_FAB2(SCH_1):PAGE233
     9 VR_FET_SW_P12V_STBY_PVPP_GHJ @BASEBOARD_FAB2_LIB.BASEBOARD_FAB2(SCH_1):VR_FET_SW_P12V_STBY_PVPP_GHJ   I225 @BASEBOARD_FAB2_LIB.BASEBOARD_FAB2(SCH_1):PAGE233
     8 VR_FET_SW_P12V_STBY_PVPP_GHJ @BASEBOARD_FAB2_LIB.BASEBOARD_FAB2(SCH_1):VR_FET_SW_P12V_STBY_PVPP_GHJ   I225 @BASEBOARD_FAB2_LIB.BASEBOARD_FAB2(SCH_1):PAGE233
    35 VR_PVPP_GHJ_PHASE @BASEBOARD_FAB2_LIB.BASEBOARD_FAB2(SCH_1):VR_PVPP_GHJ_PHASE   I225 @BASEBOARD_FAB2_LIB.BASEBOARD_FAB2(SCH_1):PAGE233
    43 VR_PVPP_GHJ_PHASE @BASEBOARD_FAB2_LIB.BASEBOARD_FAB2(SCH_1):VR_PVPP_GHJ_PHASE   I225 @BASEBOARD_FAB2_LIB.BASEBOARD_FAB2(SCH_1):PAGE233
    34 VR_PVPP_GHJ_PHASE @BASEBOARD_FAB2_LIB.BASEBOARD_FAB2(SCH_1):VR_PVPP_GHJ_PHASE   I225 @BASEBOARD_FAB2_LIB.BASEBOARD_FAB2(SCH_1):PAGE233
    33 VR_PVPP_GHJ_PHASE @BASEBOARD_FAB2_LIB.BASEBOARD_FAB2(SCH_1):VR_PVPP_GHJ_PHASE   I225 @BASEBOARD_FAB2_LIB.BASEBOARD_FAB2(SCH_1):PAGE233
    32 VR_PVPP_GHJ_PHASE @BASEBOARD_FAB2_LIB.BASEBOARD_FAB2(SCH_1):VR_PVPP_GHJ_PHASE   I225 @BASEBOARD_FAB2_LIB.BASEBOARD_FAB2(SCH_1):PAGE233
    31 VR_PVPP_GHJ_PHASE @BASEBOARD_FAB2_LIB.BASEBOARD_FAB2(SCH_1):VR_PVPP_GHJ_PHASE   I225 @BASEBOARD_FAB2_LIB.BASEBOARD_FAB2(SCH_1):PAGE233
    30 VR_PVPP_GHJ_PHASE @BASEBOARD_FAB2_LIB.BASEBOARD_FAB2(SCH_1):VR_PVPP_GHJ_PHASE   I225 @BASEBOARD_FAB2_LIB.BASEBOARD_FAB2(SCH_1):PAGE233
    29 VR_PVPP_GHJ_PHASE @BASEBOARD_FAB2_LIB.BASEBOARD_FAB2(SCH_1):VR_PVPP_GHJ_PHASE   I225 @BASEBOARD_FAB2_LIB.BASEBOARD_FAB2(SCH_1):PAGE233
    15 VR_PVPP_GHJ_PHASE @BASEBOARD_FAB2_LIB.BASEBOARD_FAB2(SCH_1):VR_PVPP_GHJ_PHASE   I225 @BASEBOARD_FAB2_LIB.BASEBOARD_FAB2(SCH_1):PAGE233

EU4G2 MIC5166_DFN-IC,H55101-001
     7 FM_PVTT_GHJ_EN_R @BASEBOARD_FAB2_LIB.BASEBOARD_FAB2(SCH_1):FM_PVTT_GHJ_EN_R    I24 @BASEBOARD_FAB2_LIB.BASEBOARD_FAB2(SCH_1):PAGE229
    10 PVDDQ_GHJ @BASEBOARD_FAB2_LIB.BASEBOARD_FAB2(SCH_1):PVDDQ_GHJ    I24 @BASEBOARD_FAB2_LIB.BASEBOARD_FAB2(SCH_1):PAGE229
     1 VR_PVTT_GHJ_VREF @BASEBOARD_FAB2_LIB.BASEBOARD_FAB2(SCH_1):VR_PVTT_GHJ_VREF    I24 @BASEBOARD_FAB2_LIB.BASEBOARD_FAB2(SCH_1):PAGE229
     2 VR_PVTT_GHJ_BIAS @BASEBOARD_FAB2_LIB.BASEBOARD_FAB2(SCH_1):VR_PVTT_GHJ_BIAS    I24 @BASEBOARD_FAB2_LIB.BASEBOARD_FAB2(SCH_1):PAGE229
     3    GND @BASEBOARD_FAB2_LIB.BASEBOARD_FAB2(SCH_1):GND    I24 @BASEBOARD_FAB2_LIB.BASEBOARD_FAB2(SCH_1):PAGE229
     5 PWRGD_PVTT_GHJ_CPU1_R @BASEBOARD_FAB2_LIB.BASEBOARD_FAB2(SCH_1):PWRGD_PVTT_GHJ_CPU1_R    I24 @BASEBOARD_FAB2_LIB.BASEBOARD_FAB2(SCH_1):PAGE229
     4 VSENSE_PVDDQ_GHJ_VTT @BASEBOARD_FAB2_LIB.BASEBOARD_FAB2(SCH_1):VSENSE_PVDDQ_GHJ_VTT    I24 @BASEBOARD_FAB2_LIB.BASEBOARD_FAB2(SCH_1):PAGE229
     6 VR_PVTT_GHJ_SNS @BASEBOARD_FAB2_LIB.BASEBOARD_FAB2(SCH_1):VR_PVTT_GHJ_SNS    I24 @BASEBOARD_FAB2_LIB.BASEBOARD_FAB2(SCH_1):PAGE229
     8    GND @BASEBOARD_FAB2_LIB.BASEBOARD_FAB2(SCH_1):GND    I24 @BASEBOARD_FAB2_LIB.BASEBOARD_FAB2(SCH_1):PAGE229
     9 PVTT_GHJ @BASEBOARD_FAB2_LIB.BASEBOARD_FAB2(SCH_1):PVTT_GHJ    I24 @BASEBOARD_FAB2_LIB.BASEBOARD_FAB2(SCH_1):PAGE229
    11    GND @BASEBOARD_FAB2_LIB.BASEBOARD_FAB2(SCH_1):GND    I24 @BASEBOARD_FAB2_LIB.BASEBOARD_FAB2(SCH_1):PAGE229

EU4G3 MIC5166_DFN-IC,H55101-001
     7 FM_PVTT_ABC_EN_R @BASEBOARD_FAB2_LIB.BASEBOARD_FAB2(SCH_1):FM_PVTT_ABC_EN_R     I1 @BASEBOARD_FAB2_LIB.BASEBOARD_FAB2(SCH_1):PAGE221
    10 PVDDQ_ABC @BASEBOARD_FAB2_LIB.BASEBOARD_FAB2(SCH_1):PVDDQ_ABC     I1 @BASEBOARD_FAB2_LIB.BASEBOARD_FAB2(SCH_1):PAGE221
     1 VR_PVTT_ABC_VREF @BASEBOARD_FAB2_LIB.BASEBOARD_FAB2(SCH_1):VR_PVTT_ABC_VREF     I1 @BASEBOARD_FAB2_LIB.BASEBOARD_FAB2(SCH_1):PAGE221
     2 VR_PVTT_ABC_BIAS @BASEBOARD_FAB2_LIB.BASEBOARD_FAB2(SCH_1):VR_PVTT_ABC_BIAS     I1 @BASEBOARD_FAB2_LIB.BASEBOARD_FAB2(SCH_1):PAGE221
     3    GND @BASEBOARD_FAB2_LIB.BASEBOARD_FAB2(SCH_1):GND     I1 @BASEBOARD_FAB2_LIB.BASEBOARD_FAB2(SCH_1):PAGE221
     5 PWRGD_PVTT_ABC_CPU0_R @BASEBOARD_FAB2_LIB.BASEBOARD_FAB2(SCH_1):PWRGD_PVTT_ABC_CPU0_R     I1 @BASEBOARD_FAB2_LIB.BASEBOARD_FAB2(SCH_1):PAGE221
     4 VSENSE_PVDDQ_ABC_VTT @BASEBOARD_FAB2_LIB.BASEBOARD_FAB2(SCH_1):VSENSE_PVDDQ_ABC_VTT     I1 @BASEBOARD_FAB2_LIB.BASEBOARD_FAB2(SCH_1):PAGE221
     6 VR_PVTT_ABC_SNS @BASEBOARD_FAB2_LIB.BASEBOARD_FAB2(SCH_1):VR_PVTT_ABC_SNS     I1 @BASEBOARD_FAB2_LIB.BASEBOARD_FAB2(SCH_1):PAGE221
     8    GND @BASEBOARD_FAB2_LIB.BASEBOARD_FAB2(SCH_1):GND     I1 @BASEBOARD_FAB2_LIB.BASEBOARD_FAB2(SCH_1):PAGE221
     9 PVTT_ABC @BASEBOARD_FAB2_LIB.BASEBOARD_FAB2(SCH_1):PVTT_ABC     I1 @BASEBOARD_FAB2_LIB.BASEBOARD_FAB2(SCH_1):PAGE221
    11    GND @BASEBOARD_FAB2_LIB.BASEBOARD_FAB2(SCH_1):GND     I1 @BASEBOARD_FAB2_LIB.BASEBOARD_FAB2(SCH_1):PAGE221

EU7A1 IR354XX_SM-IR35411,IC,H73688-0A
    33 VR_PVDDQ_DEF_PH1_BOOT_R @BASEBOARD_FAB2_LIB.BASEBOARD_FAB2(SCH_1):VR_PVDDQ_DEF_PH1_BOOT_R   I106 @BASEBOARD_FAB2_LIB.BASEBOARD_FAB2(SCH_1):PAGE219
    35 P5V_STBY @BASEBOARD_FAB2_LIB.BASEBOARD_FAB2(SCH_1):P5V_STBY   I106 @BASEBOARD_FAB2_LIB.BASEBOARD_FAB2(SCH_1):PAGE219
    41 TP_PVDDQ_DEF_PH1_GL_1 @BASEBOARD_FAB2_LIB.BASEBOARD_FAB2(SCH_1):TP_PVDDQ_DEF_PH1_GL_1   I106 @BASEBOARD_FAB2_LIB.BASEBOARD_FAB2(SCH_1):PAGE219
     6 TP_PVDDQ_DEF_PH1_GL_0 @BASEBOARD_FAB2_LIB.BASEBOARD_FAB2(SCH_1):TP_PVDDQ_DEF_PH1_GL_0   I106 @BASEBOARD_FAB2_LIB.BASEBOARD_FAB2(SCH_1):PAGE219
    38 ISENSE_PVDDQ_DEF_PH1_IMON @BASEBOARD_FAB2_LIB.BASEBOARD_FAB2(SCH_1):ISENSE_PVDDQ_DEF_PH1_IMON   I106 @BASEBOARD_FAB2_LIB.BASEBOARD_FAB2(SCH_1):PAGE219
     2    GND @BASEBOARD_FAB2_LIB.BASEBOARD_FAB2(SCH_1):GND   I106 @BASEBOARD_FAB2_LIB.BASEBOARD_FAB2(SCH_1):PAGE219
    31 NC_PVDDQ_DEF_PH1_P31 @BASEBOARD_FAB2_LIB.BASEBOARD_FAB2(SCH_1):NC_PVDDQ_DEF_PH1_P31   I106 @BASEBOARD_FAB2_LIB.BASEBOARD_FAB2(SCH_1):PAGE219
    37 VR_PVDDQ_DEF_PH1_OCSET @BASEBOARD_FAB2_LIB.BASEBOARD_FAB2(SCH_1):VR_PVDDQ_DEF_PH1_OCSET   I106 @BASEBOARD_FAB2_LIB.BASEBOARD_FAB2(SCH_1):PAGE219
    40    GND @BASEBOARD_FAB2_LIB.BASEBOARD_FAB2(SCH_1):GND   I106 @BASEBOARD_FAB2_LIB.BASEBOARD_FAB2(SCH_1):PAGE219
     7    GND @BASEBOARD_FAB2_LIB.BASEBOARD_FAB2(SCH_1):GND   I106 @BASEBOARD_FAB2_LIB.BASEBOARD_FAB2(SCH_1):PAGE219
     5    GND @BASEBOARD_FAB2_LIB.BASEBOARD_FAB2(SCH_1):GND   I106 @BASEBOARD_FAB2_LIB.BASEBOARD_FAB2(SCH_1):PAGE219
    32 VR_PVDDQ_DEF_PH1_PHASE @BASEBOARD_FAB2_LIB.BASEBOARD_FAB2(SCH_1):VR_PVDDQ_DEF_PH1_PHASE   I106 @BASEBOARD_FAB2_LIB.BASEBOARD_FAB2(SCH_1):PAGE219
    34 VR_PVDDQ_DEF_PWM1 @BASEBOARD_FAB2_LIB.BASEBOARD_FAB2(SCH_1):VR_PVDDQ_DEF_PWM1   I106 @BASEBOARD_FAB2_LIB.BASEBOARD_FAB2(SCH_1):PAGE219
    39 VR_PVDDQ_DEF_AIREF1 @BASEBOARD_FAB2_LIB.BASEBOARD_FAB2(SCH_1):VR_PVDDQ_DEF_AIREF1   I106 @BASEBOARD_FAB2_LIB.BASEBOARD_FAB2(SCH_1):PAGE219
    10 VR_PVDDQ_DEF_PH1_SW @BASEBOARD_FAB2_LIB.BASEBOARD_FAB2(SCH_1):VR_PVDDQ_DEF_PH1_SW   I106 @BASEBOARD_FAB2_LIB.BASEBOARD_FAB2(SCH_1):PAGE219
    36 A_TSENSE_PVDDQ_DEF @BASEBOARD_FAB2_LIB.BASEBOARD_FAB2(SCH_1):A_TSENSE_PVDDQ_DEF   I106 @BASEBOARD_FAB2_LIB.BASEBOARD_FAB2(SCH_1):PAGE219
     3 VR_PVDDQ_DEF_PH1_VCIN @BASEBOARD_FAB2_LIB.BASEBOARD_FAB2(SCH_1):VR_PVDDQ_DEF_PH1_VCIN   I106 @BASEBOARD_FAB2_LIB.BASEBOARD_FAB2(SCH_1):PAGE219
     4 P5V_STBY @BASEBOARD_FAB2_LIB.BASEBOARD_FAB2(SCH_1):P5V_STBY   I106 @BASEBOARD_FAB2_LIB.BASEBOARD_FAB2(SCH_1):PAGE219
    30 VR_FET_SW_P12V_STBY_PVDDQ_DEF @BASEBOARD_FAB2_LIB.BASEBOARD_FAB2(SCH_1):VR_FET_SW_P12V_STBY_PVDDQ_DEF   I106 @BASEBOARD_FAB2_LIB.BASEBOARD_FAB2(SCH_1):PAGE219
    25 VR_FET_SW_P12V_STBY_PVDDQ_DEF @BASEBOARD_FAB2_LIB.BASEBOARD_FAB2(SCH_1):VR_FET_SW_P12V_STBY_PVDDQ_DEF   I106 @BASEBOARD_FAB2_LIB.BASEBOARD_FAB2(SCH_1):PAGE219
     1 PVDDQ_DEF @BASEBOARD_FAB2_LIB.BASEBOARD_FAB2(SCH_1):PVDDQ_DEF   I106 @BASEBOARD_FAB2_LIB.BASEBOARD_FAB2(SCH_1):PAGE219

EU7A2 IR354XX_SM-IR35412,IC,H73684-0A
    33 VR_P1V05_PCH_STBY_PH1_BOOT_R @BASEBOARD_FAB2_LIB.BASEBOARD_FAB2(SCH_1):VR_P1V05_PCH_STBY_PH1_BOOT_R   I117 @BASEBOARD_FAB2_LIB.BASEBOARD_FAB2(SCH_1):PAGE236
    35 P5V_STBY @BASEBOARD_FAB2_LIB.BASEBOARD_FAB2(SCH_1):P5V_STBY   I117 @BASEBOARD_FAB2_LIB.BASEBOARD_FAB2(SCH_1):PAGE236
    41 TP_P1V05_PCH_GL_1 @BASEBOARD_FAB2_LIB.BASEBOARD_FAB2(SCH_1):TP_P1V05_PCH_GL_1   I117 @BASEBOARD_FAB2_LIB.BASEBOARD_FAB2(SCH_1):PAGE236
     6 TP_P1V05_PCH_GL_0 @BASEBOARD_FAB2_LIB.BASEBOARD_FAB2(SCH_1):TP_P1V05_PCH_GL_0   I117 @BASEBOARD_FAB2_LIB.BASEBOARD_FAB2(SCH_1):PAGE236
    38 ISENSE_P1V05_PCH_STBY_PH1_IMON @BASEBOARD_FAB2_LIB.BASEBOARD_FAB2(SCH_1):ISENSE_P1V05_PCH_STBY_PH1_IMON   I117 @BASEBOARD_FAB2_LIB.BASEBOARD_FAB2(SCH_1):PAGE236
     2    GND @BASEBOARD_FAB2_LIB.BASEBOARD_FAB2(SCH_1):GND   I117 @BASEBOARD_FAB2_LIB.BASEBOARD_FAB2(SCH_1):PAGE236
    31 NC_P1V05_PCH_STBY_PH1_P31 @BASEBOARD_FAB2_LIB.BASEBOARD_FAB2(SCH_1):NC_P1V05_PCH_STBY_PH1_P31   I117 @BASEBOARD_FAB2_LIB.BASEBOARD_FAB2(SCH_1):PAGE236
    37 VR_P1V05_PCH_STBY_OCSET @BASEBOARD_FAB2_LIB.BASEBOARD_FAB2(SCH_1):VR_P1V05_PCH_STBY_OCSET   I117 @BASEBOARD_FAB2_LIB.BASEBOARD_FAB2(SCH_1):PAGE236
    40    GND @BASEBOARD_FAB2_LIB.BASEBOARD_FAB2(SCH_1):GND   I117 @BASEBOARD_FAB2_LIB.BASEBOARD_FAB2(SCH_1):PAGE236
     7    GND @BASEBOARD_FAB2_LIB.BASEBOARD_FAB2(SCH_1):GND   I117 @BASEBOARD_FAB2_LIB.BASEBOARD_FAB2(SCH_1):PAGE236
     5    GND @BASEBOARD_FAB2_LIB.BASEBOARD_FAB2(SCH_1):GND   I117 @BASEBOARD_FAB2_LIB.BASEBOARD_FAB2(SCH_1):PAGE236
    32 VR_P1V05_PCH_STBY_PH1_PHASE @BASEBOARD_FAB2_LIB.BASEBOARD_FAB2(SCH_1):VR_P1V05_PCH_STBY_PH1_PHASE   I117 @BASEBOARD_FAB2_LIB.BASEBOARD_FAB2(SCH_1):PAGE236
    34 VR_P1V05_PCH_STBY_PWM1 @BASEBOARD_FAB2_LIB.BASEBOARD_FAB2(SCH_1):VR_P1V05_PCH_STBY_PWM1   I117 @BASEBOARD_FAB2_LIB.BASEBOARD_FAB2(SCH_1):PAGE236
    39 VR_P1V05_PCH_BIREF1 @BASEBOARD_FAB2_LIB.BASEBOARD_FAB2(SCH_1):VR_P1V05_PCH_BIREF1   I117 @BASEBOARD_FAB2_LIB.BASEBOARD_FAB2(SCH_1):PAGE236
    10 VR_P1V05_PCH_STBY_PH1_PHASE_SW @BASEBOARD_FAB2_LIB.BASEBOARD_FAB2(SCH_1):VR_P1V05_PCH_STBY_PH1_PHASE_SW   I117 @BASEBOARD_FAB2_LIB.BASEBOARD_FAB2(SCH_1):PAGE236
    36 A_TSENSE_P1V05_PCH_STBY_TMON @BASEBOARD_FAB2_LIB.BASEBOARD_FAB2(SCH_1):A_TSENSE_P1V05_PCH_STBY_TMON   I117 @BASEBOARD_FAB2_LIB.BASEBOARD_FAB2(SCH_1):PAGE236
     3 VR_P1V05_PCH_STBY_PH1_VCIN @BASEBOARD_FAB2_LIB.BASEBOARD_FAB2(SCH_1):VR_P1V05_PCH_STBY_PH1_VCIN   I117 @BASEBOARD_FAB2_LIB.BASEBOARD_FAB2(SCH_1):PAGE236
     4 P5V_STBY @BASEBOARD_FAB2_LIB.BASEBOARD_FAB2(SCH_1):P5V_STBY   I117 @BASEBOARD_FAB2_LIB.BASEBOARD_FAB2(SCH_1):PAGE236
    30 VR_FET_SW_P12V_STBY_PVDDQ_DEF @BASEBOARD_FAB2_LIB.BASEBOARD_FAB2(SCH_1):VR_FET_SW_P12V_STBY_PVDDQ_DEF   I117 @BASEBOARD_FAB2_LIB.BASEBOARD_FAB2(SCH_1):PAGE236
    25 VR_FET_SW_P12V_STBY_PVDDQ_DEF @BASEBOARD_FAB2_LIB.BASEBOARD_FAB2(SCH_1):VR_FET_SW_P12V_STBY_PVDDQ_DEF   I117 @BASEBOARD_FAB2_LIB.BASEBOARD_FAB2(SCH_1):PAGE236
     1 P1V05_PCH_STBY @BASEBOARD_FAB2_LIB.BASEBOARD_FAB2(SCH_1):P1V05_PCH_STBY   I117 @BASEBOARD_FAB2_LIB.BASEBOARD_FAB2(SCH_1):PAGE236

EU7A3 IR354XX_SM-IR35412,IC,H73684-0A
    33 VR_PVNN_PCH_PH1_BOOT_R @BASEBOARD_FAB2_LIB.BASEBOARD_FAB2(SCH_1):VR_PVNN_PCH_PH1_BOOT_R   I116 @BASEBOARD_FAB2_LIB.BASEBOARD_FAB2(SCH_1):PAGE236
    35 P5V_STBY @BASEBOARD_FAB2_LIB.BASEBOARD_FAB2(SCH_1):P5V_STBY   I116 @BASEBOARD_FAB2_LIB.BASEBOARD_FAB2(SCH_1):PAGE236
    41 TP_PVNN_PCH_GL_1 @BASEBOARD_FAB2_LIB.BASEBOARD_FAB2(SCH_1):TP_PVNN_PCH_GL_1   I116 @BASEBOARD_FAB2_LIB.BASEBOARD_FAB2(SCH_1):PAGE236
     6 TP_PVNN_PCH_GL_0 @BASEBOARD_FAB2_LIB.BASEBOARD_FAB2(SCH_1):TP_PVNN_PCH_GL_0   I116 @BASEBOARD_FAB2_LIB.BASEBOARD_FAB2(SCH_1):PAGE236
    38 ISENSE_PVNN_PCH_PH1_IMON @BASEBOARD_FAB2_LIB.BASEBOARD_FAB2(SCH_1):ISENSE_PVNN_PCH_PH1_IMON   I116 @BASEBOARD_FAB2_LIB.BASEBOARD_FAB2(SCH_1):PAGE236
     2    GND @BASEBOARD_FAB2_LIB.BASEBOARD_FAB2(SCH_1):GND   I116 @BASEBOARD_FAB2_LIB.BASEBOARD_FAB2(SCH_1):PAGE236
    31 NC_PVNN_PCH_PH1_P31 @BASEBOARD_FAB2_LIB.BASEBOARD_FAB2(SCH_1):NC_PVNN_PCH_PH1_P31   I116 @BASEBOARD_FAB2_LIB.BASEBOARD_FAB2(SCH_1):PAGE236
    37 VR_PVNN_PCH_STBY_OCSET @BASEBOARD_FAB2_LIB.BASEBOARD_FAB2(SCH_1):VR_PVNN_PCH_STBY_OCSET   I116 @BASEBOARD_FAB2_LIB.BASEBOARD_FAB2(SCH_1):PAGE236
    40    GND @BASEBOARD_FAB2_LIB.BASEBOARD_FAB2(SCH_1):GND   I116 @BASEBOARD_FAB2_LIB.BASEBOARD_FAB2(SCH_1):PAGE236
     7    GND @BASEBOARD_FAB2_LIB.BASEBOARD_FAB2(SCH_1):GND   I116 @BASEBOARD_FAB2_LIB.BASEBOARD_FAB2(SCH_1):PAGE236
     5    GND @BASEBOARD_FAB2_LIB.BASEBOARD_FAB2(SCH_1):GND   I116 @BASEBOARD_FAB2_LIB.BASEBOARD_FAB2(SCH_1):PAGE236
    32 VR_PVNN_PCH_PH1_PHASE @BASEBOARD_FAB2_LIB.BASEBOARD_FAB2(SCH_1):VR_PVNN_PCH_PH1_PHASE   I116 @BASEBOARD_FAB2_LIB.BASEBOARD_FAB2(SCH_1):PAGE236
    34 VR_PVNN_PCH_PWM1 @BASEBOARD_FAB2_LIB.BASEBOARD_FAB2(SCH_1):VR_PVNN_PCH_PWM1   I116 @BASEBOARD_FAB2_LIB.BASEBOARD_FAB2(SCH_1):PAGE236
    39 VR_PVNN_PCH_AIREF1 @BASEBOARD_FAB2_LIB.BASEBOARD_FAB2(SCH_1):VR_PVNN_PCH_AIREF1   I116 @BASEBOARD_FAB2_LIB.BASEBOARD_FAB2(SCH_1):PAGE236
    10 VR_PVNN_PCH_PH1_PHASE_SW @BASEBOARD_FAB2_LIB.BASEBOARD_FAB2(SCH_1):VR_PVNN_PCH_PH1_PHASE_SW   I116 @BASEBOARD_FAB2_LIB.BASEBOARD_FAB2(SCH_1):PAGE236
    36 A_TSENSE_PVNN_PCH_TMON @BASEBOARD_FAB2_LIB.BASEBOARD_FAB2(SCH_1):A_TSENSE_PVNN_PCH_TMON   I116 @BASEBOARD_FAB2_LIB.BASEBOARD_FAB2(SCH_1):PAGE236
     3 VR_PVNN_PCH_PH1_VCIN @BASEBOARD_FAB2_LIB.BASEBOARD_FAB2(SCH_1):VR_PVNN_PCH_PH1_VCIN   I116 @BASEBOARD_FAB2_LIB.BASEBOARD_FAB2(SCH_1):PAGE236
     4 P5V_STBY @BASEBOARD_FAB2_LIB.BASEBOARD_FAB2(SCH_1):P5V_STBY   I116 @BASEBOARD_FAB2_LIB.BASEBOARD_FAB2(SCH_1):PAGE236
    30 VR_FET_SW_P12V_STBY_PVDDQ_DEF @BASEBOARD_FAB2_LIB.BASEBOARD_FAB2(SCH_1):VR_FET_SW_P12V_STBY_PVDDQ_DEF   I116 @BASEBOARD_FAB2_LIB.BASEBOARD_FAB2(SCH_1):PAGE236
    25 VR_FET_SW_P12V_STBY_PVDDQ_DEF @BASEBOARD_FAB2_LIB.BASEBOARD_FAB2(SCH_1):VR_FET_SW_P12V_STBY_PVDDQ_DEF   I116 @BASEBOARD_FAB2_LIB.BASEBOARD_FAB2(SCH_1):PAGE236
     1 PVNN_PCH_STBY @BASEBOARD_FAB2_LIB.BASEBOARD_FAB2(SCH_1):PVNN_PCH_STBY   I116 @BASEBOARD_FAB2_LIB.BASEBOARD_FAB2(SCH_1):PAGE236

EU7A4 IR354XX_SM-IR35411,IC,H73688-0A
    33 VR_PVDDQ_DEF_PH2_BOOT_R @BASEBOARD_FAB2_LIB.BASEBOARD_FAB2(SCH_1):VR_PVDDQ_DEF_PH2_BOOT_R   I107 @BASEBOARD_FAB2_LIB.BASEBOARD_FAB2(SCH_1):PAGE219
    35 P5V_STBY @BASEBOARD_FAB2_LIB.BASEBOARD_FAB2(SCH_1):P5V_STBY   I107 @BASEBOARD_FAB2_LIB.BASEBOARD_FAB2(SCH_1):PAGE219
    41 TP_PVDDQ_DEF_PH2_GL_1 @BASEBOARD_FAB2_LIB.BASEBOARD_FAB2(SCH_1):TP_PVDDQ_DEF_PH2_GL_1   I107 @BASEBOARD_FAB2_LIB.BASEBOARD_FAB2(SCH_1):PAGE219
     6 TP_PVDDQ_DEF_PH2_GL_0 @BASEBOARD_FAB2_LIB.BASEBOARD_FAB2(SCH_1):TP_PVDDQ_DEF_PH2_GL_0   I107 @BASEBOARD_FAB2_LIB.BASEBOARD_FAB2(SCH_1):PAGE219
    38 ISENSE_PVDDQ_DEF_PH2_IMON @BASEBOARD_FAB2_LIB.BASEBOARD_FAB2(SCH_1):ISENSE_PVDDQ_DEF_PH2_IMON   I107 @BASEBOARD_FAB2_LIB.BASEBOARD_FAB2(SCH_1):PAGE219
     2    GND @BASEBOARD_FAB2_LIB.BASEBOARD_FAB2(SCH_1):GND   I107 @BASEBOARD_FAB2_LIB.BASEBOARD_FAB2(SCH_1):PAGE219
    31 NC_PVDDQ_DEF_PH2_P31 @BASEBOARD_FAB2_LIB.BASEBOARD_FAB2(SCH_1):NC_PVDDQ_DEF_PH2_P31   I107 @BASEBOARD_FAB2_LIB.BASEBOARD_FAB2(SCH_1):PAGE219
    37 VR_PVDDQ_DEF_PH2_OCSET @BASEBOARD_FAB2_LIB.BASEBOARD_FAB2(SCH_1):VR_PVDDQ_DEF_PH2_OCSET   I107 @BASEBOARD_FAB2_LIB.BASEBOARD_FAB2(SCH_1):PAGE219
    40    GND @BASEBOARD_FAB2_LIB.BASEBOARD_FAB2(SCH_1):GND   I107 @BASEBOARD_FAB2_LIB.BASEBOARD_FAB2(SCH_1):PAGE219
     7    GND @BASEBOARD_FAB2_LIB.BASEBOARD_FAB2(SCH_1):GND   I107 @BASEBOARD_FAB2_LIB.BASEBOARD_FAB2(SCH_1):PAGE219
     5    GND @BASEBOARD_FAB2_LIB.BASEBOARD_FAB2(SCH_1):GND   I107 @BASEBOARD_FAB2_LIB.BASEBOARD_FAB2(SCH_1):PAGE219
    32 VR_PVDDQ_DEF_PH2_PHASE @BASEBOARD_FAB2_LIB.BASEBOARD_FAB2(SCH_1):VR_PVDDQ_DEF_PH2_PHASE   I107 @BASEBOARD_FAB2_LIB.BASEBOARD_FAB2(SCH_1):PAGE219
    34 VR_PVDDQ_DEF_PWM2 @BASEBOARD_FAB2_LIB.BASEBOARD_FAB2(SCH_1):VR_PVDDQ_DEF_PWM2   I107 @BASEBOARD_FAB2_LIB.BASEBOARD_FAB2(SCH_1):PAGE219
    39 VR_PVDDQ_DEF_AIREF2 @BASEBOARD_FAB2_LIB.BASEBOARD_FAB2(SCH_1):VR_PVDDQ_DEF_AIREF2   I107 @BASEBOARD_FAB2_LIB.BASEBOARD_FAB2(SCH_1):PAGE219
    10 VR_PVDDQ_DEF_PH2_SW @BASEBOARD_FAB2_LIB.BASEBOARD_FAB2(SCH_1):VR_PVDDQ_DEF_PH2_SW   I107 @BASEBOARD_FAB2_LIB.BASEBOARD_FAB2(SCH_1):PAGE219
    36 A_TSENSE_PVDDQ_DEF @BASEBOARD_FAB2_LIB.BASEBOARD_FAB2(SCH_1):A_TSENSE_PVDDQ_DEF   I107 @BASEBOARD_FAB2_LIB.BASEBOARD_FAB2(SCH_1):PAGE219
     3 VR_PVDDQ_DEF_PH2_VCIN @BASEBOARD_FAB2_LIB.BASEBOARD_FAB2(SCH_1):VR_PVDDQ_DEF_PH2_VCIN   I107 @BASEBOARD_FAB2_LIB.BASEBOARD_FAB2(SCH_1):PAGE219
     4 P5V_STBY @BASEBOARD_FAB2_LIB.BASEBOARD_FAB2(SCH_1):P5V_STBY   I107 @BASEBOARD_FAB2_LIB.BASEBOARD_FAB2(SCH_1):PAGE219
    30 VR_FET_SW_P12V_STBY_PVDDQ_DEF @BASEBOARD_FAB2_LIB.BASEBOARD_FAB2(SCH_1):VR_FET_SW_P12V_STBY_PVDDQ_DEF   I107 @BASEBOARD_FAB2_LIB.BASEBOARD_FAB2(SCH_1):PAGE219
    25 VR_FET_SW_P12V_STBY_PVDDQ_DEF @BASEBOARD_FAB2_LIB.BASEBOARD_FAB2(SCH_1):VR_FET_SW_P12V_STBY_PVDDQ_DEF   I107 @BASEBOARD_FAB2_LIB.BASEBOARD_FAB2(SCH_1):PAGE219
     1 PVDDQ_DEF @BASEBOARD_FAB2_LIB.BASEBOARD_FAB2(SCH_1):PVDDQ_DEF   I107 @BASEBOARD_FAB2_LIB.BASEBOARD_FAB2(SCH_1):PAGE219

EU7A5 PXM1310B_QFN-IC,H89186-001
     1 TP_PVDDQ_DEF_BPWM1 @BASEBOARD_FAB2_LIB.BASEBOARD_FAB2(SCH_1):TP_PVDDQ_DEF_BPWM1    I75 @BASEBOARD_FAB2_LIB.BASEBOARD_FAB2(SCH_1):PAGE218
     2 NC_PVDDQ_DEF_DNC0 @BASEBOARD_FAB2_LIB.BASEBOARD_FAB2(SCH_1):NC_PVDDQ_DEF_DNC0    I75 @BASEBOARD_FAB2_LIB.BASEBOARD_FAB2(SCH_1):PAGE218
     3 TP_PVDDQ_DEF_PWM3 @BASEBOARD_FAB2_LIB.BASEBOARD_FAB2(SCH_1):TP_PVDDQ_DEF_PWM3    I75 @BASEBOARD_FAB2_LIB.BASEBOARD_FAB2(SCH_1):PAGE218
     4 VR_PVDDQ_DEF_PWM2 @BASEBOARD_FAB2_LIB.BASEBOARD_FAB2(SCH_1):VR_PVDDQ_DEF_PWM2    I75 @BASEBOARD_FAB2_LIB.BASEBOARD_FAB2(SCH_1):PAGE218
     5 VR_PVDDQ_DEF_PWM1 @BASEBOARD_FAB2_LIB.BASEBOARD_FAB2(SCH_1):VR_PVDDQ_DEF_PWM1    I75 @BASEBOARD_FAB2_LIB.BASEBOARD_FAB2(SCH_1):PAGE218
     6 SMB_VR_SDA_VDDQ_DEF @BASEBOARD_FAB2_LIB.BASEBOARD_FAB2(SCH_1):SMB_VR_SDA_VDDQ_DEF    I75 @BASEBOARD_FAB2_LIB.BASEBOARD_FAB2(SCH_1):PAGE218
     7 SMB_VR_SCL_VDDQ_DEF @BASEBOARD_FAB2_LIB.BASEBOARD_FAB2(SCH_1):SMB_VR_SCL_VDDQ_DEF    I75 @BASEBOARD_FAB2_LIB.BASEBOARD_FAB2(SCH_1):PAGE218
     8 TP_PVDDQ_DEF_RESET_N @BASEBOARD_FAB2_LIB.BASEBOARD_FAB2(SCH_1):TP_PVDDQ_DEF_RESET_N    I75 @BASEBOARD_FAB2_LIB.BASEBOARD_FAB2(SCH_1):PAGE218
     9 PWRGD_PVDDQ_DEF_R @BASEBOARD_FAB2_LIB.BASEBOARD_FAB2(SCH_1):PWRGD_PVDDQ_DEF_R    I75 @BASEBOARD_FAB2_LIB.BASEBOARD_FAB2(SCH_1):PAGE218
    10 VR_PVDDQ_DEF_VREN @BASEBOARD_FAB2_LIB.BASEBOARD_FAB2(SCH_1):VR_PVDDQ_DEF_VREN    I75 @BASEBOARD_FAB2_LIB.BASEBOARD_FAB2(SCH_1):PAGE218
    11 IRQ_PVDDQ_DEF_VRHOT_LVT3_R_N @BASEBOARD_FAB2_LIB.BASEBOARD_FAB2(SCH_1):IRQ_PVDDQ_DEF_VRHOT_LVT3_R_N    I75 @BASEBOARD_FAB2_LIB.BASEBOARD_FAB2(SCH_1):PAGE218
    12 TP_PVDDQ_DEF_PINALRT_N @BASEBOARD_FAB2_LIB.BASEBOARD_FAB2(SCH_1):TP_PVDDQ_DEF_PINALRT_N    I75 @BASEBOARD_FAB2_LIB.BASEBOARD_FAB2(SCH_1):PAGE218
    13 PU_VR_PVDDQ_DEF_FAULT1 @BASEBOARD_FAB2_LIB.BASEBOARD_FAB2(SCH_1):PU_VR_PVDDQ_DEF_FAULT1    I75 @BASEBOARD_FAB2_LIB.BASEBOARD_FAB2(SCH_1):PAGE218
    14 TP_PVDDQ_DEF_MP1 @BASEBOARD_FAB2_LIB.BASEBOARD_FAB2(SCH_1):TP_PVDDQ_DEF_MP1    I75 @BASEBOARD_FAB2_LIB.BASEBOARD_FAB2(SCH_1):PAGE218
    15 SVID_CLK_PVDDQ_DEF @BASEBOARD_FAB2_LIB.BASEBOARD_FAB2(SCH_1):SVID_CLK_PVDDQ_DEF    I75 @BASEBOARD_FAB2_LIB.BASEBOARD_FAB2(SCH_1):PAGE218
    16 SVID_VDIO_PVDDQ_DEF @BASEBOARD_FAB2_LIB.BASEBOARD_FAB2(SCH_1):SVID_VDIO_PVDDQ_DEF    I75 @BASEBOARD_FAB2_LIB.BASEBOARD_FAB2(SCH_1):PAGE218
    17 SVID_ALERT_PVDDQ_DEF @BASEBOARD_FAB2_LIB.BASEBOARD_FAB2(SCH_1):SVID_ALERT_PVDDQ_DEF    I75 @BASEBOARD_FAB2_LIB.BASEBOARD_FAB2(SCH_1):PAGE218
    18 TP_PVDDQ_DEF_MP2 @BASEBOARD_FAB2_LIB.BASEBOARD_FAB2(SCH_1):TP_PVDDQ_DEF_MP2    I75 @BASEBOARD_FAB2_LIB.BASEBOARD_FAB2(SCH_1):PAGE218
    19 VR_PVDDQ_DEF_AVSP @BASEBOARD_FAB2_LIB.BASEBOARD_FAB2(SCH_1):VR_PVDDQ_DEF_AVSP    I75 @BASEBOARD_FAB2_LIB.BASEBOARD_FAB2(SCH_1):PAGE218
    20 VSENSE_PVDDQ_DEF_N @BASEBOARD_FAB2_LIB.BASEBOARD_FAB2(SCH_1):VSENSE_PVDDQ_DEF_N    I75 @BASEBOARD_FAB2_LIB.BASEBOARD_FAB2(SCH_1):PAGE218
    21 VR_PVDDQ_DEF_AIREF1 @BASEBOARD_FAB2_LIB.BASEBOARD_FAB2(SCH_1):VR_PVDDQ_DEF_AIREF1    I75 @BASEBOARD_FAB2_LIB.BASEBOARD_FAB2(SCH_1):PAGE218
    22 ISENSE_PVDDQ_DEF_PH1_IMON @BASEBOARD_FAB2_LIB.BASEBOARD_FAB2(SCH_1):ISENSE_PVDDQ_DEF_PH1_IMON    I75 @BASEBOARD_FAB2_LIB.BASEBOARD_FAB2(SCH_1):PAGE218
    23 VR_PVDDQ_DEF_AIREF2 @BASEBOARD_FAB2_LIB.BASEBOARD_FAB2(SCH_1):VR_PVDDQ_DEF_AIREF2    I75 @BASEBOARD_FAB2_LIB.BASEBOARD_FAB2(SCH_1):PAGE218
    24 ISENSE_PVDDQ_DEF_PH2_IMON @BASEBOARD_FAB2_LIB.BASEBOARD_FAB2(SCH_1):ISENSE_PVDDQ_DEF_PH2_IMON    I75 @BASEBOARD_FAB2_LIB.BASEBOARD_FAB2(SCH_1):PAGE218
    25 TP_PVDDQ_DEF_PH3_IMON_REF @BASEBOARD_FAB2_LIB.BASEBOARD_FAB2(SCH_1):TP_PVDDQ_DEF_PH3_IMON_REF    I75 @BASEBOARD_FAB2_LIB.BASEBOARD_FAB2(SCH_1):PAGE218
    26 TP_PVDDQ_DEF_PH3_IMON @BASEBOARD_FAB2_LIB.BASEBOARD_FAB2(SCH_1):TP_PVDDQ_DEF_PH3_IMON    I75 @BASEBOARD_FAB2_LIB.BASEBOARD_FAB2(SCH_1):PAGE218
    27    GND @BASEBOARD_FAB2_LIB.BASEBOARD_FAB2(SCH_1):GND    I75 @BASEBOARD_FAB2_LIB.BASEBOARD_FAB2(SCH_1):PAGE218
    28 NC_PVDDQ_DEF_DNC1 @BASEBOARD_FAB2_LIB.BASEBOARD_FAB2(SCH_1):NC_PVDDQ_DEF_DNC1    I75 @BASEBOARD_FAB2_LIB.BASEBOARD_FAB2(SCH_1):PAGE218
    29 TP_PVDDQ_DEF_BVSEN @BASEBOARD_FAB2_LIB.BASEBOARD_FAB2(SCH_1):TP_PVDDQ_DEF_BVSEN    I75 @BASEBOARD_FAB2_LIB.BASEBOARD_FAB2(SCH_1):PAGE218
    30 TP_PVDDQ_DEF_BVREF @BASEBOARD_FAB2_LIB.BASEBOARD_FAB2(SCH_1):TP_PVDDQ_DEF_BVREF    I75 @BASEBOARD_FAB2_LIB.BASEBOARD_FAB2(SCH_1):PAGE218
    31 TP_PVDDQ_DEF_BREF1 @BASEBOARD_FAB2_LIB.BASEBOARD_FAB2(SCH_1):TP_PVDDQ_DEF_BREF1    I75 @BASEBOARD_FAB2_LIB.BASEBOARD_FAB2(SCH_1):PAGE218
    32    GND @BASEBOARD_FAB2_LIB.BASEBOARD_FAB2(SCH_1):GND    I75 @BASEBOARD_FAB2_LIB.BASEBOARD_FAB2(SCH_1):PAGE218
    33 VR_PVDDQ_DEF_XADDR2 @BASEBOARD_FAB2_LIB.BASEBOARD_FAB2(SCH_1):VR_PVDDQ_DEF_XADDR2    I75 @BASEBOARD_FAB2_LIB.BASEBOARD_FAB2(SCH_1):PAGE218
    34 TP_PVDDQ_DEF_BTSEN @BASEBOARD_FAB2_LIB.BASEBOARD_FAB2(SCH_1):TP_PVDDQ_DEF_BTSEN    I75 @BASEBOARD_FAB2_LIB.BASEBOARD_FAB2(SCH_1):PAGE218
    35 A_TSENSE_PVDDQ_DEF @BASEBOARD_FAB2_LIB.BASEBOARD_FAB2(SCH_1):A_TSENSE_PVDDQ_DEF    I75 @BASEBOARD_FAB2_LIB.BASEBOARD_FAB2(SCH_1):PAGE218
    36 VR_PVDDQ_DEF_XADDR1 @BASEBOARD_FAB2_LIB.BASEBOARD_FAB2(SCH_1):VR_PVDDQ_DEF_XADDR1    I75 @BASEBOARD_FAB2_LIB.BASEBOARD_FAB2(SCH_1):PAGE218
    37 VR_PVDDQ_DEF_VINSEN @BASEBOARD_FAB2_LIB.BASEBOARD_FAB2(SCH_1):VR_PVDDQ_DEF_VINSEN    I75 @BASEBOARD_FAB2_LIB.BASEBOARD_FAB2(SCH_1):PAGE218
    38 VR_PVDDQ_DEF_AIINSEN @BASEBOARD_FAB2_LIB.BASEBOARD_FAB2(SCH_1):VR_PVDDQ_DEF_AIINSEN    I75 @BASEBOARD_FAB2_LIB.BASEBOARD_FAB2(SCH_1):PAGE218
    39 VR_PVDDQ_DEF_VDD @BASEBOARD_FAB2_LIB.BASEBOARD_FAB2(SCH_1):VR_PVDDQ_DEF_VDD    I75 @BASEBOARD_FAB2_LIB.BASEBOARD_FAB2(SCH_1):PAGE218
    40 VR_PVDDQ_DEF_VD12 @BASEBOARD_FAB2_LIB.BASEBOARD_FAB2(SCH_1):VR_PVDDQ_DEF_VD12    I75 @BASEBOARD_FAB2_LIB.BASEBOARD_FAB2(SCH_1):PAGE218
    41    GND @BASEBOARD_FAB2_LIB.BASEBOARD_FAB2(SCH_1):GND    I75 @BASEBOARD_FAB2_LIB.BASEBOARD_FAB2(SCH_1):PAGE218

EU7B1 NCP3232L_SM-IC,H86355-001
     5 AGND_PVPP_DEF @BASEBOARD_FAB2_LIB.BASEBOARD_FAB2(SCH_1):AGND_PVPP_DEF   I214 @BASEBOARD_FAB2_LIB.BASEBOARD_FAB2(SCH_1):PAGE232
    36 VR_PVPP_DEF_BOOT @BASEBOARD_FAB2_LIB.BASEBOARD_FAB2(SCH_1):VR_PVPP_DEF_BOOT   I214 @BASEBOARD_FAB2_LIB.BASEBOARD_FAB2(SCH_1):PAGE232
     3 VR_COMP_PVPP_DEF_3 @BASEBOARD_FAB2_LIB.BASEBOARD_FAB2(SCH_1):VR_COMP_PVPP_DEF_3   I214 @BASEBOARD_FAB2_LIB.BASEBOARD_FAB2(SCH_1):PAGE232
    40 FM_PVPP_PVDDQ_CPU0_EN_DEF @BASEBOARD_FAB2_LIB.BASEBOARD_FAB2(SCH_1):FM_PVPP_PVDDQ_CPU0_EN_DEF   I214 @BASEBOARD_FAB2_LIB.BASEBOARD_FAB2(SCH_1):PAGE232
     2 VR_FB_PVPP_DEF @BASEBOARD_FAB2_LIB.BASEBOARD_FAB2(SCH_1):VR_FB_PVPP_DEF   I214 @BASEBOARD_FAB2_LIB.BASEBOARD_FAB2(SCH_1):PAGE232
    41    GND @BASEBOARD_FAB2_LIB.BASEBOARD_FAB2(SCH_1):GND   I214 @BASEBOARD_FAB2_LIB.BASEBOARD_FAB2(SCH_1):PAGE232
     4 VR_PVPP_DEF_ISET @BASEBOARD_FAB2_LIB.BASEBOARD_FAB2(SCH_1):VR_PVPP_DEF_ISET   I214 @BASEBOARD_FAB2_LIB.BASEBOARD_FAB2(SCH_1):PAGE232
     6 AGND_PVPP_DEF @BASEBOARD_FAB2_LIB.BASEBOARD_FAB2(SCH_1):AGND_PVPP_DEF   I214 @BASEBOARD_FAB2_LIB.BASEBOARD_FAB2(SCH_1):PAGE232
     7 PWRGD_PVPP_DEF_R @BASEBOARD_FAB2_LIB.BASEBOARD_FAB2(SCH_1):PWRGD_PVPP_DEF_R   I214 @BASEBOARD_FAB2_LIB.BASEBOARD_FAB2(SCH_1):PAGE232
    37    GND @BASEBOARD_FAB2_LIB.BASEBOARD_FAB2(SCH_1):GND   I214 @BASEBOARD_FAB2_LIB.BASEBOARD_FAB2(SCH_1):PAGE232
    28    GND @BASEBOARD_FAB2_LIB.BASEBOARD_FAB2(SCH_1):GND   I214 @BASEBOARD_FAB2_LIB.BASEBOARD_FAB2(SCH_1):PAGE232
    27    GND @BASEBOARD_FAB2_LIB.BASEBOARD_FAB2(SCH_1):GND   I214 @BASEBOARD_FAB2_LIB.BASEBOARD_FAB2(SCH_1):PAGE232
    26    GND @BASEBOARD_FAB2_LIB.BASEBOARD_FAB2(SCH_1):GND   I214 @BASEBOARD_FAB2_LIB.BASEBOARD_FAB2(SCH_1):PAGE232
    25    GND @BASEBOARD_FAB2_LIB.BASEBOARD_FAB2(SCH_1):GND   I214 @BASEBOARD_FAB2_LIB.BASEBOARD_FAB2(SCH_1):PAGE232
    24    GND @BASEBOARD_FAB2_LIB.BASEBOARD_FAB2(SCH_1):GND   I214 @BASEBOARD_FAB2_LIB.BASEBOARD_FAB2(SCH_1):PAGE232
    23    GND @BASEBOARD_FAB2_LIB.BASEBOARD_FAB2(SCH_1):GND   I214 @BASEBOARD_FAB2_LIB.BASEBOARD_FAB2(SCH_1):PAGE232
    22    GND @BASEBOARD_FAB2_LIB.BASEBOARD_FAB2(SCH_1):GND   I214 @BASEBOARD_FAB2_LIB.BASEBOARD_FAB2(SCH_1):PAGE232
    21    GND @BASEBOARD_FAB2_LIB.BASEBOARD_FAB2(SCH_1):GND   I214 @BASEBOARD_FAB2_LIB.BASEBOARD_FAB2(SCH_1):PAGE232
    20    GND @BASEBOARD_FAB2_LIB.BASEBOARD_FAB2(SCH_1):GND   I214 @BASEBOARD_FAB2_LIB.BASEBOARD_FAB2(SCH_1):PAGE232
    19    GND @BASEBOARD_FAB2_LIB.BASEBOARD_FAB2(SCH_1):GND   I214 @BASEBOARD_FAB2_LIB.BASEBOARD_FAB2(SCH_1):PAGE232
    18    GND @BASEBOARD_FAB2_LIB.BASEBOARD_FAB2(SCH_1):GND   I214 @BASEBOARD_FAB2_LIB.BASEBOARD_FAB2(SCH_1):PAGE232
    17    GND @BASEBOARD_FAB2_LIB.BASEBOARD_FAB2(SCH_1):GND   I214 @BASEBOARD_FAB2_LIB.BASEBOARD_FAB2(SCH_1):PAGE232
    16    GND @BASEBOARD_FAB2_LIB.BASEBOARD_FAB2(SCH_1):GND   I214 @BASEBOARD_FAB2_LIB.BASEBOARD_FAB2(SCH_1):PAGE232
     1 VR_PVPP_DEF_SS @BASEBOARD_FAB2_LIB.BASEBOARD_FAB2(SCH_1):VR_PVPP_DEF_SS   I214 @BASEBOARD_FAB2_LIB.BASEBOARD_FAB2(SCH_1):PAGE232
    38 VR_VB_PVPP_DEF @BASEBOARD_FAB2_LIB.BASEBOARD_FAB2(SCH_1):VR_VB_PVPP_DEF   I214 @BASEBOARD_FAB2_LIB.BASEBOARD_FAB2(SCH_1):PAGE232
    39 VR_FET_SW_P12V_STBY_PVPP_DEF @BASEBOARD_FAB2_LIB.BASEBOARD_FAB2(SCH_1):VR_FET_SW_P12V_STBY_PVPP_DEF   I214 @BASEBOARD_FAB2_LIB.BASEBOARD_FAB2(SCH_1):PAGE232
    42 VR_FET_SW_P12V_STBY_PVPP_DEF @BASEBOARD_FAB2_LIB.BASEBOARD_FAB2(SCH_1):VR_FET_SW_P12V_STBY_PVPP_DEF   I214 @BASEBOARD_FAB2_LIB.BASEBOARD_FAB2(SCH_1):PAGE232
    14 VR_FET_SW_P12V_STBY_PVPP_DEF @BASEBOARD_FAB2_LIB.BASEBOARD_FAB2(SCH_1):VR_FET_SW_P12V_STBY_PVPP_DEF   I214 @BASEBOARD_FAB2_LIB.BASEBOARD_FAB2(SCH_1):PAGE232
    13 VR_FET_SW_P12V_STBY_PVPP_DEF @BASEBOARD_FAB2_LIB.BASEBOARD_FAB2(SCH_1):VR_FET_SW_P12V_STBY_PVPP_DEF   I214 @BASEBOARD_FAB2_LIB.BASEBOARD_FAB2(SCH_1):PAGE232
    12 VR_FET_SW_P12V_STBY_PVPP_DEF @BASEBOARD_FAB2_LIB.BASEBOARD_FAB2(SCH_1):VR_FET_SW_P12V_STBY_PVPP_DEF   I214 @BASEBOARD_FAB2_LIB.BASEBOARD_FAB2(SCH_1):PAGE232
    11 VR_FET_SW_P12V_STBY_PVPP_DEF @BASEBOARD_FAB2_LIB.BASEBOARD_FAB2(SCH_1):VR_FET_SW_P12V_STBY_PVPP_DEF   I214 @BASEBOARD_FAB2_LIB.BASEBOARD_FAB2(SCH_1):PAGE232
    10 VR_FET_SW_P12V_STBY_PVPP_DEF @BASEBOARD_FAB2_LIB.BASEBOARD_FAB2(SCH_1):VR_FET_SW_P12V_STBY_PVPP_DEF   I214 @BASEBOARD_FAB2_LIB.BASEBOARD_FAB2(SCH_1):PAGE232
     9 VR_FET_SW_P12V_STBY_PVPP_DEF @BASEBOARD_FAB2_LIB.BASEBOARD_FAB2(SCH_1):VR_FET_SW_P12V_STBY_PVPP_DEF   I214 @BASEBOARD_FAB2_LIB.BASEBOARD_FAB2(SCH_1):PAGE232
     8 VR_FET_SW_P12V_STBY_PVPP_DEF @BASEBOARD_FAB2_LIB.BASEBOARD_FAB2(SCH_1):VR_FET_SW_P12V_STBY_PVPP_DEF   I214 @BASEBOARD_FAB2_LIB.BASEBOARD_FAB2(SCH_1):PAGE232
    35 VR_PVPP_DEF_PHASE @BASEBOARD_FAB2_LIB.BASEBOARD_FAB2(SCH_1):VR_PVPP_DEF_PHASE   I214 @BASEBOARD_FAB2_LIB.BASEBOARD_FAB2(SCH_1):PAGE232
    43 VR_PVPP_DEF_PHASE @BASEBOARD_FAB2_LIB.BASEBOARD_FAB2(SCH_1):VR_PVPP_DEF_PHASE   I214 @BASEBOARD_FAB2_LIB.BASEBOARD_FAB2(SCH_1):PAGE232
    34 VR_PVPP_DEF_PHASE @BASEBOARD_FAB2_LIB.BASEBOARD_FAB2(SCH_1):VR_PVPP_DEF_PHASE   I214 @BASEBOARD_FAB2_LIB.BASEBOARD_FAB2(SCH_1):PAGE232
    33 VR_PVPP_DEF_PHASE @BASEBOARD_FAB2_LIB.BASEBOARD_FAB2(SCH_1):VR_PVPP_DEF_PHASE   I214 @BASEBOARD_FAB2_LIB.BASEBOARD_FAB2(SCH_1):PAGE232
    32 VR_PVPP_DEF_PHASE @BASEBOARD_FAB2_LIB.BASEBOARD_FAB2(SCH_1):VR_PVPP_DEF_PHASE   I214 @BASEBOARD_FAB2_LIB.BASEBOARD_FAB2(SCH_1):PAGE232
    31 VR_PVPP_DEF_PHASE @BASEBOARD_FAB2_LIB.BASEBOARD_FAB2(SCH_1):VR_PVPP_DEF_PHASE   I214 @BASEBOARD_FAB2_LIB.BASEBOARD_FAB2(SCH_1):PAGE232
    30 VR_PVPP_DEF_PHASE @BASEBOARD_FAB2_LIB.BASEBOARD_FAB2(SCH_1):VR_PVPP_DEF_PHASE   I214 @BASEBOARD_FAB2_LIB.BASEBOARD_FAB2(SCH_1):PAGE232
    29 VR_PVPP_DEF_PHASE @BASEBOARD_FAB2_LIB.BASEBOARD_FAB2(SCH_1):VR_PVPP_DEF_PHASE   I214 @BASEBOARD_FAB2_LIB.BASEBOARD_FAB2(SCH_1):PAGE232
    15 VR_PVPP_DEF_PHASE @BASEBOARD_FAB2_LIB.BASEBOARD_FAB2(SCH_1):VR_PVPP_DEF_PHASE   I214 @BASEBOARD_FAB2_LIB.BASEBOARD_FAB2(SCH_1):PAGE232

EU7C1 IR354XX_SM-IR35412,IC,H73684-0A
    33 VR_PVCCIO_CPU0_PH1_BOOT_R @BASEBOARD_FAB2_LIB.BASEBOARD_FAB2(SCH_1):VR_PVCCIO_CPU0_PH1_BOOT_R   I101 @BASEBOARD_FAB2_LIB.BASEBOARD_FAB2(SCH_1):PAGE212
    35 P5V_STBY @BASEBOARD_FAB2_LIB.BASEBOARD_FAB2(SCH_1):P5V_STBY   I101 @BASEBOARD_FAB2_LIB.BASEBOARD_FAB2(SCH_1):PAGE212
    41 TP_PVCCIO_CPU0_GL_1 @BASEBOARD_FAB2_LIB.BASEBOARD_FAB2(SCH_1):TP_PVCCIO_CPU0_GL_1   I101 @BASEBOARD_FAB2_LIB.BASEBOARD_FAB2(SCH_1):PAGE212
     6 TP_PVCCIO_CPU0_GL_0 @BASEBOARD_FAB2_LIB.BASEBOARD_FAB2(SCH_1):TP_PVCCIO_CPU0_GL_0   I101 @BASEBOARD_FAB2_LIB.BASEBOARD_FAB2(SCH_1):PAGE212
    38 ISENSE_PVCCIO_CPU0_PH1_IMON @BASEBOARD_FAB2_LIB.BASEBOARD_FAB2(SCH_1):ISENSE_PVCCIO_CPU0_PH1_IMON   I101 @BASEBOARD_FAB2_LIB.BASEBOARD_FAB2(SCH_1):PAGE212
     2    GND @BASEBOARD_FAB2_LIB.BASEBOARD_FAB2(SCH_1):GND   I101 @BASEBOARD_FAB2_LIB.BASEBOARD_FAB2(SCH_1):PAGE212
    31 NC_PVCCIO_CPU0_PH1_P31 @BASEBOARD_FAB2_LIB.BASEBOARD_FAB2(SCH_1):NC_PVCCIO_CPU0_PH1_P31   I101 @BASEBOARD_FAB2_LIB.BASEBOARD_FAB2(SCH_1):PAGE212
    37 VR_PVCCIO_CPU0_OCSET @BASEBOARD_FAB2_LIB.BASEBOARD_FAB2(SCH_1):VR_PVCCIO_CPU0_OCSET   I101 @BASEBOARD_FAB2_LIB.BASEBOARD_FAB2(SCH_1):PAGE212
    40    GND @BASEBOARD_FAB2_LIB.BASEBOARD_FAB2(SCH_1):GND   I101 @BASEBOARD_FAB2_LIB.BASEBOARD_FAB2(SCH_1):PAGE212
     7    GND @BASEBOARD_FAB2_LIB.BASEBOARD_FAB2(SCH_1):GND   I101 @BASEBOARD_FAB2_LIB.BASEBOARD_FAB2(SCH_1):PAGE212
     5    GND @BASEBOARD_FAB2_LIB.BASEBOARD_FAB2(SCH_1):GND   I101 @BASEBOARD_FAB2_LIB.BASEBOARD_FAB2(SCH_1):PAGE212
    32 VR_PVCCIO_CPU0_PH1_PHASE @BASEBOARD_FAB2_LIB.BASEBOARD_FAB2(SCH_1):VR_PVCCIO_CPU0_PH1_PHASE   I101 @BASEBOARD_FAB2_LIB.BASEBOARD_FAB2(SCH_1):PAGE212
    34 VR_PVCCIO_CPU0_PWM1 @BASEBOARD_FAB2_LIB.BASEBOARD_FAB2(SCH_1):VR_PVCCIO_CPU0_PWM1   I101 @BASEBOARD_FAB2_LIB.BASEBOARD_FAB2(SCH_1):PAGE212
    39 VR_PVCCIO_CPU0_AIREF1 @BASEBOARD_FAB2_LIB.BASEBOARD_FAB2(SCH_1):VR_PVCCIO_CPU0_AIREF1   I101 @BASEBOARD_FAB2_LIB.BASEBOARD_FAB2(SCH_1):PAGE212
    10 VR_PVCCIO_CPU0_PH1_SW @BASEBOARD_FAB2_LIB.BASEBOARD_FAB2(SCH_1):VR_PVCCIO_CPU0_PH1_SW   I101 @BASEBOARD_FAB2_LIB.BASEBOARD_FAB2(SCH_1):PAGE212
    36 A_TSENSE_PVCCIO_CPU0 @BASEBOARD_FAB2_LIB.BASEBOARD_FAB2(SCH_1):A_TSENSE_PVCCIO_CPU0   I101 @BASEBOARD_FAB2_LIB.BASEBOARD_FAB2(SCH_1):PAGE212
     3 VR_PVCCIO_CPU0_PH1_VCIN @BASEBOARD_FAB2_LIB.BASEBOARD_FAB2(SCH_1):VR_PVCCIO_CPU0_PH1_VCIN   I101 @BASEBOARD_FAB2_LIB.BASEBOARD_FAB2(SCH_1):PAGE212
     4 P5V_STBY @BASEBOARD_FAB2_LIB.BASEBOARD_FAB2(SCH_1):P5V_STBY   I101 @BASEBOARD_FAB2_LIB.BASEBOARD_FAB2(SCH_1):PAGE212
    30 VR_FET_SW_P12V_STBY_PVCCIO_CPU0 @BASEBOARD_FAB2_LIB.BASEBOARD_FAB2(SCH_1):VR_FET_SW_P12V_STBY_PVCCIO_CPU0   I101 @BASEBOARD_FAB2_LIB.BASEBOARD_FAB2(SCH_1):PAGE212
    25 VR_FET_SW_P12V_STBY_PVCCIO_CPU0 @BASEBOARD_FAB2_LIB.BASEBOARD_FAB2(SCH_1):VR_FET_SW_P12V_STBY_PVCCIO_CPU0   I101 @BASEBOARD_FAB2_LIB.BASEBOARD_FAB2(SCH_1):PAGE212
     1 PVCCIO_CPU0 @BASEBOARD_FAB2_LIB.BASEBOARD_FAB2(SCH_1):PVCCIO_CPU0   I101 @BASEBOARD_FAB2_LIB.BASEBOARD_FAB2(SCH_1):PAGE212

EU7E1 SLG55021_SM-IC,G56246-001
     4    GND @BASEBOARD_FAB2_LIB.BASEBOARD_FAB2(SCH_1):GND    I19 @BASEBOARD_FAB2_LIB.BASEBOARD_FAB2(SCH_1):PAGE198
     9    GND @BASEBOARD_FAB2_LIB.BASEBOARD_FAB2(SCH_1):GND    I19 @BASEBOARD_FAB2_LIB.BASEBOARD_FAB2(SCH_1):PAGE198
     1 P5V_STBY @BASEBOARD_FAB2_LIB.BASEBOARD_FAB2(SCH_1):P5V_STBY    I19 @BASEBOARD_FAB2_LIB.BASEBOARD_FAB2(SCH_1):PAGE198
     2 FM_P12V_MAIN_SW_EN @BASEBOARD_FAB2_LIB.BASEBOARD_FAB2(SCH_1):FM_P12V_MAIN_SW_EN    I19 @BASEBOARD_FAB2_LIB.BASEBOARD_FAB2(SCH_1):PAGE198
     3 P5V_STBY @BASEBOARD_FAB2_LIB.BASEBOARD_FAB2(SCH_1):P5V_STBY    I19 @BASEBOARD_FAB2_LIB.BASEBOARD_FAB2(SCH_1):PAGE198
     5 P12V_STBY @BASEBOARD_FAB2_LIB.BASEBOARD_FAB2(SCH_1):P12V_STBY    I19 @BASEBOARD_FAB2_LIB.BASEBOARD_FAB2(SCH_1):PAGE198
     6   P12V @BASEBOARD_FAB2_LIB.BASEBOARD_FAB2(SCH_1):P12V    I19 @BASEBOARD_FAB2_LIB.BASEBOARD_FAB2(SCH_1):PAGE198
     7 P12V_SWITCH_G @BASEBOARD_FAB2_LIB.BASEBOARD_FAB2(SCH_1):P12V_SWITCH_G    I19 @BASEBOARD_FAB2_LIB.BASEBOARD_FAB2(SCH_1):PAGE198
     8 TP_SLG55021_P12V_MAIN_8 @BASEBOARD_FAB2_LIB.BASEBOARD_FAB2(SCH_1):TP_SLG55021_P12V_MAIN_8    I19 @BASEBOARD_FAB2_LIB.BASEBOARD_FAB2(SCH_1):PAGE198

EU7E2 TPS54821_LCC-IC,H63269-001
    13 VR_P5V_STBY_BOOT @BASEBOARD_FAB2_LIB.BASEBOARD_FAB2(SCH_1):VR_P5V_STBY_BOOT    I83 @BASEBOARD_FAB2_LIB.BASEBOARD_FAB2(SCH_1):PAGE241
     8 VR_P5V_STBY_COMP @BASEBOARD_FAB2_LIB.BASEBOARD_FAB2(SCH_1):VR_P5V_STBY_COMP    I83 @BASEBOARD_FAB2_LIB.BASEBOARD_FAB2(SCH_1):PAGE241
    10 VR_P5V_STBY_EN @BASEBOARD_FAB2_LIB.BASEBOARD_FAB2(SCH_1):VR_P5V_STBY_EN    I83 @BASEBOARD_FAB2_LIB.BASEBOARD_FAB2(SCH_1):PAGE241
     3    GND @BASEBOARD_FAB2_LIB.BASEBOARD_FAB2(SCH_1):GND    I83 @BASEBOARD_FAB2_LIB.BASEBOARD_FAB2(SCH_1):PAGE241
     2    GND @BASEBOARD_FAB2_LIB.BASEBOARD_FAB2(SCH_1):GND    I83 @BASEBOARD_FAB2_LIB.BASEBOARD_FAB2(SCH_1):PAGE241
    12 VR_P5V_STBY_PHASE @BASEBOARD_FAB2_LIB.BASEBOARD_FAB2(SCH_1):VR_P5V_STBY_PHASE    I83 @BASEBOARD_FAB2_LIB.BASEBOARD_FAB2(SCH_1):PAGE241
    11 VR_P5V_STBY_PHASE @BASEBOARD_FAB2_LIB.BASEBOARD_FAB2(SCH_1):VR_P5V_STBY_PHASE    I83 @BASEBOARD_FAB2_LIB.BASEBOARD_FAB2(SCH_1):PAGE241
     5 VR_FET_SW_P5V_STBY_PVIN @BASEBOARD_FAB2_LIB.BASEBOARD_FAB2(SCH_1):VR_FET_SW_P5V_STBY_PVIN    I83 @BASEBOARD_FAB2_LIB.BASEBOARD_FAB2(SCH_1):PAGE241
     4 VR_FET_SW_P5V_STBY_PVIN @BASEBOARD_FAB2_LIB.BASEBOARD_FAB2(SCH_1):VR_FET_SW_P5V_STBY_PVIN    I83 @BASEBOARD_FAB2_LIB.BASEBOARD_FAB2(SCH_1):PAGE241
    14 PWRGD_P5V_STBY_R @BASEBOARD_FAB2_LIB.BASEBOARD_FAB2(SCH_1):PWRGD_P5V_STBY_R    I83 @BASEBOARD_FAB2_LIB.BASEBOARD_FAB2(SCH_1):PAGE241
     1 VR_P5V_STBY_RT @BASEBOARD_FAB2_LIB.BASEBOARD_FAB2(SCH_1):VR_P5V_STBY_RT    I83 @BASEBOARD_FAB2_LIB.BASEBOARD_FAB2(SCH_1):PAGE241
     9 VR_P5V_STBY_SS @BASEBOARD_FAB2_LIB.BASEBOARD_FAB2(SCH_1):VR_P5V_STBY_SS    I83 @BASEBOARD_FAB2_LIB.BASEBOARD_FAB2(SCH_1):PAGE241
    15    GND @BASEBOARD_FAB2_LIB.BASEBOARD_FAB2(SCH_1):GND    I83 @BASEBOARD_FAB2_LIB.BASEBOARD_FAB2(SCH_1):PAGE241
     6 VR_P5V_STBY_VIN @BASEBOARD_FAB2_LIB.BASEBOARD_FAB2(SCH_1):VR_P5V_STBY_VIN    I83 @BASEBOARD_FAB2_LIB.BASEBOARD_FAB2(SCH_1):PAGE241
     7 VR_P5V_STBY_VSENSE @BASEBOARD_FAB2_LIB.BASEBOARD_FAB2(SCH_1):VR_P5V_STBY_VSENSE    I83 @BASEBOARD_FAB2_LIB.BASEBOARD_FAB2(SCH_1):PAGE241

EU7F1 NCP3232L_SM-IC,H86355-001
     5 AGND_PVPP_ABC @BASEBOARD_FAB2_LIB.BASEBOARD_FAB2(SCH_1):AGND_PVPP_ABC   I193 @BASEBOARD_FAB2_LIB.BASEBOARD_FAB2(SCH_1):PAGE231
    36 VR_PVPP_ABC_BOOT @BASEBOARD_FAB2_LIB.BASEBOARD_FAB2(SCH_1):VR_PVPP_ABC_BOOT   I193 @BASEBOARD_FAB2_LIB.BASEBOARD_FAB2(SCH_1):PAGE231
     3 VR_COMP_PVPP_ABC_3 @BASEBOARD_FAB2_LIB.BASEBOARD_FAB2(SCH_1):VR_COMP_PVPP_ABC_3   I193 @BASEBOARD_FAB2_LIB.BASEBOARD_FAB2(SCH_1):PAGE231
    40 FM_PVPP_PVDDQ_CPU0_EN_ABC @BASEBOARD_FAB2_LIB.BASEBOARD_FAB2(SCH_1):FM_PVPP_PVDDQ_CPU0_EN_ABC   I193 @BASEBOARD_FAB2_LIB.BASEBOARD_FAB2(SCH_1):PAGE231
     2 VR_FB_PVPP_ABC @BASEBOARD_FAB2_LIB.BASEBOARD_FAB2(SCH_1):VR_FB_PVPP_ABC   I193 @BASEBOARD_FAB2_LIB.BASEBOARD_FAB2(SCH_1):PAGE231
    41    GND @BASEBOARD_FAB2_LIB.BASEBOARD_FAB2(SCH_1):GND   I193 @BASEBOARD_FAB2_LIB.BASEBOARD_FAB2(SCH_1):PAGE231
     4 VR_PVPP_ABC_ISET @BASEBOARD_FAB2_LIB.BASEBOARD_FAB2(SCH_1):VR_PVPP_ABC_ISET   I193 @BASEBOARD_FAB2_LIB.BASEBOARD_FAB2(SCH_1):PAGE231
     6 AGND_PVPP_ABC @BASEBOARD_FAB2_LIB.BASEBOARD_FAB2(SCH_1):AGND_PVPP_ABC   I193 @BASEBOARD_FAB2_LIB.BASEBOARD_FAB2(SCH_1):PAGE231
     7 PWRGD_PVPP_ABC_R @BASEBOARD_FAB2_LIB.BASEBOARD_FAB2(SCH_1):PWRGD_PVPP_ABC_R   I193 @BASEBOARD_FAB2_LIB.BASEBOARD_FAB2(SCH_1):PAGE231
    37    GND @BASEBOARD_FAB2_LIB.BASEBOARD_FAB2(SCH_1):GND   I193 @BASEBOARD_FAB2_LIB.BASEBOARD_FAB2(SCH_1):PAGE231
    28    GND @BASEBOARD_FAB2_LIB.BASEBOARD_FAB2(SCH_1):GND   I193 @BASEBOARD_FAB2_LIB.BASEBOARD_FAB2(SCH_1):PAGE231
    27    GND @BASEBOARD_FAB2_LIB.BASEBOARD_FAB2(SCH_1):GND   I193 @BASEBOARD_FAB2_LIB.BASEBOARD_FAB2(SCH_1):PAGE231
    26    GND @BASEBOARD_FAB2_LIB.BASEBOARD_FAB2(SCH_1):GND   I193 @BASEBOARD_FAB2_LIB.BASEBOARD_FAB2(SCH_1):PAGE231
    25    GND @BASEBOARD_FAB2_LIB.BASEBOARD_FAB2(SCH_1):GND   I193 @BASEBOARD_FAB2_LIB.BASEBOARD_FAB2(SCH_1):PAGE231
    24    GND @BASEBOARD_FAB2_LIB.BASEBOARD_FAB2(SCH_1):GND   I193 @BASEBOARD_FAB2_LIB.BASEBOARD_FAB2(SCH_1):PAGE231
    23    GND @BASEBOARD_FAB2_LIB.BASEBOARD_FAB2(SCH_1):GND   I193 @BASEBOARD_FAB2_LIB.BASEBOARD_FAB2(SCH_1):PAGE231
    22    GND @BASEBOARD_FAB2_LIB.BASEBOARD_FAB2(SCH_1):GND   I193 @BASEBOARD_FAB2_LIB.BASEBOARD_FAB2(SCH_1):PAGE231
    21    GND @BASEBOARD_FAB2_LIB.BASEBOARD_FAB2(SCH_1):GND   I193 @BASEBOARD_FAB2_LIB.BASEBOARD_FAB2(SCH_1):PAGE231
    20    GND @BASEBOARD_FAB2_LIB.BASEBOARD_FAB2(SCH_1):GND   I193 @BASEBOARD_FAB2_LIB.BASEBOARD_FAB2(SCH_1):PAGE231
    19    GND @BASEBOARD_FAB2_LIB.BASEBOARD_FAB2(SCH_1):GND   I193 @BASEBOARD_FAB2_LIB.BASEBOARD_FAB2(SCH_1):PAGE231
    18    GND @BASEBOARD_FAB2_LIB.BASEBOARD_FAB2(SCH_1):GND   I193 @BASEBOARD_FAB2_LIB.BASEBOARD_FAB2(SCH_1):PAGE231
    17    GND @BASEBOARD_FAB2_LIB.BASEBOARD_FAB2(SCH_1):GND   I193 @BASEBOARD_FAB2_LIB.BASEBOARD_FAB2(SCH_1):PAGE231
    16    GND @BASEBOARD_FAB2_LIB.BASEBOARD_FAB2(SCH_1):GND   I193 @BASEBOARD_FAB2_LIB.BASEBOARD_FAB2(SCH_1):PAGE231
     1 VR_PVPP_ABC_SS @BASEBOARD_FAB2_LIB.BASEBOARD_FAB2(SCH_1):VR_PVPP_ABC_SS   I193 @BASEBOARD_FAB2_LIB.BASEBOARD_FAB2(SCH_1):PAGE231
    38 VR_VB_PVPP_ABC @BASEBOARD_FAB2_LIB.BASEBOARD_FAB2(SCH_1):VR_VB_PVPP_ABC   I193 @BASEBOARD_FAB2_LIB.BASEBOARD_FAB2(SCH_1):PAGE231
    39 VR_FET_SW_P12V_STBY_PVPP_ABC @BASEBOARD_FAB2_LIB.BASEBOARD_FAB2(SCH_1):VR_FET_SW_P12V_STBY_PVPP_ABC   I193 @BASEBOARD_FAB2_LIB.BASEBOARD_FAB2(SCH_1):PAGE231
    42 VR_FET_SW_P12V_STBY_PVPP_ABC @BASEBOARD_FAB2_LIB.BASEBOARD_FAB2(SCH_1):VR_FET_SW_P12V_STBY_PVPP_ABC   I193 @BASEBOARD_FAB2_LIB.BASEBOARD_FAB2(SCH_1):PAGE231
    14 VR_FET_SW_P12V_STBY_PVPP_ABC @BASEBOARD_FAB2_LIB.BASEBOARD_FAB2(SCH_1):VR_FET_SW_P12V_STBY_PVPP_ABC   I193 @BASEBOARD_FAB2_LIB.BASEBOARD_FAB2(SCH_1):PAGE231
    13 VR_FET_SW_P12V_STBY_PVPP_ABC @BASEBOARD_FAB2_LIB.BASEBOARD_FAB2(SCH_1):VR_FET_SW_P12V_STBY_PVPP_ABC   I193 @BASEBOARD_FAB2_LIB.BASEBOARD_FAB2(SCH_1):PAGE231
    12 VR_FET_SW_P12V_STBY_PVPP_ABC @BASEBOARD_FAB2_LIB.BASEBOARD_FAB2(SCH_1):VR_FET_SW_P12V_STBY_PVPP_ABC   I193 @BASEBOARD_FAB2_LIB.BASEBOARD_FAB2(SCH_1):PAGE231
    11 VR_FET_SW_P12V_STBY_PVPP_ABC @BASEBOARD_FAB2_LIB.BASEBOARD_FAB2(SCH_1):VR_FET_SW_P12V_STBY_PVPP_ABC   I193 @BASEBOARD_FAB2_LIB.BASEBOARD_FAB2(SCH_1):PAGE231
    10 VR_FET_SW_P12V_STBY_PVPP_ABC @BASEBOARD_FAB2_LIB.BASEBOARD_FAB2(SCH_1):VR_FET_SW_P12V_STBY_PVPP_ABC   I193 @BASEBOARD_FAB2_LIB.BASEBOARD_FAB2(SCH_1):PAGE231
     9 VR_FET_SW_P12V_STBY_PVPP_ABC @BASEBOARD_FAB2_LIB.BASEBOARD_FAB2(SCH_1):VR_FET_SW_P12V_STBY_PVPP_ABC   I193 @BASEBOARD_FAB2_LIB.BASEBOARD_FAB2(SCH_1):PAGE231
     8 VR_FET_SW_P12V_STBY_PVPP_ABC @BASEBOARD_FAB2_LIB.BASEBOARD_FAB2(SCH_1):VR_FET_SW_P12V_STBY_PVPP_ABC   I193 @BASEBOARD_FAB2_LIB.BASEBOARD_FAB2(SCH_1):PAGE231
    35 VR_PVPP_ABC_PHASE @BASEBOARD_FAB2_LIB.BASEBOARD_FAB2(SCH_1):VR_PVPP_ABC_PHASE   I193 @BASEBOARD_FAB2_LIB.BASEBOARD_FAB2(SCH_1):PAGE231
    43 VR_PVPP_ABC_PHASE @BASEBOARD_FAB2_LIB.BASEBOARD_FAB2(SCH_1):VR_PVPP_ABC_PHASE   I193 @BASEBOARD_FAB2_LIB.BASEBOARD_FAB2(SCH_1):PAGE231
    34 VR_PVPP_ABC_PHASE @BASEBOARD_FAB2_LIB.BASEBOARD_FAB2(SCH_1):VR_PVPP_ABC_PHASE   I193 @BASEBOARD_FAB2_LIB.BASEBOARD_FAB2(SCH_1):PAGE231
    33 VR_PVPP_ABC_PHASE @BASEBOARD_FAB2_LIB.BASEBOARD_FAB2(SCH_1):VR_PVPP_ABC_PHASE   I193 @BASEBOARD_FAB2_LIB.BASEBOARD_FAB2(SCH_1):PAGE231
    32 VR_PVPP_ABC_PHASE @BASEBOARD_FAB2_LIB.BASEBOARD_FAB2(SCH_1):VR_PVPP_ABC_PHASE   I193 @BASEBOARD_FAB2_LIB.BASEBOARD_FAB2(SCH_1):PAGE231
    31 VR_PVPP_ABC_PHASE @BASEBOARD_FAB2_LIB.BASEBOARD_FAB2(SCH_1):VR_PVPP_ABC_PHASE   I193 @BASEBOARD_FAB2_LIB.BASEBOARD_FAB2(SCH_1):PAGE231
    30 VR_PVPP_ABC_PHASE @BASEBOARD_FAB2_LIB.BASEBOARD_FAB2(SCH_1):VR_PVPP_ABC_PHASE   I193 @BASEBOARD_FAB2_LIB.BASEBOARD_FAB2(SCH_1):PAGE231
    29 VR_PVPP_ABC_PHASE @BASEBOARD_FAB2_LIB.BASEBOARD_FAB2(SCH_1):VR_PVPP_ABC_PHASE   I193 @BASEBOARD_FAB2_LIB.BASEBOARD_FAB2(SCH_1):PAGE231
    15 VR_PVPP_ABC_PHASE @BASEBOARD_FAB2_LIB.BASEBOARD_FAB2(SCH_1):VR_PVPP_ABC_PHASE   I193 @BASEBOARD_FAB2_LIB.BASEBOARD_FAB2(SCH_1):PAGE231

EU7G1 PXM1310B_QFN-IC,H89186-001
     1 TP_PVDDQ_ABC_BPWM1 @BASEBOARD_FAB2_LIB.BASEBOARD_FAB2(SCH_1):TP_PVDDQ_ABC_BPWM1   I358 @BASEBOARD_FAB2_LIB.BASEBOARD_FAB2(SCH_1):PAGE215
     2 NC_PVDDQ_ABC_DNC0 @BASEBOARD_FAB2_LIB.BASEBOARD_FAB2(SCH_1):NC_PVDDQ_ABC_DNC0   I358 @BASEBOARD_FAB2_LIB.BASEBOARD_FAB2(SCH_1):PAGE215
     3 TP_PVDDQ_ABC_PWM3 @BASEBOARD_FAB2_LIB.BASEBOARD_FAB2(SCH_1):TP_PVDDQ_ABC_PWM3   I358 @BASEBOARD_FAB2_LIB.BASEBOARD_FAB2(SCH_1):PAGE215
     4 VR_PVDDQ_ABC_PWM2 @BASEBOARD_FAB2_LIB.BASEBOARD_FAB2(SCH_1):VR_PVDDQ_ABC_PWM2   I358 @BASEBOARD_FAB2_LIB.BASEBOARD_FAB2(SCH_1):PAGE215
     5 VR_PVDDQ_ABC_PWM1 @BASEBOARD_FAB2_LIB.BASEBOARD_FAB2(SCH_1):VR_PVDDQ_ABC_PWM1   I358 @BASEBOARD_FAB2_LIB.BASEBOARD_FAB2(SCH_1):PAGE215
     6 SMB_VR_SDA_VDDQ_ABC @BASEBOARD_FAB2_LIB.BASEBOARD_FAB2(SCH_1):SMB_VR_SDA_VDDQ_ABC   I358 @BASEBOARD_FAB2_LIB.BASEBOARD_FAB2(SCH_1):PAGE215
     7 SMB_VR_SCL_VDDQ_ABC @BASEBOARD_FAB2_LIB.BASEBOARD_FAB2(SCH_1):SMB_VR_SCL_VDDQ_ABC   I358 @BASEBOARD_FAB2_LIB.BASEBOARD_FAB2(SCH_1):PAGE215
     8 TP_PVDDQ_ABC_RESET_N @BASEBOARD_FAB2_LIB.BASEBOARD_FAB2(SCH_1):TP_PVDDQ_ABC_RESET_N   I358 @BASEBOARD_FAB2_LIB.BASEBOARD_FAB2(SCH_1):PAGE215
     9 PWRGD_PVDDQ_ABC_R @BASEBOARD_FAB2_LIB.BASEBOARD_FAB2(SCH_1):PWRGD_PVDDQ_ABC_R   I358 @BASEBOARD_FAB2_LIB.BASEBOARD_FAB2(SCH_1):PAGE215
    10 VR_PVDDQ_ABC_VREN @BASEBOARD_FAB2_LIB.BASEBOARD_FAB2(SCH_1):VR_PVDDQ_ABC_VREN   I358 @BASEBOARD_FAB2_LIB.BASEBOARD_FAB2(SCH_1):PAGE215
    11 IRQ_PVDDQ_ABC_VRHOT_LVT3_R_N @BASEBOARD_FAB2_LIB.BASEBOARD_FAB2(SCH_1):IRQ_PVDDQ_ABC_VRHOT_LVT3_R_N   I358 @BASEBOARD_FAB2_LIB.BASEBOARD_FAB2(SCH_1):PAGE215
    12 TP_PVDDQ_ABC_PINALRT_N @BASEBOARD_FAB2_LIB.BASEBOARD_FAB2(SCH_1):TP_PVDDQ_ABC_PINALRT_N   I358 @BASEBOARD_FAB2_LIB.BASEBOARD_FAB2(SCH_1):PAGE215
    13 PU_VR_PVDDQ_ABC_FAULT1 @BASEBOARD_FAB2_LIB.BASEBOARD_FAB2(SCH_1):PU_VR_PVDDQ_ABC_FAULT1   I358 @BASEBOARD_FAB2_LIB.BASEBOARD_FAB2(SCH_1):PAGE215
    14 TP_PVDDQ_ABC_MP1 @BASEBOARD_FAB2_LIB.BASEBOARD_FAB2(SCH_1):TP_PVDDQ_ABC_MP1   I358 @BASEBOARD_FAB2_LIB.BASEBOARD_FAB2(SCH_1):PAGE215
    15 SVID_CLK_PVDDQ_ABC @BASEBOARD_FAB2_LIB.BASEBOARD_FAB2(SCH_1):SVID_CLK_PVDDQ_ABC   I358 @BASEBOARD_FAB2_LIB.BASEBOARD_FAB2(SCH_1):PAGE215
    16 SVID_VDIO_PVDDQ_ABC @BASEBOARD_FAB2_LIB.BASEBOARD_FAB2(SCH_1):SVID_VDIO_PVDDQ_ABC   I358 @BASEBOARD_FAB2_LIB.BASEBOARD_FAB2(SCH_1):PAGE215
    17 SVID_ALERT_PVDDQ_ABC @BASEBOARD_FAB2_LIB.BASEBOARD_FAB2(SCH_1):SVID_ALERT_PVDDQ_ABC   I358 @BASEBOARD_FAB2_LIB.BASEBOARD_FAB2(SCH_1):PAGE215
    18 TP_PVDDQ_ABC_MP2 @BASEBOARD_FAB2_LIB.BASEBOARD_FAB2(SCH_1):TP_PVDDQ_ABC_MP2   I358 @BASEBOARD_FAB2_LIB.BASEBOARD_FAB2(SCH_1):PAGE215
    19 VR_PVDDQ_ABC_AVSP @BASEBOARD_FAB2_LIB.BASEBOARD_FAB2(SCH_1):VR_PVDDQ_ABC_AVSP   I358 @BASEBOARD_FAB2_LIB.BASEBOARD_FAB2(SCH_1):PAGE215
    20 VSENSE_PVDDQ_ABC_N @BASEBOARD_FAB2_LIB.BASEBOARD_FAB2(SCH_1):VSENSE_PVDDQ_ABC_N   I358 @BASEBOARD_FAB2_LIB.BASEBOARD_FAB2(SCH_1):PAGE215
    21 VR_PVDDQ_ABC_AIREF1 @BASEBOARD_FAB2_LIB.BASEBOARD_FAB2(SCH_1):VR_PVDDQ_ABC_AIREF1   I358 @BASEBOARD_FAB2_LIB.BASEBOARD_FAB2(SCH_1):PAGE215
    22 ISENSE_PVDDQ_ABC_PH1_IMON @BASEBOARD_FAB2_LIB.BASEBOARD_FAB2(SCH_1):ISENSE_PVDDQ_ABC_PH1_IMON   I358 @BASEBOARD_FAB2_LIB.BASEBOARD_FAB2(SCH_1):PAGE215
    23 VR_PVDDQ_ABC_AIREF2 @BASEBOARD_FAB2_LIB.BASEBOARD_FAB2(SCH_1):VR_PVDDQ_ABC_AIREF2   I358 @BASEBOARD_FAB2_LIB.BASEBOARD_FAB2(SCH_1):PAGE215
    24 ISENSE_PVDDQ_ABC_PH2_IMON @BASEBOARD_FAB2_LIB.BASEBOARD_FAB2(SCH_1):ISENSE_PVDDQ_ABC_PH2_IMON   I358 @BASEBOARD_FAB2_LIB.BASEBOARD_FAB2(SCH_1):PAGE215
    25 TP_PVDDQ_ABC_PH3_IMON_REF @BASEBOARD_FAB2_LIB.BASEBOARD_FAB2(SCH_1):TP_PVDDQ_ABC_PH3_IMON_REF   I358 @BASEBOARD_FAB2_LIB.BASEBOARD_FAB2(SCH_1):PAGE215
    26 TP_PVDDQ_ABC_PH3_IMON @BASEBOARD_FAB2_LIB.BASEBOARD_FAB2(SCH_1):TP_PVDDQ_ABC_PH3_IMON   I358 @BASEBOARD_FAB2_LIB.BASEBOARD_FAB2(SCH_1):PAGE215
    27    GND @BASEBOARD_FAB2_LIB.BASEBOARD_FAB2(SCH_1):GND   I358 @BASEBOARD_FAB2_LIB.BASEBOARD_FAB2(SCH_1):PAGE215
    28 NC_PVDDQ_ABC_DNC1 @BASEBOARD_FAB2_LIB.BASEBOARD_FAB2(SCH_1):NC_PVDDQ_ABC_DNC1   I358 @BASEBOARD_FAB2_LIB.BASEBOARD_FAB2(SCH_1):PAGE215
    29 TP_PVDDQ_ABC_BVSEN @BASEBOARD_FAB2_LIB.BASEBOARD_FAB2(SCH_1):TP_PVDDQ_ABC_BVSEN   I358 @BASEBOARD_FAB2_LIB.BASEBOARD_FAB2(SCH_1):PAGE215
    30 TP_PVDDQ_ABC_BVREF @BASEBOARD_FAB2_LIB.BASEBOARD_FAB2(SCH_1):TP_PVDDQ_ABC_BVREF   I358 @BASEBOARD_FAB2_LIB.BASEBOARD_FAB2(SCH_1):PAGE215
    31 TP_PVDDQ_ABC_BREF1 @BASEBOARD_FAB2_LIB.BASEBOARD_FAB2(SCH_1):TP_PVDDQ_ABC_BREF1   I358 @BASEBOARD_FAB2_LIB.BASEBOARD_FAB2(SCH_1):PAGE215
    32    GND @BASEBOARD_FAB2_LIB.BASEBOARD_FAB2(SCH_1):GND   I358 @BASEBOARD_FAB2_LIB.BASEBOARD_FAB2(SCH_1):PAGE215
    33 VR_PVDDQ_ABC_XADDR2 @BASEBOARD_FAB2_LIB.BASEBOARD_FAB2(SCH_1):VR_PVDDQ_ABC_XADDR2   I358 @BASEBOARD_FAB2_LIB.BASEBOARD_FAB2(SCH_1):PAGE215
    34 TP_PVDDQ_ABC_BTSEN @BASEBOARD_FAB2_LIB.BASEBOARD_FAB2(SCH_1):TP_PVDDQ_ABC_BTSEN   I358 @BASEBOARD_FAB2_LIB.BASEBOARD_FAB2(SCH_1):PAGE215
    35 A_TSENSE_PVDDQ_ABC @BASEBOARD_FAB2_LIB.BASEBOARD_FAB2(SCH_1):A_TSENSE_PVDDQ_ABC   I358 @BASEBOARD_FAB2_LIB.BASEBOARD_FAB2(SCH_1):PAGE215
    36 VR_PVDDQ_ABC_XADDR1 @BASEBOARD_FAB2_LIB.BASEBOARD_FAB2(SCH_1):VR_PVDDQ_ABC_XADDR1   I358 @BASEBOARD_FAB2_LIB.BASEBOARD_FAB2(SCH_1):PAGE215
    37 VR_PVDDQ_ABC_VINSEN @BASEBOARD_FAB2_LIB.BASEBOARD_FAB2(SCH_1):VR_PVDDQ_ABC_VINSEN   I358 @BASEBOARD_FAB2_LIB.BASEBOARD_FAB2(SCH_1):PAGE215
    38 VR_PVDDQ_ABC_AIINSEN @BASEBOARD_FAB2_LIB.BASEBOARD_FAB2(SCH_1):VR_PVDDQ_ABC_AIINSEN   I358 @BASEBOARD_FAB2_LIB.BASEBOARD_FAB2(SCH_1):PAGE215
    39 VR_PVDDQ_ABC_VDD @BASEBOARD_FAB2_LIB.BASEBOARD_FAB2(SCH_1):VR_PVDDQ_ABC_VDD   I358 @BASEBOARD_FAB2_LIB.BASEBOARD_FAB2(SCH_1):PAGE215
    40 VR_PVDDQ_ABC_VD12 @BASEBOARD_FAB2_LIB.BASEBOARD_FAB2(SCH_1):VR_PVDDQ_ABC_VD12   I358 @BASEBOARD_FAB2_LIB.BASEBOARD_FAB2(SCH_1):PAGE215
    41    GND @BASEBOARD_FAB2_LIB.BASEBOARD_FAB2(SCH_1):GND   I358 @BASEBOARD_FAB2_LIB.BASEBOARD_FAB2(SCH_1):PAGE215

EU7G2 IR354XX_SM-IR35411,IC,H73688-0A
    33 VR_PVDDQ_ABC_PH1_BOOT_R @BASEBOARD_FAB2_LIB.BASEBOARD_FAB2(SCH_1):VR_PVDDQ_ABC_PH1_BOOT_R   I102 @BASEBOARD_FAB2_LIB.BASEBOARD_FAB2(SCH_1):PAGE216
    35 P5V_STBY @BASEBOARD_FAB2_LIB.BASEBOARD_FAB2(SCH_1):P5V_STBY   I102 @BASEBOARD_FAB2_LIB.BASEBOARD_FAB2(SCH_1):PAGE216
    41 TP_PVDDQ_ABC_PH1_GL_1 @BASEBOARD_FAB2_LIB.BASEBOARD_FAB2(SCH_1):TP_PVDDQ_ABC_PH1_GL_1   I102 @BASEBOARD_FAB2_LIB.BASEBOARD_FAB2(SCH_1):PAGE216
     6 TP_PVDDQ_ABC_PH1_GL_0 @BASEBOARD_FAB2_LIB.BASEBOARD_FAB2(SCH_1):TP_PVDDQ_ABC_PH1_GL_0   I102 @BASEBOARD_FAB2_LIB.BASEBOARD_FAB2(SCH_1):PAGE216
    38 ISENSE_PVDDQ_ABC_PH1_IMON @BASEBOARD_FAB2_LIB.BASEBOARD_FAB2(SCH_1):ISENSE_PVDDQ_ABC_PH1_IMON   I102 @BASEBOARD_FAB2_LIB.BASEBOARD_FAB2(SCH_1):PAGE216
     2    GND @BASEBOARD_FAB2_LIB.BASEBOARD_FAB2(SCH_1):GND   I102 @BASEBOARD_FAB2_LIB.BASEBOARD_FAB2(SCH_1):PAGE216
    31 NC_PVDDQ_ABC_PH1_P31 @BASEBOARD_FAB2_LIB.BASEBOARD_FAB2(SCH_1):NC_PVDDQ_ABC_PH1_P31   I102 @BASEBOARD_FAB2_LIB.BASEBOARD_FAB2(SCH_1):PAGE216
    37 VR_PVDDQ_ABC_PH1_OCSET @BASEBOARD_FAB2_LIB.BASEBOARD_FAB2(SCH_1):VR_PVDDQ_ABC_PH1_OCSET   I102 @BASEBOARD_FAB2_LIB.BASEBOARD_FAB2(SCH_1):PAGE216
    40    GND @BASEBOARD_FAB2_LIB.BASEBOARD_FAB2(SCH_1):GND   I102 @BASEBOARD_FAB2_LIB.BASEBOARD_FAB2(SCH_1):PAGE216
     7    GND @BASEBOARD_FAB2_LIB.BASEBOARD_FAB2(SCH_1):GND   I102 @BASEBOARD_FAB2_LIB.BASEBOARD_FAB2(SCH_1):PAGE216
     5    GND @BASEBOARD_FAB2_LIB.BASEBOARD_FAB2(SCH_1):GND   I102 @BASEBOARD_FAB2_LIB.BASEBOARD_FAB2(SCH_1):PAGE216
    32 VR_PVDDQ_ABC_PH1_PHASE @BASEBOARD_FAB2_LIB.BASEBOARD_FAB2(SCH_1):VR_PVDDQ_ABC_PH1_PHASE   I102 @BASEBOARD_FAB2_LIB.BASEBOARD_FAB2(SCH_1):PAGE216
    34 VR_PVDDQ_ABC_PWM1 @BASEBOARD_FAB2_LIB.BASEBOARD_FAB2(SCH_1):VR_PVDDQ_ABC_PWM1   I102 @BASEBOARD_FAB2_LIB.BASEBOARD_FAB2(SCH_1):PAGE216
    39 VR_PVDDQ_ABC_AIREF1 @BASEBOARD_FAB2_LIB.BASEBOARD_FAB2(SCH_1):VR_PVDDQ_ABC_AIREF1   I102 @BASEBOARD_FAB2_LIB.BASEBOARD_FAB2(SCH_1):PAGE216
    10 VR_PVDDQ_ABC_PH1_SW @BASEBOARD_FAB2_LIB.BASEBOARD_FAB2(SCH_1):VR_PVDDQ_ABC_PH1_SW   I102 @BASEBOARD_FAB2_LIB.BASEBOARD_FAB2(SCH_1):PAGE216
    36 A_TSENSE_PVDDQ_ABC @BASEBOARD_FAB2_LIB.BASEBOARD_FAB2(SCH_1):A_TSENSE_PVDDQ_ABC   I102 @BASEBOARD_FAB2_LIB.BASEBOARD_FAB2(SCH_1):PAGE216
     3 VR_PVDDQ_ABC_PH1_VCIN @BASEBOARD_FAB2_LIB.BASEBOARD_FAB2(SCH_1):VR_PVDDQ_ABC_PH1_VCIN   I102 @BASEBOARD_FAB2_LIB.BASEBOARD_FAB2(SCH_1):PAGE216
     4 P5V_STBY @BASEBOARD_FAB2_LIB.BASEBOARD_FAB2(SCH_1):P5V_STBY   I102 @BASEBOARD_FAB2_LIB.BASEBOARD_FAB2(SCH_1):PAGE216
    30 VR_FET_SW_P12V_STBY_PVDDQ_ABC @BASEBOARD_FAB2_LIB.BASEBOARD_FAB2(SCH_1):VR_FET_SW_P12V_STBY_PVDDQ_ABC   I102 @BASEBOARD_FAB2_LIB.BASEBOARD_FAB2(SCH_1):PAGE216
    25 VR_FET_SW_P12V_STBY_PVDDQ_ABC @BASEBOARD_FAB2_LIB.BASEBOARD_FAB2(SCH_1):VR_FET_SW_P12V_STBY_PVDDQ_ABC   I102 @BASEBOARD_FAB2_LIB.BASEBOARD_FAB2(SCH_1):PAGE216
     1 PVDDQ_ABC @BASEBOARD_FAB2_LIB.BASEBOARD_FAB2(SCH_1):PVDDQ_ABC   I102 @BASEBOARD_FAB2_LIB.BASEBOARD_FAB2(SCH_1):PAGE216

EU7G3 IR354XX_SM-IR35411,IC,H73688-0A
    33 VR_PVDDQ_ABC_PH2_BOOT_R @BASEBOARD_FAB2_LIB.BASEBOARD_FAB2(SCH_1):VR_PVDDQ_ABC_PH2_BOOT_R   I103 @BASEBOARD_FAB2_LIB.BASEBOARD_FAB2(SCH_1):PAGE216
    35 P5V_STBY @BASEBOARD_FAB2_LIB.BASEBOARD_FAB2(SCH_1):P5V_STBY   I103 @BASEBOARD_FAB2_LIB.BASEBOARD_FAB2(SCH_1):PAGE216
    41 TP_PVDDQ_ABC_PH2_GL_1 @BASEBOARD_FAB2_LIB.BASEBOARD_FAB2(SCH_1):TP_PVDDQ_ABC_PH2_GL_1   I103 @BASEBOARD_FAB2_LIB.BASEBOARD_FAB2(SCH_1):PAGE216
     6 TP_PVDDQ_ABC_PH2_GL_0 @BASEBOARD_FAB2_LIB.BASEBOARD_FAB2(SCH_1):TP_PVDDQ_ABC_PH2_GL_0   I103 @BASEBOARD_FAB2_LIB.BASEBOARD_FAB2(SCH_1):PAGE216
    38 ISENSE_PVDDQ_ABC_PH2_IMON @BASEBOARD_FAB2_LIB.BASEBOARD_FAB2(SCH_1):ISENSE_PVDDQ_ABC_PH2_IMON   I103 @BASEBOARD_FAB2_LIB.BASEBOARD_FAB2(SCH_1):PAGE216
     2    GND @BASEBOARD_FAB2_LIB.BASEBOARD_FAB2(SCH_1):GND   I103 @BASEBOARD_FAB2_LIB.BASEBOARD_FAB2(SCH_1):PAGE216
    31 NC_PVDDQ_ABC_PH2_P31 @BASEBOARD_FAB2_LIB.BASEBOARD_FAB2(SCH_1):NC_PVDDQ_ABC_PH2_P31   I103 @BASEBOARD_FAB2_LIB.BASEBOARD_FAB2(SCH_1):PAGE216
    37 VR_PVDDQ_ABC_PH2_OCSET @BASEBOARD_FAB2_LIB.BASEBOARD_FAB2(SCH_1):VR_PVDDQ_ABC_PH2_OCSET   I103 @BASEBOARD_FAB2_LIB.BASEBOARD_FAB2(SCH_1):PAGE216
    40    GND @BASEBOARD_FAB2_LIB.BASEBOARD_FAB2(SCH_1):GND   I103 @BASEBOARD_FAB2_LIB.BASEBOARD_FAB2(SCH_1):PAGE216
     7    GND @BASEBOARD_FAB2_LIB.BASEBOARD_FAB2(SCH_1):GND   I103 @BASEBOARD_FAB2_LIB.BASEBOARD_FAB2(SCH_1):PAGE216
     5    GND @BASEBOARD_FAB2_LIB.BASEBOARD_FAB2(SCH_1):GND   I103 @BASEBOARD_FAB2_LIB.BASEBOARD_FAB2(SCH_1):PAGE216
    32 VR_PVDDQ_ABC_PH2_PHASE @BASEBOARD_FAB2_LIB.BASEBOARD_FAB2(SCH_1):VR_PVDDQ_ABC_PH2_PHASE   I103 @BASEBOARD_FAB2_LIB.BASEBOARD_FAB2(SCH_1):PAGE216
    34 VR_PVDDQ_ABC_PWM2 @BASEBOARD_FAB2_LIB.BASEBOARD_FAB2(SCH_1):VR_PVDDQ_ABC_PWM2   I103 @BASEBOARD_FAB2_LIB.BASEBOARD_FAB2(SCH_1):PAGE216
    39 VR_PVDDQ_ABC_AIREF2 @BASEBOARD_FAB2_LIB.BASEBOARD_FAB2(SCH_1):VR_PVDDQ_ABC_AIREF2   I103 @BASEBOARD_FAB2_LIB.BASEBOARD_FAB2(SCH_1):PAGE216
    10 VR_PVDDQ_ABC_PH2_SW @BASEBOARD_FAB2_LIB.BASEBOARD_FAB2(SCH_1):VR_PVDDQ_ABC_PH2_SW   I103 @BASEBOARD_FAB2_LIB.BASEBOARD_FAB2(SCH_1):PAGE216
    36 A_TSENSE_PVDDQ_ABC @BASEBOARD_FAB2_LIB.BASEBOARD_FAB2(SCH_1):A_TSENSE_PVDDQ_ABC   I103 @BASEBOARD_FAB2_LIB.BASEBOARD_FAB2(SCH_1):PAGE216
     3 VR_PVDDQ_ABC_PH2_VCIN @BASEBOARD_FAB2_LIB.BASEBOARD_FAB2(SCH_1):VR_PVDDQ_ABC_PH2_VCIN   I103 @BASEBOARD_FAB2_LIB.BASEBOARD_FAB2(SCH_1):PAGE216
     4 P5V_STBY @BASEBOARD_FAB2_LIB.BASEBOARD_FAB2(SCH_1):P5V_STBY   I103 @BASEBOARD_FAB2_LIB.BASEBOARD_FAB2(SCH_1):PAGE216
    30 VR_FET_SW_P12V_STBY_PVDDQ_ABC @BASEBOARD_FAB2_LIB.BASEBOARD_FAB2(SCH_1):VR_FET_SW_P12V_STBY_PVDDQ_ABC   I103 @BASEBOARD_FAB2_LIB.BASEBOARD_FAB2(SCH_1):PAGE216
    25 VR_FET_SW_P12V_STBY_PVDDQ_ABC @BASEBOARD_FAB2_LIB.BASEBOARD_FAB2(SCH_1):VR_FET_SW_P12V_STBY_PVDDQ_ABC   I103 @BASEBOARD_FAB2_LIB.BASEBOARD_FAB2(SCH_1):PAGE216
     1 PVDDQ_ABC @BASEBOARD_FAB2_LIB.BASEBOARD_FAB2(SCH_1):PVDDQ_ABC   I103 @BASEBOARD_FAB2_LIB.BASEBOARD_FAB2(SCH_1):PAGE216

EU8A1 PXE1110B_QFN-IC,H89187-001
     1 NC_PVNN_PCH_DNC0 @BASEBOARD_FAB2_LIB.BASEBOARD_FAB2(SCH_1):NC_PVNN_PCH_DNC0   I229 @BASEBOARD_FAB2_LIB.BASEBOARD_FAB2(SCH_1):PAGE235
     2 NC_PVNN_PCH_DNC1 @BASEBOARD_FAB2_LIB.BASEBOARD_FAB2(SCH_1):NC_PVNN_PCH_DNC1   I229 @BASEBOARD_FAB2_LIB.BASEBOARD_FAB2(SCH_1):PAGE235
     3 VR_P1V05_PCH_STBY_PWM1 @BASEBOARD_FAB2_LIB.BASEBOARD_FAB2(SCH_1):VR_P1V05_PCH_STBY_PWM1   I229 @BASEBOARD_FAB2_LIB.BASEBOARD_FAB2(SCH_1):PAGE235
     4 NC_PVNN_PCH_DNC2 @BASEBOARD_FAB2_LIB.BASEBOARD_FAB2(SCH_1):NC_PVNN_PCH_DNC2   I229 @BASEBOARD_FAB2_LIB.BASEBOARD_FAB2(SCH_1):PAGE235
     5 VR_PVNN_PCH_PWM1 @BASEBOARD_FAB2_LIB.BASEBOARD_FAB2(SCH_1):VR_PVNN_PCH_PWM1   I229 @BASEBOARD_FAB2_LIB.BASEBOARD_FAB2(SCH_1):PAGE235
     6 SMB_VR_SDA_PVNN_PCH @BASEBOARD_FAB2_LIB.BASEBOARD_FAB2(SCH_1):SMB_VR_SDA_PVNN_PCH   I229 @BASEBOARD_FAB2_LIB.BASEBOARD_FAB2(SCH_1):PAGE235
     7 SMB_VR_SCL_PVNN_PCH @BASEBOARD_FAB2_LIB.BASEBOARD_FAB2(SCH_1):SMB_VR_SCL_PVNN_PCH   I229 @BASEBOARD_FAB2_LIB.BASEBOARD_FAB2(SCH_1):PAGE235
     8 TP_PVNN_PCH_RESET_N @BASEBOARD_FAB2_LIB.BASEBOARD_FAB2(SCH_1):TP_PVNN_PCH_RESET_N   I229 @BASEBOARD_FAB2_LIB.BASEBOARD_FAB2(SCH_1):PAGE235
     9 PWRGD_PVNN_PCH_R @BASEBOARD_FAB2_LIB.BASEBOARD_FAB2(SCH_1):PWRGD_PVNN_PCH_R   I229 @BASEBOARD_FAB2_LIB.BASEBOARD_FAB2(SCH_1):PAGE235
    10 VR_PVNN_PCH_VREN @BASEBOARD_FAB2_LIB.BASEBOARD_FAB2(SCH_1):VR_PVNN_PCH_VREN   I229 @BASEBOARD_FAB2_LIB.BASEBOARD_FAB2(SCH_1):PAGE235
    11 IRQ_PVNN_PCH_VRHOT_N @BASEBOARD_FAB2_LIB.BASEBOARD_FAB2(SCH_1):IRQ_PVNN_PCH_VRHOT_N   I229 @BASEBOARD_FAB2_LIB.BASEBOARD_FAB2(SCH_1):PAGE235
    12 TP_PVNN_PCH_PINALRT_N @BASEBOARD_FAB2_LIB.BASEBOARD_FAB2(SCH_1):TP_PVNN_PCH_PINALRT_N   I229 @BASEBOARD_FAB2_LIB.BASEBOARD_FAB2(SCH_1):PAGE235
    13 VID_PCH_CORE_PVNN_AUX_VID_0 @BASEBOARD_FAB2_LIB.BASEBOARD_FAB2(SCH_1):VID_PCH_CORE_PVNN_AUX_VID_0   I229 @BASEBOARD_FAB2_LIB.BASEBOARD_FAB2(SCH_1):PAGE235
    14 VID_PCH_CORE_PVNN_AUX_VID_1 @BASEBOARD_FAB2_LIB.BASEBOARD_FAB2(SCH_1):VID_PCH_CORE_PVNN_AUX_VID_1   I229 @BASEBOARD_FAB2_LIB.BASEBOARD_FAB2(SCH_1):PAGE235
    15 TP_PVNN_PCH_VCLK @BASEBOARD_FAB2_LIB.BASEBOARD_FAB2(SCH_1):TP_PVNN_PCH_VCLK   I229 @BASEBOARD_FAB2_LIB.BASEBOARD_FAB2(SCH_1):PAGE235
    16 TP_PVNN_PCH_VDIO @BASEBOARD_FAB2_LIB.BASEBOARD_FAB2(SCH_1):TP_PVNN_PCH_VDIO   I229 @BASEBOARD_FAB2_LIB.BASEBOARD_FAB2(SCH_1):PAGE235
    17 TP_PVNN_PCH_SVID_ALERT @BASEBOARD_FAB2_LIB.BASEBOARD_FAB2(SCH_1):TP_PVNN_PCH_SVID_ALERT   I229 @BASEBOARD_FAB2_LIB.BASEBOARD_FAB2(SCH_1):PAGE235
    18 TP_PVNN_PCH_MP2 @BASEBOARD_FAB2_LIB.BASEBOARD_FAB2(SCH_1):TP_PVNN_PCH_MP2   I229 @BASEBOARD_FAB2_LIB.BASEBOARD_FAB2(SCH_1):PAGE235
    19 VR_PVNN_PCH_AVSP @BASEBOARD_FAB2_LIB.BASEBOARD_FAB2(SCH_1):VR_PVNN_PCH_AVSP   I229 @BASEBOARD_FAB2_LIB.BASEBOARD_FAB2(SCH_1):PAGE235
    20 VSENSE_PVNN_PCH_STBY_AVSN @BASEBOARD_FAB2_LIB.BASEBOARD_FAB2(SCH_1):VSENSE_PVNN_PCH_STBY_AVSN   I229 @BASEBOARD_FAB2_LIB.BASEBOARD_FAB2(SCH_1):PAGE235
    21 VR_PVNN_PCH_AIREF1 @BASEBOARD_FAB2_LIB.BASEBOARD_FAB2(SCH_1):VR_PVNN_PCH_AIREF1   I229 @BASEBOARD_FAB2_LIB.BASEBOARD_FAB2(SCH_1):PAGE235
    22 ISENSE_PVNN_PCH_PH1_IMON @BASEBOARD_FAB2_LIB.BASEBOARD_FAB2(SCH_1):ISENSE_PVNN_PCH_PH1_IMON   I229 @BASEBOARD_FAB2_LIB.BASEBOARD_FAB2(SCH_1):PAGE235
    23    GND @BASEBOARD_FAB2_LIB.BASEBOARD_FAB2(SCH_1):GND   I229 @BASEBOARD_FAB2_LIB.BASEBOARD_FAB2(SCH_1):PAGE235
    24 NC_PVNN_PCH_DNC3 @BASEBOARD_FAB2_LIB.BASEBOARD_FAB2(SCH_1):NC_PVNN_PCH_DNC3   I229 @BASEBOARD_FAB2_LIB.BASEBOARD_FAB2(SCH_1):PAGE235
    25 VR_P1V05_PCH_BIREF1 @BASEBOARD_FAB2_LIB.BASEBOARD_FAB2(SCH_1):VR_P1V05_PCH_BIREF1   I229 @BASEBOARD_FAB2_LIB.BASEBOARD_FAB2(SCH_1):PAGE235
    26 ISENSE_P1V05_PCH_STBY_PH1_IMON @BASEBOARD_FAB2_LIB.BASEBOARD_FAB2(SCH_1):ISENSE_P1V05_PCH_STBY_PH1_IMON   I229 @BASEBOARD_FAB2_LIB.BASEBOARD_FAB2(SCH_1):PAGE235
    27    GND @BASEBOARD_FAB2_LIB.BASEBOARD_FAB2(SCH_1):GND   I229 @BASEBOARD_FAB2_LIB.BASEBOARD_FAB2(SCH_1):PAGE235
    28 NC_PVNN_PCH_DNC4 @BASEBOARD_FAB2_LIB.BASEBOARD_FAB2(SCH_1):NC_PVNN_PCH_DNC4   I229 @BASEBOARD_FAB2_LIB.BASEBOARD_FAB2(SCH_1):PAGE235
    29 VR_P1V05_PCH_STBY_AVSP @BASEBOARD_FAB2_LIB.BASEBOARD_FAB2(SCH_1):VR_P1V05_PCH_STBY_AVSP   I229 @BASEBOARD_FAB2_LIB.BASEBOARD_FAB2(SCH_1):PAGE235
    30 VSENSE_P1V05_PCH_STBY_AVSN @BASEBOARD_FAB2_LIB.BASEBOARD_FAB2(SCH_1):VSENSE_P1V05_PCH_STBY_AVSN   I229 @BASEBOARD_FAB2_LIB.BASEBOARD_FAB2(SCH_1):PAGE235
    31 TP_PVNN_PCH_MP3 @BASEBOARD_FAB2_LIB.BASEBOARD_FAB2(SCH_1):TP_PVNN_PCH_MP3   I229 @BASEBOARD_FAB2_LIB.BASEBOARD_FAB2(SCH_1):PAGE235
    32 PU_VR_PVNN_PCH_FAULT1 @BASEBOARD_FAB2_LIB.BASEBOARD_FAB2(SCH_1):PU_VR_PVNN_PCH_FAULT1   I229 @BASEBOARD_FAB2_LIB.BASEBOARD_FAB2(SCH_1):PAGE235
    33 VR_PVNN_PCH_XADDR2 @BASEBOARD_FAB2_LIB.BASEBOARD_FAB2(SCH_1):VR_PVNN_PCH_XADDR2   I229 @BASEBOARD_FAB2_LIB.BASEBOARD_FAB2(SCH_1):PAGE235
    34 A_TSENSE_P1V05_PCH_STBY_TMON @BASEBOARD_FAB2_LIB.BASEBOARD_FAB2(SCH_1):A_TSENSE_P1V05_PCH_STBY_TMON   I229 @BASEBOARD_FAB2_LIB.BASEBOARD_FAB2(SCH_1):PAGE235
    35 A_TSENSE_PVNN_PCH_TMON @BASEBOARD_FAB2_LIB.BASEBOARD_FAB2(SCH_1):A_TSENSE_PVNN_PCH_TMON   I229 @BASEBOARD_FAB2_LIB.BASEBOARD_FAB2(SCH_1):PAGE235
    36 VR_PVNN_PCH_XADDR1 @BASEBOARD_FAB2_LIB.BASEBOARD_FAB2(SCH_1):VR_PVNN_PCH_XADDR1   I229 @BASEBOARD_FAB2_LIB.BASEBOARD_FAB2(SCH_1):PAGE235
    37 VR_PVNN_PCH_VINSEN @BASEBOARD_FAB2_LIB.BASEBOARD_FAB2(SCH_1):VR_PVNN_PCH_VINSEN   I229 @BASEBOARD_FAB2_LIB.BASEBOARD_FAB2(SCH_1):PAGE235
    38 TP_VR_PVNN_PCH_AIINSEN @BASEBOARD_FAB2_LIB.BASEBOARD_FAB2(SCH_1):TP_VR_PVNN_PCH_AIINSEN   I229 @BASEBOARD_FAB2_LIB.BASEBOARD_FAB2(SCH_1):PAGE235
    39 VR_PVNN_PCH_VDD @BASEBOARD_FAB2_LIB.BASEBOARD_FAB2(SCH_1):VR_PVNN_PCH_VDD   I229 @BASEBOARD_FAB2_LIB.BASEBOARD_FAB2(SCH_1):PAGE235
    40 VR_PVNN_P1V05_PCH_VD12 @BASEBOARD_FAB2_LIB.BASEBOARD_FAB2(SCH_1):VR_PVNN_P1V05_PCH_VD12   I229 @BASEBOARD_FAB2_LIB.BASEBOARD_FAB2(SCH_1):PAGE235
    41    GND @BASEBOARD_FAB2_LIB.BASEBOARD_FAB2(SCH_1):GND   I229 @BASEBOARD_FAB2_LIB.BASEBOARD_FAB2(SCH_1):PAGE235

EU8A2 RT9059_DFN-IC,H65765-001
     4 VR_P1V8_PCH_STBY_FB @BASEBOARD_FAB2_LIB.BASEBOARD_FAB2(SCH_1):VR_P1V8_PCH_STBY_FB    I86 @BASEBOARD_FAB2_LIB.BASEBOARD_FAB2(SCH_1):PAGE237
     6 PWRGD_P3V3_STBY @BASEBOARD_FAB2_LIB.BASEBOARD_FAB2(SCH_1):PWRGD_P3V3_STBY    I86 @BASEBOARD_FAB2_LIB.BASEBOARD_FAB2(SCH_1):PAGE237
    11    GND @BASEBOARD_FAB2_LIB.BASEBOARD_FAB2(SCH_1):GND    I86 @BASEBOARD_FAB2_LIB.BASEBOARD_FAB2(SCH_1):PAGE237
     5 PWRGD_P1V8_PCH_STBY_R @BASEBOARD_FAB2_LIB.BASEBOARD_FAB2(SCH_1):PWRGD_P1V8_PCH_STBY_R    I86 @BASEBOARD_FAB2_LIB.BASEBOARD_FAB2(SCH_1):PAGE237
    10 P3V3_STBY @BASEBOARD_FAB2_LIB.BASEBOARD_FAB2(SCH_1):P3V3_STBY    I86 @BASEBOARD_FAB2_LIB.BASEBOARD_FAB2(SCH_1):PAGE237
     9 P3V3_STBY @BASEBOARD_FAB2_LIB.BASEBOARD_FAB2(SCH_1):P3V3_STBY    I86 @BASEBOARD_FAB2_LIB.BASEBOARD_FAB2(SCH_1):PAGE237
     8 P3V3_STBY @BASEBOARD_FAB2_LIB.BASEBOARD_FAB2(SCH_1):P3V3_STBY    I86 @BASEBOARD_FAB2_LIB.BASEBOARD_FAB2(SCH_1):PAGE237
     7 P3V3_STBY @BASEBOARD_FAB2_LIB.BASEBOARD_FAB2(SCH_1):P3V3_STBY    I86 @BASEBOARD_FAB2_LIB.BASEBOARD_FAB2(SCH_1):PAGE237
     3 P1V8_PCH_STBY @BASEBOARD_FAB2_LIB.BASEBOARD_FAB2(SCH_1):P1V8_PCH_STBY    I86 @BASEBOARD_FAB2_LIB.BASEBOARD_FAB2(SCH_1):PAGE237
     2 P1V8_PCH_STBY @BASEBOARD_FAB2_LIB.BASEBOARD_FAB2(SCH_1):P1V8_PCH_STBY    I86 @BASEBOARD_FAB2_LIB.BASEBOARD_FAB2(SCH_1):PAGE237
     1 P1V8_PCH_STBY @BASEBOARD_FAB2_LIB.BASEBOARD_FAB2(SCH_1):P1V8_PCH_STBY    I86 @BASEBOARD_FAB2_LIB.BASEBOARD_FAB2(SCH_1):PAGE237

EU8B1 SLG55021_SM-IC,G56246-001
     4    GND @BASEBOARD_FAB2_LIB.BASEBOARD_FAB2(SCH_1):GND    I13 @BASEBOARD_FAB2_LIB.BASEBOARD_FAB2(SCH_1):PAGE198
     9    GND @BASEBOARD_FAB2_LIB.BASEBOARD_FAB2(SCH_1):GND    I13 @BASEBOARD_FAB2_LIB.BASEBOARD_FAB2(SCH_1):PAGE198
     1 P5V_STBY @BASEBOARD_FAB2_LIB.BASEBOARD_FAB2(SCH_1):P5V_STBY    I13 @BASEBOARD_FAB2_LIB.BASEBOARD_FAB2(SCH_1):PAGE198
     2 FM_CTNR_PS_ON @BASEBOARD_FAB2_LIB.BASEBOARD_FAB2(SCH_1):FM_CTNR_PS_ON    I13 @BASEBOARD_FAB2_LIB.BASEBOARD_FAB2(SCH_1):PAGE198
     3 P5V_STBY @BASEBOARD_FAB2_LIB.BASEBOARD_FAB2(SCH_1):P5V_STBY    I13 @BASEBOARD_FAB2_LIB.BASEBOARD_FAB2(SCH_1):PAGE198
     5 P5V_STBY @BASEBOARD_FAB2_LIB.BASEBOARD_FAB2(SCH_1):P5V_STBY    I13 @BASEBOARD_FAB2_LIB.BASEBOARD_FAB2(SCH_1):PAGE198
     6    P5V @BASEBOARD_FAB2_LIB.BASEBOARD_FAB2(SCH_1):P5V    I13 @BASEBOARD_FAB2_LIB.BASEBOARD_FAB2(SCH_1):PAGE198
     7 P5V_SWITCH_G @BASEBOARD_FAB2_LIB.BASEBOARD_FAB2(SCH_1):P5V_SWITCH_G    I13 @BASEBOARD_FAB2_LIB.BASEBOARD_FAB2(SCH_1):PAGE198
     8 TP_SLG55021_P5V_8 @BASEBOARD_FAB2_LIB.BASEBOARD_FAB2(SCH_1):TP_SLG55021_P5V_8    I13 @BASEBOARD_FAB2_LIB.BASEBOARD_FAB2(SCH_1):PAGE198

EU8E1 CSD87384M_SM-IC,H66258-001
     4 VR_P3V3_STBY_LGATE @BASEBOARD_FAB2_LIB.BASEBOARD_FAB2(SCH_1):VR_P3V3_STBY_LGATE   I170 @BASEBOARD_FAB2_LIB.BASEBOARD_FAB2(SCH_1):PAGE240
     3    GND @BASEBOARD_FAB2_LIB.BASEBOARD_FAB2(SCH_1):GND   I170 @BASEBOARD_FAB2_LIB.BASEBOARD_FAB2(SCH_1):PAGE240
     1 VR_P3V3_STBY_UGATE @BASEBOARD_FAB2_LIB.BASEBOARD_FAB2(SCH_1):VR_P3V3_STBY_UGATE   I170 @BASEBOARD_FAB2_LIB.BASEBOARD_FAB2(SCH_1):PAGE240
     2 VR_FET_SW_P12V_STBY_P3V3_STBY @BASEBOARD_FAB2_LIB.BASEBOARD_FAB2(SCH_1):VR_FET_SW_P12V_STBY_P3V3_STBY   I170 @BASEBOARD_FAB2_LIB.BASEBOARD_FAB2(SCH_1):PAGE240
     5 VR_P3V3_STBY_PHASE @BASEBOARD_FAB2_LIB.BASEBOARD_FAB2(SCH_1):VR_P3V3_STBY_PHASE   I170 @BASEBOARD_FAB2_LIB.BASEBOARD_FAB2(SCH_1):PAGE240

EU8F1 RT8240_QFN-IC,H66262-001
     4 VR_P3V3_STBY_BOOT @BASEBOARD_FAB2_LIB.BASEBOARD_FAB2(SCH_1):VR_P3V3_STBY_BOOT   I125 @BASEBOARD_FAB2_LIB.BASEBOARD_FAB2(SCH_1):PAGE240
    10 VR_P3V3_STBY_OCSELECT @BASEBOARD_FAB2_LIB.BASEBOARD_FAB2(SCH_1):VR_P3V3_STBY_OCSELECT   I125 @BASEBOARD_FAB2_LIB.BASEBOARD_FAB2(SCH_1):PAGE240
     8 VR_P3V3_STBY_EN @BASEBOARD_FAB2_LIB.BASEBOARD_FAB2(SCH_1):VR_P3V3_STBY_EN   I125 @BASEBOARD_FAB2_LIB.BASEBOARD_FAB2(SCH_1):PAGE240
    11 AGND_P3V3_STBY @BASEBOARD_FAB2_LIB.BASEBOARD_FAB2(SCH_1):AGND_P3V3_STBY   I125 @BASEBOARD_FAB2_LIB.BASEBOARD_FAB2(SCH_1):PAGE240
    13 AGND_P3V3_STBY @BASEBOARD_FAB2_LIB.BASEBOARD_FAB2(SCH_1):AGND_P3V3_STBY   I125 @BASEBOARD_FAB2_LIB.BASEBOARD_FAB2(SCH_1):PAGE240
    12 AGND_P3V3_STBY @BASEBOARD_FAB2_LIB.BASEBOARD_FAB2(SCH_1):AGND_P3V3_STBY   I125 @BASEBOARD_FAB2_LIB.BASEBOARD_FAB2(SCH_1):PAGE240
     1 VR_P3V3_STBY_LGATE @BASEBOARD_FAB2_LIB.BASEBOARD_FAB2(SCH_1):VR_P3V3_STBY_LGATE   I125 @BASEBOARD_FAB2_LIB.BASEBOARD_FAB2(SCH_1):PAGE240
     9 PWRGD_P3V3_STBY_R @BASEBOARD_FAB2_LIB.BASEBOARD_FAB2(SCH_1):PWRGD_P3V3_STBY_R   I125 @BASEBOARD_FAB2_LIB.BASEBOARD_FAB2(SCH_1):PAGE240
     2 VR_P3V3_STBY_PHASE @BASEBOARD_FAB2_LIB.BASEBOARD_FAB2(SCH_1):VR_P3V3_STBY_PHASE   I125 @BASEBOARD_FAB2_LIB.BASEBOARD_FAB2(SCH_1):PAGE240
     7 VSENSE_RGND_P3V3_STBY @BASEBOARD_FAB2_LIB.BASEBOARD_FAB2(SCH_1):VSENSE_RGND_P3V3_STBY   I125 @BASEBOARD_FAB2_LIB.BASEBOARD_FAB2(SCH_1):PAGE240
     3 VR_P3V3_STBY_UGATE @BASEBOARD_FAB2_LIB.BASEBOARD_FAB2(SCH_1):VR_P3V3_STBY_UGATE   I125 @BASEBOARD_FAB2_LIB.BASEBOARD_FAB2(SCH_1):PAGE240
     5 P5V_STBY @BASEBOARD_FAB2_LIB.BASEBOARD_FAB2(SCH_1):P5V_STBY   I125 @BASEBOARD_FAB2_LIB.BASEBOARD_FAB2(SCH_1):PAGE240
     6 VSENSE_VOUT_P3V3_STBY @BASEBOARD_FAB2_LIB.BASEBOARD_FAB2(SCH_1):VSENSE_VOUT_P3V3_STBY   I125 @BASEBOARD_FAB2_LIB.BASEBOARD_FAB2(SCH_1):PAGE240

EU8F2 ICS9FGP204_MLFP-IC,E95226-001
    12 P3V3_STBY_MNG @BASEBOARD_FAB2_LIB.BASEBOARD_FAB2(SCH_1):P3V3_STBY_MNG    I34 @BASEBOARD_FAB2_LIB.BASEBOARD_FAB2(SCH_1):PAGE101
    13 CLK_32K_SUSCLK_PLD_R @BASEBOARD_FAB2_LIB.BASEBOARD_FAB2(SCH_1):CLK_32K_SUSCLK_PLD_R    I34 @BASEBOARD_FAB2_LIB.BASEBOARD_FAB2(SCH_1):PAGE101
    14    GND @BASEBOARD_FAB2_LIB.BASEBOARD_FAB2(SCH_1):GND    I34 @BASEBOARD_FAB2_LIB.BASEBOARD_FAB2(SCH_1):PAGE101
    16 CLK_25M_BMC_R @BASEBOARD_FAB2_LIB.BASEBOARD_FAB2(SCH_1):CLK_25M_BMC_R    I34 @BASEBOARD_FAB2_LIB.BASEBOARD_FAB2(SCH_1):PAGE101
    17 CLK_25M_CPLD_R @BASEBOARD_FAB2_LIB.BASEBOARD_FAB2(SCH_1):CLK_25M_CPLD_R    I34 @BASEBOARD_FAB2_LIB.BASEBOARD_FAB2(SCH_1):PAGE101
    32 CLK_50M_CKMNG_BMC_1_R @BASEBOARD_FAB2_LIB.BASEBOARD_FAB2(SCH_1):CLK_50M_CKMNG_BMC_1_R    I34 @BASEBOARD_FAB2_LIB.BASEBOARD_FAB2(SCH_1):PAGE101
    29 CLK_50M_CKMNG_BMC_2_R @BASEBOARD_FAB2_LIB.BASEBOARD_FAB2(SCH_1):CLK_50M_CKMNG_BMC_2_R    I34 @BASEBOARD_FAB2_LIB.BASEBOARD_FAB2(SCH_1):PAGE101
    24 TP_CLK5_50M_CKMNG @BASEBOARD_FAB2_LIB.BASEBOARD_FAB2(SCH_1):TP_CLK5_50M_CKMNG    I34 @BASEBOARD_FAB2_LIB.BASEBOARD_FAB2(SCH_1):PAGE101
    25 CLK_50M_CKMNG_PCH_10GBE_R @BASEBOARD_FAB2_LIB.BASEBOARD_FAB2(SCH_1):CLK_50M_CKMNG_PCH_10GBE_R    I34 @BASEBOARD_FAB2_LIB.BASEBOARD_FAB2(SCH_1):PAGE101
    28 CLK_50M_CKMNG_SPRVLLE_R @BASEBOARD_FAB2_LIB.BASEBOARD_FAB2(SCH_1):CLK_50M_CKMNG_SPRVLLE_R    I34 @BASEBOARD_FAB2_LIB.BASEBOARD_FAB2(SCH_1):PAGE101
    33 CLK_50M_CKMNG_OCP_R @BASEBOARD_FAB2_LIB.BASEBOARD_FAB2(SCH_1):CLK_50M_CKMNG_OCP_R    I34 @BASEBOARD_FAB2_LIB.BASEBOARD_FAB2(SCH_1):PAGE101
    41    GND @BASEBOARD_FAB2_LIB.BASEBOARD_FAB2(SCH_1):GND    I34 @BASEBOARD_FAB2_LIB.BASEBOARD_FAB2(SCH_1):PAGE101
    21    GND @BASEBOARD_FAB2_LIB.BASEBOARD_FAB2(SCH_1):GND    I34 @BASEBOARD_FAB2_LIB.BASEBOARD_FAB2(SCH_1):PAGE101
     1    GND @BASEBOARD_FAB2_LIB.BASEBOARD_FAB2(SCH_1):GND    I34 @BASEBOARD_FAB2_LIB.BASEBOARD_FAB2(SCH_1):PAGE101
     4 TP_CLK_96M_CKMNG_N @BASEBOARD_FAB2_LIB.BASEBOARD_FAB2(SCH_1):TP_CLK_96M_CKMNG_N    I34 @BASEBOARD_FAB2_LIB.BASEBOARD_FAB2(SCH_1):PAGE101
     3 TP_CLK_96M_CKMNG_P @BASEBOARD_FAB2_LIB.BASEBOARD_FAB2(SCH_1):TP_CLK_96M_CKMNG_P    I34 @BASEBOARD_FAB2_LIB.BASEBOARD_FAB2(SCH_1):PAGE101
     8 TP_CLK_100M_R_DN @BASEBOARD_FAB2_LIB.BASEBOARD_FAB2(SCH_1):TP_CLK_100M_R_DN    I34 @BASEBOARD_FAB2_LIB.BASEBOARD_FAB2(SCH_1):PAGE101
    18    GND @BASEBOARD_FAB2_LIB.BASEBOARD_FAB2(SCH_1):GND    I34 @BASEBOARD_FAB2_LIB.BASEBOARD_FAB2(SCH_1):PAGE101
     7 TP_CLK_100M_R_DP @BASEBOARD_FAB2_LIB.BASEBOARD_FAB2(SCH_1):TP_CLK_100M_R_DP    I34 @BASEBOARD_FAB2_LIB.BASEBOARD_FAB2(SCH_1):PAGE101
    15 P3V3_STBY_MNG @BASEBOARD_FAB2_LIB.BASEBOARD_FAB2(SCH_1):P3V3_STBY_MNG    I34 @BASEBOARD_FAB2_LIB.BASEBOARD_FAB2(SCH_1):PAGE101
    11 A_COMP_CKMNG @BASEBOARD_FAB2_LIB.BASEBOARD_FAB2(SCH_1):A_COMP_CKMNG    I34 @BASEBOARD_FAB2_LIB.BASEBOARD_FAB2(SCH_1):PAGE101
    19 XTAL_CK_MNG_IN @BASEBOARD_FAB2_LIB.BASEBOARD_FAB2(SCH_1):XTAL_CK_MNG_IN    I34 @BASEBOARD_FAB2_LIB.BASEBOARD_FAB2(SCH_1):PAGE101
    27    GND @BASEBOARD_FAB2_LIB.BASEBOARD_FAB2(SCH_1):GND    I34 @BASEBOARD_FAB2_LIB.BASEBOARD_FAB2(SCH_1):PAGE101
    26 P3V3_STBY_MNG_RMII @BASEBOARD_FAB2_LIB.BASEBOARD_FAB2(SCH_1):P3V3_STBY_MNG_RMII    I34 @BASEBOARD_FAB2_LIB.BASEBOARD_FAB2(SCH_1):PAGE101
    31 P3V3_STBY_MNG_RMII @BASEBOARD_FAB2_LIB.BASEBOARD_FAB2(SCH_1):P3V3_STBY_MNG_RMII    I34 @BASEBOARD_FAB2_LIB.BASEBOARD_FAB2(SCH_1):PAGE101
    30    GND @BASEBOARD_FAB2_LIB.BASEBOARD_FAB2(SCH_1):GND    I34 @BASEBOARD_FAB2_LIB.BASEBOARD_FAB2(SCH_1):PAGE101
    22 TP_33P_33M_SMBADR @BASEBOARD_FAB2_LIB.BASEBOARD_FAB2(SCH_1):TP_33P_33M_SMBADR    I34 @BASEBOARD_FAB2_LIB.BASEBOARD_FAB2(SCH_1):PAGE101
    23 P3V3_STBY_MNG @BASEBOARD_FAB2_LIB.BASEBOARD_FAB2(SCH_1):P3V3_STBY_MNG    I34 @BASEBOARD_FAB2_LIB.BASEBOARD_FAB2(SCH_1):PAGE101
     5 PD_CKMNG_OE @BASEBOARD_FAB2_LIB.BASEBOARD_FAB2(SCH_1):PD_CKMNG_OE    I34 @BASEBOARD_FAB2_LIB.BASEBOARD_FAB2(SCH_1):PAGE101
     2 P3V3_STBY_MNG @BASEBOARD_FAB2_LIB.BASEBOARD_FAB2(SCH_1):P3V3_STBY_MNG    I34 @BASEBOARD_FAB2_LIB.BASEBOARD_FAB2(SCH_1):PAGE101
     6 PD_CKMNG_OE @BASEBOARD_FAB2_LIB.BASEBOARD_FAB2(SCH_1):PD_CKMNG_OE    I34 @BASEBOARD_FAB2_LIB.BASEBOARD_FAB2(SCH_1):PAGE101
    10    GND @BASEBOARD_FAB2_LIB.BASEBOARD_FAB2(SCH_1):GND    I34 @BASEBOARD_FAB2_LIB.BASEBOARD_FAB2(SCH_1):PAGE101
     9 P3V3_STBY_MNG_CPU @BASEBOARD_FAB2_LIB.BASEBOARD_FAB2(SCH_1):P3V3_STBY_MNG_CPU    I34 @BASEBOARD_FAB2_LIB.BASEBOARD_FAB2(SCH_1):PAGE101
    40 PWRGD_P3V3_STBY @BASEBOARD_FAB2_LIB.BASEBOARD_FAB2(SCH_1):PWRGD_P3V3_STBY    I34 @BASEBOARD_FAB2_LIB.BASEBOARD_FAB2(SCH_1):PAGE101
    38 SMB_HOST_STBY_LVC3_SCL @BASEBOARD_FAB2_LIB.BASEBOARD_FAB2(SCH_1):SMB_HOST_STBY_LVC3_SCL    I34 @BASEBOARD_FAB2_LIB.BASEBOARD_FAB2(SCH_1):PAGE101
    20 XTAL_CK_MNG_OUT @BASEBOARD_FAB2_LIB.BASEBOARD_FAB2(SCH_1):XTAL_CK_MNG_OUT    I34 @BASEBOARD_FAB2_LIB.BASEBOARD_FAB2(SCH_1):PAGE101
    39 SMB_HOST_STBY_LVC3_SDA @BASEBOARD_FAB2_LIB.BASEBOARD_FAB2(SCH_1):SMB_HOST_STBY_LVC3_SDA    I34 @BASEBOARD_FAB2_LIB.BASEBOARD_FAB2(SCH_1):PAGE101
    34 P3V3_STBY_MNG_RGMII @BASEBOARD_FAB2_LIB.BASEBOARD_FAB2(SCH_1):P3V3_STBY_MNG_RGMII    I34 @BASEBOARD_FAB2_LIB.BASEBOARD_FAB2(SCH_1):PAGE101
    35    GND @BASEBOARD_FAB2_LIB.BASEBOARD_FAB2(SCH_1):GND    I34 @BASEBOARD_FAB2_LIB.BASEBOARD_FAB2(SCH_1):PAGE101
    37 TP_CLK_125M_BMCA @BASEBOARD_FAB2_LIB.BASEBOARD_FAB2(SCH_1):TP_CLK_125M_BMCA    I34 @BASEBOARD_FAB2_LIB.BASEBOARD_FAB2(SCH_1):PAGE101
    36 TP_CLK_125M @BASEBOARD_FAB2_LIB.BASEBOARD_FAB2(SCH_1):TP_CLK_125M    I34 @BASEBOARD_FAB2_LIB.BASEBOARD_FAB2(SCH_1):PAGE101

EU9E1 SPRINGVILLE_SM1-IC,G47144-004
    37 A_CBOT @BASEBOARD_FAB2_LIB.BASEBOARD_FAB2(SCH_1):A_CBOT    I72 @BASEBOARD_FAB2_LIB.BASEBOARD_FAB2(SCH_1):PAGE139
    40 A_CTOP @BASEBOARD_FAB2_LIB.BASEBOARD_FAB2(SCH_1):A_CTOP    I72 @BASEBOARD_FAB2_LIB.BASEBOARD_FAB2(SCH_1):PAGE139
    28 FM_1GB_LOM_DISABLE_N @BASEBOARD_FAB2_LIB.BASEBOARD_FAB2(SCH_1):FM_1GB_LOM_DISABLE_N    I72 @BASEBOARD_FAB2_LIB.BASEBOARD_FAB2(SCH_1):PAGE139
    65    GND @BASEBOARD_FAB2_LIB.BASEBOARD_FAB2(SCH_1):GND    I72 @BASEBOARD_FAB2_LIB.BASEBOARD_FAB2(SCH_1):PAGE139
    19 PU_JTAG_SPRV_TCK @BASEBOARD_FAB2_LIB.BASEBOARD_FAB2(SCH_1):PU_JTAG_SPRV_TCK    I72 @BASEBOARD_FAB2_LIB.BASEBOARD_FAB2(SCH_1):PAGE139
    29 PU_JTAG_SPRV_TDI @BASEBOARD_FAB2_LIB.BASEBOARD_FAB2(SCH_1):PU_JTAG_SPRV_TDI    I72 @BASEBOARD_FAB2_LIB.BASEBOARD_FAB2(SCH_1):PAGE139
     4 PU_JTAG_SPRV_TDO @BASEBOARD_FAB2_LIB.BASEBOARD_FAB2(SCH_1):PU_JTAG_SPRV_TDO    I72 @BASEBOARD_FAB2_LIB.BASEBOARD_FAB2(SCH_1):PAGE139
    18 PU_JTAG_SPRV_TMS @BASEBOARD_FAB2_LIB.BASEBOARD_FAB2(SCH_1):PU_JTAG_SPRV_TMS    I72 @BASEBOARD_FAB2_LIB.BASEBOARD_FAB2(SCH_1):PAGE139
     1 PU_SPRV_LAN_PWR_GOOD @BASEBOARD_FAB2_LIB.BASEBOARD_FAB2(SCH_1):PU_SPRV_LAN_PWR_GOOD    I72 @BASEBOARD_FAB2_LIB.BASEBOARD_FAB2(SCH_1):PAGE139
    31 LED_LAN_0_N @BASEBOARD_FAB2_LIB.BASEBOARD_FAB2(SCH_1):LED_LAN_0_N    I72 @BASEBOARD_FAB2_LIB.BASEBOARD_FAB2(SCH_1):PAGE139
    30 LED_LAN_1_N @BASEBOARD_FAB2_LIB.BASEBOARD_FAB2(SCH_1):LED_LAN_1_N    I72 @BASEBOARD_FAB2_LIB.BASEBOARD_FAB2(SCH_1):PAGE139
    33 LED_LAN_2_N @BASEBOARD_FAB2_LIB.BASEBOARD_FAB2(SCH_1):LED_LAN_2_N    I72 @BASEBOARD_FAB2_LIB.BASEBOARD_FAB2(SCH_1):PAGE139
    57 NIC_MDI_SPRV_RJ45_0_DN @BASEBOARD_FAB2_LIB.BASEBOARD_FAB2(SCH_1):NIC_MDI_SPRV_RJ45_0_DN    I72 @BASEBOARD_FAB2_LIB.BASEBOARD_FAB2(SCH_1):PAGE139
    54 NIC_MDI_SPRV_RJ45_1_DN @BASEBOARD_FAB2_LIB.BASEBOARD_FAB2(SCH_1):NIC_MDI_SPRV_RJ45_1_DN    I72 @BASEBOARD_FAB2_LIB.BASEBOARD_FAB2(SCH_1):PAGE139
    52 NIC_SET_N_MDI_2_DN @BASEBOARD_FAB2_LIB.BASEBOARD_FAB2(SCH_1):NIC_SET_N_MDI_2_DN    I72 @BASEBOARD_FAB2_LIB.BASEBOARD_FAB2(SCH_1):PAGE139
    49 NIC_SER_N_MDI_3_DN @BASEBOARD_FAB2_LIB.BASEBOARD_FAB2(SCH_1):NIC_SER_N_MDI_3_DN    I72 @BASEBOARD_FAB2_LIB.BASEBOARD_FAB2(SCH_1):PAGE139
    58 NIC_MDI_SPRV_RJ45_0_DP @BASEBOARD_FAB2_LIB.BASEBOARD_FAB2(SCH_1):NIC_MDI_SPRV_RJ45_0_DP    I72 @BASEBOARD_FAB2_LIB.BASEBOARD_FAB2(SCH_1):PAGE139
    55 NIC_MDI_SPRV_RJ45_1_DP @BASEBOARD_FAB2_LIB.BASEBOARD_FAB2(SCH_1):NIC_MDI_SPRV_RJ45_1_DP    I72 @BASEBOARD_FAB2_LIB.BASEBOARD_FAB2(SCH_1):PAGE139
    53 NIC_SET_P_MDI_2_DP @BASEBOARD_FAB2_LIB.BASEBOARD_FAB2(SCH_1):NIC_SET_P_MDI_2_DP    I72 @BASEBOARD_FAB2_LIB.BASEBOARD_FAB2(SCH_1):PAGE139
    50 NIC_SER_P_MDI_3_DP @BASEBOARD_FAB2_LIB.BASEBOARD_FAB2(SCH_1):NIC_SER_P_MDI_3_DP    I72 @BASEBOARD_FAB2_LIB.BASEBOARD_FAB2(SCH_1):PAGE139
    22 NC_SPRNGVLLE_22 @BASEBOARD_FAB2_LIB.BASEBOARD_FAB2(SCH_1):NC_SPRNGVLLE_22    I72 @BASEBOARD_FAB2_LIB.BASEBOARD_FAB2(SCH_1):PAGE139
    43 RMII_PCH_SPRNGVLLE_ARB_OUT @BASEBOARD_FAB2_LIB.BASEBOARD_FAB2(SCH_1):RMII_PCH_SPRNGVLLE_ARB_OUT    I72 @BASEBOARD_FAB2_LIB.BASEBOARD_FAB2(SCH_1):PAGE139
    44 RMII_PCH_SPRNGVLLE_ARB_IN_R @BASEBOARD_FAB2_LIB.BASEBOARD_FAB2(SCH_1):RMII_PCH_SPRNGVLLE_ARB_IN_R    I72 @BASEBOARD_FAB2_LIB.BASEBOARD_FAB2(SCH_1):PAGE139
     2 CLK_50M_CKMNG_SPRVLLE @BASEBOARD_FAB2_LIB.BASEBOARD_FAB2(SCH_1):CLK_50M_CKMNG_SPRVLLE    I72 @BASEBOARD_FAB2_LIB.BASEBOARD_FAB2(SCH_1):PAGE139
     3 RMII_BMC_PCH_SPRNGVLLE_CRSDV_R @BASEBOARD_FAB2_LIB.BASEBOARD_FAB2(SCH_1):RMII_BMC_PCH_SPRNGVLLE_CRSDV_R    I72 @BASEBOARD_FAB2_LIB.BASEBOARD_FAB2(SCH_1):PAGE139
     6 RMII_SPRNGVLLE_BMC_PCH_RXD0_R @BASEBOARD_FAB2_LIB.BASEBOARD_FAB2(SCH_1):RMII_SPRNGVLLE_BMC_PCH_RXD0_R    I72 @BASEBOARD_FAB2_LIB.BASEBOARD_FAB2(SCH_1):PAGE139
     5 RMII_SPRNGVLLE_BMC_PCH_RXD1_R @BASEBOARD_FAB2_LIB.BASEBOARD_FAB2(SCH_1):RMII_SPRNGVLLE_BMC_PCH_RXD1_R    I72 @BASEBOARD_FAB2_LIB.BASEBOARD_FAB2(SCH_1):PAGE139
     9 RMII_BMC_PCH_SPRNGVLLE_TXD0 @BASEBOARD_FAB2_LIB.BASEBOARD_FAB2(SCH_1):RMII_BMC_PCH_SPRNGVLLE_TXD0    I72 @BASEBOARD_FAB2_LIB.BASEBOARD_FAB2(SCH_1):PAGE139
     8 RMII_BMC_PCH_SPRNGVLLE_TXD1 @BASEBOARD_FAB2_LIB.BASEBOARD_FAB2(SCH_1):RMII_BMC_PCH_SPRNGVLLE_TXD1    I72 @BASEBOARD_FAB2_LIB.BASEBOARD_FAB2(SCH_1):PAGE139
     7 RMII_BMC_PCH_SPRNGVLLE_TXEN @BASEBOARD_FAB2_LIB.BASEBOARD_FAB2(SCH_1):RMII_BMC_PCH_SPRNGVLLE_TXEN    I72 @BASEBOARD_FAB2_LIB.BASEBOARD_FAB2(SCH_1):PAGE139
    15 SPI_NIC_CS_R_N @BASEBOARD_FAB2_LIB.BASEBOARD_FAB2(SCH_1):SPI_NIC_CS_R_N    I72 @BASEBOARD_FAB2_LIB.BASEBOARD_FAB2(SCH_1):PAGE139
    12 SPI_NIC_MOSI_R @BASEBOARD_FAB2_LIB.BASEBOARD_FAB2(SCH_1):SPI_NIC_MOSI_R    I72 @BASEBOARD_FAB2_LIB.BASEBOARD_FAB2(SCH_1):PAGE139
    13 SPI_NIC_SCLK_R @BASEBOARD_FAB2_LIB.BASEBOARD_FAB2(SCH_1):SPI_NIC_SCLK_R    I72 @BASEBOARD_FAB2_LIB.BASEBOARD_FAB2(SCH_1):PAGE139
    14 SPI_NIC_MISO @BASEBOARD_FAB2_LIB.BASEBOARD_FAB2(SCH_1):SPI_NIC_MISO    I72 @BASEBOARD_FAB2_LIB.BASEBOARD_FAB2(SCH_1):PAGE139
    25 CLK_100M_SPRV_DN @BASEBOARD_FAB2_LIB.BASEBOARD_FAB2(SCH_1):CLK_100M_SPRV_DN    I72 @BASEBOARD_FAB2_LIB.BASEBOARD_FAB2(SCH_1):PAGE139
    26 CLK_100M_SPRV_DP @BASEBOARD_FAB2_LIB.BASEBOARD_FAB2(SCH_1):CLK_100M_SPRV_DP    I72 @BASEBOARD_FAB2_LIB.BASEBOARD_FAB2(SCH_1):PAGE139
    23 PE_PCH_SPRV_TX_C_DN @BASEBOARD_FAB2_LIB.BASEBOARD_FAB2(SCH_1):PE_PCH_SPRV_TX_C_DN    I72 @BASEBOARD_FAB2_LIB.BASEBOARD_FAB2(SCH_1):PAGE139
    24 PE_PCH_SPRV_TX_C_DP @BASEBOARD_FAB2_LIB.BASEBOARD_FAB2(SCH_1):PE_PCH_SPRV_TX_C_DP    I72 @BASEBOARD_FAB2_LIB.BASEBOARD_FAB2(SCH_1):PAGE139
    17 RST_PLTRST_SPRV_R_N @BASEBOARD_FAB2_LIB.BASEBOARD_FAB2(SCH_1):RST_PLTRST_SPRV_R_N    I72 @BASEBOARD_FAB2_LIB.BASEBOARD_FAB2(SCH_1):PAGE139
    20 PE_PCH_SPRV_RX_DN @BASEBOARD_FAB2_LIB.BASEBOARD_FAB2(SCH_1):PE_PCH_SPRV_RX_DN    I72 @BASEBOARD_FAB2_LIB.BASEBOARD_FAB2(SCH_1):PAGE139
    21 PE_PCH_SPRV_RX_DP @BASEBOARD_FAB2_LIB.BASEBOARD_FAB2(SCH_1):PE_PCH_SPRV_RX_DP    I72 @BASEBOARD_FAB2_LIB.BASEBOARD_FAB2(SCH_1):PAGE139
    16 FM_PE_SPRV_WAKE_N @BASEBOARD_FAB2_LIB.BASEBOARD_FAB2(SCH_1):FM_PE_SPRV_WAKE_N    I72 @BASEBOARD_FAB2_LIB.BASEBOARD_FAB2(SCH_1):PAGE139
    48 PD_SPRV_RSET @BASEBOARD_FAB2_LIB.BASEBOARD_FAB2(SCH_1):PD_SPRV_RSET    I72 @BASEBOARD_FAB2_LIB.BASEBOARD_FAB2(SCH_1):PAGE139
    63 TP_SPRV_SDP0 @BASEBOARD_FAB2_LIB.BASEBOARD_FAB2(SCH_1):TP_SPRV_SDP0    I72 @BASEBOARD_FAB2_LIB.BASEBOARD_FAB2(SCH_1):PAGE139
    61 TP_SPRV_SDP1 @BASEBOARD_FAB2_LIB.BASEBOARD_FAB2(SCH_1):TP_SPRV_SDP1    I72 @BASEBOARD_FAB2_LIB.BASEBOARD_FAB2(SCH_1):PAGE139
    62 TP_SPRV_SDP2 @BASEBOARD_FAB2_LIB.BASEBOARD_FAB2(SCH_1):TP_SPRV_SDP2    I72 @BASEBOARD_FAB2_LIB.BASEBOARD_FAB2(SCH_1):PAGE139
    60 TP_SPRV_SDP3 @BASEBOARD_FAB2_LIB.BASEBOARD_FAB2(SCH_1):TP_SPRV_SDP3    I72 @BASEBOARD_FAB2_LIB.BASEBOARD_FAB2(SCH_1):PAGE139
    35 IRQ_LOM_ALERT_N @BASEBOARD_FAB2_LIB.BASEBOARD_FAB2(SCH_1):IRQ_LOM_ALERT_N    I72 @BASEBOARD_FAB2_LIB.BASEBOARD_FAB2(SCH_1):PAGE139
    34 SMB_SPRINGVILLE_STBY_LVC3_SCL @BASEBOARD_FAB2_LIB.BASEBOARD_FAB2(SCH_1):SMB_SPRINGVILLE_STBY_LVC3_SCL    I72 @BASEBOARD_FAB2_LIB.BASEBOARD_FAB2(SCH_1):PAGE139
    36 SMB_SPRINGVILLE_STBY_LVC3_SDA @BASEBOARD_FAB2_LIB.BASEBOARD_FAB2(SCH_1):SMB_SPRINGVILLE_STBY_LVC3_SDA    I72 @BASEBOARD_FAB2_LIB.BASEBOARD_FAB2(SCH_1):PAGE139
    42 P0V9_LAN @BASEBOARD_FAB2_LIB.BASEBOARD_FAB2(SCH_1):P0V9_LAN    I72 @BASEBOARD_FAB2_LIB.BASEBOARD_FAB2(SCH_1):PAGE139
    11 P0V9_LAN @BASEBOARD_FAB2_LIB.BASEBOARD_FAB2(SCH_1):P0V9_LAN    I72 @BASEBOARD_FAB2_LIB.BASEBOARD_FAB2(SCH_1):PAGE139
    32 P0V9_LAN @BASEBOARD_FAB2_LIB.BASEBOARD_FAB2(SCH_1):P0V9_LAN    I72 @BASEBOARD_FAB2_LIB.BASEBOARD_FAB2(SCH_1):PAGE139
    59 P0V9_LAN @BASEBOARD_FAB2_LIB.BASEBOARD_FAB2(SCH_1):P0V9_LAN    I72 @BASEBOARD_FAB2_LIB.BASEBOARD_FAB2(SCH_1):PAGE139
    38 P0V9_LAN_I210 @BASEBOARD_FAB2_LIB.BASEBOARD_FAB2(SCH_1):P0V9_LAN_I210    I72 @BASEBOARD_FAB2_LIB.BASEBOARD_FAB2(SCH_1):PAGE139
    47 P1V5_LAN @BASEBOARD_FAB2_LIB.BASEBOARD_FAB2(SCH_1):P1V5_LAN    I72 @BASEBOARD_FAB2_LIB.BASEBOARD_FAB2(SCH_1):PAGE139
    56 P1V5_LAN_I210 @BASEBOARD_FAB2_LIB.BASEBOARD_FAB2(SCH_1):P1V5_LAN_I210    I72 @BASEBOARD_FAB2_LIB.BASEBOARD_FAB2(SCH_1):PAGE139
    39 P1V5_LAN @BASEBOARD_FAB2_LIB.BASEBOARD_FAB2(SCH_1):P1V5_LAN    I72 @BASEBOARD_FAB2_LIB.BASEBOARD_FAB2(SCH_1):PAGE139
    10 P3V3_STBY @BASEBOARD_FAB2_LIB.BASEBOARD_FAB2(SCH_1):P3V3_STBY    I72 @BASEBOARD_FAB2_LIB.BASEBOARD_FAB2(SCH_1):PAGE139
    27 P3V3_STBY @BASEBOARD_FAB2_LIB.BASEBOARD_FAB2(SCH_1):P3V3_STBY    I72 @BASEBOARD_FAB2_LIB.BASEBOARD_FAB2(SCH_1):PAGE139
    41 P3V3_STBY @BASEBOARD_FAB2_LIB.BASEBOARD_FAB2(SCH_1):P3V3_STBY    I72 @BASEBOARD_FAB2_LIB.BASEBOARD_FAB2(SCH_1):PAGE139
    51 P3V3_STBY_P1V5_LAN_I210 @BASEBOARD_FAB2_LIB.BASEBOARD_FAB2(SCH_1):P3V3_STBY_P1V5_LAN_I210    I72 @BASEBOARD_FAB2_LIB.BASEBOARD_FAB2(SCH_1):PAGE139
    64 P3V3_STBY @BASEBOARD_FAB2_LIB.BASEBOARD_FAB2(SCH_1):P3V3_STBY    I72 @BASEBOARD_FAB2_LIB.BASEBOARD_FAB2(SCH_1):PAGE139
    46 XTAL_25MHZ_IN_R @BASEBOARD_FAB2_LIB.BASEBOARD_FAB2(SCH_1):XTAL_25MHZ_IN_R    I72 @BASEBOARD_FAB2_LIB.BASEBOARD_FAB2(SCH_1):PAGE139
    45 XTAL_25MHZ_OUT @BASEBOARD_FAB2_LIB.BASEBOARD_FAB2(SCH_1):XTAL_25MHZ_OUT    I72 @BASEBOARD_FAB2_LIB.BASEBOARD_FAB2(SCH_1):PAGE139

EU9F1 RT9059_DFN-IC,H65765-001
     4 VR_P1V26_BMC_STBY_FB @BASEBOARD_FAB2_LIB.BASEBOARD_FAB2(SCH_1):VR_P1V26_BMC_STBY_FB    I40 @BASEBOARD_FAB2_LIB.BASEBOARD_FAB2(SCH_1):PAGE238
     6 PWRGD_P1V538_BMC_STBY @BASEBOARD_FAB2_LIB.BASEBOARD_FAB2(SCH_1):PWRGD_P1V538_BMC_STBY    I40 @BASEBOARD_FAB2_LIB.BASEBOARD_FAB2(SCH_1):PAGE238
    11    GND @BASEBOARD_FAB2_LIB.BASEBOARD_FAB2(SCH_1):GND    I40 @BASEBOARD_FAB2_LIB.BASEBOARD_FAB2(SCH_1):PAGE238
     5 PWRGD_P1V26_BMC_STBY_R @BASEBOARD_FAB2_LIB.BASEBOARD_FAB2(SCH_1):PWRGD_P1V26_BMC_STBY_R    I40 @BASEBOARD_FAB2_LIB.BASEBOARD_FAB2(SCH_1):PAGE238
    10 P3V3_STBY @BASEBOARD_FAB2_LIB.BASEBOARD_FAB2(SCH_1):P3V3_STBY    I40 @BASEBOARD_FAB2_LIB.BASEBOARD_FAB2(SCH_1):PAGE238
     9 P3V3_STBY @BASEBOARD_FAB2_LIB.BASEBOARD_FAB2(SCH_1):P3V3_STBY    I40 @BASEBOARD_FAB2_LIB.BASEBOARD_FAB2(SCH_1):PAGE238
     8 P3V3_STBY @BASEBOARD_FAB2_LIB.BASEBOARD_FAB2(SCH_1):P3V3_STBY    I40 @BASEBOARD_FAB2_LIB.BASEBOARD_FAB2(SCH_1):PAGE238
     7 P3V3_STBY @BASEBOARD_FAB2_LIB.BASEBOARD_FAB2(SCH_1):P3V3_STBY    I40 @BASEBOARD_FAB2_LIB.BASEBOARD_FAB2(SCH_1):PAGE238
     3 P1V15_AUX_BMC @BASEBOARD_FAB2_LIB.BASEBOARD_FAB2(SCH_1):P1V15_AUX_BMC    I40 @BASEBOARD_FAB2_LIB.BASEBOARD_FAB2(SCH_1):PAGE238
     2 P1V15_AUX_BMC @BASEBOARD_FAB2_LIB.BASEBOARD_FAB2(SCH_1):P1V15_AUX_BMC    I40 @BASEBOARD_FAB2_LIB.BASEBOARD_FAB2(SCH_1):PAGE238
     1 P1V15_AUX_BMC @BASEBOARD_FAB2_LIB.BASEBOARD_FAB2(SCH_1):P1V15_AUX_BMC    I40 @BASEBOARD_FAB2_LIB.BASEBOARD_FAB2(SCH_1):PAGE238

EU9F2 RT9059_DFN-IC,H65765-001
     4 VR_P1V538_BMC_STBY_FB @BASEBOARD_FAB2_LIB.BASEBOARD_FAB2(SCH_1):VR_P1V538_BMC_STBY_FB    I70 @BASEBOARD_FAB2_LIB.BASEBOARD_FAB2(SCH_1):PAGE239
     6 PWRGD_P3V3_STBY @BASEBOARD_FAB2_LIB.BASEBOARD_FAB2(SCH_1):PWRGD_P3V3_STBY    I70 @BASEBOARD_FAB2_LIB.BASEBOARD_FAB2(SCH_1):PAGE239
    11    GND @BASEBOARD_FAB2_LIB.BASEBOARD_FAB2(SCH_1):GND    I70 @BASEBOARD_FAB2_LIB.BASEBOARD_FAB2(SCH_1):PAGE239
     5 PWRGD_P1V538_BMC_STBY_R @BASEBOARD_FAB2_LIB.BASEBOARD_FAB2(SCH_1):PWRGD_P1V538_BMC_STBY_R    I70 @BASEBOARD_FAB2_LIB.BASEBOARD_FAB2(SCH_1):PAGE239
    10 P3V3_STBY @BASEBOARD_FAB2_LIB.BASEBOARD_FAB2(SCH_1):P3V3_STBY    I70 @BASEBOARD_FAB2_LIB.BASEBOARD_FAB2(SCH_1):PAGE239
     9 P3V3_STBY @BASEBOARD_FAB2_LIB.BASEBOARD_FAB2(SCH_1):P3V3_STBY    I70 @BASEBOARD_FAB2_LIB.BASEBOARD_FAB2(SCH_1):PAGE239
     8 P3V3_STBY @BASEBOARD_FAB2_LIB.BASEBOARD_FAB2(SCH_1):P3V3_STBY    I70 @BASEBOARD_FAB2_LIB.BASEBOARD_FAB2(SCH_1):PAGE239
     7 P3V3_STBY @BASEBOARD_FAB2_LIB.BASEBOARD_FAB2(SCH_1):P3V3_STBY    I70 @BASEBOARD_FAB2_LIB.BASEBOARD_FAB2(SCH_1):PAGE239
     3 P1V2_AUX_BMC @BASEBOARD_FAB2_LIB.BASEBOARD_FAB2(SCH_1):P1V2_AUX_BMC    I70 @BASEBOARD_FAB2_LIB.BASEBOARD_FAB2(SCH_1):PAGE239
     2 P1V2_AUX_BMC @BASEBOARD_FAB2_LIB.BASEBOARD_FAB2(SCH_1):P1V2_AUX_BMC    I70 @BASEBOARD_FAB2_LIB.BASEBOARD_FAB2(SCH_1):PAGE239
     1 P1V2_AUX_BMC @BASEBOARD_FAB2_LIB.BASEBOARD_FAB2(SCH_1):P1V2_AUX_BMC    I70 @BASEBOARD_FAB2_LIB.BASEBOARD_FAB2(SCH_1):PAGE239

EU9F3 PI7C9X1172_QFN-IC,H66899-001
    30 FM_PI7C9X1172_A0 @BASEBOARD_FAB2_LIB.BASEBOARD_FAB2(SCH_1):FM_PI7C9X1172_A0     I1 @BASEBOARD_FAB2_LIB.BASEBOARD_FAB2(SCH_1):PAGE183
    31 FM_PI7C9X1172_A1 @BASEBOARD_FAB2_LIB.BASEBOARD_FAB2(SCH_1):FM_PI7C9X1172_A1     I1 @BASEBOARD_FAB2_LIB.BASEBOARD_FAB2(SCH_1):PAGE183
    25    GND @BASEBOARD_FAB2_LIB.BASEBOARD_FAB2(SCH_1):GND     I1 @BASEBOARD_FAB2_LIB.BASEBOARD_FAB2(SCH_1):PAGE183
    16    GND @BASEBOARD_FAB2_LIB.BASEBOARD_FAB2(SCH_1):GND     I1 @BASEBOARD_FAB2_LIB.BASEBOARD_FAB2(SCH_1):PAGE183
    19 TP_PI7C9X1172_EN485_N @BASEBOARD_FAB2_LIB.BASEBOARD_FAB2(SCH_1):TP_PI7C9X1172_EN485_N     I1 @BASEBOARD_FAB2_LIB.BASEBOARD_FAB2(SCH_1):PAGE183
    18 TP_PI7C9X1172_ENIR_N @BASEBOARD_FAB2_LIB.BASEBOARD_FAB2(SCH_1):TP_PI7C9X1172_ENIR_N     I1 @BASEBOARD_FAB2_LIB.BASEBOARD_FAB2(SCH_1):PAGE183
    12    GND @BASEBOARD_FAB2_LIB.BASEBOARD_FAB2(SCH_1):GND     I1 @BASEBOARD_FAB2_LIB.BASEBOARD_FAB2(SCH_1):PAGE183
    13 TP_GPIO0_DSRB_N @BASEBOARD_FAB2_LIB.BASEBOARD_FAB2(SCH_1):TP_GPIO0_DSRB_N     I1 @BASEBOARD_FAB2_LIB.BASEBOARD_FAB2(SCH_1):PAGE183
    23 TP_GPIO1_DTRB_N @BASEBOARD_FAB2_LIB.BASEBOARD_FAB2(SCH_1):TP_GPIO1_DTRB_N     I1 @BASEBOARD_FAB2_LIB.BASEBOARD_FAB2(SCH_1):PAGE183
    11 TP_GPIO2_CDB_N @BASEBOARD_FAB2_LIB.BASEBOARD_FAB2(SCH_1):TP_GPIO2_CDB_N     I1 @BASEBOARD_FAB2_LIB.BASEBOARD_FAB2(SCH_1):PAGE183
    14 TP_GPIO3_RIB_N @BASEBOARD_FAB2_LIB.BASEBOARD_FAB2(SCH_1):TP_GPIO3_RIB_N     I1 @BASEBOARD_FAB2_LIB.BASEBOARD_FAB2(SCH_1):PAGE183
    26 TP_GPIO4_DSRA_N @BASEBOARD_FAB2_LIB.BASEBOARD_FAB2(SCH_1):TP_GPIO4_DSRA_N     I1 @BASEBOARD_FAB2_LIB.BASEBOARD_FAB2(SCH_1):PAGE183
    22 TP_GPIO5_DTRA_N @BASEBOARD_FAB2_LIB.BASEBOARD_FAB2(SCH_1):TP_GPIO5_DTRA_N     I1 @BASEBOARD_FAB2_LIB.BASEBOARD_FAB2(SCH_1):PAGE183
    27 TP_GPIO6_CDA_N @BASEBOARD_FAB2_LIB.BASEBOARD_FAB2(SCH_1):TP_GPIO6_CDA_N     I1 @BASEBOARD_FAB2_LIB.BASEBOARD_FAB2(SCH_1):PAGE183
    28 TP_GPIO7_RIA_N @BASEBOARD_FAB2_LIB.BASEBOARD_FAB2(SCH_1):TP_GPIO7_RIA_N     I1 @BASEBOARD_FAB2_LIB.BASEBOARD_FAB2(SCH_1):PAGE183
    32 PU_PI7C9X1172_I2C_SPI_N @BASEBOARD_FAB2_LIB.BASEBOARD_FAB2(SCH_1):PU_PI7C9X1172_I2C_SPI_N     I1 @BASEBOARD_FAB2_LIB.BASEBOARD_FAB2(SCH_1):PAGE183
    20 FM_UART_ALERT_N @BASEBOARD_FAB2_LIB.BASEBOARD_FAB2(SCH_1):FM_UART_ALERT_N     I1 @BASEBOARD_FAB2_LIB.BASEBOARD_FAB2(SCH_1):PAGE183
     8 NC_PI7C9X1172_8 @BASEBOARD_FAB2_LIB.BASEBOARD_FAB2(SCH_1):NC_PI7C9X1172_8     I1 @BASEBOARD_FAB2_LIB.BASEBOARD_FAB2(SCH_1):PAGE183
     1 NC_PI7C9X1172_1 @BASEBOARD_FAB2_LIB.BASEBOARD_FAB2(SCH_1):NC_PI7C9X1172_1     I1 @BASEBOARD_FAB2_LIB.BASEBOARD_FAB2(SCH_1):PAGE183
    24 PWRGD_DSW_PWROK @BASEBOARD_FAB2_LIB.BASEBOARD_FAB2(SCH_1):PWRGD_DSW_PWROK     I1 @BASEBOARD_FAB2_LIB.BASEBOARD_FAB2(SCH_1):PAGE183
    21 TP_PI7C9X1172_RTSA_N @BASEBOARD_FAB2_LIB.BASEBOARD_FAB2(SCH_1):TP_PI7C9X1172_RTSA_N     I1 @BASEBOARD_FAB2_LIB.BASEBOARD_FAB2(SCH_1):PAGE183
    15 TP_PI7C9X1172_RTSB_N @BASEBOARD_FAB2_LIB.BASEBOARD_FAB2(SCH_1):TP_PI7C9X1172_RTSB_N     I1 @BASEBOARD_FAB2_LIB.BASEBOARD_FAB2(SCH_1):PAGE183
     5 SP1_HOST_BRIDGE_UART_RX @BASEBOARD_FAB2_LIB.BASEBOARD_FAB2(SCH_1):SP1_HOST_BRIDGE_UART_RX     I1 @BASEBOARD_FAB2_LIB.BASEBOARD_FAB2(SCH_1):PAGE183
     4 UART_BRIDGE_RXD5 @BASEBOARD_FAB2_LIB.BASEBOARD_FAB2(SCH_1):UART_BRIDGE_RXD5     I1 @BASEBOARD_FAB2_LIB.BASEBOARD_FAB2(SCH_1):PAGE183
    17 SMB_SLOTX24_PCH_STBY_LVC3_SCL @BASEBOARD_FAB2_LIB.BASEBOARD_FAB2(SCH_1):SMB_SLOTX24_PCH_STBY_LVC3_SCL     I1 @BASEBOARD_FAB2_LIB.BASEBOARD_FAB2(SCH_1):PAGE183
     3 SMB_SLOTX24_PCH_STBY_LVC3_SDA @BASEBOARD_FAB2_LIB.BASEBOARD_FAB2(SCH_1):SMB_SLOTX24_PCH_STBY_LVC3_SDA     I1 @BASEBOARD_FAB2_LIB.BASEBOARD_FAB2(SCH_1):PAGE183
     2 TP_PI7C9X1172_SO @BASEBOARD_FAB2_LIB.BASEBOARD_FAB2(SCH_1):TP_PI7C9X1172_SO     I1 @BASEBOARD_FAB2_LIB.BASEBOARD_FAB2(SCH_1):PAGE183
    33    GND @BASEBOARD_FAB2_LIB.BASEBOARD_FAB2(SCH_1):GND     I1 @BASEBOARD_FAB2_LIB.BASEBOARD_FAB2(SCH_1):PAGE183
     6 SP1_HOST_BRIDGE_UART_TX @BASEBOARD_FAB2_LIB.BASEBOARD_FAB2(SCH_1):SP1_HOST_BRIDGE_UART_TX     I1 @BASEBOARD_FAB2_LIB.BASEBOARD_FAB2(SCH_1):PAGE183
     7 UART_BRIDGE_TXD5 @BASEBOARD_FAB2_LIB.BASEBOARD_FAB2(SCH_1):UART_BRIDGE_TXD5     I1 @BASEBOARD_FAB2_LIB.BASEBOARD_FAB2(SCH_1):PAGE183
    29 P3V3_STBY @BASEBOARD_FAB2_LIB.BASEBOARD_FAB2(SCH_1):P3V3_STBY     I1 @BASEBOARD_FAB2_LIB.BASEBOARD_FAB2(SCH_1):PAGE183
     9 XTAL_24MHZ_IN_R @BASEBOARD_FAB2_LIB.BASEBOARD_FAB2(SCH_1):XTAL_24MHZ_IN_R     I1 @BASEBOARD_FAB2_LIB.BASEBOARD_FAB2(SCH_1):PAGE183
    10 XTAL_24MHZ_OUT_R @BASEBOARD_FAB2_LIB.BASEBOARD_FAB2(SCH_1):XTAL_24MHZ_OUT_R     I1 @BASEBOARD_FAB2_LIB.BASEBOARD_FAB2(SCH_1):PAGE183

EU9G1 ADC128D818_SM-IC,H63642-001
     7 FM_ADC128_A0 @BASEBOARD_FAB2_LIB.BASEBOARD_FAB2(SCH_1):FM_ADC128_A0    I52 @BASEBOARD_FAB2_LIB.BASEBOARD_FAB2(SCH_1):PAGE165
     8 FM_ADC128_A1 @BASEBOARD_FAB2_LIB.BASEBOARD_FAB2(SCH_1):FM_ADC128_A1    I52 @BASEBOARD_FAB2_LIB.BASEBOARD_FAB2(SCH_1):PAGE165
     4    GND @BASEBOARD_FAB2_LIB.BASEBOARD_FAB2(SCH_1):GND    I52 @BASEBOARD_FAB2_LIB.BASEBOARD_FAB2(SCH_1):PAGE165
    16 A_P3V3_SCALED @BASEBOARD_FAB2_LIB.BASEBOARD_FAB2(SCH_1):A_P3V3_SCALED    I52 @BASEBOARD_FAB2_LIB.BASEBOARD_FAB2(SCH_1):PAGE165
    15 A_P5V_SCALED @BASEBOARD_FAB2_LIB.BASEBOARD_FAB2(SCH_1):A_P5V_SCALED    I52 @BASEBOARD_FAB2_LIB.BASEBOARD_FAB2(SCH_1):PAGE165
    14 A_P12V_STBY_SCALED @BASEBOARD_FAB2_LIB.BASEBOARD_FAB2(SCH_1):A_P12V_STBY_SCALED    I52 @BASEBOARD_FAB2_LIB.BASEBOARD_FAB2(SCH_1):PAGE165
    13 A_P1V05_STBY_PCH_SENSOR @BASEBOARD_FAB2_LIB.BASEBOARD_FAB2(SCH_1):A_P1V05_STBY_PCH_SENSOR    I52 @BASEBOARD_FAB2_LIB.BASEBOARD_FAB2(SCH_1):PAGE165
    12 A_PVNN_STBY_PCH_SENSOR @BASEBOARD_FAB2_LIB.BASEBOARD_FAB2(SCH_1):A_PVNN_STBY_PCH_SENSOR    I52 @BASEBOARD_FAB2_LIB.BASEBOARD_FAB2(SCH_1):PAGE165
    11 A_P3V3_STBY_SCALED @BASEBOARD_FAB2_LIB.BASEBOARD_FAB2(SCH_1):A_P3V3_STBY_SCALED    I52 @BASEBOARD_FAB2_LIB.BASEBOARD_FAB2(SCH_1):PAGE165
    10 A_P5V_STBY_SCALED @BASEBOARD_FAB2_LIB.BASEBOARD_FAB2(SCH_1):A_P5V_STBY_SCALED    I52 @BASEBOARD_FAB2_LIB.BASEBOARD_FAB2(SCH_1):PAGE165
     9 A_P3V_BAT_SCALED @BASEBOARD_FAB2_LIB.BASEBOARD_FAB2(SCH_1):A_P3V_BAT_SCALED    I52 @BASEBOARD_FAB2_LIB.BASEBOARD_FAB2(SCH_1):PAGE165
     6 IRQ_VM_INT_R_N @BASEBOARD_FAB2_LIB.BASEBOARD_FAB2(SCH_1):IRQ_VM_INT_R_N    I52 @BASEBOARD_FAB2_LIB.BASEBOARD_FAB2(SCH_1):PAGE165
     3 SMB_SENSOR_PCH_STBY_LVC3_SCL @BASEBOARD_FAB2_LIB.BASEBOARD_FAB2(SCH_1):SMB_SENSOR_PCH_STBY_LVC3_SCL    I52 @BASEBOARD_FAB2_LIB.BASEBOARD_FAB2(SCH_1):PAGE165
     2 SMB_SENSOR_PCH_STBY_LVC3_SDA @BASEBOARD_FAB2_LIB.BASEBOARD_FAB2(SCH_1):SMB_SENSOR_PCH_STBY_LVC3_SDA    I52 @BASEBOARD_FAB2_LIB.BASEBOARD_FAB2(SCH_1):PAGE165
     5 P3V3_FB_ADC128_VCC @BASEBOARD_FAB2_LIB.BASEBOARD_FAB2(SCH_1):P3V3_FB_ADC128_VCC    I52 @BASEBOARD_FAB2_LIB.BASEBOARD_FAB2(SCH_1):PAGE165
     1 TP_ADC128_VREF @BASEBOARD_FAB2_LIB.BASEBOARD_FAB2(SCH_1):TP_ADC128_VREF    I52 @BASEBOARD_FAB2_LIB.BASEBOARD_FAB2(SCH_1):PAGE165

EU9M1 SLG55021_SM-IC,G56246-001
     4    GND @BASEBOARD_FAB2_LIB.BASEBOARD_FAB2(SCH_1):GND    I69 @BASEBOARD_FAB2_LIB.BASEBOARD_FAB2(SCH_1):PAGE198
     9    GND @BASEBOARD_FAB2_LIB.BASEBOARD_FAB2(SCH_1):GND    I69 @BASEBOARD_FAB2_LIB.BASEBOARD_FAB2(SCH_1):PAGE198
     1 P5V_STBY @BASEBOARD_FAB2_LIB.BASEBOARD_FAB2(SCH_1):P5V_STBY    I69 @BASEBOARD_FAB2_LIB.BASEBOARD_FAB2(SCH_1):PAGE198
     2 FM_ENABLE_FAN_POWER @BASEBOARD_FAB2_LIB.BASEBOARD_FAB2(SCH_1):FM_ENABLE_FAN_POWER    I69 @BASEBOARD_FAB2_LIB.BASEBOARD_FAB2(SCH_1):PAGE198
     3 P5V_STBY @BASEBOARD_FAB2_LIB.BASEBOARD_FAB2(SCH_1):P5V_STBY    I69 @BASEBOARD_FAB2_LIB.BASEBOARD_FAB2(SCH_1):PAGE198
     5 P12V_STBY @BASEBOARD_FAB2_LIB.BASEBOARD_FAB2(SCH_1):P12V_STBY    I69 @BASEBOARD_FAB2_LIB.BASEBOARD_FAB2(SCH_1):PAGE198
     6 P12V_FAN @BASEBOARD_FAB2_LIB.BASEBOARD_FAB2(SCH_1):P12V_FAN    I69 @BASEBOARD_FAB2_LIB.BASEBOARD_FAB2(SCH_1):PAGE198
     7 P12V_FAN_SWITCH_G @BASEBOARD_FAB2_LIB.BASEBOARD_FAB2(SCH_1):P12V_FAN_SWITCH_G    I69 @BASEBOARD_FAB2_LIB.BASEBOARD_FAB2(SCH_1):PAGE198
     8 TP_SLG55021_P12V_FAN_8 @BASEBOARD_FAB2_LIB.BASEBOARD_FAB2(SCH_1):TP_SLG55021_P12V_FAN_8    I69 @BASEBOARD_FAB2_LIB.BASEBOARD_FAB2(SCH_1):PAGE198

EU9R1 MOSFETN_1D3S_SOT5-IC,G68777-001
     1 P12V_STBY @BASEBOARD_FAB2_LIB.BASEBOARD_FAB2(SCH_1):P12V_STBY    I57 @BASEBOARD_FAB2_LIB.BASEBOARD_FAB2(SCH_1):PAGE200
     2 P12V_STBY @BASEBOARD_FAB2_LIB.BASEBOARD_FAB2(SCH_1):P12V_STBY    I57 @BASEBOARD_FAB2_LIB.BASEBOARD_FAB2(SCH_1):PAGE200
     3 P12V_STBY @BASEBOARD_FAB2_LIB.BASEBOARD_FAB2(SCH_1):P12V_STBY    I57 @BASEBOARD_FAB2_LIB.BASEBOARD_FAB2(SCH_1):PAGE200
     5 P12V_MB0_SW @BASEBOARD_FAB2_LIB.BASEBOARD_FAB2(SCH_1):P12V_MB0_SW    I57 @BASEBOARD_FAB2_LIB.BASEBOARD_FAB2(SCH_1):PAGE200
     4 A_HSC_GATE2_R @BASEBOARD_FAB2_LIB.BASEBOARD_FAB2(SCH_1):A_HSC_GATE2_R    I57 @BASEBOARD_FAB2_LIB.BASEBOARD_FAB2(SCH_1):PAGE200

EU25F2 RT9059_DFN-IC,H65765-001
     4 UNNAMED_239_21K5R2F-GP_I99_2 @BASEBOARD_FAB2_LIB.BASEBOARD_FAB2(SCH_1):UNNAMED_239_21K5R2F-GP_I99_2    I73 @BASEBOARD_FAB2_LIB.BASEBOARD_FAB2(SCH_1):PAGE239
     6 UNNAMED_239_CAP_I91_A @BASEBOARD_FAB2_LIB.BASEBOARD_FAB2(SCH_1):UNNAMED_239_CAP_I91_A    I73 @BASEBOARD_FAB2_LIB.BASEBOARD_FAB2(SCH_1):PAGE239
    11    GND @BASEBOARD_FAB2_LIB.BASEBOARD_FAB2(SCH_1):GND    I73 @BASEBOARD_FAB2_LIB.BASEBOARD_FAB2(SCH_1):PAGE239
     5 UNNAMED_239_CAP_I84_A @BASEBOARD_FAB2_LIB.BASEBOARD_FAB2(SCH_1):UNNAMED_239_CAP_I84_A    I73 @BASEBOARD_FAB2_LIB.BASEBOARD_FAB2(SCH_1):PAGE239
    10 P3V3_STBY @BASEBOARD_FAB2_LIB.BASEBOARD_FAB2(SCH_1):P3V3_STBY    I73 @BASEBOARD_FAB2_LIB.BASEBOARD_FAB2(SCH_1):PAGE239
     9 P3V3_STBY @BASEBOARD_FAB2_LIB.BASEBOARD_FAB2(SCH_1):P3V3_STBY    I73 @BASEBOARD_FAB2_LIB.BASEBOARD_FAB2(SCH_1):PAGE239
     8 P3V3_STBY @BASEBOARD_FAB2_LIB.BASEBOARD_FAB2(SCH_1):P3V3_STBY    I73 @BASEBOARD_FAB2_LIB.BASEBOARD_FAB2(SCH_1):PAGE239
     7 P3V3_STBY @BASEBOARD_FAB2_LIB.BASEBOARD_FAB2(SCH_1):P3V3_STBY    I73 @BASEBOARD_FAB2_LIB.BASEBOARD_FAB2(SCH_1):PAGE239
     3 P2V5_AUX_BMC @BASEBOARD_FAB2_LIB.BASEBOARD_FAB2(SCH_1):P2V5_AUX_BMC    I73 @BASEBOARD_FAB2_LIB.BASEBOARD_FAB2(SCH_1):PAGE239
     2 P2V5_AUX_BMC @BASEBOARD_FAB2_LIB.BASEBOARD_FAB2(SCH_1):P2V5_AUX_BMC    I73 @BASEBOARD_FAB2_LIB.BASEBOARD_FAB2(SCH_1):PAGE239
     1 P2V5_AUX_BMC @BASEBOARD_FAB2_LIB.BASEBOARD_FAB2(SCH_1):P2V5_AUX_BMC    I73 @BASEBOARD_FAB2_LIB.BASEBOARD_FAB2(SCH_1):PAGE239

F1L1 FUSE_SMT-IC,H45581-001
     1 P5V_STBY_DBG @BASEBOARD_FAB2_LIB.BASEBOARD_FAB2(SCH_1):P5V_STBY_DBG   I129 @BASEBOARD_FAB2_LIB.BASEBOARD_FAB2(SCH_1):PAGE155
     2 P5V_STBY_DGB_FS @BASEBOARD_FAB2_LIB.BASEBOARD_FAB2(SCH_1):P5V_STBY_DGB_FS   I129 @BASEBOARD_FAB2_LIB.BASEBOARD_FAB2(SCH_1):PAGE155

F8B1 FUSE_SMLF-IC,C94311-006
     1    P5V @BASEBOARD_FAB2_LIB.BASEBOARD_FAB2(SCH_1):P5V    I41 @BASEBOARD_FAB2_LIB.BASEBOARD_FAB2(SCH_1):PAGE172
     2 P5V_HDD_SATA @BASEBOARD_FAB2_LIB.BASEBOARD_FAB2(SCH_1):P5V_HDD_SATA    I41 @BASEBOARD_FAB2_LIB.BASEBOARD_FAB2(SCH_1):PAGE172

F9B1 FUSE_SM-IC,C94311-016
     1   P12V @BASEBOARD_FAB2_LIB.BASEBOARD_FAB2(SCH_1):P12V    I38 @BASEBOARD_FAB2_LIB.BASEBOARD_FAB2(SCH_1):PAGE172
     2 P12V_HDD_SATA @BASEBOARD_FAB2_LIB.BASEBOARD_FAB2(SCH_1):P12V_HDD_SATA    I38 @BASEBOARD_FAB2_LIB.BASEBOARD_FAB2(SCH_1):PAGE172

FB1U2 FERRITE_SMLF-60,FB,693286-001
     1 P3V3_STBY @BASEBOARD_FAB2_LIB.BASEBOARD_FAB2(SCH_1):P3V3_STBY    I79 @BASEBOARD_FAB2_LIB.BASEBOARD_FAB2(SCH_1):PAGE165
     2 P3V3_FB_ADC128_VCC @BASEBOARD_FAB2_LIB.BASEBOARD_FAB2(SCH_1):P3V3_FB_ADC128_VCC    I79 @BASEBOARD_FAB2_LIB.BASEBOARD_FAB2(SCH_1):PAGE165

FB1U3 FERRITE_SMLF-30,FB,693286-021
     1 A_P1V05_STBY_PCH_SENSOR @BASEBOARD_FAB2_LIB.BASEBOARD_FAB2(SCH_1):A_P1V05_STBY_PCH_SENSOR    I57 @BASEBOARD_FAB2_LIB.BASEBOARD_FAB2(SCH_1):PAGE169
     2 P1V05_PCH_STBY @BASEBOARD_FAB2_LIB.BASEBOARD_FAB2(SCH_1):P1V05_PCH_STBY    I57 @BASEBOARD_FAB2_LIB.BASEBOARD_FAB2(SCH_1):PAGE169

FB1U4 FERRITE_SMLF-30,FB,693286-021
     1 A_PVNN_STBY_PCH_SENSOR @BASEBOARD_FAB2_LIB.BASEBOARD_FAB2(SCH_1):A_PVNN_STBY_PCH_SENSOR   I155 @BASEBOARD_FAB2_LIB.BASEBOARD_FAB2(SCH_1):PAGE169
     2 PVNN_PCH_STBY @BASEBOARD_FAB2_LIB.BASEBOARD_FAB2(SCH_1):PVNN_PCH_STBY   I155 @BASEBOARD_FAB2_LIB.BASEBOARD_FAB2(SCH_1):PAGE169

FB2M1 FERRITE_SM-120,FB,693286-027
     1 P1V05_PCH_STBY @BASEBOARD_FAB2_LIB.BASEBOARD_FAB2(SCH_1):P1V05_PCH_STBY    I46 @BASEBOARD_FAB2_LIB.BASEBOARD_FAB2(SCH_1):PAGE127
     2 P1V05_PCH_STBY_WM20_PLL @BASEBOARD_FAB2_LIB.BASEBOARD_FAB2(SCH_1):P1V05_PCH_STBY_WM20_PLL    I46 @BASEBOARD_FAB2_LIB.BASEBOARD_FAB2(SCH_1):PAGE127

FB2M2 FERRITE_SM-120,FB,693286-027
     1 P1V05_PCH_STBY @BASEBOARD_FAB2_LIB.BASEBOARD_FAB2(SCH_1):P1V05_PCH_STBY    I69 @BASEBOARD_FAB2_LIB.BASEBOARD_FAB2(SCH_1):PAGE127
     2 P1V05_PCH_STBY_WM26_PLL @BASEBOARD_FAB2_LIB.BASEBOARD_FAB2(SCH_1):P1V05_PCH_STBY_WM26_PLL    I69 @BASEBOARD_FAB2_LIB.BASEBOARD_FAB2(SCH_1):PAGE127

FB2T1 HCB1608KF-800T30-GP_DISCRET-G9A
     1 P3V3_STBY @BASEBOARD_FAB2_LIB.BASEBOARD_FAB2(SCH_1):P3V3_STBY    I32 @BASEBOARD_FAB2_LIB.BASEBOARD_FAB2(SCH_1):PAGE150
     2 VCC_VA_3V3 @BASEBOARD_FAB2_LIB.BASEBOARD_FAB2(SCH_1):VCC_VA_3V3    I32 @BASEBOARD_FAB2_LIB.BASEBOARD_FAB2(SCH_1):PAGE150

FB2T2 FERRITE_SMLF-600,FB,656554-043
     1 P3V3_STBY @BASEBOARD_FAB2_LIB.BASEBOARD_FAB2(SCH_1):P3V3_STBY   I114 @BASEBOARD_FAB2_LIB.BASEBOARD_FAB2(SCH_1):PAGE101
     2 P3V3_STBY_MNG @BASEBOARD_FAB2_LIB.BASEBOARD_FAB2(SCH_1):P3V3_STBY_MNG   I114 @BASEBOARD_FAB2_LIB.BASEBOARD_FAB2(SCH_1):PAGE101

FB2T3 HCB1608KF-800T30-GP_DISCRET-G9A
     1 P3V3_STBY @BASEBOARD_FAB2_LIB.BASEBOARD_FAB2(SCH_1):P3V3_STBY    I76 @BASEBOARD_FAB2_LIB.BASEBOARD_FAB2(SCH_1):PAGE150
     2 VCC_ADCAV3V3 @BASEBOARD_FAB2_LIB.BASEBOARD_FAB2(SCH_1):VCC_ADCAV3V3    I76 @BASEBOARD_FAB2_LIB.BASEBOARD_FAB2(SCH_1):PAGE150

FB2T4 HCB1608KF-800T30-GP_DISCRET-G9A
     1 P3V3_STBY @BASEBOARD_FAB2_LIB.BASEBOARD_FAB2(SCH_1):P3V3_STBY    I84 @BASEBOARD_FAB2_LIB.BASEBOARD_FAB2(SCH_1):PAGE150
     2 VCC_D_3V3 @BASEBOARD_FAB2_LIB.BASEBOARD_FAB2(SCH_1):VCC_D_3V3    I84 @BASEBOARD_FAB2_LIB.BASEBOARD_FAB2(SCH_1):PAGE150

FB2T5 HCB1608KF-800T30-GP_DISCRET-G9A
     1 P3V3_STBY @BASEBOARD_FAB2_LIB.BASEBOARD_FAB2(SCH_1):P3V3_STBY    I89 @BASEBOARD_FAB2_LIB.BASEBOARD_FAB2(SCH_1):PAGE150
     2 VCC_PA_3V3 @BASEBOARD_FAB2_LIB.BASEBOARD_FAB2(SCH_1):VCC_PA_3V3    I89 @BASEBOARD_FAB2_LIB.BASEBOARD_FAB2(SCH_1):PAGE150

FB2T6 HCB1608KF-800T30-GP_DISCRET-G9A
     1 P3V3_STBY @BASEBOARD_FAB2_LIB.BASEBOARD_FAB2(SCH_1):P3V3_STBY    I26 @BASEBOARD_FAB2_LIB.BASEBOARD_FAB2(SCH_1):PAGE150
     2 VCC_D_PLL_3V3 @BASEBOARD_FAB2_LIB.BASEBOARD_FAB2(SCH_1):VCC_D_PLL_3V3    I26 @BASEBOARD_FAB2_LIB.BASEBOARD_FAB2(SCH_1):PAGE150

FB2T7 HCB1608KF-800T30-GP_DISCRET-G9A
     1 P1V15_AUX_BMC @BASEBOARD_FAB2_LIB.BASEBOARD_FAB2(SCH_1):P1V15_AUX_BMC    I39 @BASEBOARD_FAB2_LIB.BASEBOARD_FAB2(SCH_1):PAGE150
     2 VCC_A_1V1 @BASEBOARD_FAB2_LIB.BASEBOARD_FAB2(SCH_1):VCC_A_1V1    I39 @BASEBOARD_FAB2_LIB.BASEBOARD_FAB2(SCH_1):PAGE150

FB3M1 FERRITE_SM-120,FB,693286-027
     1 P1V05_PCH_STBY @BASEBOARD_FAB2_LIB.BASEBOARD_FAB2(SCH_1):P1V05_PCH_STBY     I8 @BASEBOARD_FAB2_LIB.BASEBOARD_FAB2(SCH_1):PAGE127
     2 P1V05_PCH_STBY_VCCA_PLL1 @BASEBOARD_FAB2_LIB.BASEBOARD_FAB2(SCH_1):P1V05_PCH_STBY_VCCA_PLL1     I8 @BASEBOARD_FAB2_LIB.BASEBOARD_FAB2(SCH_1):PAGE127

FB3M2 FERRITE_SM-120,FB,693286-027
     1 P1V05_PCH_STBY @BASEBOARD_FAB2_LIB.BASEBOARD_FAB2(SCH_1):P1V05_PCH_STBY    I17 @BASEBOARD_FAB2_LIB.BASEBOARD_FAB2(SCH_1):PAGE127
     2 P1V05_PCH_STBY_VCCA_PLL0 @BASEBOARD_FAB2_LIB.BASEBOARD_FAB2(SCH_1):P1V05_PCH_STBY_VCCA_PLL0    I17 @BASEBOARD_FAB2_LIB.BASEBOARD_FAB2(SCH_1):PAGE127

FB3M3 FERRITE_SM-120,FB,693286-027
     1 P1V05_PCH_STBY @BASEBOARD_FAB2_LIB.BASEBOARD_FAB2(SCH_1):P1V05_PCH_STBY    I26 @BASEBOARD_FAB2_LIB.BASEBOARD_FAB2(SCH_1):PAGE127
     2 P1V05_PCH_STBY_VCCA_XTAL @BASEBOARD_FAB2_LIB.BASEBOARD_FAB2(SCH_1):P1V05_PCH_STBY_VCCA_XTAL    I26 @BASEBOARD_FAB2_LIB.BASEBOARD_FAB2(SCH_1):PAGE127

FB3M4 FERRITE_SM-120,FB,693286-027
     1 P1V05_PCH_STBY @BASEBOARD_FAB2_LIB.BASEBOARD_FAB2(SCH_1):P1V05_PCH_STBY    I56 @BASEBOARD_FAB2_LIB.BASEBOARD_FAB2(SCH_1):PAGE127
     2 P1V05_PCH_STBY_ISCLK_PLL @BASEBOARD_FAB2_LIB.BASEBOARD_FAB2(SCH_1):P1V05_PCH_STBY_ISCLK_PLL    I56 @BASEBOARD_FAB2_LIB.BASEBOARD_FAB2(SCH_1):PAGE127

FB4A1 FERRITE_SM-22,FB,656554-051
     1 P12V_STBY @BASEBOARD_FAB2_LIB.BASEBOARD_FAB2(SCH_1):P12V_STBY   I154 @BASEBOARD_FAB2_LIB.BASEBOARD_FAB2(SCH_1):PAGE234
     2 VR_FET_SW_P12V_STBY_PVPP_KLM @BASEBOARD_FAB2_LIB.BASEBOARD_FAB2(SCH_1):VR_FET_SW_P12V_STBY_PVPP_KLM   I154 @BASEBOARD_FAB2_LIB.BASEBOARD_FAB2(SCH_1):PAGE234

FB4G1 FERRITE_SM-22,FB,656554-051
     1 P12V_STBY @BASEBOARD_FAB2_LIB.BASEBOARD_FAB2(SCH_1):P12V_STBY   I198 @BASEBOARD_FAB2_LIB.BASEBOARD_FAB2(SCH_1):PAGE233
     2 VR_FET_SW_P12V_STBY_PVPP_GHJ @BASEBOARD_FAB2_LIB.BASEBOARD_FAB2(SCH_1):VR_FET_SW_P12V_STBY_PVPP_GHJ   I198 @BASEBOARD_FAB2_LIB.BASEBOARD_FAB2(SCH_1):PAGE233

FB6P1 FERRITE_SMLF-600,FB,656554-043
     1   P3V3 @BASEBOARD_FAB2_LIB.BASEBOARD_FAB2(SCH_1):P3V3     I8 @BASEBOARD_FAB2_LIB.BASEBOARD_FAB2(SCH_1):PAGE102
     2 P3V3_DB1200 @BASEBOARD_FAB2_LIB.BASEBOARD_FAB2(SCH_1):P3V3_DB1200     I8 @BASEBOARD_FAB2_LIB.BASEBOARD_FAB2(SCH_1):PAGE102

FB7B1 FERRITE_SM-22,FB,656554-051
     1 P12V_STBY @BASEBOARD_FAB2_LIB.BASEBOARD_FAB2(SCH_1):P12V_STBY   I200 @BASEBOARD_FAB2_LIB.BASEBOARD_FAB2(SCH_1):PAGE232
     2 VR_FET_SW_P12V_STBY_PVPP_DEF @BASEBOARD_FAB2_LIB.BASEBOARD_FAB2(SCH_1):VR_FET_SW_P12V_STBY_PVPP_DEF   I200 @BASEBOARD_FAB2_LIB.BASEBOARD_FAB2(SCH_1):PAGE232

FB7E1 FERRITE_SM-22,FB,656554-051
     1 P12V_STBY @BASEBOARD_FAB2_LIB.BASEBOARD_FAB2(SCH_1):P12V_STBY    I82 @BASEBOARD_FAB2_LIB.BASEBOARD_FAB2(SCH_1):PAGE241
     2 VR_FET_SW_P5V_STBY_PVIN @BASEBOARD_FAB2_LIB.BASEBOARD_FAB2(SCH_1):VR_FET_SW_P5V_STBY_PVIN    I82 @BASEBOARD_FAB2_LIB.BASEBOARD_FAB2(SCH_1):PAGE241

FB7F1 FERRITE_SM-22,FB,656554-051
     1 P12V_STBY @BASEBOARD_FAB2_LIB.BASEBOARD_FAB2(SCH_1):P12V_STBY   I162 @BASEBOARD_FAB2_LIB.BASEBOARD_FAB2(SCH_1):PAGE231
     2 VR_FET_SW_P12V_STBY_PVPP_ABC @BASEBOARD_FAB2_LIB.BASEBOARD_FAB2(SCH_1):VR_FET_SW_P12V_STBY_PVPP_ABC   I162 @BASEBOARD_FAB2_LIB.BASEBOARD_FAB2(SCH_1):PAGE231

FB9E1 FERRITE_SM-22,FB,656554-051
     1 P12V_STBY @BASEBOARD_FAB2_LIB.BASEBOARD_FAB2(SCH_1):P12V_STBY   I132 @BASEBOARD_FAB2_LIB.BASEBOARD_FAB2(SCH_1):PAGE240
     2 VR_FET_SW_P12V_STBY_P3V3_STBY @BASEBOARD_FAB2_LIB.BASEBOARD_FAB2(SCH_1):VR_FET_SW_P12V_STBY_P3V3_STBY   I132 @BASEBOARD_FAB2_LIB.BASEBOARD_FAB2(SCH_1):PAGE240

J1A1 SCONN288_H44441004_PIP-SCONN,HA
    79 M_M_MA<0> @BASEBOARD_FAB2_LIB.BASEBOARD_FAB2(SCH_1):M_M_MA(0)   I186 @BASEBOARD_FAB2_LIB.BASEBOARD_FAB2(SCH_1):PAGE87
    72 M_M_MA<1> @BASEBOARD_FAB2_LIB.BASEBOARD_FAB2(SCH_1):M_M_MA(1)   I186 @BASEBOARD_FAB2_LIB.BASEBOARD_FAB2(SCH_1):PAGE87
   225 M_M_MA<10> @BASEBOARD_FAB2_LIB.BASEBOARD_FAB2(SCH_1):M_M_MA(10)   I186 @BASEBOARD_FAB2_LIB.BASEBOARD_FAB2(SCH_1):PAGE87
   210 M_M_MA<11> @BASEBOARD_FAB2_LIB.BASEBOARD_FAB2(SCH_1):M_M_MA(11)   I186 @BASEBOARD_FAB2_LIB.BASEBOARD_FAB2(SCH_1):PAGE87
    65 M_M_MA<12> @BASEBOARD_FAB2_LIB.BASEBOARD_FAB2(SCH_1):M_M_MA(12)   I186 @BASEBOARD_FAB2_LIB.BASEBOARD_FAB2(SCH_1):PAGE87
   232 M_M_MA<13> @BASEBOARD_FAB2_LIB.BASEBOARD_FAB2(SCH_1):M_M_MA(13)   I186 @BASEBOARD_FAB2_LIB.BASEBOARD_FAB2(SCH_1):PAGE87
   228 M_M_MA<14> @BASEBOARD_FAB2_LIB.BASEBOARD_FAB2(SCH_1):M_M_MA(14)   I186 @BASEBOARD_FAB2_LIB.BASEBOARD_FAB2(SCH_1):PAGE87
    86 M_M_MA<15> @BASEBOARD_FAB2_LIB.BASEBOARD_FAB2(SCH_1):M_M_MA(15)   I186 @BASEBOARD_FAB2_LIB.BASEBOARD_FAB2(SCH_1):PAGE87
    82 M_M_MA<16> @BASEBOARD_FAB2_LIB.BASEBOARD_FAB2(SCH_1):M_M_MA(16)   I186 @BASEBOARD_FAB2_LIB.BASEBOARD_FAB2(SCH_1):PAGE87
   234 M_M_MA<17> @BASEBOARD_FAB2_LIB.BASEBOARD_FAB2(SCH_1):M_M_MA(17)   I186 @BASEBOARD_FAB2_LIB.BASEBOARD_FAB2(SCH_1):PAGE87
   216 M_M_MA<2> @BASEBOARD_FAB2_LIB.BASEBOARD_FAB2(SCH_1):M_M_MA(2)   I186 @BASEBOARD_FAB2_LIB.BASEBOARD_FAB2(SCH_1):PAGE87
    71 M_M_MA<3> @BASEBOARD_FAB2_LIB.BASEBOARD_FAB2(SCH_1):M_M_MA(3)   I186 @BASEBOARD_FAB2_LIB.BASEBOARD_FAB2(SCH_1):PAGE87
   214 M_M_MA<4> @BASEBOARD_FAB2_LIB.BASEBOARD_FAB2(SCH_1):M_M_MA(4)   I186 @BASEBOARD_FAB2_LIB.BASEBOARD_FAB2(SCH_1):PAGE87
   213 M_M_MA<5> @BASEBOARD_FAB2_LIB.BASEBOARD_FAB2(SCH_1):M_M_MA(5)   I186 @BASEBOARD_FAB2_LIB.BASEBOARD_FAB2(SCH_1):PAGE87
    69 M_M_MA<6> @BASEBOARD_FAB2_LIB.BASEBOARD_FAB2(SCH_1):M_M_MA(6)   I186 @BASEBOARD_FAB2_LIB.BASEBOARD_FAB2(SCH_1):PAGE87
   211 M_M_MA<7> @BASEBOARD_FAB2_LIB.BASEBOARD_FAB2(SCH_1):M_M_MA(7)   I186 @BASEBOARD_FAB2_LIB.BASEBOARD_FAB2(SCH_1):PAGE87
    68 M_M_MA<8> @BASEBOARD_FAB2_LIB.BASEBOARD_FAB2(SCH_1):M_M_MA(8)   I186 @BASEBOARD_FAB2_LIB.BASEBOARD_FAB2(SCH_1):PAGE87
    66 M_M_MA<9> @BASEBOARD_FAB2_LIB.BASEBOARD_FAB2(SCH_1):M_M_MA(9)   I186 @BASEBOARD_FAB2_LIB.BASEBOARD_FAB2(SCH_1):PAGE87
    62 M_M_ACT_N @BASEBOARD_FAB2_LIB.BASEBOARD_FAB2(SCH_1):M_M_ACT_N   I186 @BASEBOARD_FAB2_LIB.BASEBOARD_FAB2(SCH_1):PAGE87
   208 M_M_ALERT_N @BASEBOARD_FAB2_LIB.BASEBOARD_FAB2(SCH_1):M_M_ALERT_N   I186 @BASEBOARD_FAB2_LIB.BASEBOARD_FAB2(SCH_1):PAGE87
   224 M_M_BA<1> @BASEBOARD_FAB2_LIB.BASEBOARD_FAB2(SCH_1):M_M_BA(1)   I186 @BASEBOARD_FAB2_LIB.BASEBOARD_FAB2(SCH_1):PAGE87
    81 M_M_BA<0> @BASEBOARD_FAB2_LIB.BASEBOARD_FAB2(SCH_1):M_M_BA(0)   I186 @BASEBOARD_FAB2_LIB.BASEBOARD_FAB2(SCH_1):PAGE87
   207 M_M_BG<1> @BASEBOARD_FAB2_LIB.BASEBOARD_FAB2(SCH_1):M_M_BG(1)   I186 @BASEBOARD_FAB2_LIB.BASEBOARD_FAB2(SCH_1):PAGE87
    63 M_M_BG<0> @BASEBOARD_FAB2_LIB.BASEBOARD_FAB2(SCH_1):M_M_BG(0)   I186 @BASEBOARD_FAB2_LIB.BASEBOARD_FAB2(SCH_1):PAGE87
   235 M_M_C<2> @BASEBOARD_FAB2_LIB.BASEBOARD_FAB2(SCH_1):M_M_C(2)   I186 @BASEBOARD_FAB2_LIB.BASEBOARD_FAB2(SCH_1):PAGE87
   199 M_M_ECC<6> @BASEBOARD_FAB2_LIB.BASEBOARD_FAB2(SCH_1):M_M_ECC(6)   I186 @BASEBOARD_FAB2_LIB.BASEBOARD_FAB2(SCH_1):PAGE87
    54 M_M_ECC<7> @BASEBOARD_FAB2_LIB.BASEBOARD_FAB2(SCH_1):M_M_ECC(7)   I186 @BASEBOARD_FAB2_LIB.BASEBOARD_FAB2(SCH_1):PAGE87
   192 M_M_ECC<4> @BASEBOARD_FAB2_LIB.BASEBOARD_FAB2(SCH_1):M_M_ECC(4)   I186 @BASEBOARD_FAB2_LIB.BASEBOARD_FAB2(SCH_1):PAGE87
    47 M_M_ECC<5> @BASEBOARD_FAB2_LIB.BASEBOARD_FAB2(SCH_1):M_M_ECC(5)   I186 @BASEBOARD_FAB2_LIB.BASEBOARD_FAB2(SCH_1):PAGE87
   201 M_M_ECC<2> @BASEBOARD_FAB2_LIB.BASEBOARD_FAB2(SCH_1):M_M_ECC(2)   I186 @BASEBOARD_FAB2_LIB.BASEBOARD_FAB2(SCH_1):PAGE87
    56 M_M_ECC<3> @BASEBOARD_FAB2_LIB.BASEBOARD_FAB2(SCH_1):M_M_ECC(3)   I186 @BASEBOARD_FAB2_LIB.BASEBOARD_FAB2(SCH_1):PAGE87
   194 M_M_ECC<0> @BASEBOARD_FAB2_LIB.BASEBOARD_FAB2(SCH_1):M_M_ECC(0)   I186 @BASEBOARD_FAB2_LIB.BASEBOARD_FAB2(SCH_1):PAGE87
    49 M_M_ECC<1> @BASEBOARD_FAB2_LIB.BASEBOARD_FAB2(SCH_1):M_M_ECC(1)   I186 @BASEBOARD_FAB2_LIB.BASEBOARD_FAB2(SCH_1):PAGE87
    75 M_M_CLK_DN<0> @BASEBOARD_FAB2_LIB.BASEBOARD_FAB2(SCH_1):M_M_CLK_DN(0)   I186 @BASEBOARD_FAB2_LIB.BASEBOARD_FAB2(SCH_1):PAGE87
    74 M_M_CLK_DP<0> @BASEBOARD_FAB2_LIB.BASEBOARD_FAB2(SCH_1):M_M_CLK_DP(0)   I186 @BASEBOARD_FAB2_LIB.BASEBOARD_FAB2(SCH_1):PAGE87
   219 M_M_CLK_DN<1> @BASEBOARD_FAB2_LIB.BASEBOARD_FAB2(SCH_1):M_M_CLK_DN(1)   I186 @BASEBOARD_FAB2_LIB.BASEBOARD_FAB2(SCH_1):PAGE87
   218 M_M_CLK_DP<1> @BASEBOARD_FAB2_LIB.BASEBOARD_FAB2(SCH_1):M_M_CLK_DP(1)   I186 @BASEBOARD_FAB2_LIB.BASEBOARD_FAB2(SCH_1):PAGE87
   203 M_M_CKE<1> @BASEBOARD_FAB2_LIB.BASEBOARD_FAB2(SCH_1):M_M_CKE(1)   I186 @BASEBOARD_FAB2_LIB.BASEBOARD_FAB2(SCH_1):PAGE87
    60 M_M_CKE<0> @BASEBOARD_FAB2_LIB.BASEBOARD_FAB2(SCH_1):M_M_CKE(0)   I186 @BASEBOARD_FAB2_LIB.BASEBOARD_FAB2(SCH_1):PAGE87
   280 M_M_DQ<62> @BASEBOARD_FAB2_LIB.BASEBOARD_FAB2(SCH_1):M_M_DQ(62)   I186 @BASEBOARD_FAB2_LIB.BASEBOARD_FAB2(SCH_1):PAGE87
   135 M_M_DQ<63> @BASEBOARD_FAB2_LIB.BASEBOARD_FAB2(SCH_1):M_M_DQ(63)   I186 @BASEBOARD_FAB2_LIB.BASEBOARD_FAB2(SCH_1):PAGE87
   273 M_M_DQ<60> @BASEBOARD_FAB2_LIB.BASEBOARD_FAB2(SCH_1):M_M_DQ(60)   I186 @BASEBOARD_FAB2_LIB.BASEBOARD_FAB2(SCH_1):PAGE87
   128 M_M_DQ<61> @BASEBOARD_FAB2_LIB.BASEBOARD_FAB2(SCH_1):M_M_DQ(61)   I186 @BASEBOARD_FAB2_LIB.BASEBOARD_FAB2(SCH_1):PAGE87
   282 M_M_DQ<58> @BASEBOARD_FAB2_LIB.BASEBOARD_FAB2(SCH_1):M_M_DQ(58)   I186 @BASEBOARD_FAB2_LIB.BASEBOARD_FAB2(SCH_1):PAGE87
   137 M_M_DQ<59> @BASEBOARD_FAB2_LIB.BASEBOARD_FAB2(SCH_1):M_M_DQ(59)   I186 @BASEBOARD_FAB2_LIB.BASEBOARD_FAB2(SCH_1):PAGE87
   275 M_M_DQ<56> @BASEBOARD_FAB2_LIB.BASEBOARD_FAB2(SCH_1):M_M_DQ(56)   I186 @BASEBOARD_FAB2_LIB.BASEBOARD_FAB2(SCH_1):PAGE87
   130 M_M_DQ<57> @BASEBOARD_FAB2_LIB.BASEBOARD_FAB2(SCH_1):M_M_DQ(57)   I186 @BASEBOARD_FAB2_LIB.BASEBOARD_FAB2(SCH_1):PAGE87
   269 M_M_DQ<54> @BASEBOARD_FAB2_LIB.BASEBOARD_FAB2(SCH_1):M_M_DQ(54)   I186 @BASEBOARD_FAB2_LIB.BASEBOARD_FAB2(SCH_1):PAGE87
   124 M_M_DQ<55> @BASEBOARD_FAB2_LIB.BASEBOARD_FAB2(SCH_1):M_M_DQ(55)   I186 @BASEBOARD_FAB2_LIB.BASEBOARD_FAB2(SCH_1):PAGE87
   262 M_M_DQ<52> @BASEBOARD_FAB2_LIB.BASEBOARD_FAB2(SCH_1):M_M_DQ(52)   I186 @BASEBOARD_FAB2_LIB.BASEBOARD_FAB2(SCH_1):PAGE87
   117 M_M_DQ<53> @BASEBOARD_FAB2_LIB.BASEBOARD_FAB2(SCH_1):M_M_DQ(53)   I186 @BASEBOARD_FAB2_LIB.BASEBOARD_FAB2(SCH_1):PAGE87
   271 M_M_DQ<50> @BASEBOARD_FAB2_LIB.BASEBOARD_FAB2(SCH_1):M_M_DQ(50)   I186 @BASEBOARD_FAB2_LIB.BASEBOARD_FAB2(SCH_1):PAGE87
   126 M_M_DQ<51> @BASEBOARD_FAB2_LIB.BASEBOARD_FAB2(SCH_1):M_M_DQ(51)   I186 @BASEBOARD_FAB2_LIB.BASEBOARD_FAB2(SCH_1):PAGE87
   264 M_M_DQ<48> @BASEBOARD_FAB2_LIB.BASEBOARD_FAB2(SCH_1):M_M_DQ(48)   I186 @BASEBOARD_FAB2_LIB.BASEBOARD_FAB2(SCH_1):PAGE87
   119 M_M_DQ<49> @BASEBOARD_FAB2_LIB.BASEBOARD_FAB2(SCH_1):M_M_DQ(49)   I186 @BASEBOARD_FAB2_LIB.BASEBOARD_FAB2(SCH_1):PAGE87
   258 M_M_DQ<46> @BASEBOARD_FAB2_LIB.BASEBOARD_FAB2(SCH_1):M_M_DQ(46)   I186 @BASEBOARD_FAB2_LIB.BASEBOARD_FAB2(SCH_1):PAGE87
   113 M_M_DQ<47> @BASEBOARD_FAB2_LIB.BASEBOARD_FAB2(SCH_1):M_M_DQ(47)   I186 @BASEBOARD_FAB2_LIB.BASEBOARD_FAB2(SCH_1):PAGE87
   251 M_M_DQ<44> @BASEBOARD_FAB2_LIB.BASEBOARD_FAB2(SCH_1):M_M_DQ(44)   I186 @BASEBOARD_FAB2_LIB.BASEBOARD_FAB2(SCH_1):PAGE87
   106 M_M_DQ<45> @BASEBOARD_FAB2_LIB.BASEBOARD_FAB2(SCH_1):M_M_DQ(45)   I186 @BASEBOARD_FAB2_LIB.BASEBOARD_FAB2(SCH_1):PAGE87
   260 M_M_DQ<42> @BASEBOARD_FAB2_LIB.BASEBOARD_FAB2(SCH_1):M_M_DQ(42)   I186 @BASEBOARD_FAB2_LIB.BASEBOARD_FAB2(SCH_1):PAGE87
   115 M_M_DQ<43> @BASEBOARD_FAB2_LIB.BASEBOARD_FAB2(SCH_1):M_M_DQ(43)   I186 @BASEBOARD_FAB2_LIB.BASEBOARD_FAB2(SCH_1):PAGE87
   253 M_M_DQ<40> @BASEBOARD_FAB2_LIB.BASEBOARD_FAB2(SCH_1):M_M_DQ(40)   I186 @BASEBOARD_FAB2_LIB.BASEBOARD_FAB2(SCH_1):PAGE87
   108 M_M_DQ<41> @BASEBOARD_FAB2_LIB.BASEBOARD_FAB2(SCH_1):M_M_DQ(41)   I186 @BASEBOARD_FAB2_LIB.BASEBOARD_FAB2(SCH_1):PAGE87
   247 M_M_DQ<38> @BASEBOARD_FAB2_LIB.BASEBOARD_FAB2(SCH_1):M_M_DQ(38)   I186 @BASEBOARD_FAB2_LIB.BASEBOARD_FAB2(SCH_1):PAGE87
   102 M_M_DQ<39> @BASEBOARD_FAB2_LIB.BASEBOARD_FAB2(SCH_1):M_M_DQ(39)   I186 @BASEBOARD_FAB2_LIB.BASEBOARD_FAB2(SCH_1):PAGE87
   240 M_M_DQ<36> @BASEBOARD_FAB2_LIB.BASEBOARD_FAB2(SCH_1):M_M_DQ(36)   I186 @BASEBOARD_FAB2_LIB.BASEBOARD_FAB2(SCH_1):PAGE87
    95 M_M_DQ<37> @BASEBOARD_FAB2_LIB.BASEBOARD_FAB2(SCH_1):M_M_DQ(37)   I186 @BASEBOARD_FAB2_LIB.BASEBOARD_FAB2(SCH_1):PAGE87
   249 M_M_DQ<34> @BASEBOARD_FAB2_LIB.BASEBOARD_FAB2(SCH_1):M_M_DQ(34)   I186 @BASEBOARD_FAB2_LIB.BASEBOARD_FAB2(SCH_1):PAGE87
   104 M_M_DQ<35> @BASEBOARD_FAB2_LIB.BASEBOARD_FAB2(SCH_1):M_M_DQ(35)   I186 @BASEBOARD_FAB2_LIB.BASEBOARD_FAB2(SCH_1):PAGE87
   242 M_M_DQ<32> @BASEBOARD_FAB2_LIB.BASEBOARD_FAB2(SCH_1):M_M_DQ(32)   I186 @BASEBOARD_FAB2_LIB.BASEBOARD_FAB2(SCH_1):PAGE87
    97 M_M_DQ<33> @BASEBOARD_FAB2_LIB.BASEBOARD_FAB2(SCH_1):M_M_DQ(33)   I186 @BASEBOARD_FAB2_LIB.BASEBOARD_FAB2(SCH_1):PAGE87
   188 M_M_DQ<30> @BASEBOARD_FAB2_LIB.BASEBOARD_FAB2(SCH_1):M_M_DQ(30)   I186 @BASEBOARD_FAB2_LIB.BASEBOARD_FAB2(SCH_1):PAGE87
    43 M_M_DQ<31> @BASEBOARD_FAB2_LIB.BASEBOARD_FAB2(SCH_1):M_M_DQ(31)   I186 @BASEBOARD_FAB2_LIB.BASEBOARD_FAB2(SCH_1):PAGE87
   181 M_M_DQ<28> @BASEBOARD_FAB2_LIB.BASEBOARD_FAB2(SCH_1):M_M_DQ(28)   I186 @BASEBOARD_FAB2_LIB.BASEBOARD_FAB2(SCH_1):PAGE87
    36 M_M_DQ<29> @BASEBOARD_FAB2_LIB.BASEBOARD_FAB2(SCH_1):M_M_DQ(29)   I186 @BASEBOARD_FAB2_LIB.BASEBOARD_FAB2(SCH_1):PAGE87
   190 M_M_DQ<26> @BASEBOARD_FAB2_LIB.BASEBOARD_FAB2(SCH_1):M_M_DQ(26)   I186 @BASEBOARD_FAB2_LIB.BASEBOARD_FAB2(SCH_1):PAGE87
    45 M_M_DQ<27> @BASEBOARD_FAB2_LIB.BASEBOARD_FAB2(SCH_1):M_M_DQ(27)   I186 @BASEBOARD_FAB2_LIB.BASEBOARD_FAB2(SCH_1):PAGE87
   183 M_M_DQ<24> @BASEBOARD_FAB2_LIB.BASEBOARD_FAB2(SCH_1):M_M_DQ(24)   I186 @BASEBOARD_FAB2_LIB.BASEBOARD_FAB2(SCH_1):PAGE87
    38 M_M_DQ<25> @BASEBOARD_FAB2_LIB.BASEBOARD_FAB2(SCH_1):M_M_DQ(25)   I186 @BASEBOARD_FAB2_LIB.BASEBOARD_FAB2(SCH_1):PAGE87
   177 M_M_DQ<22> @BASEBOARD_FAB2_LIB.BASEBOARD_FAB2(SCH_1):M_M_DQ(22)   I186 @BASEBOARD_FAB2_LIB.BASEBOARD_FAB2(SCH_1):PAGE87
    32 M_M_DQ<23> @BASEBOARD_FAB2_LIB.BASEBOARD_FAB2(SCH_1):M_M_DQ(23)   I186 @BASEBOARD_FAB2_LIB.BASEBOARD_FAB2(SCH_1):PAGE87
   170 M_M_DQ<20> @BASEBOARD_FAB2_LIB.BASEBOARD_FAB2(SCH_1):M_M_DQ(20)   I186 @BASEBOARD_FAB2_LIB.BASEBOARD_FAB2(SCH_1):PAGE87
    25 M_M_DQ<21> @BASEBOARD_FAB2_LIB.BASEBOARD_FAB2(SCH_1):M_M_DQ(21)   I186 @BASEBOARD_FAB2_LIB.BASEBOARD_FAB2(SCH_1):PAGE87
   179 M_M_DQ<18> @BASEBOARD_FAB2_LIB.BASEBOARD_FAB2(SCH_1):M_M_DQ(18)   I186 @BASEBOARD_FAB2_LIB.BASEBOARD_FAB2(SCH_1):PAGE87
    34 M_M_DQ<19> @BASEBOARD_FAB2_LIB.BASEBOARD_FAB2(SCH_1):M_M_DQ(19)   I186 @BASEBOARD_FAB2_LIB.BASEBOARD_FAB2(SCH_1):PAGE87
   172 M_M_DQ<16> @BASEBOARD_FAB2_LIB.BASEBOARD_FAB2(SCH_1):M_M_DQ(16)   I186 @BASEBOARD_FAB2_LIB.BASEBOARD_FAB2(SCH_1):PAGE87
    27 M_M_DQ<17> @BASEBOARD_FAB2_LIB.BASEBOARD_FAB2(SCH_1):M_M_DQ(17)   I186 @BASEBOARD_FAB2_LIB.BASEBOARD_FAB2(SCH_1):PAGE87
   166 M_M_DQ<14> @BASEBOARD_FAB2_LIB.BASEBOARD_FAB2(SCH_1):M_M_DQ(14)   I186 @BASEBOARD_FAB2_LIB.BASEBOARD_FAB2(SCH_1):PAGE87
    21 M_M_DQ<15> @BASEBOARD_FAB2_LIB.BASEBOARD_FAB2(SCH_1):M_M_DQ(15)   I186 @BASEBOARD_FAB2_LIB.BASEBOARD_FAB2(SCH_1):PAGE87
   159 M_M_DQ<12> @BASEBOARD_FAB2_LIB.BASEBOARD_FAB2(SCH_1):M_M_DQ(12)   I186 @BASEBOARD_FAB2_LIB.BASEBOARD_FAB2(SCH_1):PAGE87
    14 M_M_DQ<13> @BASEBOARD_FAB2_LIB.BASEBOARD_FAB2(SCH_1):M_M_DQ(13)   I186 @BASEBOARD_FAB2_LIB.BASEBOARD_FAB2(SCH_1):PAGE87
   168 M_M_DQ<10> @BASEBOARD_FAB2_LIB.BASEBOARD_FAB2(SCH_1):M_M_DQ(10)   I186 @BASEBOARD_FAB2_LIB.BASEBOARD_FAB2(SCH_1):PAGE87
    23 M_M_DQ<11> @BASEBOARD_FAB2_LIB.BASEBOARD_FAB2(SCH_1):M_M_DQ(11)   I186 @BASEBOARD_FAB2_LIB.BASEBOARD_FAB2(SCH_1):PAGE87
   161 M_M_DQ<8> @BASEBOARD_FAB2_LIB.BASEBOARD_FAB2(SCH_1):M_M_DQ(8)   I186 @BASEBOARD_FAB2_LIB.BASEBOARD_FAB2(SCH_1):PAGE87
    16 M_M_DQ<9> @BASEBOARD_FAB2_LIB.BASEBOARD_FAB2(SCH_1):M_M_DQ(9)   I186 @BASEBOARD_FAB2_LIB.BASEBOARD_FAB2(SCH_1):PAGE87
   155 M_M_DQ<6> @BASEBOARD_FAB2_LIB.BASEBOARD_FAB2(SCH_1):M_M_DQ(6)   I186 @BASEBOARD_FAB2_LIB.BASEBOARD_FAB2(SCH_1):PAGE87
    10 M_M_DQ<7> @BASEBOARD_FAB2_LIB.BASEBOARD_FAB2(SCH_1):M_M_DQ(7)   I186 @BASEBOARD_FAB2_LIB.BASEBOARD_FAB2(SCH_1):PAGE87
   148 M_M_DQ<4> @BASEBOARD_FAB2_LIB.BASEBOARD_FAB2(SCH_1):M_M_DQ(4)   I186 @BASEBOARD_FAB2_LIB.BASEBOARD_FAB2(SCH_1):PAGE87
     3 M_M_DQ<5> @BASEBOARD_FAB2_LIB.BASEBOARD_FAB2(SCH_1):M_M_DQ(5)   I186 @BASEBOARD_FAB2_LIB.BASEBOARD_FAB2(SCH_1):PAGE87
   157 M_M_DQ<2> @BASEBOARD_FAB2_LIB.BASEBOARD_FAB2(SCH_1):M_M_DQ(2)   I186 @BASEBOARD_FAB2_LIB.BASEBOARD_FAB2(SCH_1):PAGE87
    12 M_M_DQ<3> @BASEBOARD_FAB2_LIB.BASEBOARD_FAB2(SCH_1):M_M_DQ(3)   I186 @BASEBOARD_FAB2_LIB.BASEBOARD_FAB2(SCH_1):PAGE87
   150 M_M_DQ<0> @BASEBOARD_FAB2_LIB.BASEBOARD_FAB2(SCH_1):M_M_DQ(0)   I186 @BASEBOARD_FAB2_LIB.BASEBOARD_FAB2(SCH_1):PAGE87
     5 M_M_DQ<1> @BASEBOARD_FAB2_LIB.BASEBOARD_FAB2(SCH_1):M_M_DQ(1)   I186 @BASEBOARD_FAB2_LIB.BASEBOARD_FAB2(SCH_1):PAGE87
    78 FM_DIMM_EVENT_COD_N @BASEBOARD_FAB2_LIB.BASEBOARD_FAB2(SCH_1):FM_DIMM_EVENT_COD_N   I186 @BASEBOARD_FAB2_LIB.BASEBOARD_FAB2(SCH_1):PAGE87
    91 M_M_ODT<1> @BASEBOARD_FAB2_LIB.BASEBOARD_FAB2(SCH_1):M_M_ODT(1)   I186 @BASEBOARD_FAB2_LIB.BASEBOARD_FAB2(SCH_1):PAGE87
    87 M_M_ODT<0> @BASEBOARD_FAB2_LIB.BASEBOARD_FAB2(SCH_1):M_M_ODT(0)   I186 @BASEBOARD_FAB2_LIB.BASEBOARD_FAB2(SCH_1):PAGE87
   222 M_M_PAR @BASEBOARD_FAB2_LIB.BASEBOARD_FAB2(SCH_1):M_M_PAR   I186 @BASEBOARD_FAB2_LIB.BASEBOARD_FAB2(SCH_1):PAGE87
    58 M_KLM_RST_N @BASEBOARD_FAB2_LIB.BASEBOARD_FAB2(SCH_1):M_KLM_RST_N   I186 @BASEBOARD_FAB2_LIB.BASEBOARD_FAB2(SCH_1):PAGE87
   144 TP_CH_M_DIMM_M0_RFU_2 @BASEBOARD_FAB2_LIB.BASEBOARD_FAB2(SCH_1):TP_CH_M_DIMM_M0_RFU_2   I186 @BASEBOARD_FAB2_LIB.BASEBOARD_FAB2(SCH_1):PAGE87
   227 TP_CH_M_DIMM_M0_RFU_1 @BASEBOARD_FAB2_LIB.BASEBOARD_FAB2(SCH_1):TP_CH_M_DIMM_M0_RFU_1   I186 @BASEBOARD_FAB2_LIB.BASEBOARD_FAB2(SCH_1):PAGE87
   205 TP_CH_M_DIMM_M0_RFU_0 @BASEBOARD_FAB2_LIB.BASEBOARD_FAB2(SCH_1):TP_CH_M_DIMM_M0_RFU_0   I186 @BASEBOARD_FAB2_LIB.BASEBOARD_FAB2(SCH_1):PAGE87
    84 M_M_CS_N<0> @BASEBOARD_FAB2_LIB.BASEBOARD_FAB2(SCH_1):M_M_CS_N(0)   I186 @BASEBOARD_FAB2_LIB.BASEBOARD_FAB2(SCH_1):PAGE87
    89 M_M_CS_N<1> @BASEBOARD_FAB2_LIB.BASEBOARD_FAB2(SCH_1):M_M_CS_N(1)   I186 @BASEBOARD_FAB2_LIB.BASEBOARD_FAB2(SCH_1):PAGE87
    93 M_M_CS_N<2> @BASEBOARD_FAB2_LIB.BASEBOARD_FAB2(SCH_1):M_M_CS_N(2)   I186 @BASEBOARD_FAB2_LIB.BASEBOARD_FAB2(SCH_1):PAGE87
   237 M_M_CS_N<3> @BASEBOARD_FAB2_LIB.BASEBOARD_FAB2(SCH_1):M_M_CS_N(3)   I186 @BASEBOARD_FAB2_LIB.BASEBOARD_FAB2(SCH_1):PAGE87
   238 PVPP_KLM @BASEBOARD_FAB2_LIB.BASEBOARD_FAB2(SCH_1):PVPP_KLM   I186 @BASEBOARD_FAB2_LIB.BASEBOARD_FAB2(SCH_1):PAGE87
   140    GND @BASEBOARD_FAB2_LIB.BASEBOARD_FAB2(SCH_1):GND   I186 @BASEBOARD_FAB2_LIB.BASEBOARD_FAB2(SCH_1):PAGE87
   139    GND @BASEBOARD_FAB2_LIB.BASEBOARD_FAB2(SCH_1):GND   I186 @BASEBOARD_FAB2_LIB.BASEBOARD_FAB2(SCH_1):PAGE87
   230 FM_ADR_COMPLETE_KLM_N @BASEBOARD_FAB2_LIB.BASEBOARD_FAB2(SCH_1):FM_ADR_COMPLETE_KLM_N   I186 @BASEBOARD_FAB2_LIB.BASEBOARD_FAB2(SCH_1):PAGE87
   141 SMB_DDR_KLM_VPP_SCL @BASEBOARD_FAB2_LIB.BASEBOARD_FAB2(SCH_1):SMB_DDR_KLM_VPP_SCL   I186 @BASEBOARD_FAB2_LIB.BASEBOARD_FAB2(SCH_1):PAGE87
   285 SMB_DDR_KLM_VPP_SDA @BASEBOARD_FAB2_LIB.BASEBOARD_FAB2(SCH_1):SMB_DDR_KLM_VPP_SDA   I186 @BASEBOARD_FAB2_LIB.BASEBOARD_FAB2(SCH_1):PAGE87
   284 PVPP_KLM @BASEBOARD_FAB2_LIB.BASEBOARD_FAB2(SCH_1):PVPP_KLM   I186 @BASEBOARD_FAB2_LIB.BASEBOARD_FAB2(SCH_1):PAGE87
   146 M_M_VREF @BASEBOARD_FAB2_LIB.BASEBOARD_FAB2(SCH_1):M_M_VREF   I186 @BASEBOARD_FAB2_LIB.BASEBOARD_FAB2(SCH_1):PAGE87
   152 M_M_DQS_DN<0> @BASEBOARD_FAB2_LIB.BASEBOARD_FAB2(SCH_1):M_M_DQS_DN(0)   I187 @BASEBOARD_FAB2_LIB.BASEBOARD_FAB2(SCH_1):PAGE87
   153 M_M_DQS_DP<0> @BASEBOARD_FAB2_LIB.BASEBOARD_FAB2(SCH_1):M_M_DQS_DP(0)   I187 @BASEBOARD_FAB2_LIB.BASEBOARD_FAB2(SCH_1):PAGE87
    19 M_M_DQS_DN<10> @BASEBOARD_FAB2_LIB.BASEBOARD_FAB2(SCH_1):M_M_DQS_DN(10)   I187 @BASEBOARD_FAB2_LIB.BASEBOARD_FAB2(SCH_1):PAGE87
    18 M_M_DQS_DP<10> @BASEBOARD_FAB2_LIB.BASEBOARD_FAB2(SCH_1):M_M_DQS_DP(10)   I187 @BASEBOARD_FAB2_LIB.BASEBOARD_FAB2(SCH_1):PAGE87
    30 M_M_DQS_DN<11> @BASEBOARD_FAB2_LIB.BASEBOARD_FAB2(SCH_1):M_M_DQS_DN(11)   I187 @BASEBOARD_FAB2_LIB.BASEBOARD_FAB2(SCH_1):PAGE87
    29 M_M_DQS_DP<11> @BASEBOARD_FAB2_LIB.BASEBOARD_FAB2(SCH_1):M_M_DQS_DP(11)   I187 @BASEBOARD_FAB2_LIB.BASEBOARD_FAB2(SCH_1):PAGE87
    41 M_M_DQS_DN<12> @BASEBOARD_FAB2_LIB.BASEBOARD_FAB2(SCH_1):M_M_DQS_DN(12)   I187 @BASEBOARD_FAB2_LIB.BASEBOARD_FAB2(SCH_1):PAGE87
    40 M_M_DQS_DP<12> @BASEBOARD_FAB2_LIB.BASEBOARD_FAB2(SCH_1):M_M_DQS_DP(12)   I187 @BASEBOARD_FAB2_LIB.BASEBOARD_FAB2(SCH_1):PAGE87
   100 M_M_DQS_DN<13> @BASEBOARD_FAB2_LIB.BASEBOARD_FAB2(SCH_1):M_M_DQS_DN(13)   I187 @BASEBOARD_FAB2_LIB.BASEBOARD_FAB2(SCH_1):PAGE87
    99 M_M_DQS_DP<13> @BASEBOARD_FAB2_LIB.BASEBOARD_FAB2(SCH_1):M_M_DQS_DP(13)   I187 @BASEBOARD_FAB2_LIB.BASEBOARD_FAB2(SCH_1):PAGE87
   111 M_M_DQS_DN<14> @BASEBOARD_FAB2_LIB.BASEBOARD_FAB2(SCH_1):M_M_DQS_DN(14)   I187 @BASEBOARD_FAB2_LIB.BASEBOARD_FAB2(SCH_1):PAGE87
   110 M_M_DQS_DP<14> @BASEBOARD_FAB2_LIB.BASEBOARD_FAB2(SCH_1):M_M_DQS_DP(14)   I187 @BASEBOARD_FAB2_LIB.BASEBOARD_FAB2(SCH_1):PAGE87
   122 M_M_DQS_DN<15> @BASEBOARD_FAB2_LIB.BASEBOARD_FAB2(SCH_1):M_M_DQS_DN(15)   I187 @BASEBOARD_FAB2_LIB.BASEBOARD_FAB2(SCH_1):PAGE87
   121 M_M_DQS_DP<15> @BASEBOARD_FAB2_LIB.BASEBOARD_FAB2(SCH_1):M_M_DQS_DP(15)   I187 @BASEBOARD_FAB2_LIB.BASEBOARD_FAB2(SCH_1):PAGE87
   133 M_M_DQS_DN<16> @BASEBOARD_FAB2_LIB.BASEBOARD_FAB2(SCH_1):M_M_DQS_DN(16)   I187 @BASEBOARD_FAB2_LIB.BASEBOARD_FAB2(SCH_1):PAGE87
   132 M_M_DQS_DP<16> @BASEBOARD_FAB2_LIB.BASEBOARD_FAB2(SCH_1):M_M_DQS_DP(16)   I187 @BASEBOARD_FAB2_LIB.BASEBOARD_FAB2(SCH_1):PAGE87
    52 M_M_DQS_DN<17> @BASEBOARD_FAB2_LIB.BASEBOARD_FAB2(SCH_1):M_M_DQS_DN(17)   I187 @BASEBOARD_FAB2_LIB.BASEBOARD_FAB2(SCH_1):PAGE87
    51 M_M_DQS_DP<17> @BASEBOARD_FAB2_LIB.BASEBOARD_FAB2(SCH_1):M_M_DQS_DP(17)   I187 @BASEBOARD_FAB2_LIB.BASEBOARD_FAB2(SCH_1):PAGE87
   163 M_M_DQS_DN<1> @BASEBOARD_FAB2_LIB.BASEBOARD_FAB2(SCH_1):M_M_DQS_DN(1)   I187 @BASEBOARD_FAB2_LIB.BASEBOARD_FAB2(SCH_1):PAGE87
   164 M_M_DQS_DP<1> @BASEBOARD_FAB2_LIB.BASEBOARD_FAB2(SCH_1):M_M_DQS_DP(1)   I187 @BASEBOARD_FAB2_LIB.BASEBOARD_FAB2(SCH_1):PAGE87
   174 M_M_DQS_DN<2> @BASEBOARD_FAB2_LIB.BASEBOARD_FAB2(SCH_1):M_M_DQS_DN(2)   I187 @BASEBOARD_FAB2_LIB.BASEBOARD_FAB2(SCH_1):PAGE87
   175 M_M_DQS_DP<2> @BASEBOARD_FAB2_LIB.BASEBOARD_FAB2(SCH_1):M_M_DQS_DP(2)   I187 @BASEBOARD_FAB2_LIB.BASEBOARD_FAB2(SCH_1):PAGE87
   185 M_M_DQS_DN<3> @BASEBOARD_FAB2_LIB.BASEBOARD_FAB2(SCH_1):M_M_DQS_DN(3)   I187 @BASEBOARD_FAB2_LIB.BASEBOARD_FAB2(SCH_1):PAGE87
   186 M_M_DQS_DP<3> @BASEBOARD_FAB2_LIB.BASEBOARD_FAB2(SCH_1):M_M_DQS_DP(3)   I187 @BASEBOARD_FAB2_LIB.BASEBOARD_FAB2(SCH_1):PAGE87
   244 M_M_DQS_DN<4> @BASEBOARD_FAB2_LIB.BASEBOARD_FAB2(SCH_1):M_M_DQS_DN(4)   I187 @BASEBOARD_FAB2_LIB.BASEBOARD_FAB2(SCH_1):PAGE87
   245 M_M_DQS_DP<4> @BASEBOARD_FAB2_LIB.BASEBOARD_FAB2(SCH_1):M_M_DQS_DP(4)   I187 @BASEBOARD_FAB2_LIB.BASEBOARD_FAB2(SCH_1):PAGE87
   255 M_M_DQS_DN<5> @BASEBOARD_FAB2_LIB.BASEBOARD_FAB2(SCH_1):M_M_DQS_DN(5)   I187 @BASEBOARD_FAB2_LIB.BASEBOARD_FAB2(SCH_1):PAGE87
   256 M_M_DQS_DP<5> @BASEBOARD_FAB2_LIB.BASEBOARD_FAB2(SCH_1):M_M_DQS_DP(5)   I187 @BASEBOARD_FAB2_LIB.BASEBOARD_FAB2(SCH_1):PAGE87
   266 M_M_DQS_DN<6> @BASEBOARD_FAB2_LIB.BASEBOARD_FAB2(SCH_1):M_M_DQS_DN(6)   I187 @BASEBOARD_FAB2_LIB.BASEBOARD_FAB2(SCH_1):PAGE87
   267 M_M_DQS_DP<6> @BASEBOARD_FAB2_LIB.BASEBOARD_FAB2(SCH_1):M_M_DQS_DP(6)   I187 @BASEBOARD_FAB2_LIB.BASEBOARD_FAB2(SCH_1):PAGE87
   277 M_M_DQS_DN<7> @BASEBOARD_FAB2_LIB.BASEBOARD_FAB2(SCH_1):M_M_DQS_DN(7)   I187 @BASEBOARD_FAB2_LIB.BASEBOARD_FAB2(SCH_1):PAGE87
   278 M_M_DQS_DP<7> @BASEBOARD_FAB2_LIB.BASEBOARD_FAB2(SCH_1):M_M_DQS_DP(7)   I187 @BASEBOARD_FAB2_LIB.BASEBOARD_FAB2(SCH_1):PAGE87
   196 M_M_DQS_DN<8> @BASEBOARD_FAB2_LIB.BASEBOARD_FAB2(SCH_1):M_M_DQS_DN(8)   I187 @BASEBOARD_FAB2_LIB.BASEBOARD_FAB2(SCH_1):PAGE87
   197 M_M_DQS_DP<8> @BASEBOARD_FAB2_LIB.BASEBOARD_FAB2(SCH_1):M_M_DQS_DP(8)   I187 @BASEBOARD_FAB2_LIB.BASEBOARD_FAB2(SCH_1):PAGE87
     8 M_M_DQS_DN<9> @BASEBOARD_FAB2_LIB.BASEBOARD_FAB2(SCH_1):M_M_DQS_DN(9)   I187 @BASEBOARD_FAB2_LIB.BASEBOARD_FAB2(SCH_1):PAGE87
     7 M_M_DQS_DP<9> @BASEBOARD_FAB2_LIB.BASEBOARD_FAB2(SCH_1):M_M_DQS_DP(9)   I187 @BASEBOARD_FAB2_LIB.BASEBOARD_FAB2(SCH_1):PAGE87
     2    GND @BASEBOARD_FAB2_LIB.BASEBOARD_FAB2(SCH_1):GND   I185 @BASEBOARD_FAB2_LIB.BASEBOARD_FAB2(SCH_1):PAGE87
     4    GND @BASEBOARD_FAB2_LIB.BASEBOARD_FAB2(SCH_1):GND   I185 @BASEBOARD_FAB2_LIB.BASEBOARD_FAB2(SCH_1):PAGE87
     6    GND @BASEBOARD_FAB2_LIB.BASEBOARD_FAB2(SCH_1):GND   I185 @BASEBOARD_FAB2_LIB.BASEBOARD_FAB2(SCH_1):PAGE87
     9    GND @BASEBOARD_FAB2_LIB.BASEBOARD_FAB2(SCH_1):GND   I185 @BASEBOARD_FAB2_LIB.BASEBOARD_FAB2(SCH_1):PAGE87
    11    GND @BASEBOARD_FAB2_LIB.BASEBOARD_FAB2(SCH_1):GND   I185 @BASEBOARD_FAB2_LIB.BASEBOARD_FAB2(SCH_1):PAGE87
    13    GND @BASEBOARD_FAB2_LIB.BASEBOARD_FAB2(SCH_1):GND   I185 @BASEBOARD_FAB2_LIB.BASEBOARD_FAB2(SCH_1):PAGE87
    15    GND @BASEBOARD_FAB2_LIB.BASEBOARD_FAB2(SCH_1):GND   I185 @BASEBOARD_FAB2_LIB.BASEBOARD_FAB2(SCH_1):PAGE87
    17    GND @BASEBOARD_FAB2_LIB.BASEBOARD_FAB2(SCH_1):GND   I185 @BASEBOARD_FAB2_LIB.BASEBOARD_FAB2(SCH_1):PAGE87
    20    GND @BASEBOARD_FAB2_LIB.BASEBOARD_FAB2(SCH_1):GND   I185 @BASEBOARD_FAB2_LIB.BASEBOARD_FAB2(SCH_1):PAGE87
    22    GND @BASEBOARD_FAB2_LIB.BASEBOARD_FAB2(SCH_1):GND   I185 @BASEBOARD_FAB2_LIB.BASEBOARD_FAB2(SCH_1):PAGE87
    24    GND @BASEBOARD_FAB2_LIB.BASEBOARD_FAB2(SCH_1):GND   I185 @BASEBOARD_FAB2_LIB.BASEBOARD_FAB2(SCH_1):PAGE87
    26    GND @BASEBOARD_FAB2_LIB.BASEBOARD_FAB2(SCH_1):GND   I185 @BASEBOARD_FAB2_LIB.BASEBOARD_FAB2(SCH_1):PAGE87
    28    GND @BASEBOARD_FAB2_LIB.BASEBOARD_FAB2(SCH_1):GND   I185 @BASEBOARD_FAB2_LIB.BASEBOARD_FAB2(SCH_1):PAGE87
    31    GND @BASEBOARD_FAB2_LIB.BASEBOARD_FAB2(SCH_1):GND   I185 @BASEBOARD_FAB2_LIB.BASEBOARD_FAB2(SCH_1):PAGE87
    33    GND @BASEBOARD_FAB2_LIB.BASEBOARD_FAB2(SCH_1):GND   I185 @BASEBOARD_FAB2_LIB.BASEBOARD_FAB2(SCH_1):PAGE87
    35    GND @BASEBOARD_FAB2_LIB.BASEBOARD_FAB2(SCH_1):GND   I185 @BASEBOARD_FAB2_LIB.BASEBOARD_FAB2(SCH_1):PAGE87
    37    GND @BASEBOARD_FAB2_LIB.BASEBOARD_FAB2(SCH_1):GND   I185 @BASEBOARD_FAB2_LIB.BASEBOARD_FAB2(SCH_1):PAGE87
    39    GND @BASEBOARD_FAB2_LIB.BASEBOARD_FAB2(SCH_1):GND   I185 @BASEBOARD_FAB2_LIB.BASEBOARD_FAB2(SCH_1):PAGE87
    42    GND @BASEBOARD_FAB2_LIB.BASEBOARD_FAB2(SCH_1):GND   I185 @BASEBOARD_FAB2_LIB.BASEBOARD_FAB2(SCH_1):PAGE87
    44    GND @BASEBOARD_FAB2_LIB.BASEBOARD_FAB2(SCH_1):GND   I185 @BASEBOARD_FAB2_LIB.BASEBOARD_FAB2(SCH_1):PAGE87
    46    GND @BASEBOARD_FAB2_LIB.BASEBOARD_FAB2(SCH_1):GND   I185 @BASEBOARD_FAB2_LIB.BASEBOARD_FAB2(SCH_1):PAGE87
    48    GND @BASEBOARD_FAB2_LIB.BASEBOARD_FAB2(SCH_1):GND   I185 @BASEBOARD_FAB2_LIB.BASEBOARD_FAB2(SCH_1):PAGE87
    50    GND @BASEBOARD_FAB2_LIB.BASEBOARD_FAB2(SCH_1):GND   I185 @BASEBOARD_FAB2_LIB.BASEBOARD_FAB2(SCH_1):PAGE87
    53    GND @BASEBOARD_FAB2_LIB.BASEBOARD_FAB2(SCH_1):GND   I185 @BASEBOARD_FAB2_LIB.BASEBOARD_FAB2(SCH_1):PAGE87
    55    GND @BASEBOARD_FAB2_LIB.BASEBOARD_FAB2(SCH_1):GND   I185 @BASEBOARD_FAB2_LIB.BASEBOARD_FAB2(SCH_1):PAGE87
    57    GND @BASEBOARD_FAB2_LIB.BASEBOARD_FAB2(SCH_1):GND   I185 @BASEBOARD_FAB2_LIB.BASEBOARD_FAB2(SCH_1):PAGE87
    94    GND @BASEBOARD_FAB2_LIB.BASEBOARD_FAB2(SCH_1):GND   I185 @BASEBOARD_FAB2_LIB.BASEBOARD_FAB2(SCH_1):PAGE87
    96    GND @BASEBOARD_FAB2_LIB.BASEBOARD_FAB2(SCH_1):GND   I185 @BASEBOARD_FAB2_LIB.BASEBOARD_FAB2(SCH_1):PAGE87
    98    GND @BASEBOARD_FAB2_LIB.BASEBOARD_FAB2(SCH_1):GND   I185 @BASEBOARD_FAB2_LIB.BASEBOARD_FAB2(SCH_1):PAGE87
   101    GND @BASEBOARD_FAB2_LIB.BASEBOARD_FAB2(SCH_1):GND   I185 @BASEBOARD_FAB2_LIB.BASEBOARD_FAB2(SCH_1):PAGE87
   103    GND @BASEBOARD_FAB2_LIB.BASEBOARD_FAB2(SCH_1):GND   I185 @BASEBOARD_FAB2_LIB.BASEBOARD_FAB2(SCH_1):PAGE87
   105    GND @BASEBOARD_FAB2_LIB.BASEBOARD_FAB2(SCH_1):GND   I185 @BASEBOARD_FAB2_LIB.BASEBOARD_FAB2(SCH_1):PAGE87
   107    GND @BASEBOARD_FAB2_LIB.BASEBOARD_FAB2(SCH_1):GND   I185 @BASEBOARD_FAB2_LIB.BASEBOARD_FAB2(SCH_1):PAGE87
   109    GND @BASEBOARD_FAB2_LIB.BASEBOARD_FAB2(SCH_1):GND   I185 @BASEBOARD_FAB2_LIB.BASEBOARD_FAB2(SCH_1):PAGE87
   112    GND @BASEBOARD_FAB2_LIB.BASEBOARD_FAB2(SCH_1):GND   I185 @BASEBOARD_FAB2_LIB.BASEBOARD_FAB2(SCH_1):PAGE87
   114    GND @BASEBOARD_FAB2_LIB.BASEBOARD_FAB2(SCH_1):GND   I185 @BASEBOARD_FAB2_LIB.BASEBOARD_FAB2(SCH_1):PAGE87
   116    GND @BASEBOARD_FAB2_LIB.BASEBOARD_FAB2(SCH_1):GND   I185 @BASEBOARD_FAB2_LIB.BASEBOARD_FAB2(SCH_1):PAGE87
   118    GND @BASEBOARD_FAB2_LIB.BASEBOARD_FAB2(SCH_1):GND   I185 @BASEBOARD_FAB2_LIB.BASEBOARD_FAB2(SCH_1):PAGE87
   120    GND @BASEBOARD_FAB2_LIB.BASEBOARD_FAB2(SCH_1):GND   I185 @BASEBOARD_FAB2_LIB.BASEBOARD_FAB2(SCH_1):PAGE87
   123    GND @BASEBOARD_FAB2_LIB.BASEBOARD_FAB2(SCH_1):GND   I185 @BASEBOARD_FAB2_LIB.BASEBOARD_FAB2(SCH_1):PAGE87
   125    GND @BASEBOARD_FAB2_LIB.BASEBOARD_FAB2(SCH_1):GND   I185 @BASEBOARD_FAB2_LIB.BASEBOARD_FAB2(SCH_1):PAGE87
   127    GND @BASEBOARD_FAB2_LIB.BASEBOARD_FAB2(SCH_1):GND   I185 @BASEBOARD_FAB2_LIB.BASEBOARD_FAB2(SCH_1):PAGE87
   129    GND @BASEBOARD_FAB2_LIB.BASEBOARD_FAB2(SCH_1):GND   I185 @BASEBOARD_FAB2_LIB.BASEBOARD_FAB2(SCH_1):PAGE87
   131    GND @BASEBOARD_FAB2_LIB.BASEBOARD_FAB2(SCH_1):GND   I185 @BASEBOARD_FAB2_LIB.BASEBOARD_FAB2(SCH_1):PAGE87
   134    GND @BASEBOARD_FAB2_LIB.BASEBOARD_FAB2(SCH_1):GND   I185 @BASEBOARD_FAB2_LIB.BASEBOARD_FAB2(SCH_1):PAGE87
   136    GND @BASEBOARD_FAB2_LIB.BASEBOARD_FAB2(SCH_1):GND   I185 @BASEBOARD_FAB2_LIB.BASEBOARD_FAB2(SCH_1):PAGE87
   138    GND @BASEBOARD_FAB2_LIB.BASEBOARD_FAB2(SCH_1):GND   I185 @BASEBOARD_FAB2_LIB.BASEBOARD_FAB2(SCH_1):PAGE87
   147    GND @BASEBOARD_FAB2_LIB.BASEBOARD_FAB2(SCH_1):GND   I185 @BASEBOARD_FAB2_LIB.BASEBOARD_FAB2(SCH_1):PAGE87
   149    GND @BASEBOARD_FAB2_LIB.BASEBOARD_FAB2(SCH_1):GND   I185 @BASEBOARD_FAB2_LIB.BASEBOARD_FAB2(SCH_1):PAGE87
   151    GND @BASEBOARD_FAB2_LIB.BASEBOARD_FAB2(SCH_1):GND   I185 @BASEBOARD_FAB2_LIB.BASEBOARD_FAB2(SCH_1):PAGE87
   154    GND @BASEBOARD_FAB2_LIB.BASEBOARD_FAB2(SCH_1):GND   I185 @BASEBOARD_FAB2_LIB.BASEBOARD_FAB2(SCH_1):PAGE87
   156    GND @BASEBOARD_FAB2_LIB.BASEBOARD_FAB2(SCH_1):GND   I185 @BASEBOARD_FAB2_LIB.BASEBOARD_FAB2(SCH_1):PAGE87
   158    GND @BASEBOARD_FAB2_LIB.BASEBOARD_FAB2(SCH_1):GND   I185 @BASEBOARD_FAB2_LIB.BASEBOARD_FAB2(SCH_1):PAGE87
   160    GND @BASEBOARD_FAB2_LIB.BASEBOARD_FAB2(SCH_1):GND   I185 @BASEBOARD_FAB2_LIB.BASEBOARD_FAB2(SCH_1):PAGE87
   162    GND @BASEBOARD_FAB2_LIB.BASEBOARD_FAB2(SCH_1):GND   I185 @BASEBOARD_FAB2_LIB.BASEBOARD_FAB2(SCH_1):PAGE87
   165    GND @BASEBOARD_FAB2_LIB.BASEBOARD_FAB2(SCH_1):GND   I185 @BASEBOARD_FAB2_LIB.BASEBOARD_FAB2(SCH_1):PAGE87
   167    GND @BASEBOARD_FAB2_LIB.BASEBOARD_FAB2(SCH_1):GND   I185 @BASEBOARD_FAB2_LIB.BASEBOARD_FAB2(SCH_1):PAGE87
   169    GND @BASEBOARD_FAB2_LIB.BASEBOARD_FAB2(SCH_1):GND   I185 @BASEBOARD_FAB2_LIB.BASEBOARD_FAB2(SCH_1):PAGE87
   171    GND @BASEBOARD_FAB2_LIB.BASEBOARD_FAB2(SCH_1):GND   I185 @BASEBOARD_FAB2_LIB.BASEBOARD_FAB2(SCH_1):PAGE87
   173    GND @BASEBOARD_FAB2_LIB.BASEBOARD_FAB2(SCH_1):GND   I185 @BASEBOARD_FAB2_LIB.BASEBOARD_FAB2(SCH_1):PAGE87
   176    GND @BASEBOARD_FAB2_LIB.BASEBOARD_FAB2(SCH_1):GND   I185 @BASEBOARD_FAB2_LIB.BASEBOARD_FAB2(SCH_1):PAGE87
   178    GND @BASEBOARD_FAB2_LIB.BASEBOARD_FAB2(SCH_1):GND   I185 @BASEBOARD_FAB2_LIB.BASEBOARD_FAB2(SCH_1):PAGE87
   180    GND @BASEBOARD_FAB2_LIB.BASEBOARD_FAB2(SCH_1):GND   I185 @BASEBOARD_FAB2_LIB.BASEBOARD_FAB2(SCH_1):PAGE87
   182    GND @BASEBOARD_FAB2_LIB.BASEBOARD_FAB2(SCH_1):GND   I185 @BASEBOARD_FAB2_LIB.BASEBOARD_FAB2(SCH_1):PAGE87
   184    GND @BASEBOARD_FAB2_LIB.BASEBOARD_FAB2(SCH_1):GND   I185 @BASEBOARD_FAB2_LIB.BASEBOARD_FAB2(SCH_1):PAGE87
   187    GND @BASEBOARD_FAB2_LIB.BASEBOARD_FAB2(SCH_1):GND   I185 @BASEBOARD_FAB2_LIB.BASEBOARD_FAB2(SCH_1):PAGE87
   189    GND @BASEBOARD_FAB2_LIB.BASEBOARD_FAB2(SCH_1):GND   I185 @BASEBOARD_FAB2_LIB.BASEBOARD_FAB2(SCH_1):PAGE87
   191    GND @BASEBOARD_FAB2_LIB.BASEBOARD_FAB2(SCH_1):GND   I185 @BASEBOARD_FAB2_LIB.BASEBOARD_FAB2(SCH_1):PAGE87
   193    GND @BASEBOARD_FAB2_LIB.BASEBOARD_FAB2(SCH_1):GND   I185 @BASEBOARD_FAB2_LIB.BASEBOARD_FAB2(SCH_1):PAGE87
   195    GND @BASEBOARD_FAB2_LIB.BASEBOARD_FAB2(SCH_1):GND   I185 @BASEBOARD_FAB2_LIB.BASEBOARD_FAB2(SCH_1):PAGE87
   198    GND @BASEBOARD_FAB2_LIB.BASEBOARD_FAB2(SCH_1):GND   I185 @BASEBOARD_FAB2_LIB.BASEBOARD_FAB2(SCH_1):PAGE87
   200    GND @BASEBOARD_FAB2_LIB.BASEBOARD_FAB2(SCH_1):GND   I185 @BASEBOARD_FAB2_LIB.BASEBOARD_FAB2(SCH_1):PAGE87
   202    GND @BASEBOARD_FAB2_LIB.BASEBOARD_FAB2(SCH_1):GND   I185 @BASEBOARD_FAB2_LIB.BASEBOARD_FAB2(SCH_1):PAGE87
   239    GND @BASEBOARD_FAB2_LIB.BASEBOARD_FAB2(SCH_1):GND   I185 @BASEBOARD_FAB2_LIB.BASEBOARD_FAB2(SCH_1):PAGE87
   241    GND @BASEBOARD_FAB2_LIB.BASEBOARD_FAB2(SCH_1):GND   I185 @BASEBOARD_FAB2_LIB.BASEBOARD_FAB2(SCH_1):PAGE87
   243    GND @BASEBOARD_FAB2_LIB.BASEBOARD_FAB2(SCH_1):GND   I185 @BASEBOARD_FAB2_LIB.BASEBOARD_FAB2(SCH_1):PAGE87
   246    GND @BASEBOARD_FAB2_LIB.BASEBOARD_FAB2(SCH_1):GND   I185 @BASEBOARD_FAB2_LIB.BASEBOARD_FAB2(SCH_1):PAGE87
   248    GND @BASEBOARD_FAB2_LIB.BASEBOARD_FAB2(SCH_1):GND   I185 @BASEBOARD_FAB2_LIB.BASEBOARD_FAB2(SCH_1):PAGE87
   250    GND @BASEBOARD_FAB2_LIB.BASEBOARD_FAB2(SCH_1):GND   I185 @BASEBOARD_FAB2_LIB.BASEBOARD_FAB2(SCH_1):PAGE87
   252    GND @BASEBOARD_FAB2_LIB.BASEBOARD_FAB2(SCH_1):GND   I185 @BASEBOARD_FAB2_LIB.BASEBOARD_FAB2(SCH_1):PAGE87
   254    GND @BASEBOARD_FAB2_LIB.BASEBOARD_FAB2(SCH_1):GND   I185 @BASEBOARD_FAB2_LIB.BASEBOARD_FAB2(SCH_1):PAGE87
   257    GND @BASEBOARD_FAB2_LIB.BASEBOARD_FAB2(SCH_1):GND   I185 @BASEBOARD_FAB2_LIB.BASEBOARD_FAB2(SCH_1):PAGE87
   259    GND @BASEBOARD_FAB2_LIB.BASEBOARD_FAB2(SCH_1):GND   I185 @BASEBOARD_FAB2_LIB.BASEBOARD_FAB2(SCH_1):PAGE87
   261    GND @BASEBOARD_FAB2_LIB.BASEBOARD_FAB2(SCH_1):GND   I185 @BASEBOARD_FAB2_LIB.BASEBOARD_FAB2(SCH_1):PAGE87
   263    GND @BASEBOARD_FAB2_LIB.BASEBOARD_FAB2(SCH_1):GND   I185 @BASEBOARD_FAB2_LIB.BASEBOARD_FAB2(SCH_1):PAGE87
   265    GND @BASEBOARD_FAB2_LIB.BASEBOARD_FAB2(SCH_1):GND   I185 @BASEBOARD_FAB2_LIB.BASEBOARD_FAB2(SCH_1):PAGE87
   268    GND @BASEBOARD_FAB2_LIB.BASEBOARD_FAB2(SCH_1):GND   I185 @BASEBOARD_FAB2_LIB.BASEBOARD_FAB2(SCH_1):PAGE87
   270    GND @BASEBOARD_FAB2_LIB.BASEBOARD_FAB2(SCH_1):GND   I185 @BASEBOARD_FAB2_LIB.BASEBOARD_FAB2(SCH_1):PAGE87
   272    GND @BASEBOARD_FAB2_LIB.BASEBOARD_FAB2(SCH_1):GND   I185 @BASEBOARD_FAB2_LIB.BASEBOARD_FAB2(SCH_1):PAGE87
   274    GND @BASEBOARD_FAB2_LIB.BASEBOARD_FAB2(SCH_1):GND   I185 @BASEBOARD_FAB2_LIB.BASEBOARD_FAB2(SCH_1):PAGE87
   276    GND @BASEBOARD_FAB2_LIB.BASEBOARD_FAB2(SCH_1):GND   I185 @BASEBOARD_FAB2_LIB.BASEBOARD_FAB2(SCH_1):PAGE87
   279    GND @BASEBOARD_FAB2_LIB.BASEBOARD_FAB2(SCH_1):GND   I185 @BASEBOARD_FAB2_LIB.BASEBOARD_FAB2(SCH_1):PAGE87
   281    GND @BASEBOARD_FAB2_LIB.BASEBOARD_FAB2(SCH_1):GND   I185 @BASEBOARD_FAB2_LIB.BASEBOARD_FAB2(SCH_1):PAGE87
   283    GND @BASEBOARD_FAB2_LIB.BASEBOARD_FAB2(SCH_1):GND   I185 @BASEBOARD_FAB2_LIB.BASEBOARD_FAB2(SCH_1):PAGE87
     1 P12V_NVDIMM_KLM @BASEBOARD_FAB2_LIB.BASEBOARD_FAB2(SCH_1):P12V_NVDIMM_KLM   I169 @BASEBOARD_FAB2_LIB.BASEBOARD_FAB2(SCH_1):PAGE87
   145 P12V_NVDIMM_KLM @BASEBOARD_FAB2_LIB.BASEBOARD_FAB2(SCH_1):P12V_NVDIMM_KLM   I169 @BASEBOARD_FAB2_LIB.BASEBOARD_FAB2(SCH_1):PAGE87
    59 PVDDQ_KLM @BASEBOARD_FAB2_LIB.BASEBOARD_FAB2(SCH_1):PVDDQ_KLM   I169 @BASEBOARD_FAB2_LIB.BASEBOARD_FAB2(SCH_1):PAGE87
    61 PVDDQ_KLM @BASEBOARD_FAB2_LIB.BASEBOARD_FAB2(SCH_1):PVDDQ_KLM   I169 @BASEBOARD_FAB2_LIB.BASEBOARD_FAB2(SCH_1):PAGE87
    64 PVDDQ_KLM @BASEBOARD_FAB2_LIB.BASEBOARD_FAB2(SCH_1):PVDDQ_KLM   I169 @BASEBOARD_FAB2_LIB.BASEBOARD_FAB2(SCH_1):PAGE87
    67 PVDDQ_KLM @BASEBOARD_FAB2_LIB.BASEBOARD_FAB2(SCH_1):PVDDQ_KLM   I169 @BASEBOARD_FAB2_LIB.BASEBOARD_FAB2(SCH_1):PAGE87
    70 PVDDQ_KLM @BASEBOARD_FAB2_LIB.BASEBOARD_FAB2(SCH_1):PVDDQ_KLM   I169 @BASEBOARD_FAB2_LIB.BASEBOARD_FAB2(SCH_1):PAGE87
    73 PVDDQ_KLM @BASEBOARD_FAB2_LIB.BASEBOARD_FAB2(SCH_1):PVDDQ_KLM   I169 @BASEBOARD_FAB2_LIB.BASEBOARD_FAB2(SCH_1):PAGE87
    76 PVDDQ_KLM @BASEBOARD_FAB2_LIB.BASEBOARD_FAB2(SCH_1):PVDDQ_KLM   I169 @BASEBOARD_FAB2_LIB.BASEBOARD_FAB2(SCH_1):PAGE87
    80 PVDDQ_KLM @BASEBOARD_FAB2_LIB.BASEBOARD_FAB2(SCH_1):PVDDQ_KLM   I169 @BASEBOARD_FAB2_LIB.BASEBOARD_FAB2(SCH_1):PAGE87
    83 PVDDQ_KLM @BASEBOARD_FAB2_LIB.BASEBOARD_FAB2(SCH_1):PVDDQ_KLM   I169 @BASEBOARD_FAB2_LIB.BASEBOARD_FAB2(SCH_1):PAGE87
    85 PVDDQ_KLM @BASEBOARD_FAB2_LIB.BASEBOARD_FAB2(SCH_1):PVDDQ_KLM   I169 @BASEBOARD_FAB2_LIB.BASEBOARD_FAB2(SCH_1):PAGE87
    88 PVDDQ_KLM @BASEBOARD_FAB2_LIB.BASEBOARD_FAB2(SCH_1):PVDDQ_KLM   I169 @BASEBOARD_FAB2_LIB.BASEBOARD_FAB2(SCH_1):PAGE87
    90 PVDDQ_KLM @BASEBOARD_FAB2_LIB.BASEBOARD_FAB2(SCH_1):PVDDQ_KLM   I169 @BASEBOARD_FAB2_LIB.BASEBOARD_FAB2(SCH_1):PAGE87
    92 PVDDQ_KLM @BASEBOARD_FAB2_LIB.BASEBOARD_FAB2(SCH_1):PVDDQ_KLM   I169 @BASEBOARD_FAB2_LIB.BASEBOARD_FAB2(SCH_1):PAGE87
   204 PVDDQ_KLM @BASEBOARD_FAB2_LIB.BASEBOARD_FAB2(SCH_1):PVDDQ_KLM   I169 @BASEBOARD_FAB2_LIB.BASEBOARD_FAB2(SCH_1):PAGE87
   206 PVDDQ_KLM @BASEBOARD_FAB2_LIB.BASEBOARD_FAB2(SCH_1):PVDDQ_KLM   I169 @BASEBOARD_FAB2_LIB.BASEBOARD_FAB2(SCH_1):PAGE87
   209 PVDDQ_KLM @BASEBOARD_FAB2_LIB.BASEBOARD_FAB2(SCH_1):PVDDQ_KLM   I169 @BASEBOARD_FAB2_LIB.BASEBOARD_FAB2(SCH_1):PAGE87
   212 PVDDQ_KLM @BASEBOARD_FAB2_LIB.BASEBOARD_FAB2(SCH_1):PVDDQ_KLM   I169 @BASEBOARD_FAB2_LIB.BASEBOARD_FAB2(SCH_1):PAGE87
   215 PVDDQ_KLM @BASEBOARD_FAB2_LIB.BASEBOARD_FAB2(SCH_1):PVDDQ_KLM   I169 @BASEBOARD_FAB2_LIB.BASEBOARD_FAB2(SCH_1):PAGE87
   217 PVDDQ_KLM @BASEBOARD_FAB2_LIB.BASEBOARD_FAB2(SCH_1):PVDDQ_KLM   I169 @BASEBOARD_FAB2_LIB.BASEBOARD_FAB2(SCH_1):PAGE87
   220 PVDDQ_KLM @BASEBOARD_FAB2_LIB.BASEBOARD_FAB2(SCH_1):PVDDQ_KLM   I169 @BASEBOARD_FAB2_LIB.BASEBOARD_FAB2(SCH_1):PAGE87
   223 PVDDQ_KLM @BASEBOARD_FAB2_LIB.BASEBOARD_FAB2(SCH_1):PVDDQ_KLM   I169 @BASEBOARD_FAB2_LIB.BASEBOARD_FAB2(SCH_1):PAGE87
   226 PVDDQ_KLM @BASEBOARD_FAB2_LIB.BASEBOARD_FAB2(SCH_1):PVDDQ_KLM   I169 @BASEBOARD_FAB2_LIB.BASEBOARD_FAB2(SCH_1):PAGE87
   229 PVDDQ_KLM @BASEBOARD_FAB2_LIB.BASEBOARD_FAB2(SCH_1):PVDDQ_KLM   I169 @BASEBOARD_FAB2_LIB.BASEBOARD_FAB2(SCH_1):PAGE87
   231 PVDDQ_KLM @BASEBOARD_FAB2_LIB.BASEBOARD_FAB2(SCH_1):PVDDQ_KLM   I169 @BASEBOARD_FAB2_LIB.BASEBOARD_FAB2(SCH_1):PAGE87
   233 PVDDQ_KLM @BASEBOARD_FAB2_LIB.BASEBOARD_FAB2(SCH_1):PVDDQ_KLM   I169 @BASEBOARD_FAB2_LIB.BASEBOARD_FAB2(SCH_1):PAGE87
   236 PVDDQ_KLM @BASEBOARD_FAB2_LIB.BASEBOARD_FAB2(SCH_1):PVDDQ_KLM   I169 @BASEBOARD_FAB2_LIB.BASEBOARD_FAB2(SCH_1):PAGE87
   142 PVPP_KLM @BASEBOARD_FAB2_LIB.BASEBOARD_FAB2(SCH_1):PVPP_KLM   I169 @BASEBOARD_FAB2_LIB.BASEBOARD_FAB2(SCH_1):PAGE87
   143 PVPP_KLM @BASEBOARD_FAB2_LIB.BASEBOARD_FAB2(SCH_1):PVPP_KLM   I169 @BASEBOARD_FAB2_LIB.BASEBOARD_FAB2(SCH_1):PAGE87
   288 PVPP_KLM @BASEBOARD_FAB2_LIB.BASEBOARD_FAB2(SCH_1):PVPP_KLM   I169 @BASEBOARD_FAB2_LIB.BASEBOARD_FAB2(SCH_1):PAGE87
   286 PVPP_KLM @BASEBOARD_FAB2_LIB.BASEBOARD_FAB2(SCH_1):PVPP_KLM   I169 @BASEBOARD_FAB2_LIB.BASEBOARD_FAB2(SCH_1):PAGE87
   287 PVPP_KLM @BASEBOARD_FAB2_LIB.BASEBOARD_FAB2(SCH_1):PVPP_KLM   I169 @BASEBOARD_FAB2_LIB.BASEBOARD_FAB2(SCH_1):PAGE87
    77 PVTT_KLM @BASEBOARD_FAB2_LIB.BASEBOARD_FAB2(SCH_1):PVTT_KLM   I169 @BASEBOARD_FAB2_LIB.BASEBOARD_FAB2(SCH_1):PAGE87
   221 PVTT_KLM @BASEBOARD_FAB2_LIB.BASEBOARD_FAB2(SCH_1):PVTT_KLM   I169 @BASEBOARD_FAB2_LIB.BASEBOARD_FAB2(SCH_1):PAGE87

J1A2 SCONN288_H44441004_PIP-SCONN,HA
    79 M_L_MA<0> @BASEBOARD_FAB2_LIB.BASEBOARD_FAB2(SCH_1):M_L_MA(0)   I111 @BASEBOARD_FAB2_LIB.BASEBOARD_FAB2(SCH_1):PAGE85
    72 M_L_MA<1> @BASEBOARD_FAB2_LIB.BASEBOARD_FAB2(SCH_1):M_L_MA(1)   I111 @BASEBOARD_FAB2_LIB.BASEBOARD_FAB2(SCH_1):PAGE85
   225 M_L_MA<10> @BASEBOARD_FAB2_LIB.BASEBOARD_FAB2(SCH_1):M_L_MA(10)   I111 @BASEBOARD_FAB2_LIB.BASEBOARD_FAB2(SCH_1):PAGE85
   210 M_L_MA<11> @BASEBOARD_FAB2_LIB.BASEBOARD_FAB2(SCH_1):M_L_MA(11)   I111 @BASEBOARD_FAB2_LIB.BASEBOARD_FAB2(SCH_1):PAGE85
    65 M_L_MA<12> @BASEBOARD_FAB2_LIB.BASEBOARD_FAB2(SCH_1):M_L_MA(12)   I111 @BASEBOARD_FAB2_LIB.BASEBOARD_FAB2(SCH_1):PAGE85
   232 M_L_MA<13> @BASEBOARD_FAB2_LIB.BASEBOARD_FAB2(SCH_1):M_L_MA(13)   I111 @BASEBOARD_FAB2_LIB.BASEBOARD_FAB2(SCH_1):PAGE85
   228 M_L_MA<14> @BASEBOARD_FAB2_LIB.BASEBOARD_FAB2(SCH_1):M_L_MA(14)   I111 @BASEBOARD_FAB2_LIB.BASEBOARD_FAB2(SCH_1):PAGE85
    86 M_L_MA<15> @BASEBOARD_FAB2_LIB.BASEBOARD_FAB2(SCH_1):M_L_MA(15)   I111 @BASEBOARD_FAB2_LIB.BASEBOARD_FAB2(SCH_1):PAGE85
    82 M_L_MA<16> @BASEBOARD_FAB2_LIB.BASEBOARD_FAB2(SCH_1):M_L_MA(16)   I111 @BASEBOARD_FAB2_LIB.BASEBOARD_FAB2(SCH_1):PAGE85
   234 M_L_MA<17> @BASEBOARD_FAB2_LIB.BASEBOARD_FAB2(SCH_1):M_L_MA(17)   I111 @BASEBOARD_FAB2_LIB.BASEBOARD_FAB2(SCH_1):PAGE85
   216 M_L_MA<2> @BASEBOARD_FAB2_LIB.BASEBOARD_FAB2(SCH_1):M_L_MA(2)   I111 @BASEBOARD_FAB2_LIB.BASEBOARD_FAB2(SCH_1):PAGE85
    71 M_L_MA<3> @BASEBOARD_FAB2_LIB.BASEBOARD_FAB2(SCH_1):M_L_MA(3)   I111 @BASEBOARD_FAB2_LIB.BASEBOARD_FAB2(SCH_1):PAGE85
   214 M_L_MA<4> @BASEBOARD_FAB2_LIB.BASEBOARD_FAB2(SCH_1):M_L_MA(4)   I111 @BASEBOARD_FAB2_LIB.BASEBOARD_FAB2(SCH_1):PAGE85
   213 M_L_MA<5> @BASEBOARD_FAB2_LIB.BASEBOARD_FAB2(SCH_1):M_L_MA(5)   I111 @BASEBOARD_FAB2_LIB.BASEBOARD_FAB2(SCH_1):PAGE85
    69 M_L_MA<6> @BASEBOARD_FAB2_LIB.BASEBOARD_FAB2(SCH_1):M_L_MA(6)   I111 @BASEBOARD_FAB2_LIB.BASEBOARD_FAB2(SCH_1):PAGE85
   211 M_L_MA<7> @BASEBOARD_FAB2_LIB.BASEBOARD_FAB2(SCH_1):M_L_MA(7)   I111 @BASEBOARD_FAB2_LIB.BASEBOARD_FAB2(SCH_1):PAGE85
    68 M_L_MA<8> @BASEBOARD_FAB2_LIB.BASEBOARD_FAB2(SCH_1):M_L_MA(8)   I111 @BASEBOARD_FAB2_LIB.BASEBOARD_FAB2(SCH_1):PAGE85
    66 M_L_MA<9> @BASEBOARD_FAB2_LIB.BASEBOARD_FAB2(SCH_1):M_L_MA(9)   I111 @BASEBOARD_FAB2_LIB.BASEBOARD_FAB2(SCH_1):PAGE85
    62 M_L_ACT_N @BASEBOARD_FAB2_LIB.BASEBOARD_FAB2(SCH_1):M_L_ACT_N   I111 @BASEBOARD_FAB2_LIB.BASEBOARD_FAB2(SCH_1):PAGE85
   208 M_L_ALERT_N @BASEBOARD_FAB2_LIB.BASEBOARD_FAB2(SCH_1):M_L_ALERT_N   I111 @BASEBOARD_FAB2_LIB.BASEBOARD_FAB2(SCH_1):PAGE85
   224 M_L_BA<1> @BASEBOARD_FAB2_LIB.BASEBOARD_FAB2(SCH_1):M_L_BA(1)   I111 @BASEBOARD_FAB2_LIB.BASEBOARD_FAB2(SCH_1):PAGE85
    81 M_L_BA<0> @BASEBOARD_FAB2_LIB.BASEBOARD_FAB2(SCH_1):M_L_BA(0)   I111 @BASEBOARD_FAB2_LIB.BASEBOARD_FAB2(SCH_1):PAGE85
   207 M_L_BG<1> @BASEBOARD_FAB2_LIB.BASEBOARD_FAB2(SCH_1):M_L_BG(1)   I111 @BASEBOARD_FAB2_LIB.BASEBOARD_FAB2(SCH_1):PAGE85
    63 M_L_BG<0> @BASEBOARD_FAB2_LIB.BASEBOARD_FAB2(SCH_1):M_L_BG(0)   I111 @BASEBOARD_FAB2_LIB.BASEBOARD_FAB2(SCH_1):PAGE85
   235 M_L_C<2> @BASEBOARD_FAB2_LIB.BASEBOARD_FAB2(SCH_1):M_L_C(2)   I111 @BASEBOARD_FAB2_LIB.BASEBOARD_FAB2(SCH_1):PAGE85
   199 M_L_ECC<6> @BASEBOARD_FAB2_LIB.BASEBOARD_FAB2(SCH_1):M_L_ECC(6)   I111 @BASEBOARD_FAB2_LIB.BASEBOARD_FAB2(SCH_1):PAGE85
    54 M_L_ECC<7> @BASEBOARD_FAB2_LIB.BASEBOARD_FAB2(SCH_1):M_L_ECC(7)   I111 @BASEBOARD_FAB2_LIB.BASEBOARD_FAB2(SCH_1):PAGE85
   192 M_L_ECC<4> @BASEBOARD_FAB2_LIB.BASEBOARD_FAB2(SCH_1):M_L_ECC(4)   I111 @BASEBOARD_FAB2_LIB.BASEBOARD_FAB2(SCH_1):PAGE85
    47 M_L_ECC<5> @BASEBOARD_FAB2_LIB.BASEBOARD_FAB2(SCH_1):M_L_ECC(5)   I111 @BASEBOARD_FAB2_LIB.BASEBOARD_FAB2(SCH_1):PAGE85
   201 M_L_ECC<2> @BASEBOARD_FAB2_LIB.BASEBOARD_FAB2(SCH_1):M_L_ECC(2)   I111 @BASEBOARD_FAB2_LIB.BASEBOARD_FAB2(SCH_1):PAGE85
    56 M_L_ECC<3> @BASEBOARD_FAB2_LIB.BASEBOARD_FAB2(SCH_1):M_L_ECC(3)   I111 @BASEBOARD_FAB2_LIB.BASEBOARD_FAB2(SCH_1):PAGE85
   194 M_L_ECC<0> @BASEBOARD_FAB2_LIB.BASEBOARD_FAB2(SCH_1):M_L_ECC(0)   I111 @BASEBOARD_FAB2_LIB.BASEBOARD_FAB2(SCH_1):PAGE85
    49 M_L_ECC<1> @BASEBOARD_FAB2_LIB.BASEBOARD_FAB2(SCH_1):M_L_ECC(1)   I111 @BASEBOARD_FAB2_LIB.BASEBOARD_FAB2(SCH_1):PAGE85
    75 M_L_CLK_DN<0> @BASEBOARD_FAB2_LIB.BASEBOARD_FAB2(SCH_1):M_L_CLK_DN(0)   I111 @BASEBOARD_FAB2_LIB.BASEBOARD_FAB2(SCH_1):PAGE85
    74 M_L_CLK_DP<0> @BASEBOARD_FAB2_LIB.BASEBOARD_FAB2(SCH_1):M_L_CLK_DP(0)   I111 @BASEBOARD_FAB2_LIB.BASEBOARD_FAB2(SCH_1):PAGE85
   219 M_L_CLK_DN<1> @BASEBOARD_FAB2_LIB.BASEBOARD_FAB2(SCH_1):M_L_CLK_DN(1)   I111 @BASEBOARD_FAB2_LIB.BASEBOARD_FAB2(SCH_1):PAGE85
   218 M_L_CLK_DP<1> @BASEBOARD_FAB2_LIB.BASEBOARD_FAB2(SCH_1):M_L_CLK_DP(1)   I111 @BASEBOARD_FAB2_LIB.BASEBOARD_FAB2(SCH_1):PAGE85
   203 M_L_CKE<1> @BASEBOARD_FAB2_LIB.BASEBOARD_FAB2(SCH_1):M_L_CKE(1)   I111 @BASEBOARD_FAB2_LIB.BASEBOARD_FAB2(SCH_1):PAGE85
    60 M_L_CKE<0> @BASEBOARD_FAB2_LIB.BASEBOARD_FAB2(SCH_1):M_L_CKE(0)   I111 @BASEBOARD_FAB2_LIB.BASEBOARD_FAB2(SCH_1):PAGE85
   280 M_L_DQ<62> @BASEBOARD_FAB2_LIB.BASEBOARD_FAB2(SCH_1):M_L_DQ(62)   I111 @BASEBOARD_FAB2_LIB.BASEBOARD_FAB2(SCH_1):PAGE85
   135 M_L_DQ<63> @BASEBOARD_FAB2_LIB.BASEBOARD_FAB2(SCH_1):M_L_DQ(63)   I111 @BASEBOARD_FAB2_LIB.BASEBOARD_FAB2(SCH_1):PAGE85
   273 M_L_DQ<60> @BASEBOARD_FAB2_LIB.BASEBOARD_FAB2(SCH_1):M_L_DQ(60)   I111 @BASEBOARD_FAB2_LIB.BASEBOARD_FAB2(SCH_1):PAGE85
   128 M_L_DQ<61> @BASEBOARD_FAB2_LIB.BASEBOARD_FAB2(SCH_1):M_L_DQ(61)   I111 @BASEBOARD_FAB2_LIB.BASEBOARD_FAB2(SCH_1):PAGE85
   282 M_L_DQ<58> @BASEBOARD_FAB2_LIB.BASEBOARD_FAB2(SCH_1):M_L_DQ(58)   I111 @BASEBOARD_FAB2_LIB.BASEBOARD_FAB2(SCH_1):PAGE85
   137 M_L_DQ<59> @BASEBOARD_FAB2_LIB.BASEBOARD_FAB2(SCH_1):M_L_DQ(59)   I111 @BASEBOARD_FAB2_LIB.BASEBOARD_FAB2(SCH_1):PAGE85
   275 M_L_DQ<56> @BASEBOARD_FAB2_LIB.BASEBOARD_FAB2(SCH_1):M_L_DQ(56)   I111 @BASEBOARD_FAB2_LIB.BASEBOARD_FAB2(SCH_1):PAGE85
   130 M_L_DQ<57> @BASEBOARD_FAB2_LIB.BASEBOARD_FAB2(SCH_1):M_L_DQ(57)   I111 @BASEBOARD_FAB2_LIB.BASEBOARD_FAB2(SCH_1):PAGE85
   269 M_L_DQ<54> @BASEBOARD_FAB2_LIB.BASEBOARD_FAB2(SCH_1):M_L_DQ(54)   I111 @BASEBOARD_FAB2_LIB.BASEBOARD_FAB2(SCH_1):PAGE85
   124 M_L_DQ<55> @BASEBOARD_FAB2_LIB.BASEBOARD_FAB2(SCH_1):M_L_DQ(55)   I111 @BASEBOARD_FAB2_LIB.BASEBOARD_FAB2(SCH_1):PAGE85
   262 M_L_DQ<52> @BASEBOARD_FAB2_LIB.BASEBOARD_FAB2(SCH_1):M_L_DQ(52)   I111 @BASEBOARD_FAB2_LIB.BASEBOARD_FAB2(SCH_1):PAGE85
   117 M_L_DQ<53> @BASEBOARD_FAB2_LIB.BASEBOARD_FAB2(SCH_1):M_L_DQ(53)   I111 @BASEBOARD_FAB2_LIB.BASEBOARD_FAB2(SCH_1):PAGE85
   271 M_L_DQ<50> @BASEBOARD_FAB2_LIB.BASEBOARD_FAB2(SCH_1):M_L_DQ(50)   I111 @BASEBOARD_FAB2_LIB.BASEBOARD_FAB2(SCH_1):PAGE85
   126 M_L_DQ<51> @BASEBOARD_FAB2_LIB.BASEBOARD_FAB2(SCH_1):M_L_DQ(51)   I111 @BASEBOARD_FAB2_LIB.BASEBOARD_FAB2(SCH_1):PAGE85
   264 M_L_DQ<48> @BASEBOARD_FAB2_LIB.BASEBOARD_FAB2(SCH_1):M_L_DQ(48)   I111 @BASEBOARD_FAB2_LIB.BASEBOARD_FAB2(SCH_1):PAGE85
   119 M_L_DQ<49> @BASEBOARD_FAB2_LIB.BASEBOARD_FAB2(SCH_1):M_L_DQ(49)   I111 @BASEBOARD_FAB2_LIB.BASEBOARD_FAB2(SCH_1):PAGE85
   258 M_L_DQ<46> @BASEBOARD_FAB2_LIB.BASEBOARD_FAB2(SCH_1):M_L_DQ(46)   I111 @BASEBOARD_FAB2_LIB.BASEBOARD_FAB2(SCH_1):PAGE85
   113 M_L_DQ<47> @BASEBOARD_FAB2_LIB.BASEBOARD_FAB2(SCH_1):M_L_DQ(47)   I111 @BASEBOARD_FAB2_LIB.BASEBOARD_FAB2(SCH_1):PAGE85
   251 M_L_DQ<44> @BASEBOARD_FAB2_LIB.BASEBOARD_FAB2(SCH_1):M_L_DQ(44)   I111 @BASEBOARD_FAB2_LIB.BASEBOARD_FAB2(SCH_1):PAGE85
   106 M_L_DQ<45> @BASEBOARD_FAB2_LIB.BASEBOARD_FAB2(SCH_1):M_L_DQ(45)   I111 @BASEBOARD_FAB2_LIB.BASEBOARD_FAB2(SCH_1):PAGE85
   260 M_L_DQ<42> @BASEBOARD_FAB2_LIB.BASEBOARD_FAB2(SCH_1):M_L_DQ(42)   I111 @BASEBOARD_FAB2_LIB.BASEBOARD_FAB2(SCH_1):PAGE85
   115 M_L_DQ<43> @BASEBOARD_FAB2_LIB.BASEBOARD_FAB2(SCH_1):M_L_DQ(43)   I111 @BASEBOARD_FAB2_LIB.BASEBOARD_FAB2(SCH_1):PAGE85
   253 M_L_DQ<40> @BASEBOARD_FAB2_LIB.BASEBOARD_FAB2(SCH_1):M_L_DQ(40)   I111 @BASEBOARD_FAB2_LIB.BASEBOARD_FAB2(SCH_1):PAGE85
   108 M_L_DQ<41> @BASEBOARD_FAB2_LIB.BASEBOARD_FAB2(SCH_1):M_L_DQ(41)   I111 @BASEBOARD_FAB2_LIB.BASEBOARD_FAB2(SCH_1):PAGE85
   247 M_L_DQ<38> @BASEBOARD_FAB2_LIB.BASEBOARD_FAB2(SCH_1):M_L_DQ(38)   I111 @BASEBOARD_FAB2_LIB.BASEBOARD_FAB2(SCH_1):PAGE85
   102 M_L_DQ<39> @BASEBOARD_FAB2_LIB.BASEBOARD_FAB2(SCH_1):M_L_DQ(39)   I111 @BASEBOARD_FAB2_LIB.BASEBOARD_FAB2(SCH_1):PAGE85
   240 M_L_DQ<36> @BASEBOARD_FAB2_LIB.BASEBOARD_FAB2(SCH_1):M_L_DQ(36)   I111 @BASEBOARD_FAB2_LIB.BASEBOARD_FAB2(SCH_1):PAGE85
    95 M_L_DQ<37> @BASEBOARD_FAB2_LIB.BASEBOARD_FAB2(SCH_1):M_L_DQ(37)   I111 @BASEBOARD_FAB2_LIB.BASEBOARD_FAB2(SCH_1):PAGE85
   249 M_L_DQ<34> @BASEBOARD_FAB2_LIB.BASEBOARD_FAB2(SCH_1):M_L_DQ(34)   I111 @BASEBOARD_FAB2_LIB.BASEBOARD_FAB2(SCH_1):PAGE85
   104 M_L_DQ<35> @BASEBOARD_FAB2_LIB.BASEBOARD_FAB2(SCH_1):M_L_DQ(35)   I111 @BASEBOARD_FAB2_LIB.BASEBOARD_FAB2(SCH_1):PAGE85
   242 M_L_DQ<32> @BASEBOARD_FAB2_LIB.BASEBOARD_FAB2(SCH_1):M_L_DQ(32)   I111 @BASEBOARD_FAB2_LIB.BASEBOARD_FAB2(SCH_1):PAGE85
    97 M_L_DQ<33> @BASEBOARD_FAB2_LIB.BASEBOARD_FAB2(SCH_1):M_L_DQ(33)   I111 @BASEBOARD_FAB2_LIB.BASEBOARD_FAB2(SCH_1):PAGE85
   188 M_L_DQ<30> @BASEBOARD_FAB2_LIB.BASEBOARD_FAB2(SCH_1):M_L_DQ(30)   I111 @BASEBOARD_FAB2_LIB.BASEBOARD_FAB2(SCH_1):PAGE85
    43 M_L_DQ<31> @BASEBOARD_FAB2_LIB.BASEBOARD_FAB2(SCH_1):M_L_DQ(31)   I111 @BASEBOARD_FAB2_LIB.BASEBOARD_FAB2(SCH_1):PAGE85
   181 M_L_DQ<28> @BASEBOARD_FAB2_LIB.BASEBOARD_FAB2(SCH_1):M_L_DQ(28)   I111 @BASEBOARD_FAB2_LIB.BASEBOARD_FAB2(SCH_1):PAGE85
    36 M_L_DQ<29> @BASEBOARD_FAB2_LIB.BASEBOARD_FAB2(SCH_1):M_L_DQ(29)   I111 @BASEBOARD_FAB2_LIB.BASEBOARD_FAB2(SCH_1):PAGE85
   190 M_L_DQ<26> @BASEBOARD_FAB2_LIB.BASEBOARD_FAB2(SCH_1):M_L_DQ(26)   I111 @BASEBOARD_FAB2_LIB.BASEBOARD_FAB2(SCH_1):PAGE85
    45 M_L_DQ<27> @BASEBOARD_FAB2_LIB.BASEBOARD_FAB2(SCH_1):M_L_DQ(27)   I111 @BASEBOARD_FAB2_LIB.BASEBOARD_FAB2(SCH_1):PAGE85
   183 M_L_DQ<24> @BASEBOARD_FAB2_LIB.BASEBOARD_FAB2(SCH_1):M_L_DQ(24)   I111 @BASEBOARD_FAB2_LIB.BASEBOARD_FAB2(SCH_1):PAGE85
    38 M_L_DQ<25> @BASEBOARD_FAB2_LIB.BASEBOARD_FAB2(SCH_1):M_L_DQ(25)   I111 @BASEBOARD_FAB2_LIB.BASEBOARD_FAB2(SCH_1):PAGE85
   177 M_L_DQ<22> @BASEBOARD_FAB2_LIB.BASEBOARD_FAB2(SCH_1):M_L_DQ(22)   I111 @BASEBOARD_FAB2_LIB.BASEBOARD_FAB2(SCH_1):PAGE85
    32 M_L_DQ<23> @BASEBOARD_FAB2_LIB.BASEBOARD_FAB2(SCH_1):M_L_DQ(23)   I111 @BASEBOARD_FAB2_LIB.BASEBOARD_FAB2(SCH_1):PAGE85
   170 M_L_DQ<20> @BASEBOARD_FAB2_LIB.BASEBOARD_FAB2(SCH_1):M_L_DQ(20)   I111 @BASEBOARD_FAB2_LIB.BASEBOARD_FAB2(SCH_1):PAGE85
    25 M_L_DQ<21> @BASEBOARD_FAB2_LIB.BASEBOARD_FAB2(SCH_1):M_L_DQ(21)   I111 @BASEBOARD_FAB2_LIB.BASEBOARD_FAB2(SCH_1):PAGE85
   179 M_L_DQ<18> @BASEBOARD_FAB2_LIB.BASEBOARD_FAB2(SCH_1):M_L_DQ(18)   I111 @BASEBOARD_FAB2_LIB.BASEBOARD_FAB2(SCH_1):PAGE85
    34 M_L_DQ<19> @BASEBOARD_FAB2_LIB.BASEBOARD_FAB2(SCH_1):M_L_DQ(19)   I111 @BASEBOARD_FAB2_LIB.BASEBOARD_FAB2(SCH_1):PAGE85
   172 M_L_DQ<16> @BASEBOARD_FAB2_LIB.BASEBOARD_FAB2(SCH_1):M_L_DQ(16)   I111 @BASEBOARD_FAB2_LIB.BASEBOARD_FAB2(SCH_1):PAGE85
    27 M_L_DQ<17> @BASEBOARD_FAB2_LIB.BASEBOARD_FAB2(SCH_1):M_L_DQ(17)   I111 @BASEBOARD_FAB2_LIB.BASEBOARD_FAB2(SCH_1):PAGE85
   166 M_L_DQ<14> @BASEBOARD_FAB2_LIB.BASEBOARD_FAB2(SCH_1):M_L_DQ(14)   I111 @BASEBOARD_FAB2_LIB.BASEBOARD_FAB2(SCH_1):PAGE85
    21 M_L_DQ<15> @BASEBOARD_FAB2_LIB.BASEBOARD_FAB2(SCH_1):M_L_DQ(15)   I111 @BASEBOARD_FAB2_LIB.BASEBOARD_FAB2(SCH_1):PAGE85
   159 M_L_DQ<12> @BASEBOARD_FAB2_LIB.BASEBOARD_FAB2(SCH_1):M_L_DQ(12)   I111 @BASEBOARD_FAB2_LIB.BASEBOARD_FAB2(SCH_1):PAGE85
    14 M_L_DQ<13> @BASEBOARD_FAB2_LIB.BASEBOARD_FAB2(SCH_1):M_L_DQ(13)   I111 @BASEBOARD_FAB2_LIB.BASEBOARD_FAB2(SCH_1):PAGE85
   168 M_L_DQ<10> @BASEBOARD_FAB2_LIB.BASEBOARD_FAB2(SCH_1):M_L_DQ(10)   I111 @BASEBOARD_FAB2_LIB.BASEBOARD_FAB2(SCH_1):PAGE85
    23 M_L_DQ<11> @BASEBOARD_FAB2_LIB.BASEBOARD_FAB2(SCH_1):M_L_DQ(11)   I111 @BASEBOARD_FAB2_LIB.BASEBOARD_FAB2(SCH_1):PAGE85
   161 M_L_DQ<8> @BASEBOARD_FAB2_LIB.BASEBOARD_FAB2(SCH_1):M_L_DQ(8)   I111 @BASEBOARD_FAB2_LIB.BASEBOARD_FAB2(SCH_1):PAGE85
    16 M_L_DQ<9> @BASEBOARD_FAB2_LIB.BASEBOARD_FAB2(SCH_1):M_L_DQ(9)   I111 @BASEBOARD_FAB2_LIB.BASEBOARD_FAB2(SCH_1):PAGE85
   155 M_L_DQ<6> @BASEBOARD_FAB2_LIB.BASEBOARD_FAB2(SCH_1):M_L_DQ(6)   I111 @BASEBOARD_FAB2_LIB.BASEBOARD_FAB2(SCH_1):PAGE85
    10 M_L_DQ<7> @BASEBOARD_FAB2_LIB.BASEBOARD_FAB2(SCH_1):M_L_DQ(7)   I111 @BASEBOARD_FAB2_LIB.BASEBOARD_FAB2(SCH_1):PAGE85
   148 M_L_DQ<4> @BASEBOARD_FAB2_LIB.BASEBOARD_FAB2(SCH_1):M_L_DQ(4)   I111 @BASEBOARD_FAB2_LIB.BASEBOARD_FAB2(SCH_1):PAGE85
     3 M_L_DQ<5> @BASEBOARD_FAB2_LIB.BASEBOARD_FAB2(SCH_1):M_L_DQ(5)   I111 @BASEBOARD_FAB2_LIB.BASEBOARD_FAB2(SCH_1):PAGE85
   157 M_L_DQ<2> @BASEBOARD_FAB2_LIB.BASEBOARD_FAB2(SCH_1):M_L_DQ(2)   I111 @BASEBOARD_FAB2_LIB.BASEBOARD_FAB2(SCH_1):PAGE85
    12 M_L_DQ<3> @BASEBOARD_FAB2_LIB.BASEBOARD_FAB2(SCH_1):M_L_DQ(3)   I111 @BASEBOARD_FAB2_LIB.BASEBOARD_FAB2(SCH_1):PAGE85
   150 M_L_DQ<0> @BASEBOARD_FAB2_LIB.BASEBOARD_FAB2(SCH_1):M_L_DQ(0)   I111 @BASEBOARD_FAB2_LIB.BASEBOARD_FAB2(SCH_1):PAGE85
     5 M_L_DQ<1> @BASEBOARD_FAB2_LIB.BASEBOARD_FAB2(SCH_1):M_L_DQ(1)   I111 @BASEBOARD_FAB2_LIB.BASEBOARD_FAB2(SCH_1):PAGE85
    78 FM_DIMM_EVENT_COD_N @BASEBOARD_FAB2_LIB.BASEBOARD_FAB2(SCH_1):FM_DIMM_EVENT_COD_N   I111 @BASEBOARD_FAB2_LIB.BASEBOARD_FAB2(SCH_1):PAGE85
    91 M_L_ODT<1> @BASEBOARD_FAB2_LIB.BASEBOARD_FAB2(SCH_1):M_L_ODT(1)   I111 @BASEBOARD_FAB2_LIB.BASEBOARD_FAB2(SCH_1):PAGE85
    87 M_L_ODT<0> @BASEBOARD_FAB2_LIB.BASEBOARD_FAB2(SCH_1):M_L_ODT(0)   I111 @BASEBOARD_FAB2_LIB.BASEBOARD_FAB2(SCH_1):PAGE85
   222 M_L_PAR @BASEBOARD_FAB2_LIB.BASEBOARD_FAB2(SCH_1):M_L_PAR   I111 @BASEBOARD_FAB2_LIB.BASEBOARD_FAB2(SCH_1):PAGE85
    58 M_KLM_RST_N @BASEBOARD_FAB2_LIB.BASEBOARD_FAB2(SCH_1):M_KLM_RST_N   I111 @BASEBOARD_FAB2_LIB.BASEBOARD_FAB2(SCH_1):PAGE85
   144 TP_CH_L_DIMM_L0_RFU_2 @BASEBOARD_FAB2_LIB.BASEBOARD_FAB2(SCH_1):TP_CH_L_DIMM_L0_RFU_2   I111 @BASEBOARD_FAB2_LIB.BASEBOARD_FAB2(SCH_1):PAGE85
   227 TP_CH_L_DIMM_L0_RFU_1 @BASEBOARD_FAB2_LIB.BASEBOARD_FAB2(SCH_1):TP_CH_L_DIMM_L0_RFU_1   I111 @BASEBOARD_FAB2_LIB.BASEBOARD_FAB2(SCH_1):PAGE85
   205 TP_CH_L_DIMM_L0_RFU_0 @BASEBOARD_FAB2_LIB.BASEBOARD_FAB2(SCH_1):TP_CH_L_DIMM_L0_RFU_0   I111 @BASEBOARD_FAB2_LIB.BASEBOARD_FAB2(SCH_1):PAGE85
    84 M_L_CS_N<0> @BASEBOARD_FAB2_LIB.BASEBOARD_FAB2(SCH_1):M_L_CS_N(0)   I111 @BASEBOARD_FAB2_LIB.BASEBOARD_FAB2(SCH_1):PAGE85
    89 M_L_CS_N<1> @BASEBOARD_FAB2_LIB.BASEBOARD_FAB2(SCH_1):M_L_CS_N(1)   I111 @BASEBOARD_FAB2_LIB.BASEBOARD_FAB2(SCH_1):PAGE85
    93 M_L_CS_N<2> @BASEBOARD_FAB2_LIB.BASEBOARD_FAB2(SCH_1):M_L_CS_N(2)   I111 @BASEBOARD_FAB2_LIB.BASEBOARD_FAB2(SCH_1):PAGE85
   237 M_L_CS_N<3> @BASEBOARD_FAB2_LIB.BASEBOARD_FAB2(SCH_1):M_L_CS_N(3)   I111 @BASEBOARD_FAB2_LIB.BASEBOARD_FAB2(SCH_1):PAGE85
   238    GND @BASEBOARD_FAB2_LIB.BASEBOARD_FAB2(SCH_1):GND   I111 @BASEBOARD_FAB2_LIB.BASEBOARD_FAB2(SCH_1):PAGE85
   140 PVPP_KLM @BASEBOARD_FAB2_LIB.BASEBOARD_FAB2(SCH_1):PVPP_KLM   I111 @BASEBOARD_FAB2_LIB.BASEBOARD_FAB2(SCH_1):PAGE85
   139    GND @BASEBOARD_FAB2_LIB.BASEBOARD_FAB2(SCH_1):GND   I111 @BASEBOARD_FAB2_LIB.BASEBOARD_FAB2(SCH_1):PAGE85
   230 FM_ADR_COMPLETE_KLM_N @BASEBOARD_FAB2_LIB.BASEBOARD_FAB2(SCH_1):FM_ADR_COMPLETE_KLM_N   I111 @BASEBOARD_FAB2_LIB.BASEBOARD_FAB2(SCH_1):PAGE85
   141 SMB_DDR_KLM_VPP_SCL @BASEBOARD_FAB2_LIB.BASEBOARD_FAB2(SCH_1):SMB_DDR_KLM_VPP_SCL   I111 @BASEBOARD_FAB2_LIB.BASEBOARD_FAB2(SCH_1):PAGE85
   285 SMB_DDR_KLM_VPP_SDA @BASEBOARD_FAB2_LIB.BASEBOARD_FAB2(SCH_1):SMB_DDR_KLM_VPP_SDA   I111 @BASEBOARD_FAB2_LIB.BASEBOARD_FAB2(SCH_1):PAGE85
   284 PVPP_KLM @BASEBOARD_FAB2_LIB.BASEBOARD_FAB2(SCH_1):PVPP_KLM   I111 @BASEBOARD_FAB2_LIB.BASEBOARD_FAB2(SCH_1):PAGE85
   146 M_L_VREF @BASEBOARD_FAB2_LIB.BASEBOARD_FAB2(SCH_1):M_L_VREF   I111 @BASEBOARD_FAB2_LIB.BASEBOARD_FAB2(SCH_1):PAGE85
   152 M_L_DQS_DN<0> @BASEBOARD_FAB2_LIB.BASEBOARD_FAB2(SCH_1):M_L_DQS_DN(0)    I66 @BASEBOARD_FAB2_LIB.BASEBOARD_FAB2(SCH_1):PAGE85
   153 M_L_DQS_DP<0> @BASEBOARD_FAB2_LIB.BASEBOARD_FAB2(SCH_1):M_L_DQS_DP(0)    I66 @BASEBOARD_FAB2_LIB.BASEBOARD_FAB2(SCH_1):PAGE85
    19 M_L_DQS_DN<10> @BASEBOARD_FAB2_LIB.BASEBOARD_FAB2(SCH_1):M_L_DQS_DN(10)    I66 @BASEBOARD_FAB2_LIB.BASEBOARD_FAB2(SCH_1):PAGE85
    18 M_L_DQS_DP<10> @BASEBOARD_FAB2_LIB.BASEBOARD_FAB2(SCH_1):M_L_DQS_DP(10)    I66 @BASEBOARD_FAB2_LIB.BASEBOARD_FAB2(SCH_1):PAGE85
    30 M_L_DQS_DN<11> @BASEBOARD_FAB2_LIB.BASEBOARD_FAB2(SCH_1):M_L_DQS_DN(11)    I66 @BASEBOARD_FAB2_LIB.BASEBOARD_FAB2(SCH_1):PAGE85
    29 M_L_DQS_DP<11> @BASEBOARD_FAB2_LIB.BASEBOARD_FAB2(SCH_1):M_L_DQS_DP(11)    I66 @BASEBOARD_FAB2_LIB.BASEBOARD_FAB2(SCH_1):PAGE85
    41 M_L_DQS_DN<12> @BASEBOARD_FAB2_LIB.BASEBOARD_FAB2(SCH_1):M_L_DQS_DN(12)    I66 @BASEBOARD_FAB2_LIB.BASEBOARD_FAB2(SCH_1):PAGE85
    40 M_L_DQS_DP<12> @BASEBOARD_FAB2_LIB.BASEBOARD_FAB2(SCH_1):M_L_DQS_DP(12)    I66 @BASEBOARD_FAB2_LIB.BASEBOARD_FAB2(SCH_1):PAGE85
   100 M_L_DQS_DN<13> @BASEBOARD_FAB2_LIB.BASEBOARD_FAB2(SCH_1):M_L_DQS_DN(13)    I66 @BASEBOARD_FAB2_LIB.BASEBOARD_FAB2(SCH_1):PAGE85
    99 M_L_DQS_DP<13> @BASEBOARD_FAB2_LIB.BASEBOARD_FAB2(SCH_1):M_L_DQS_DP(13)    I66 @BASEBOARD_FAB2_LIB.BASEBOARD_FAB2(SCH_1):PAGE85
   111 M_L_DQS_DN<14> @BASEBOARD_FAB2_LIB.BASEBOARD_FAB2(SCH_1):M_L_DQS_DN(14)    I66 @BASEBOARD_FAB2_LIB.BASEBOARD_FAB2(SCH_1):PAGE85
   110 M_L_DQS_DP<14> @BASEBOARD_FAB2_LIB.BASEBOARD_FAB2(SCH_1):M_L_DQS_DP(14)    I66 @BASEBOARD_FAB2_LIB.BASEBOARD_FAB2(SCH_1):PAGE85
   122 M_L_DQS_DN<15> @BASEBOARD_FAB2_LIB.BASEBOARD_FAB2(SCH_1):M_L_DQS_DN(15)    I66 @BASEBOARD_FAB2_LIB.BASEBOARD_FAB2(SCH_1):PAGE85
   121 M_L_DQS_DP<15> @BASEBOARD_FAB2_LIB.BASEBOARD_FAB2(SCH_1):M_L_DQS_DP(15)    I66 @BASEBOARD_FAB2_LIB.BASEBOARD_FAB2(SCH_1):PAGE85
   133 M_L_DQS_DN<16> @BASEBOARD_FAB2_LIB.BASEBOARD_FAB2(SCH_1):M_L_DQS_DN(16)    I66 @BASEBOARD_FAB2_LIB.BASEBOARD_FAB2(SCH_1):PAGE85
   132 M_L_DQS_DP<16> @BASEBOARD_FAB2_LIB.BASEBOARD_FAB2(SCH_1):M_L_DQS_DP(16)    I66 @BASEBOARD_FAB2_LIB.BASEBOARD_FAB2(SCH_1):PAGE85
    52 M_L_DQS_DN<17> @BASEBOARD_FAB2_LIB.BASEBOARD_FAB2(SCH_1):M_L_DQS_DN(17)    I66 @BASEBOARD_FAB2_LIB.BASEBOARD_FAB2(SCH_1):PAGE85
    51 M_L_DQS_DP<17> @BASEBOARD_FAB2_LIB.BASEBOARD_FAB2(SCH_1):M_L_DQS_DP(17)    I66 @BASEBOARD_FAB2_LIB.BASEBOARD_FAB2(SCH_1):PAGE85
   163 M_L_DQS_DN<1> @BASEBOARD_FAB2_LIB.BASEBOARD_FAB2(SCH_1):M_L_DQS_DN(1)    I66 @BASEBOARD_FAB2_LIB.BASEBOARD_FAB2(SCH_1):PAGE85
   164 M_L_DQS_DP<1> @BASEBOARD_FAB2_LIB.BASEBOARD_FAB2(SCH_1):M_L_DQS_DP(1)    I66 @BASEBOARD_FAB2_LIB.BASEBOARD_FAB2(SCH_1):PAGE85
   174 M_L_DQS_DN<2> @BASEBOARD_FAB2_LIB.BASEBOARD_FAB2(SCH_1):M_L_DQS_DN(2)    I66 @BASEBOARD_FAB2_LIB.BASEBOARD_FAB2(SCH_1):PAGE85
   175 M_L_DQS_DP<2> @BASEBOARD_FAB2_LIB.BASEBOARD_FAB2(SCH_1):M_L_DQS_DP(2)    I66 @BASEBOARD_FAB2_LIB.BASEBOARD_FAB2(SCH_1):PAGE85
   185 M_L_DQS_DN<3> @BASEBOARD_FAB2_LIB.BASEBOARD_FAB2(SCH_1):M_L_DQS_DN(3)    I66 @BASEBOARD_FAB2_LIB.BASEBOARD_FAB2(SCH_1):PAGE85
   186 M_L_DQS_DP<3> @BASEBOARD_FAB2_LIB.BASEBOARD_FAB2(SCH_1):M_L_DQS_DP(3)    I66 @BASEBOARD_FAB2_LIB.BASEBOARD_FAB2(SCH_1):PAGE85
   244 M_L_DQS_DN<4> @BASEBOARD_FAB2_LIB.BASEBOARD_FAB2(SCH_1):M_L_DQS_DN(4)    I66 @BASEBOARD_FAB2_LIB.BASEBOARD_FAB2(SCH_1):PAGE85
   245 M_L_DQS_DP<4> @BASEBOARD_FAB2_LIB.BASEBOARD_FAB2(SCH_1):M_L_DQS_DP(4)    I66 @BASEBOARD_FAB2_LIB.BASEBOARD_FAB2(SCH_1):PAGE85
   255 M_L_DQS_DN<5> @BASEBOARD_FAB2_LIB.BASEBOARD_FAB2(SCH_1):M_L_DQS_DN(5)    I66 @BASEBOARD_FAB2_LIB.BASEBOARD_FAB2(SCH_1):PAGE85
   256 M_L_DQS_DP<5> @BASEBOARD_FAB2_LIB.BASEBOARD_FAB2(SCH_1):M_L_DQS_DP(5)    I66 @BASEBOARD_FAB2_LIB.BASEBOARD_FAB2(SCH_1):PAGE85
   266 M_L_DQS_DN<6> @BASEBOARD_FAB2_LIB.BASEBOARD_FAB2(SCH_1):M_L_DQS_DN(6)    I66 @BASEBOARD_FAB2_LIB.BASEBOARD_FAB2(SCH_1):PAGE85
   267 M_L_DQS_DP<6> @BASEBOARD_FAB2_LIB.BASEBOARD_FAB2(SCH_1):M_L_DQS_DP(6)    I66 @BASEBOARD_FAB2_LIB.BASEBOARD_FAB2(SCH_1):PAGE85
   277 M_L_DQS_DN<7> @BASEBOARD_FAB2_LIB.BASEBOARD_FAB2(SCH_1):M_L_DQS_DN(7)    I66 @BASEBOARD_FAB2_LIB.BASEBOARD_FAB2(SCH_1):PAGE85
   278 M_L_DQS_DP<7> @BASEBOARD_FAB2_LIB.BASEBOARD_FAB2(SCH_1):M_L_DQS_DP(7)    I66 @BASEBOARD_FAB2_LIB.BASEBOARD_FAB2(SCH_1):PAGE85
   196 M_L_DQS_DN<8> @BASEBOARD_FAB2_LIB.BASEBOARD_FAB2(SCH_1):M_L_DQS_DN(8)    I66 @BASEBOARD_FAB2_LIB.BASEBOARD_FAB2(SCH_1):PAGE85
   197 M_L_DQS_DP<8> @BASEBOARD_FAB2_LIB.BASEBOARD_FAB2(SCH_1):M_L_DQS_DP(8)    I66 @BASEBOARD_FAB2_LIB.BASEBOARD_FAB2(SCH_1):PAGE85
     8 M_L_DQS_DN<9> @BASEBOARD_FAB2_LIB.BASEBOARD_FAB2(SCH_1):M_L_DQS_DN(9)    I66 @BASEBOARD_FAB2_LIB.BASEBOARD_FAB2(SCH_1):PAGE85
     7 M_L_DQS_DP<9> @BASEBOARD_FAB2_LIB.BASEBOARD_FAB2(SCH_1):M_L_DQS_DP(9)    I66 @BASEBOARD_FAB2_LIB.BASEBOARD_FAB2(SCH_1):PAGE85
     2    GND @BASEBOARD_FAB2_LIB.BASEBOARD_FAB2(SCH_1):GND    I43 @BASEBOARD_FAB2_LIB.BASEBOARD_FAB2(SCH_1):PAGE85
     4    GND @BASEBOARD_FAB2_LIB.BASEBOARD_FAB2(SCH_1):GND    I43 @BASEBOARD_FAB2_LIB.BASEBOARD_FAB2(SCH_1):PAGE85
     6    GND @BASEBOARD_FAB2_LIB.BASEBOARD_FAB2(SCH_1):GND    I43 @BASEBOARD_FAB2_LIB.BASEBOARD_FAB2(SCH_1):PAGE85
     9    GND @BASEBOARD_FAB2_LIB.BASEBOARD_FAB2(SCH_1):GND    I43 @BASEBOARD_FAB2_LIB.BASEBOARD_FAB2(SCH_1):PAGE85
    11    GND @BASEBOARD_FAB2_LIB.BASEBOARD_FAB2(SCH_1):GND    I43 @BASEBOARD_FAB2_LIB.BASEBOARD_FAB2(SCH_1):PAGE85
    13    GND @BASEBOARD_FAB2_LIB.BASEBOARD_FAB2(SCH_1):GND    I43 @BASEBOARD_FAB2_LIB.BASEBOARD_FAB2(SCH_1):PAGE85
    15    GND @BASEBOARD_FAB2_LIB.BASEBOARD_FAB2(SCH_1):GND    I43 @BASEBOARD_FAB2_LIB.BASEBOARD_FAB2(SCH_1):PAGE85
    17    GND @BASEBOARD_FAB2_LIB.BASEBOARD_FAB2(SCH_1):GND    I43 @BASEBOARD_FAB2_LIB.BASEBOARD_FAB2(SCH_1):PAGE85
    20    GND @BASEBOARD_FAB2_LIB.BASEBOARD_FAB2(SCH_1):GND    I43 @BASEBOARD_FAB2_LIB.BASEBOARD_FAB2(SCH_1):PAGE85
    22    GND @BASEBOARD_FAB2_LIB.BASEBOARD_FAB2(SCH_1):GND    I43 @BASEBOARD_FAB2_LIB.BASEBOARD_FAB2(SCH_1):PAGE85
    24    GND @BASEBOARD_FAB2_LIB.BASEBOARD_FAB2(SCH_1):GND    I43 @BASEBOARD_FAB2_LIB.BASEBOARD_FAB2(SCH_1):PAGE85
    26    GND @BASEBOARD_FAB2_LIB.BASEBOARD_FAB2(SCH_1):GND    I43 @BASEBOARD_FAB2_LIB.BASEBOARD_FAB2(SCH_1):PAGE85
    28    GND @BASEBOARD_FAB2_LIB.BASEBOARD_FAB2(SCH_1):GND    I43 @BASEBOARD_FAB2_LIB.BASEBOARD_FAB2(SCH_1):PAGE85
    31    GND @BASEBOARD_FAB2_LIB.BASEBOARD_FAB2(SCH_1):GND    I43 @BASEBOARD_FAB2_LIB.BASEBOARD_FAB2(SCH_1):PAGE85
    33    GND @BASEBOARD_FAB2_LIB.BASEBOARD_FAB2(SCH_1):GND    I43 @BASEBOARD_FAB2_LIB.BASEBOARD_FAB2(SCH_1):PAGE85
    35    GND @BASEBOARD_FAB2_LIB.BASEBOARD_FAB2(SCH_1):GND    I43 @BASEBOARD_FAB2_LIB.BASEBOARD_FAB2(SCH_1):PAGE85
    37    GND @BASEBOARD_FAB2_LIB.BASEBOARD_FAB2(SCH_1):GND    I43 @BASEBOARD_FAB2_LIB.BASEBOARD_FAB2(SCH_1):PAGE85
    39    GND @BASEBOARD_FAB2_LIB.BASEBOARD_FAB2(SCH_1):GND    I43 @BASEBOARD_FAB2_LIB.BASEBOARD_FAB2(SCH_1):PAGE85
    42    GND @BASEBOARD_FAB2_LIB.BASEBOARD_FAB2(SCH_1):GND    I43 @BASEBOARD_FAB2_LIB.BASEBOARD_FAB2(SCH_1):PAGE85
    44    GND @BASEBOARD_FAB2_LIB.BASEBOARD_FAB2(SCH_1):GND    I43 @BASEBOARD_FAB2_LIB.BASEBOARD_FAB2(SCH_1):PAGE85
    46    GND @BASEBOARD_FAB2_LIB.BASEBOARD_FAB2(SCH_1):GND    I43 @BASEBOARD_FAB2_LIB.BASEBOARD_FAB2(SCH_1):PAGE85
    48    GND @BASEBOARD_FAB2_LIB.BASEBOARD_FAB2(SCH_1):GND    I43 @BASEBOARD_FAB2_LIB.BASEBOARD_FAB2(SCH_1):PAGE85
    50    GND @BASEBOARD_FAB2_LIB.BASEBOARD_FAB2(SCH_1):GND    I43 @BASEBOARD_FAB2_LIB.BASEBOARD_FAB2(SCH_1):PAGE85
    53    GND @BASEBOARD_FAB2_LIB.BASEBOARD_FAB2(SCH_1):GND    I43 @BASEBOARD_FAB2_LIB.BASEBOARD_FAB2(SCH_1):PAGE85
    55    GND @BASEBOARD_FAB2_LIB.BASEBOARD_FAB2(SCH_1):GND    I43 @BASEBOARD_FAB2_LIB.BASEBOARD_FAB2(SCH_1):PAGE85
    57    GND @BASEBOARD_FAB2_LIB.BASEBOARD_FAB2(SCH_1):GND    I43 @BASEBOARD_FAB2_LIB.BASEBOARD_FAB2(SCH_1):PAGE85
    94    GND @BASEBOARD_FAB2_LIB.BASEBOARD_FAB2(SCH_1):GND    I43 @BASEBOARD_FAB2_LIB.BASEBOARD_FAB2(SCH_1):PAGE85
    96    GND @BASEBOARD_FAB2_LIB.BASEBOARD_FAB2(SCH_1):GND    I43 @BASEBOARD_FAB2_LIB.BASEBOARD_FAB2(SCH_1):PAGE85
    98    GND @BASEBOARD_FAB2_LIB.BASEBOARD_FAB2(SCH_1):GND    I43 @BASEBOARD_FAB2_LIB.BASEBOARD_FAB2(SCH_1):PAGE85
   101    GND @BASEBOARD_FAB2_LIB.BASEBOARD_FAB2(SCH_1):GND    I43 @BASEBOARD_FAB2_LIB.BASEBOARD_FAB2(SCH_1):PAGE85
   103    GND @BASEBOARD_FAB2_LIB.BASEBOARD_FAB2(SCH_1):GND    I43 @BASEBOARD_FAB2_LIB.BASEBOARD_FAB2(SCH_1):PAGE85
   105    GND @BASEBOARD_FAB2_LIB.BASEBOARD_FAB2(SCH_1):GND    I43 @BASEBOARD_FAB2_LIB.BASEBOARD_FAB2(SCH_1):PAGE85
   107    GND @BASEBOARD_FAB2_LIB.BASEBOARD_FAB2(SCH_1):GND    I43 @BASEBOARD_FAB2_LIB.BASEBOARD_FAB2(SCH_1):PAGE85
   109    GND @BASEBOARD_FAB2_LIB.BASEBOARD_FAB2(SCH_1):GND    I43 @BASEBOARD_FAB2_LIB.BASEBOARD_FAB2(SCH_1):PAGE85
   112    GND @BASEBOARD_FAB2_LIB.BASEBOARD_FAB2(SCH_1):GND    I43 @BASEBOARD_FAB2_LIB.BASEBOARD_FAB2(SCH_1):PAGE85
   114    GND @BASEBOARD_FAB2_LIB.BASEBOARD_FAB2(SCH_1):GND    I43 @BASEBOARD_FAB2_LIB.BASEBOARD_FAB2(SCH_1):PAGE85
   116    GND @BASEBOARD_FAB2_LIB.BASEBOARD_FAB2(SCH_1):GND    I43 @BASEBOARD_FAB2_LIB.BASEBOARD_FAB2(SCH_1):PAGE85
   118    GND @BASEBOARD_FAB2_LIB.BASEBOARD_FAB2(SCH_1):GND    I43 @BASEBOARD_FAB2_LIB.BASEBOARD_FAB2(SCH_1):PAGE85
   120    GND @BASEBOARD_FAB2_LIB.BASEBOARD_FAB2(SCH_1):GND    I43 @BASEBOARD_FAB2_LIB.BASEBOARD_FAB2(SCH_1):PAGE85
   123    GND @BASEBOARD_FAB2_LIB.BASEBOARD_FAB2(SCH_1):GND    I43 @BASEBOARD_FAB2_LIB.BASEBOARD_FAB2(SCH_1):PAGE85
   125    GND @BASEBOARD_FAB2_LIB.BASEBOARD_FAB2(SCH_1):GND    I43 @BASEBOARD_FAB2_LIB.BASEBOARD_FAB2(SCH_1):PAGE85
   127    GND @BASEBOARD_FAB2_LIB.BASEBOARD_FAB2(SCH_1):GND    I43 @BASEBOARD_FAB2_LIB.BASEBOARD_FAB2(SCH_1):PAGE85
   129    GND @BASEBOARD_FAB2_LIB.BASEBOARD_FAB2(SCH_1):GND    I43 @BASEBOARD_FAB2_LIB.BASEBOARD_FAB2(SCH_1):PAGE85
   131    GND @BASEBOARD_FAB2_LIB.BASEBOARD_FAB2(SCH_1):GND    I43 @BASEBOARD_FAB2_LIB.BASEBOARD_FAB2(SCH_1):PAGE85
   134    GND @BASEBOARD_FAB2_LIB.BASEBOARD_FAB2(SCH_1):GND    I43 @BASEBOARD_FAB2_LIB.BASEBOARD_FAB2(SCH_1):PAGE85
   136    GND @BASEBOARD_FAB2_LIB.BASEBOARD_FAB2(SCH_1):GND    I43 @BASEBOARD_FAB2_LIB.BASEBOARD_FAB2(SCH_1):PAGE85
   138    GND @BASEBOARD_FAB2_LIB.BASEBOARD_FAB2(SCH_1):GND    I43 @BASEBOARD_FAB2_LIB.BASEBOARD_FAB2(SCH_1):PAGE85
   147    GND @BASEBOARD_FAB2_LIB.BASEBOARD_FAB2(SCH_1):GND    I43 @BASEBOARD_FAB2_LIB.BASEBOARD_FAB2(SCH_1):PAGE85
   149    GND @BASEBOARD_FAB2_LIB.BASEBOARD_FAB2(SCH_1):GND    I43 @BASEBOARD_FAB2_LIB.BASEBOARD_FAB2(SCH_1):PAGE85
   151    GND @BASEBOARD_FAB2_LIB.BASEBOARD_FAB2(SCH_1):GND    I43 @BASEBOARD_FAB2_LIB.BASEBOARD_FAB2(SCH_1):PAGE85
   154    GND @BASEBOARD_FAB2_LIB.BASEBOARD_FAB2(SCH_1):GND    I43 @BASEBOARD_FAB2_LIB.BASEBOARD_FAB2(SCH_1):PAGE85
   156    GND @BASEBOARD_FAB2_LIB.BASEBOARD_FAB2(SCH_1):GND    I43 @BASEBOARD_FAB2_LIB.BASEBOARD_FAB2(SCH_1):PAGE85
   158    GND @BASEBOARD_FAB2_LIB.BASEBOARD_FAB2(SCH_1):GND    I43 @BASEBOARD_FAB2_LIB.BASEBOARD_FAB2(SCH_1):PAGE85
   160    GND @BASEBOARD_FAB2_LIB.BASEBOARD_FAB2(SCH_1):GND    I43 @BASEBOARD_FAB2_LIB.BASEBOARD_FAB2(SCH_1):PAGE85
   162    GND @BASEBOARD_FAB2_LIB.BASEBOARD_FAB2(SCH_1):GND    I43 @BASEBOARD_FAB2_LIB.BASEBOARD_FAB2(SCH_1):PAGE85
   165    GND @BASEBOARD_FAB2_LIB.BASEBOARD_FAB2(SCH_1):GND    I43 @BASEBOARD_FAB2_LIB.BASEBOARD_FAB2(SCH_1):PAGE85
   167    GND @BASEBOARD_FAB2_LIB.BASEBOARD_FAB2(SCH_1):GND    I43 @BASEBOARD_FAB2_LIB.BASEBOARD_FAB2(SCH_1):PAGE85
   169    GND @BASEBOARD_FAB2_LIB.BASEBOARD_FAB2(SCH_1):GND    I43 @BASEBOARD_FAB2_LIB.BASEBOARD_FAB2(SCH_1):PAGE85
   171    GND @BASEBOARD_FAB2_LIB.BASEBOARD_FAB2(SCH_1):GND    I43 @BASEBOARD_FAB2_LIB.BASEBOARD_FAB2(SCH_1):PAGE85
   173    GND @BASEBOARD_FAB2_LIB.BASEBOARD_FAB2(SCH_1):GND    I43 @BASEBOARD_FAB2_LIB.BASEBOARD_FAB2(SCH_1):PAGE85
   176    GND @BASEBOARD_FAB2_LIB.BASEBOARD_FAB2(SCH_1):GND    I43 @BASEBOARD_FAB2_LIB.BASEBOARD_FAB2(SCH_1):PAGE85
   178    GND @BASEBOARD_FAB2_LIB.BASEBOARD_FAB2(SCH_1):GND    I43 @BASEBOARD_FAB2_LIB.BASEBOARD_FAB2(SCH_1):PAGE85
   180    GND @BASEBOARD_FAB2_LIB.BASEBOARD_FAB2(SCH_1):GND    I43 @BASEBOARD_FAB2_LIB.BASEBOARD_FAB2(SCH_1):PAGE85
   182    GND @BASEBOARD_FAB2_LIB.BASEBOARD_FAB2(SCH_1):GND    I43 @BASEBOARD_FAB2_LIB.BASEBOARD_FAB2(SCH_1):PAGE85
   184    GND @BASEBOARD_FAB2_LIB.BASEBOARD_FAB2(SCH_1):GND    I43 @BASEBOARD_FAB2_LIB.BASEBOARD_FAB2(SCH_1):PAGE85
   187    GND @BASEBOARD_FAB2_LIB.BASEBOARD_FAB2(SCH_1):GND    I43 @BASEBOARD_FAB2_LIB.BASEBOARD_FAB2(SCH_1):PAGE85
   189    GND @BASEBOARD_FAB2_LIB.BASEBOARD_FAB2(SCH_1):GND    I43 @BASEBOARD_FAB2_LIB.BASEBOARD_FAB2(SCH_1):PAGE85
   191    GND @BASEBOARD_FAB2_LIB.BASEBOARD_FAB2(SCH_1):GND    I43 @BASEBOARD_FAB2_LIB.BASEBOARD_FAB2(SCH_1):PAGE85
   193    GND @BASEBOARD_FAB2_LIB.BASEBOARD_FAB2(SCH_1):GND    I43 @BASEBOARD_FAB2_LIB.BASEBOARD_FAB2(SCH_1):PAGE85
   195    GND @BASEBOARD_FAB2_LIB.BASEBOARD_FAB2(SCH_1):GND    I43 @BASEBOARD_FAB2_LIB.BASEBOARD_FAB2(SCH_1):PAGE85
   198    GND @BASEBOARD_FAB2_LIB.BASEBOARD_FAB2(SCH_1):GND    I43 @BASEBOARD_FAB2_LIB.BASEBOARD_FAB2(SCH_1):PAGE85
   200    GND @BASEBOARD_FAB2_LIB.BASEBOARD_FAB2(SCH_1):GND    I43 @BASEBOARD_FAB2_LIB.BASEBOARD_FAB2(SCH_1):PAGE85
   202    GND @BASEBOARD_FAB2_LIB.BASEBOARD_FAB2(SCH_1):GND    I43 @BASEBOARD_FAB2_LIB.BASEBOARD_FAB2(SCH_1):PAGE85
   239    GND @BASEBOARD_FAB2_LIB.BASEBOARD_FAB2(SCH_1):GND    I43 @BASEBOARD_FAB2_LIB.BASEBOARD_FAB2(SCH_1):PAGE85
   241    GND @BASEBOARD_FAB2_LIB.BASEBOARD_FAB2(SCH_1):GND    I43 @BASEBOARD_FAB2_LIB.BASEBOARD_FAB2(SCH_1):PAGE85
   243    GND @BASEBOARD_FAB2_LIB.BASEBOARD_FAB2(SCH_1):GND    I43 @BASEBOARD_FAB2_LIB.BASEBOARD_FAB2(SCH_1):PAGE85
   246    GND @BASEBOARD_FAB2_LIB.BASEBOARD_FAB2(SCH_1):GND    I43 @BASEBOARD_FAB2_LIB.BASEBOARD_FAB2(SCH_1):PAGE85
   248    GND @BASEBOARD_FAB2_LIB.BASEBOARD_FAB2(SCH_1):GND    I43 @BASEBOARD_FAB2_LIB.BASEBOARD_FAB2(SCH_1):PAGE85
   250    GND @BASEBOARD_FAB2_LIB.BASEBOARD_FAB2(SCH_1):GND    I43 @BASEBOARD_FAB2_LIB.BASEBOARD_FAB2(SCH_1):PAGE85
   252    GND @BASEBOARD_FAB2_LIB.BASEBOARD_FAB2(SCH_1):GND    I43 @BASEBOARD_FAB2_LIB.BASEBOARD_FAB2(SCH_1):PAGE85
   254    GND @BASEBOARD_FAB2_LIB.BASEBOARD_FAB2(SCH_1):GND    I43 @BASEBOARD_FAB2_LIB.BASEBOARD_FAB2(SCH_1):PAGE85
   257    GND @BASEBOARD_FAB2_LIB.BASEBOARD_FAB2(SCH_1):GND    I43 @BASEBOARD_FAB2_LIB.BASEBOARD_FAB2(SCH_1):PAGE85
   259    GND @BASEBOARD_FAB2_LIB.BASEBOARD_FAB2(SCH_1):GND    I43 @BASEBOARD_FAB2_LIB.BASEBOARD_FAB2(SCH_1):PAGE85
   261    GND @BASEBOARD_FAB2_LIB.BASEBOARD_FAB2(SCH_1):GND    I43 @BASEBOARD_FAB2_LIB.BASEBOARD_FAB2(SCH_1):PAGE85
   263    GND @BASEBOARD_FAB2_LIB.BASEBOARD_FAB2(SCH_1):GND    I43 @BASEBOARD_FAB2_LIB.BASEBOARD_FAB2(SCH_1):PAGE85
   265    GND @BASEBOARD_FAB2_LIB.BASEBOARD_FAB2(SCH_1):GND    I43 @BASEBOARD_FAB2_LIB.BASEBOARD_FAB2(SCH_1):PAGE85
   268    GND @BASEBOARD_FAB2_LIB.BASEBOARD_FAB2(SCH_1):GND    I43 @BASEBOARD_FAB2_LIB.BASEBOARD_FAB2(SCH_1):PAGE85
   270    GND @BASEBOARD_FAB2_LIB.BASEBOARD_FAB2(SCH_1):GND    I43 @BASEBOARD_FAB2_LIB.BASEBOARD_FAB2(SCH_1):PAGE85
   272    GND @BASEBOARD_FAB2_LIB.BASEBOARD_FAB2(SCH_1):GND    I43 @BASEBOARD_FAB2_LIB.BASEBOARD_FAB2(SCH_1):PAGE85
   274    GND @BASEBOARD_FAB2_LIB.BASEBOARD_FAB2(SCH_1):GND    I43 @BASEBOARD_FAB2_LIB.BASEBOARD_FAB2(SCH_1):PAGE85
   276    GND @BASEBOARD_FAB2_LIB.BASEBOARD_FAB2(SCH_1):GND    I43 @BASEBOARD_FAB2_LIB.BASEBOARD_FAB2(SCH_1):PAGE85
   279    GND @BASEBOARD_FAB2_LIB.BASEBOARD_FAB2(SCH_1):GND    I43 @BASEBOARD_FAB2_LIB.BASEBOARD_FAB2(SCH_1):PAGE85
   281    GND @BASEBOARD_FAB2_LIB.BASEBOARD_FAB2(SCH_1):GND    I43 @BASEBOARD_FAB2_LIB.BASEBOARD_FAB2(SCH_1):PAGE85
   283    GND @BASEBOARD_FAB2_LIB.BASEBOARD_FAB2(SCH_1):GND    I43 @BASEBOARD_FAB2_LIB.BASEBOARD_FAB2(SCH_1):PAGE85
     1 P12V_NVDIMM_KLM @BASEBOARD_FAB2_LIB.BASEBOARD_FAB2(SCH_1):P12V_NVDIMM_KLM   I172 @BASEBOARD_FAB2_LIB.BASEBOARD_FAB2(SCH_1):PAGE85
   145 P12V_NVDIMM_KLM @BASEBOARD_FAB2_LIB.BASEBOARD_FAB2(SCH_1):P12V_NVDIMM_KLM   I172 @BASEBOARD_FAB2_LIB.BASEBOARD_FAB2(SCH_1):PAGE85
    59 PVDDQ_KLM @BASEBOARD_FAB2_LIB.BASEBOARD_FAB2(SCH_1):PVDDQ_KLM   I172 @BASEBOARD_FAB2_LIB.BASEBOARD_FAB2(SCH_1):PAGE85
    61 PVDDQ_KLM @BASEBOARD_FAB2_LIB.BASEBOARD_FAB2(SCH_1):PVDDQ_KLM   I172 @BASEBOARD_FAB2_LIB.BASEBOARD_FAB2(SCH_1):PAGE85
    64 PVDDQ_KLM @BASEBOARD_FAB2_LIB.BASEBOARD_FAB2(SCH_1):PVDDQ_KLM   I172 @BASEBOARD_FAB2_LIB.BASEBOARD_FAB2(SCH_1):PAGE85
    67 PVDDQ_KLM @BASEBOARD_FAB2_LIB.BASEBOARD_FAB2(SCH_1):PVDDQ_KLM   I172 @BASEBOARD_FAB2_LIB.BASEBOARD_FAB2(SCH_1):PAGE85
    70 PVDDQ_KLM @BASEBOARD_FAB2_LIB.BASEBOARD_FAB2(SCH_1):PVDDQ_KLM   I172 @BASEBOARD_FAB2_LIB.BASEBOARD_FAB2(SCH_1):PAGE85
    73 PVDDQ_KLM @BASEBOARD_FAB2_LIB.BASEBOARD_FAB2(SCH_1):PVDDQ_KLM   I172 @BASEBOARD_FAB2_LIB.BASEBOARD_FAB2(SCH_1):PAGE85
    76 PVDDQ_KLM @BASEBOARD_FAB2_LIB.BASEBOARD_FAB2(SCH_1):PVDDQ_KLM   I172 @BASEBOARD_FAB2_LIB.BASEBOARD_FAB2(SCH_1):PAGE85
    80 PVDDQ_KLM @BASEBOARD_FAB2_LIB.BASEBOARD_FAB2(SCH_1):PVDDQ_KLM   I172 @BASEBOARD_FAB2_LIB.BASEBOARD_FAB2(SCH_1):PAGE85
    83 PVDDQ_KLM @BASEBOARD_FAB2_LIB.BASEBOARD_FAB2(SCH_1):PVDDQ_KLM   I172 @BASEBOARD_FAB2_LIB.BASEBOARD_FAB2(SCH_1):PAGE85
    85 PVDDQ_KLM @BASEBOARD_FAB2_LIB.BASEBOARD_FAB2(SCH_1):PVDDQ_KLM   I172 @BASEBOARD_FAB2_LIB.BASEBOARD_FAB2(SCH_1):PAGE85
    88 PVDDQ_KLM @BASEBOARD_FAB2_LIB.BASEBOARD_FAB2(SCH_1):PVDDQ_KLM   I172 @BASEBOARD_FAB2_LIB.BASEBOARD_FAB2(SCH_1):PAGE85
    90 PVDDQ_KLM @BASEBOARD_FAB2_LIB.BASEBOARD_FAB2(SCH_1):PVDDQ_KLM   I172 @BASEBOARD_FAB2_LIB.BASEBOARD_FAB2(SCH_1):PAGE85
    92 PVDDQ_KLM @BASEBOARD_FAB2_LIB.BASEBOARD_FAB2(SCH_1):PVDDQ_KLM   I172 @BASEBOARD_FAB2_LIB.BASEBOARD_FAB2(SCH_1):PAGE85
   204 PVDDQ_KLM @BASEBOARD_FAB2_LIB.BASEBOARD_FAB2(SCH_1):PVDDQ_KLM   I172 @BASEBOARD_FAB2_LIB.BASEBOARD_FAB2(SCH_1):PAGE85
   206 PVDDQ_KLM @BASEBOARD_FAB2_LIB.BASEBOARD_FAB2(SCH_1):PVDDQ_KLM   I172 @BASEBOARD_FAB2_LIB.BASEBOARD_FAB2(SCH_1):PAGE85
   209 PVDDQ_KLM @BASEBOARD_FAB2_LIB.BASEBOARD_FAB2(SCH_1):PVDDQ_KLM   I172 @BASEBOARD_FAB2_LIB.BASEBOARD_FAB2(SCH_1):PAGE85
   212 PVDDQ_KLM @BASEBOARD_FAB2_LIB.BASEBOARD_FAB2(SCH_1):PVDDQ_KLM   I172 @BASEBOARD_FAB2_LIB.BASEBOARD_FAB2(SCH_1):PAGE85
   215 PVDDQ_KLM @BASEBOARD_FAB2_LIB.BASEBOARD_FAB2(SCH_1):PVDDQ_KLM   I172 @BASEBOARD_FAB2_LIB.BASEBOARD_FAB2(SCH_1):PAGE85
   217 PVDDQ_KLM @BASEBOARD_FAB2_LIB.BASEBOARD_FAB2(SCH_1):PVDDQ_KLM   I172 @BASEBOARD_FAB2_LIB.BASEBOARD_FAB2(SCH_1):PAGE85
   220 PVDDQ_KLM @BASEBOARD_FAB2_LIB.BASEBOARD_FAB2(SCH_1):PVDDQ_KLM   I172 @BASEBOARD_FAB2_LIB.BASEBOARD_FAB2(SCH_1):PAGE85
   223 PVDDQ_KLM @BASEBOARD_FAB2_LIB.BASEBOARD_FAB2(SCH_1):PVDDQ_KLM   I172 @BASEBOARD_FAB2_LIB.BASEBOARD_FAB2(SCH_1):PAGE85
   226 PVDDQ_KLM @BASEBOARD_FAB2_LIB.BASEBOARD_FAB2(SCH_1):PVDDQ_KLM   I172 @BASEBOARD_FAB2_LIB.BASEBOARD_FAB2(SCH_1):PAGE85
   229 PVDDQ_KLM @BASEBOARD_FAB2_LIB.BASEBOARD_FAB2(SCH_1):PVDDQ_KLM   I172 @BASEBOARD_FAB2_LIB.BASEBOARD_FAB2(SCH_1):PAGE85
   231 PVDDQ_KLM @BASEBOARD_FAB2_LIB.BASEBOARD_FAB2(SCH_1):PVDDQ_KLM   I172 @BASEBOARD_FAB2_LIB.BASEBOARD_FAB2(SCH_1):PAGE85
   233 PVDDQ_KLM @BASEBOARD_FAB2_LIB.BASEBOARD_FAB2(SCH_1):PVDDQ_KLM   I172 @BASEBOARD_FAB2_LIB.BASEBOARD_FAB2(SCH_1):PAGE85
   236 PVDDQ_KLM @BASEBOARD_FAB2_LIB.BASEBOARD_FAB2(SCH_1):PVDDQ_KLM   I172 @BASEBOARD_FAB2_LIB.BASEBOARD_FAB2(SCH_1):PAGE85
   142 PVPP_KLM @BASEBOARD_FAB2_LIB.BASEBOARD_FAB2(SCH_1):PVPP_KLM   I172 @BASEBOARD_FAB2_LIB.BASEBOARD_FAB2(SCH_1):PAGE85
   143 PVPP_KLM @BASEBOARD_FAB2_LIB.BASEBOARD_FAB2(SCH_1):PVPP_KLM   I172 @BASEBOARD_FAB2_LIB.BASEBOARD_FAB2(SCH_1):PAGE85
   288 PVPP_KLM @BASEBOARD_FAB2_LIB.BASEBOARD_FAB2(SCH_1):PVPP_KLM   I172 @BASEBOARD_FAB2_LIB.BASEBOARD_FAB2(SCH_1):PAGE85
   286 PVPP_KLM @BASEBOARD_FAB2_LIB.BASEBOARD_FAB2(SCH_1):PVPP_KLM   I172 @BASEBOARD_FAB2_LIB.BASEBOARD_FAB2(SCH_1):PAGE85
   287 PVPP_KLM @BASEBOARD_FAB2_LIB.BASEBOARD_FAB2(SCH_1):PVPP_KLM   I172 @BASEBOARD_FAB2_LIB.BASEBOARD_FAB2(SCH_1):PAGE85
    77 PVTT_KLM @BASEBOARD_FAB2_LIB.BASEBOARD_FAB2(SCH_1):PVTT_KLM   I172 @BASEBOARD_FAB2_LIB.BASEBOARD_FAB2(SCH_1):PAGE85
   221 PVTT_KLM @BASEBOARD_FAB2_LIB.BASEBOARD_FAB2(SCH_1):PVTT_KLM   I172 @BASEBOARD_FAB2_LIB.BASEBOARD_FAB2(SCH_1):PAGE85

J1B1 SCONN288_H44441004_PIP-SCONN,HA
    79 M_K_MA<0> @BASEBOARD_FAB2_LIB.BASEBOARD_FAB2(SCH_1):M_K_MA(0)   I111 @BASEBOARD_FAB2_LIB.BASEBOARD_FAB2(SCH_1):PAGE83
    72 M_K_MA<1> @BASEBOARD_FAB2_LIB.BASEBOARD_FAB2(SCH_1):M_K_MA(1)   I111 @BASEBOARD_FAB2_LIB.BASEBOARD_FAB2(SCH_1):PAGE83
   225 M_K_MA<10> @BASEBOARD_FAB2_LIB.BASEBOARD_FAB2(SCH_1):M_K_MA(10)   I111 @BASEBOARD_FAB2_LIB.BASEBOARD_FAB2(SCH_1):PAGE83
   210 M_K_MA<11> @BASEBOARD_FAB2_LIB.BASEBOARD_FAB2(SCH_1):M_K_MA(11)   I111 @BASEBOARD_FAB2_LIB.BASEBOARD_FAB2(SCH_1):PAGE83
    65 M_K_MA<12> @BASEBOARD_FAB2_LIB.BASEBOARD_FAB2(SCH_1):M_K_MA(12)   I111 @BASEBOARD_FAB2_LIB.BASEBOARD_FAB2(SCH_1):PAGE83
   232 M_K_MA<13> @BASEBOARD_FAB2_LIB.BASEBOARD_FAB2(SCH_1):M_K_MA(13)   I111 @BASEBOARD_FAB2_LIB.BASEBOARD_FAB2(SCH_1):PAGE83
   228 M_K_MA<14> @BASEBOARD_FAB2_LIB.BASEBOARD_FAB2(SCH_1):M_K_MA(14)   I111 @BASEBOARD_FAB2_LIB.BASEBOARD_FAB2(SCH_1):PAGE83
    86 M_K_MA<15> @BASEBOARD_FAB2_LIB.BASEBOARD_FAB2(SCH_1):M_K_MA(15)   I111 @BASEBOARD_FAB2_LIB.BASEBOARD_FAB2(SCH_1):PAGE83
    82 M_K_MA<16> @BASEBOARD_FAB2_LIB.BASEBOARD_FAB2(SCH_1):M_K_MA(16)   I111 @BASEBOARD_FAB2_LIB.BASEBOARD_FAB2(SCH_1):PAGE83
   234 M_K_MA<17> @BASEBOARD_FAB2_LIB.BASEBOARD_FAB2(SCH_1):M_K_MA(17)   I111 @BASEBOARD_FAB2_LIB.BASEBOARD_FAB2(SCH_1):PAGE83
   216 M_K_MA<2> @BASEBOARD_FAB2_LIB.BASEBOARD_FAB2(SCH_1):M_K_MA(2)   I111 @BASEBOARD_FAB2_LIB.BASEBOARD_FAB2(SCH_1):PAGE83
    71 M_K_MA<3> @BASEBOARD_FAB2_LIB.BASEBOARD_FAB2(SCH_1):M_K_MA(3)   I111 @BASEBOARD_FAB2_LIB.BASEBOARD_FAB2(SCH_1):PAGE83
   214 M_K_MA<4> @BASEBOARD_FAB2_LIB.BASEBOARD_FAB2(SCH_1):M_K_MA(4)   I111 @BASEBOARD_FAB2_LIB.BASEBOARD_FAB2(SCH_1):PAGE83
   213 M_K_MA<5> @BASEBOARD_FAB2_LIB.BASEBOARD_FAB2(SCH_1):M_K_MA(5)   I111 @BASEBOARD_FAB2_LIB.BASEBOARD_FAB2(SCH_1):PAGE83
    69 M_K_MA<6> @BASEBOARD_FAB2_LIB.BASEBOARD_FAB2(SCH_1):M_K_MA(6)   I111 @BASEBOARD_FAB2_LIB.BASEBOARD_FAB2(SCH_1):PAGE83
   211 M_K_MA<7> @BASEBOARD_FAB2_LIB.BASEBOARD_FAB2(SCH_1):M_K_MA(7)   I111 @BASEBOARD_FAB2_LIB.BASEBOARD_FAB2(SCH_1):PAGE83
    68 M_K_MA<8> @BASEBOARD_FAB2_LIB.BASEBOARD_FAB2(SCH_1):M_K_MA(8)   I111 @BASEBOARD_FAB2_LIB.BASEBOARD_FAB2(SCH_1):PAGE83
    66 M_K_MA<9> @BASEBOARD_FAB2_LIB.BASEBOARD_FAB2(SCH_1):M_K_MA(9)   I111 @BASEBOARD_FAB2_LIB.BASEBOARD_FAB2(SCH_1):PAGE83
    62 M_K_ACT_N @BASEBOARD_FAB2_LIB.BASEBOARD_FAB2(SCH_1):M_K_ACT_N   I111 @BASEBOARD_FAB2_LIB.BASEBOARD_FAB2(SCH_1):PAGE83
   208 M_K_ALERT_N @BASEBOARD_FAB2_LIB.BASEBOARD_FAB2(SCH_1):M_K_ALERT_N   I111 @BASEBOARD_FAB2_LIB.BASEBOARD_FAB2(SCH_1):PAGE83
   224 M_K_BA<1> @BASEBOARD_FAB2_LIB.BASEBOARD_FAB2(SCH_1):M_K_BA(1)   I111 @BASEBOARD_FAB2_LIB.BASEBOARD_FAB2(SCH_1):PAGE83
    81 M_K_BA<0> @BASEBOARD_FAB2_LIB.BASEBOARD_FAB2(SCH_1):M_K_BA(0)   I111 @BASEBOARD_FAB2_LIB.BASEBOARD_FAB2(SCH_1):PAGE83
   207 M_K_BG<1> @BASEBOARD_FAB2_LIB.BASEBOARD_FAB2(SCH_1):M_K_BG(1)   I111 @BASEBOARD_FAB2_LIB.BASEBOARD_FAB2(SCH_1):PAGE83
    63 M_K_BG<0> @BASEBOARD_FAB2_LIB.BASEBOARD_FAB2(SCH_1):M_K_BG(0)   I111 @BASEBOARD_FAB2_LIB.BASEBOARD_FAB2(SCH_1):PAGE83
   235 M_K_C<2> @BASEBOARD_FAB2_LIB.BASEBOARD_FAB2(SCH_1):M_K_C(2)   I111 @BASEBOARD_FAB2_LIB.BASEBOARD_FAB2(SCH_1):PAGE83
   199 M_K_ECC<6> @BASEBOARD_FAB2_LIB.BASEBOARD_FAB2(SCH_1):M_K_ECC(6)   I111 @BASEBOARD_FAB2_LIB.BASEBOARD_FAB2(SCH_1):PAGE83
    54 M_K_ECC<7> @BASEBOARD_FAB2_LIB.BASEBOARD_FAB2(SCH_1):M_K_ECC(7)   I111 @BASEBOARD_FAB2_LIB.BASEBOARD_FAB2(SCH_1):PAGE83
   192 M_K_ECC<4> @BASEBOARD_FAB2_LIB.BASEBOARD_FAB2(SCH_1):M_K_ECC(4)   I111 @BASEBOARD_FAB2_LIB.BASEBOARD_FAB2(SCH_1):PAGE83
    47 M_K_ECC<5> @BASEBOARD_FAB2_LIB.BASEBOARD_FAB2(SCH_1):M_K_ECC(5)   I111 @BASEBOARD_FAB2_LIB.BASEBOARD_FAB2(SCH_1):PAGE83
   201 M_K_ECC<2> @BASEBOARD_FAB2_LIB.BASEBOARD_FAB2(SCH_1):M_K_ECC(2)   I111 @BASEBOARD_FAB2_LIB.BASEBOARD_FAB2(SCH_1):PAGE83
    56 M_K_ECC<3> @BASEBOARD_FAB2_LIB.BASEBOARD_FAB2(SCH_1):M_K_ECC(3)   I111 @BASEBOARD_FAB2_LIB.BASEBOARD_FAB2(SCH_1):PAGE83
   194 M_K_ECC<0> @BASEBOARD_FAB2_LIB.BASEBOARD_FAB2(SCH_1):M_K_ECC(0)   I111 @BASEBOARD_FAB2_LIB.BASEBOARD_FAB2(SCH_1):PAGE83
    49 M_K_ECC<1> @BASEBOARD_FAB2_LIB.BASEBOARD_FAB2(SCH_1):M_K_ECC(1)   I111 @BASEBOARD_FAB2_LIB.BASEBOARD_FAB2(SCH_1):PAGE83
    75 M_K_CLK_DN<0> @BASEBOARD_FAB2_LIB.BASEBOARD_FAB2(SCH_1):M_K_CLK_DN(0)   I111 @BASEBOARD_FAB2_LIB.BASEBOARD_FAB2(SCH_1):PAGE83
    74 M_K_CLK_DP<0> @BASEBOARD_FAB2_LIB.BASEBOARD_FAB2(SCH_1):M_K_CLK_DP(0)   I111 @BASEBOARD_FAB2_LIB.BASEBOARD_FAB2(SCH_1):PAGE83
   219 M_K_CLK_DN<1> @BASEBOARD_FAB2_LIB.BASEBOARD_FAB2(SCH_1):M_K_CLK_DN(1)   I111 @BASEBOARD_FAB2_LIB.BASEBOARD_FAB2(SCH_1):PAGE83
   218 M_K_CLK_DP<1> @BASEBOARD_FAB2_LIB.BASEBOARD_FAB2(SCH_1):M_K_CLK_DP(1)   I111 @BASEBOARD_FAB2_LIB.BASEBOARD_FAB2(SCH_1):PAGE83
   203 M_K_CKE<1> @BASEBOARD_FAB2_LIB.BASEBOARD_FAB2(SCH_1):M_K_CKE(1)   I111 @BASEBOARD_FAB2_LIB.BASEBOARD_FAB2(SCH_1):PAGE83
    60 M_K_CKE<0> @BASEBOARD_FAB2_LIB.BASEBOARD_FAB2(SCH_1):M_K_CKE(0)   I111 @BASEBOARD_FAB2_LIB.BASEBOARD_FAB2(SCH_1):PAGE83
   280 M_K_DQ<62> @BASEBOARD_FAB2_LIB.BASEBOARD_FAB2(SCH_1):M_K_DQ(62)   I111 @BASEBOARD_FAB2_LIB.BASEBOARD_FAB2(SCH_1):PAGE83
   135 M_K_DQ<63> @BASEBOARD_FAB2_LIB.BASEBOARD_FAB2(SCH_1):M_K_DQ(63)   I111 @BASEBOARD_FAB2_LIB.BASEBOARD_FAB2(SCH_1):PAGE83
   273 M_K_DQ<60> @BASEBOARD_FAB2_LIB.BASEBOARD_FAB2(SCH_1):M_K_DQ(60)   I111 @BASEBOARD_FAB2_LIB.BASEBOARD_FAB2(SCH_1):PAGE83
   128 M_K_DQ<61> @BASEBOARD_FAB2_LIB.BASEBOARD_FAB2(SCH_1):M_K_DQ(61)   I111 @BASEBOARD_FAB2_LIB.BASEBOARD_FAB2(SCH_1):PAGE83
   282 M_K_DQ<58> @BASEBOARD_FAB2_LIB.BASEBOARD_FAB2(SCH_1):M_K_DQ(58)   I111 @BASEBOARD_FAB2_LIB.BASEBOARD_FAB2(SCH_1):PAGE83
   137 M_K_DQ<59> @BASEBOARD_FAB2_LIB.BASEBOARD_FAB2(SCH_1):M_K_DQ(59)   I111 @BASEBOARD_FAB2_LIB.BASEBOARD_FAB2(SCH_1):PAGE83
   275 M_K_DQ<56> @BASEBOARD_FAB2_LIB.BASEBOARD_FAB2(SCH_1):M_K_DQ(56)   I111 @BASEBOARD_FAB2_LIB.BASEBOARD_FAB2(SCH_1):PAGE83
   130 M_K_DQ<57> @BASEBOARD_FAB2_LIB.BASEBOARD_FAB2(SCH_1):M_K_DQ(57)   I111 @BASEBOARD_FAB2_LIB.BASEBOARD_FAB2(SCH_1):PAGE83
   269 M_K_DQ<54> @BASEBOARD_FAB2_LIB.BASEBOARD_FAB2(SCH_1):M_K_DQ(54)   I111 @BASEBOARD_FAB2_LIB.BASEBOARD_FAB2(SCH_1):PAGE83
   124 M_K_DQ<55> @BASEBOARD_FAB2_LIB.BASEBOARD_FAB2(SCH_1):M_K_DQ(55)   I111 @BASEBOARD_FAB2_LIB.BASEBOARD_FAB2(SCH_1):PAGE83
   262 M_K_DQ<52> @BASEBOARD_FAB2_LIB.BASEBOARD_FAB2(SCH_1):M_K_DQ(52)   I111 @BASEBOARD_FAB2_LIB.BASEBOARD_FAB2(SCH_1):PAGE83
   117 M_K_DQ<53> @BASEBOARD_FAB2_LIB.BASEBOARD_FAB2(SCH_1):M_K_DQ(53)   I111 @BASEBOARD_FAB2_LIB.BASEBOARD_FAB2(SCH_1):PAGE83
   271 M_K_DQ<50> @BASEBOARD_FAB2_LIB.BASEBOARD_FAB2(SCH_1):M_K_DQ(50)   I111 @BASEBOARD_FAB2_LIB.BASEBOARD_FAB2(SCH_1):PAGE83
   126 M_K_DQ<51> @BASEBOARD_FAB2_LIB.BASEBOARD_FAB2(SCH_1):M_K_DQ(51)   I111 @BASEBOARD_FAB2_LIB.BASEBOARD_FAB2(SCH_1):PAGE83
   264 M_K_DQ<48> @BASEBOARD_FAB2_LIB.BASEBOARD_FAB2(SCH_1):M_K_DQ(48)   I111 @BASEBOARD_FAB2_LIB.BASEBOARD_FAB2(SCH_1):PAGE83
   119 M_K_DQ<49> @BASEBOARD_FAB2_LIB.BASEBOARD_FAB2(SCH_1):M_K_DQ(49)   I111 @BASEBOARD_FAB2_LIB.BASEBOARD_FAB2(SCH_1):PAGE83
   258 M_K_DQ<46> @BASEBOARD_FAB2_LIB.BASEBOARD_FAB2(SCH_1):M_K_DQ(46)   I111 @BASEBOARD_FAB2_LIB.BASEBOARD_FAB2(SCH_1):PAGE83
   113 M_K_DQ<47> @BASEBOARD_FAB2_LIB.BASEBOARD_FAB2(SCH_1):M_K_DQ(47)   I111 @BASEBOARD_FAB2_LIB.BASEBOARD_FAB2(SCH_1):PAGE83
   251 M_K_DQ<44> @BASEBOARD_FAB2_LIB.BASEBOARD_FAB2(SCH_1):M_K_DQ(44)   I111 @BASEBOARD_FAB2_LIB.BASEBOARD_FAB2(SCH_1):PAGE83
   106 M_K_DQ<45> @BASEBOARD_FAB2_LIB.BASEBOARD_FAB2(SCH_1):M_K_DQ(45)   I111 @BASEBOARD_FAB2_LIB.BASEBOARD_FAB2(SCH_1):PAGE83
   260 M_K_DQ<42> @BASEBOARD_FAB2_LIB.BASEBOARD_FAB2(SCH_1):M_K_DQ(42)   I111 @BASEBOARD_FAB2_LIB.BASEBOARD_FAB2(SCH_1):PAGE83
   115 M_K_DQ<43> @BASEBOARD_FAB2_LIB.BASEBOARD_FAB2(SCH_1):M_K_DQ(43)   I111 @BASEBOARD_FAB2_LIB.BASEBOARD_FAB2(SCH_1):PAGE83
   253 M_K_DQ<40> @BASEBOARD_FAB2_LIB.BASEBOARD_FAB2(SCH_1):M_K_DQ(40)   I111 @BASEBOARD_FAB2_LIB.BASEBOARD_FAB2(SCH_1):PAGE83
   108 M_K_DQ<41> @BASEBOARD_FAB2_LIB.BASEBOARD_FAB2(SCH_1):M_K_DQ(41)   I111 @BASEBOARD_FAB2_LIB.BASEBOARD_FAB2(SCH_1):PAGE83
   247 M_K_DQ<38> @BASEBOARD_FAB2_LIB.BASEBOARD_FAB2(SCH_1):M_K_DQ(38)   I111 @BASEBOARD_FAB2_LIB.BASEBOARD_FAB2(SCH_1):PAGE83
   102 M_K_DQ<39> @BASEBOARD_FAB2_LIB.BASEBOARD_FAB2(SCH_1):M_K_DQ(39)   I111 @BASEBOARD_FAB2_LIB.BASEBOARD_FAB2(SCH_1):PAGE83
   240 M_K_DQ<36> @BASEBOARD_FAB2_LIB.BASEBOARD_FAB2(SCH_1):M_K_DQ(36)   I111 @BASEBOARD_FAB2_LIB.BASEBOARD_FAB2(SCH_1):PAGE83
    95 M_K_DQ<37> @BASEBOARD_FAB2_LIB.BASEBOARD_FAB2(SCH_1):M_K_DQ(37)   I111 @BASEBOARD_FAB2_LIB.BASEBOARD_FAB2(SCH_1):PAGE83
   249 M_K_DQ<34> @BASEBOARD_FAB2_LIB.BASEBOARD_FAB2(SCH_1):M_K_DQ(34)   I111 @BASEBOARD_FAB2_LIB.BASEBOARD_FAB2(SCH_1):PAGE83
   104 M_K_DQ<35> @BASEBOARD_FAB2_LIB.BASEBOARD_FAB2(SCH_1):M_K_DQ(35)   I111 @BASEBOARD_FAB2_LIB.BASEBOARD_FAB2(SCH_1):PAGE83
   242 M_K_DQ<32> @BASEBOARD_FAB2_LIB.BASEBOARD_FAB2(SCH_1):M_K_DQ(32)   I111 @BASEBOARD_FAB2_LIB.BASEBOARD_FAB2(SCH_1):PAGE83
    97 M_K_DQ<33> @BASEBOARD_FAB2_LIB.BASEBOARD_FAB2(SCH_1):M_K_DQ(33)   I111 @BASEBOARD_FAB2_LIB.BASEBOARD_FAB2(SCH_1):PAGE83
   188 M_K_DQ<30> @BASEBOARD_FAB2_LIB.BASEBOARD_FAB2(SCH_1):M_K_DQ(30)   I111 @BASEBOARD_FAB2_LIB.BASEBOARD_FAB2(SCH_1):PAGE83
    43 M_K_DQ<31> @BASEBOARD_FAB2_LIB.BASEBOARD_FAB2(SCH_1):M_K_DQ(31)   I111 @BASEBOARD_FAB2_LIB.BASEBOARD_FAB2(SCH_1):PAGE83
   181 M_K_DQ<28> @BASEBOARD_FAB2_LIB.BASEBOARD_FAB2(SCH_1):M_K_DQ(28)   I111 @BASEBOARD_FAB2_LIB.BASEBOARD_FAB2(SCH_1):PAGE83
    36 M_K_DQ<29> @BASEBOARD_FAB2_LIB.BASEBOARD_FAB2(SCH_1):M_K_DQ(29)   I111 @BASEBOARD_FAB2_LIB.BASEBOARD_FAB2(SCH_1):PAGE83
   190 M_K_DQ<26> @BASEBOARD_FAB2_LIB.BASEBOARD_FAB2(SCH_1):M_K_DQ(26)   I111 @BASEBOARD_FAB2_LIB.BASEBOARD_FAB2(SCH_1):PAGE83
    45 M_K_DQ<27> @BASEBOARD_FAB2_LIB.BASEBOARD_FAB2(SCH_1):M_K_DQ(27)   I111 @BASEBOARD_FAB2_LIB.BASEBOARD_FAB2(SCH_1):PAGE83
   183 M_K_DQ<24> @BASEBOARD_FAB2_LIB.BASEBOARD_FAB2(SCH_1):M_K_DQ(24)   I111 @BASEBOARD_FAB2_LIB.BASEBOARD_FAB2(SCH_1):PAGE83
    38 M_K_DQ<25> @BASEBOARD_FAB2_LIB.BASEBOARD_FAB2(SCH_1):M_K_DQ(25)   I111 @BASEBOARD_FAB2_LIB.BASEBOARD_FAB2(SCH_1):PAGE83
   177 M_K_DQ<22> @BASEBOARD_FAB2_LIB.BASEBOARD_FAB2(SCH_1):M_K_DQ(22)   I111 @BASEBOARD_FAB2_LIB.BASEBOARD_FAB2(SCH_1):PAGE83
    32 M_K_DQ<23> @BASEBOARD_FAB2_LIB.BASEBOARD_FAB2(SCH_1):M_K_DQ(23)   I111 @BASEBOARD_FAB2_LIB.BASEBOARD_FAB2(SCH_1):PAGE83
   170 M_K_DQ<20> @BASEBOARD_FAB2_LIB.BASEBOARD_FAB2(SCH_1):M_K_DQ(20)   I111 @BASEBOARD_FAB2_LIB.BASEBOARD_FAB2(SCH_1):PAGE83
    25 M_K_DQ<21> @BASEBOARD_FAB2_LIB.BASEBOARD_FAB2(SCH_1):M_K_DQ(21)   I111 @BASEBOARD_FAB2_LIB.BASEBOARD_FAB2(SCH_1):PAGE83
   179 M_K_DQ<18> @BASEBOARD_FAB2_LIB.BASEBOARD_FAB2(SCH_1):M_K_DQ(18)   I111 @BASEBOARD_FAB2_LIB.BASEBOARD_FAB2(SCH_1):PAGE83
    34 M_K_DQ<19> @BASEBOARD_FAB2_LIB.BASEBOARD_FAB2(SCH_1):M_K_DQ(19)   I111 @BASEBOARD_FAB2_LIB.BASEBOARD_FAB2(SCH_1):PAGE83
   172 M_K_DQ<16> @BASEBOARD_FAB2_LIB.BASEBOARD_FAB2(SCH_1):M_K_DQ(16)   I111 @BASEBOARD_FAB2_LIB.BASEBOARD_FAB2(SCH_1):PAGE83
    27 M_K_DQ<17> @BASEBOARD_FAB2_LIB.BASEBOARD_FAB2(SCH_1):M_K_DQ(17)   I111 @BASEBOARD_FAB2_LIB.BASEBOARD_FAB2(SCH_1):PAGE83
   166 M_K_DQ<14> @BASEBOARD_FAB2_LIB.BASEBOARD_FAB2(SCH_1):M_K_DQ(14)   I111 @BASEBOARD_FAB2_LIB.BASEBOARD_FAB2(SCH_1):PAGE83
    21 M_K_DQ<15> @BASEBOARD_FAB2_LIB.BASEBOARD_FAB2(SCH_1):M_K_DQ(15)   I111 @BASEBOARD_FAB2_LIB.BASEBOARD_FAB2(SCH_1):PAGE83
   159 M_K_DQ<12> @BASEBOARD_FAB2_LIB.BASEBOARD_FAB2(SCH_1):M_K_DQ(12)   I111 @BASEBOARD_FAB2_LIB.BASEBOARD_FAB2(SCH_1):PAGE83
    14 M_K_DQ<13> @BASEBOARD_FAB2_LIB.BASEBOARD_FAB2(SCH_1):M_K_DQ(13)   I111 @BASEBOARD_FAB2_LIB.BASEBOARD_FAB2(SCH_1):PAGE83
   168 M_K_DQ<10> @BASEBOARD_FAB2_LIB.BASEBOARD_FAB2(SCH_1):M_K_DQ(10)   I111 @BASEBOARD_FAB2_LIB.BASEBOARD_FAB2(SCH_1):PAGE83
    23 M_K_DQ<11> @BASEBOARD_FAB2_LIB.BASEBOARD_FAB2(SCH_1):M_K_DQ(11)   I111 @BASEBOARD_FAB2_LIB.BASEBOARD_FAB2(SCH_1):PAGE83
   161 M_K_DQ<8> @BASEBOARD_FAB2_LIB.BASEBOARD_FAB2(SCH_1):M_K_DQ(8)   I111 @BASEBOARD_FAB2_LIB.BASEBOARD_FAB2(SCH_1):PAGE83
    16 M_K_DQ<9> @BASEBOARD_FAB2_LIB.BASEBOARD_FAB2(SCH_1):M_K_DQ(9)   I111 @BASEBOARD_FAB2_LIB.BASEBOARD_FAB2(SCH_1):PAGE83
   155 M_K_DQ<6> @BASEBOARD_FAB2_LIB.BASEBOARD_FAB2(SCH_1):M_K_DQ(6)   I111 @BASEBOARD_FAB2_LIB.BASEBOARD_FAB2(SCH_1):PAGE83
    10 M_K_DQ<7> @BASEBOARD_FAB2_LIB.BASEBOARD_FAB2(SCH_1):M_K_DQ(7)   I111 @BASEBOARD_FAB2_LIB.BASEBOARD_FAB2(SCH_1):PAGE83
   148 M_K_DQ<4> @BASEBOARD_FAB2_LIB.BASEBOARD_FAB2(SCH_1):M_K_DQ(4)   I111 @BASEBOARD_FAB2_LIB.BASEBOARD_FAB2(SCH_1):PAGE83
     3 M_K_DQ<5> @BASEBOARD_FAB2_LIB.BASEBOARD_FAB2(SCH_1):M_K_DQ(5)   I111 @BASEBOARD_FAB2_LIB.BASEBOARD_FAB2(SCH_1):PAGE83
   157 M_K_DQ<2> @BASEBOARD_FAB2_LIB.BASEBOARD_FAB2(SCH_1):M_K_DQ(2)   I111 @BASEBOARD_FAB2_LIB.BASEBOARD_FAB2(SCH_1):PAGE83
    12 M_K_DQ<3> @BASEBOARD_FAB2_LIB.BASEBOARD_FAB2(SCH_1):M_K_DQ(3)   I111 @BASEBOARD_FAB2_LIB.BASEBOARD_FAB2(SCH_1):PAGE83
   150 M_K_DQ<0> @BASEBOARD_FAB2_LIB.BASEBOARD_FAB2(SCH_1):M_K_DQ(0)   I111 @BASEBOARD_FAB2_LIB.BASEBOARD_FAB2(SCH_1):PAGE83
     5 M_K_DQ<1> @BASEBOARD_FAB2_LIB.BASEBOARD_FAB2(SCH_1):M_K_DQ(1)   I111 @BASEBOARD_FAB2_LIB.BASEBOARD_FAB2(SCH_1):PAGE83
    78 FM_DIMM_EVENT_COD_N @BASEBOARD_FAB2_LIB.BASEBOARD_FAB2(SCH_1):FM_DIMM_EVENT_COD_N   I111 @BASEBOARD_FAB2_LIB.BASEBOARD_FAB2(SCH_1):PAGE83
    91 M_K_ODT<1> @BASEBOARD_FAB2_LIB.BASEBOARD_FAB2(SCH_1):M_K_ODT(1)   I111 @BASEBOARD_FAB2_LIB.BASEBOARD_FAB2(SCH_1):PAGE83
    87 M_K_ODT<0> @BASEBOARD_FAB2_LIB.BASEBOARD_FAB2(SCH_1):M_K_ODT(0)   I111 @BASEBOARD_FAB2_LIB.BASEBOARD_FAB2(SCH_1):PAGE83
   222 M_K_PAR @BASEBOARD_FAB2_LIB.BASEBOARD_FAB2(SCH_1):M_K_PAR   I111 @BASEBOARD_FAB2_LIB.BASEBOARD_FAB2(SCH_1):PAGE83
    58 M_KLM_RST_N @BASEBOARD_FAB2_LIB.BASEBOARD_FAB2(SCH_1):M_KLM_RST_N   I111 @BASEBOARD_FAB2_LIB.BASEBOARD_FAB2(SCH_1):PAGE83
   144 TP_CH_K_DIMM_K0_RFU_2 @BASEBOARD_FAB2_LIB.BASEBOARD_FAB2(SCH_1):TP_CH_K_DIMM_K0_RFU_2   I111 @BASEBOARD_FAB2_LIB.BASEBOARD_FAB2(SCH_1):PAGE83
   227 TP_CH_K_DIMM_K0_RFU_1 @BASEBOARD_FAB2_LIB.BASEBOARD_FAB2(SCH_1):TP_CH_K_DIMM_K0_RFU_1   I111 @BASEBOARD_FAB2_LIB.BASEBOARD_FAB2(SCH_1):PAGE83
   205 TP_CH_K_DIMM_K0_RFU_0 @BASEBOARD_FAB2_LIB.BASEBOARD_FAB2(SCH_1):TP_CH_K_DIMM_K0_RFU_0   I111 @BASEBOARD_FAB2_LIB.BASEBOARD_FAB2(SCH_1):PAGE83
    84 M_K_CS_N<0> @BASEBOARD_FAB2_LIB.BASEBOARD_FAB2(SCH_1):M_K_CS_N(0)   I111 @BASEBOARD_FAB2_LIB.BASEBOARD_FAB2(SCH_1):PAGE83
    89 M_K_CS_N<1> @BASEBOARD_FAB2_LIB.BASEBOARD_FAB2(SCH_1):M_K_CS_N(1)   I111 @BASEBOARD_FAB2_LIB.BASEBOARD_FAB2(SCH_1):PAGE83
    93 M_K_CS_N<2> @BASEBOARD_FAB2_LIB.BASEBOARD_FAB2(SCH_1):M_K_CS_N(2)   I111 @BASEBOARD_FAB2_LIB.BASEBOARD_FAB2(SCH_1):PAGE83
   237 M_K_CS_N<3> @BASEBOARD_FAB2_LIB.BASEBOARD_FAB2(SCH_1):M_K_CS_N(3)   I111 @BASEBOARD_FAB2_LIB.BASEBOARD_FAB2(SCH_1):PAGE83
   238    GND @BASEBOARD_FAB2_LIB.BASEBOARD_FAB2(SCH_1):GND   I111 @BASEBOARD_FAB2_LIB.BASEBOARD_FAB2(SCH_1):PAGE83
   140    GND @BASEBOARD_FAB2_LIB.BASEBOARD_FAB2(SCH_1):GND   I111 @BASEBOARD_FAB2_LIB.BASEBOARD_FAB2(SCH_1):PAGE83
   139    GND @BASEBOARD_FAB2_LIB.BASEBOARD_FAB2(SCH_1):GND   I111 @BASEBOARD_FAB2_LIB.BASEBOARD_FAB2(SCH_1):PAGE83
   230 FM_ADR_COMPLETE_KLM_N @BASEBOARD_FAB2_LIB.BASEBOARD_FAB2(SCH_1):FM_ADR_COMPLETE_KLM_N   I111 @BASEBOARD_FAB2_LIB.BASEBOARD_FAB2(SCH_1):PAGE83
   141 SMB_DDR_KLM_VPP_SCL @BASEBOARD_FAB2_LIB.BASEBOARD_FAB2(SCH_1):SMB_DDR_KLM_VPP_SCL   I111 @BASEBOARD_FAB2_LIB.BASEBOARD_FAB2(SCH_1):PAGE83
   285 SMB_DDR_KLM_VPP_SDA @BASEBOARD_FAB2_LIB.BASEBOARD_FAB2(SCH_1):SMB_DDR_KLM_VPP_SDA   I111 @BASEBOARD_FAB2_LIB.BASEBOARD_FAB2(SCH_1):PAGE83
   284 PVPP_KLM @BASEBOARD_FAB2_LIB.BASEBOARD_FAB2(SCH_1):PVPP_KLM   I111 @BASEBOARD_FAB2_LIB.BASEBOARD_FAB2(SCH_1):PAGE83
   146 M_K_VREF @BASEBOARD_FAB2_LIB.BASEBOARD_FAB2(SCH_1):M_K_VREF   I111 @BASEBOARD_FAB2_LIB.BASEBOARD_FAB2(SCH_1):PAGE83
   152 M_K_DQS_DN<0> @BASEBOARD_FAB2_LIB.BASEBOARD_FAB2(SCH_1):M_K_DQS_DN(0)    I66 @BASEBOARD_FAB2_LIB.BASEBOARD_FAB2(SCH_1):PAGE83
   153 M_K_DQS_DP<0> @BASEBOARD_FAB2_LIB.BASEBOARD_FAB2(SCH_1):M_K_DQS_DP(0)    I66 @BASEBOARD_FAB2_LIB.BASEBOARD_FAB2(SCH_1):PAGE83
    19 M_K_DQS_DN<10> @BASEBOARD_FAB2_LIB.BASEBOARD_FAB2(SCH_1):M_K_DQS_DN(10)    I66 @BASEBOARD_FAB2_LIB.BASEBOARD_FAB2(SCH_1):PAGE83
    18 M_K_DQS_DP<10> @BASEBOARD_FAB2_LIB.BASEBOARD_FAB2(SCH_1):M_K_DQS_DP(10)    I66 @BASEBOARD_FAB2_LIB.BASEBOARD_FAB2(SCH_1):PAGE83
    30 M_K_DQS_DN<11> @BASEBOARD_FAB2_LIB.BASEBOARD_FAB2(SCH_1):M_K_DQS_DN(11)    I66 @BASEBOARD_FAB2_LIB.BASEBOARD_FAB2(SCH_1):PAGE83
    29 M_K_DQS_DP<11> @BASEBOARD_FAB2_LIB.BASEBOARD_FAB2(SCH_1):M_K_DQS_DP(11)    I66 @BASEBOARD_FAB2_LIB.BASEBOARD_FAB2(SCH_1):PAGE83
    41 M_K_DQS_DN<12> @BASEBOARD_FAB2_LIB.BASEBOARD_FAB2(SCH_1):M_K_DQS_DN(12)    I66 @BASEBOARD_FAB2_LIB.BASEBOARD_FAB2(SCH_1):PAGE83
    40 M_K_DQS_DP<12> @BASEBOARD_FAB2_LIB.BASEBOARD_FAB2(SCH_1):M_K_DQS_DP(12)    I66 @BASEBOARD_FAB2_LIB.BASEBOARD_FAB2(SCH_1):PAGE83
   100 M_K_DQS_DN<13> @BASEBOARD_FAB2_LIB.BASEBOARD_FAB2(SCH_1):M_K_DQS_DN(13)    I66 @BASEBOARD_FAB2_LIB.BASEBOARD_FAB2(SCH_1):PAGE83
    99 M_K_DQS_DP<13> @BASEBOARD_FAB2_LIB.BASEBOARD_FAB2(SCH_1):M_K_DQS_DP(13)    I66 @BASEBOARD_FAB2_LIB.BASEBOARD_FAB2(SCH_1):PAGE83
   111 M_K_DQS_DN<14> @BASEBOARD_FAB2_LIB.BASEBOARD_FAB2(SCH_1):M_K_DQS_DN(14)    I66 @BASEBOARD_FAB2_LIB.BASEBOARD_FAB2(SCH_1):PAGE83
   110 M_K_DQS_DP<14> @BASEBOARD_FAB2_LIB.BASEBOARD_FAB2(SCH_1):M_K_DQS_DP(14)    I66 @BASEBOARD_FAB2_LIB.BASEBOARD_FAB2(SCH_1):PAGE83
   122 M_K_DQS_DN<15> @BASEBOARD_FAB2_LIB.BASEBOARD_FAB2(SCH_1):M_K_DQS_DN(15)    I66 @BASEBOARD_FAB2_LIB.BASEBOARD_FAB2(SCH_1):PAGE83
   121 M_K_DQS_DP<15> @BASEBOARD_FAB2_LIB.BASEBOARD_FAB2(SCH_1):M_K_DQS_DP(15)    I66 @BASEBOARD_FAB2_LIB.BASEBOARD_FAB2(SCH_1):PAGE83
   133 M_K_DQS_DN<16> @BASEBOARD_FAB2_LIB.BASEBOARD_FAB2(SCH_1):M_K_DQS_DN(16)    I66 @BASEBOARD_FAB2_LIB.BASEBOARD_FAB2(SCH_1):PAGE83
   132 M_K_DQS_DP<16> @BASEBOARD_FAB2_LIB.BASEBOARD_FAB2(SCH_1):M_K_DQS_DP(16)    I66 @BASEBOARD_FAB2_LIB.BASEBOARD_FAB2(SCH_1):PAGE83
    52 M_K_DQS_DN<17> @BASEBOARD_FAB2_LIB.BASEBOARD_FAB2(SCH_1):M_K_DQS_DN(17)    I66 @BASEBOARD_FAB2_LIB.BASEBOARD_FAB2(SCH_1):PAGE83
    51 M_K_DQS_DP<17> @BASEBOARD_FAB2_LIB.BASEBOARD_FAB2(SCH_1):M_K_DQS_DP(17)    I66 @BASEBOARD_FAB2_LIB.BASEBOARD_FAB2(SCH_1):PAGE83
   163 M_K_DQS_DN<1> @BASEBOARD_FAB2_LIB.BASEBOARD_FAB2(SCH_1):M_K_DQS_DN(1)    I66 @BASEBOARD_FAB2_LIB.BASEBOARD_FAB2(SCH_1):PAGE83
   164 M_K_DQS_DP<1> @BASEBOARD_FAB2_LIB.BASEBOARD_FAB2(SCH_1):M_K_DQS_DP(1)    I66 @BASEBOARD_FAB2_LIB.BASEBOARD_FAB2(SCH_1):PAGE83
   174 M_K_DQS_DN<2> @BASEBOARD_FAB2_LIB.BASEBOARD_FAB2(SCH_1):M_K_DQS_DN(2)    I66 @BASEBOARD_FAB2_LIB.BASEBOARD_FAB2(SCH_1):PAGE83
   175 M_K_DQS_DP<2> @BASEBOARD_FAB2_LIB.BASEBOARD_FAB2(SCH_1):M_K_DQS_DP(2)    I66 @BASEBOARD_FAB2_LIB.BASEBOARD_FAB2(SCH_1):PAGE83
   185 M_K_DQS_DN<3> @BASEBOARD_FAB2_LIB.BASEBOARD_FAB2(SCH_1):M_K_DQS_DN(3)    I66 @BASEBOARD_FAB2_LIB.BASEBOARD_FAB2(SCH_1):PAGE83
   186 M_K_DQS_DP<3> @BASEBOARD_FAB2_LIB.BASEBOARD_FAB2(SCH_1):M_K_DQS_DP(3)    I66 @BASEBOARD_FAB2_LIB.BASEBOARD_FAB2(SCH_1):PAGE83
   244 M_K_DQS_DN<4> @BASEBOARD_FAB2_LIB.BASEBOARD_FAB2(SCH_1):M_K_DQS_DN(4)    I66 @BASEBOARD_FAB2_LIB.BASEBOARD_FAB2(SCH_1):PAGE83
   245 M_K_DQS_DP<4> @BASEBOARD_FAB2_LIB.BASEBOARD_FAB2(SCH_1):M_K_DQS_DP(4)    I66 @BASEBOARD_FAB2_LIB.BASEBOARD_FAB2(SCH_1):PAGE83
   255 M_K_DQS_DN<5> @BASEBOARD_FAB2_LIB.BASEBOARD_FAB2(SCH_1):M_K_DQS_DN(5)    I66 @BASEBOARD_FAB2_LIB.BASEBOARD_FAB2(SCH_1):PAGE83
   256 M_K_DQS_DP<5> @BASEBOARD_FAB2_LIB.BASEBOARD_FAB2(SCH_1):M_K_DQS_DP(5)    I66 @BASEBOARD_FAB2_LIB.BASEBOARD_FAB2(SCH_1):PAGE83
   266 M_K_DQS_DN<6> @BASEBOARD_FAB2_LIB.BASEBOARD_FAB2(SCH_1):M_K_DQS_DN(6)    I66 @BASEBOARD_FAB2_LIB.BASEBOARD_FAB2(SCH_1):PAGE83
   267 M_K_DQS_DP<6> @BASEBOARD_FAB2_LIB.BASEBOARD_FAB2(SCH_1):M_K_DQS_DP(6)    I66 @BASEBOARD_FAB2_LIB.BASEBOARD_FAB2(SCH_1):PAGE83
   277 M_K_DQS_DN<7> @BASEBOARD_FAB2_LIB.BASEBOARD_FAB2(SCH_1):M_K_DQS_DN(7)    I66 @BASEBOARD_FAB2_LIB.BASEBOARD_FAB2(SCH_1):PAGE83
   278 M_K_DQS_DP<7> @BASEBOARD_FAB2_LIB.BASEBOARD_FAB2(SCH_1):M_K_DQS_DP(7)    I66 @BASEBOARD_FAB2_LIB.BASEBOARD_FAB2(SCH_1):PAGE83
   196 M_K_DQS_DN<8> @BASEBOARD_FAB2_LIB.BASEBOARD_FAB2(SCH_1):M_K_DQS_DN(8)    I66 @BASEBOARD_FAB2_LIB.BASEBOARD_FAB2(SCH_1):PAGE83
   197 M_K_DQS_DP<8> @BASEBOARD_FAB2_LIB.BASEBOARD_FAB2(SCH_1):M_K_DQS_DP(8)    I66 @BASEBOARD_FAB2_LIB.BASEBOARD_FAB2(SCH_1):PAGE83
     8 M_K_DQS_DN<9> @BASEBOARD_FAB2_LIB.BASEBOARD_FAB2(SCH_1):M_K_DQS_DN(9)    I66 @BASEBOARD_FAB2_LIB.BASEBOARD_FAB2(SCH_1):PAGE83
     7 M_K_DQS_DP<9> @BASEBOARD_FAB2_LIB.BASEBOARD_FAB2(SCH_1):M_K_DQS_DP(9)    I66 @BASEBOARD_FAB2_LIB.BASEBOARD_FAB2(SCH_1):PAGE83
     2    GND @BASEBOARD_FAB2_LIB.BASEBOARD_FAB2(SCH_1):GND    I43 @BASEBOARD_FAB2_LIB.BASEBOARD_FAB2(SCH_1):PAGE83
     4    GND @BASEBOARD_FAB2_LIB.BASEBOARD_FAB2(SCH_1):GND    I43 @BASEBOARD_FAB2_LIB.BASEBOARD_FAB2(SCH_1):PAGE83
     6    GND @BASEBOARD_FAB2_LIB.BASEBOARD_FAB2(SCH_1):GND    I43 @BASEBOARD_FAB2_LIB.BASEBOARD_FAB2(SCH_1):PAGE83
     9    GND @BASEBOARD_FAB2_LIB.BASEBOARD_FAB2(SCH_1):GND    I43 @BASEBOARD_FAB2_LIB.BASEBOARD_FAB2(SCH_1):PAGE83
    11    GND @BASEBOARD_FAB2_LIB.BASEBOARD_FAB2(SCH_1):GND    I43 @BASEBOARD_FAB2_LIB.BASEBOARD_FAB2(SCH_1):PAGE83
    13    GND @BASEBOARD_FAB2_LIB.BASEBOARD_FAB2(SCH_1):GND    I43 @BASEBOARD_FAB2_LIB.BASEBOARD_FAB2(SCH_1):PAGE83
    15    GND @BASEBOARD_FAB2_LIB.BASEBOARD_FAB2(SCH_1):GND    I43 @BASEBOARD_FAB2_LIB.BASEBOARD_FAB2(SCH_1):PAGE83
    17    GND @BASEBOARD_FAB2_LIB.BASEBOARD_FAB2(SCH_1):GND    I43 @BASEBOARD_FAB2_LIB.BASEBOARD_FAB2(SCH_1):PAGE83
    20    GND @BASEBOARD_FAB2_LIB.BASEBOARD_FAB2(SCH_1):GND    I43 @BASEBOARD_FAB2_LIB.BASEBOARD_FAB2(SCH_1):PAGE83
    22    GND @BASEBOARD_FAB2_LIB.BASEBOARD_FAB2(SCH_1):GND    I43 @BASEBOARD_FAB2_LIB.BASEBOARD_FAB2(SCH_1):PAGE83
    24    GND @BASEBOARD_FAB2_LIB.BASEBOARD_FAB2(SCH_1):GND    I43 @BASEBOARD_FAB2_LIB.BASEBOARD_FAB2(SCH_1):PAGE83
    26    GND @BASEBOARD_FAB2_LIB.BASEBOARD_FAB2(SCH_1):GND    I43 @BASEBOARD_FAB2_LIB.BASEBOARD_FAB2(SCH_1):PAGE83
    28    GND @BASEBOARD_FAB2_LIB.BASEBOARD_FAB2(SCH_1):GND    I43 @BASEBOARD_FAB2_LIB.BASEBOARD_FAB2(SCH_1):PAGE83
    31    GND @BASEBOARD_FAB2_LIB.BASEBOARD_FAB2(SCH_1):GND    I43 @BASEBOARD_FAB2_LIB.BASEBOARD_FAB2(SCH_1):PAGE83
    33    GND @BASEBOARD_FAB2_LIB.BASEBOARD_FAB2(SCH_1):GND    I43 @BASEBOARD_FAB2_LIB.BASEBOARD_FAB2(SCH_1):PAGE83
    35    GND @BASEBOARD_FAB2_LIB.BASEBOARD_FAB2(SCH_1):GND    I43 @BASEBOARD_FAB2_LIB.BASEBOARD_FAB2(SCH_1):PAGE83
    37    GND @BASEBOARD_FAB2_LIB.BASEBOARD_FAB2(SCH_1):GND    I43 @BASEBOARD_FAB2_LIB.BASEBOARD_FAB2(SCH_1):PAGE83
    39    GND @BASEBOARD_FAB2_LIB.BASEBOARD_FAB2(SCH_1):GND    I43 @BASEBOARD_FAB2_LIB.BASEBOARD_FAB2(SCH_1):PAGE83
    42    GND @BASEBOARD_FAB2_LIB.BASEBOARD_FAB2(SCH_1):GND    I43 @BASEBOARD_FAB2_LIB.BASEBOARD_FAB2(SCH_1):PAGE83
    44    GND @BASEBOARD_FAB2_LIB.BASEBOARD_FAB2(SCH_1):GND    I43 @BASEBOARD_FAB2_LIB.BASEBOARD_FAB2(SCH_1):PAGE83
    46    GND @BASEBOARD_FAB2_LIB.BASEBOARD_FAB2(SCH_1):GND    I43 @BASEBOARD_FAB2_LIB.BASEBOARD_FAB2(SCH_1):PAGE83
    48    GND @BASEBOARD_FAB2_LIB.BASEBOARD_FAB2(SCH_1):GND    I43 @BASEBOARD_FAB2_LIB.BASEBOARD_FAB2(SCH_1):PAGE83
    50    GND @BASEBOARD_FAB2_LIB.BASEBOARD_FAB2(SCH_1):GND    I43 @BASEBOARD_FAB2_LIB.BASEBOARD_FAB2(SCH_1):PAGE83
    53    GND @BASEBOARD_FAB2_LIB.BASEBOARD_FAB2(SCH_1):GND    I43 @BASEBOARD_FAB2_LIB.BASEBOARD_FAB2(SCH_1):PAGE83
    55    GND @BASEBOARD_FAB2_LIB.BASEBOARD_FAB2(SCH_1):GND    I43 @BASEBOARD_FAB2_LIB.BASEBOARD_FAB2(SCH_1):PAGE83
    57    GND @BASEBOARD_FAB2_LIB.BASEBOARD_FAB2(SCH_1):GND    I43 @BASEBOARD_FAB2_LIB.BASEBOARD_FAB2(SCH_1):PAGE83
    94    GND @BASEBOARD_FAB2_LIB.BASEBOARD_FAB2(SCH_1):GND    I43 @BASEBOARD_FAB2_LIB.BASEBOARD_FAB2(SCH_1):PAGE83
    96    GND @BASEBOARD_FAB2_LIB.BASEBOARD_FAB2(SCH_1):GND    I43 @BASEBOARD_FAB2_LIB.BASEBOARD_FAB2(SCH_1):PAGE83
    98    GND @BASEBOARD_FAB2_LIB.BASEBOARD_FAB2(SCH_1):GND    I43 @BASEBOARD_FAB2_LIB.BASEBOARD_FAB2(SCH_1):PAGE83
   101    GND @BASEBOARD_FAB2_LIB.BASEBOARD_FAB2(SCH_1):GND    I43 @BASEBOARD_FAB2_LIB.BASEBOARD_FAB2(SCH_1):PAGE83
   103    GND @BASEBOARD_FAB2_LIB.BASEBOARD_FAB2(SCH_1):GND    I43 @BASEBOARD_FAB2_LIB.BASEBOARD_FAB2(SCH_1):PAGE83
   105    GND @BASEBOARD_FAB2_LIB.BASEBOARD_FAB2(SCH_1):GND    I43 @BASEBOARD_FAB2_LIB.BASEBOARD_FAB2(SCH_1):PAGE83
   107    GND @BASEBOARD_FAB2_LIB.BASEBOARD_FAB2(SCH_1):GND    I43 @BASEBOARD_FAB2_LIB.BASEBOARD_FAB2(SCH_1):PAGE83
   109    GND @BASEBOARD_FAB2_LIB.BASEBOARD_FAB2(SCH_1):GND    I43 @BASEBOARD_FAB2_LIB.BASEBOARD_FAB2(SCH_1):PAGE83
   112    GND @BASEBOARD_FAB2_LIB.BASEBOARD_FAB2(SCH_1):GND    I43 @BASEBOARD_FAB2_LIB.BASEBOARD_FAB2(SCH_1):PAGE83
   114    GND @BASEBOARD_FAB2_LIB.BASEBOARD_FAB2(SCH_1):GND    I43 @BASEBOARD_FAB2_LIB.BASEBOARD_FAB2(SCH_1):PAGE83
   116    GND @BASEBOARD_FAB2_LIB.BASEBOARD_FAB2(SCH_1):GND    I43 @BASEBOARD_FAB2_LIB.BASEBOARD_FAB2(SCH_1):PAGE83
   118    GND @BASEBOARD_FAB2_LIB.BASEBOARD_FAB2(SCH_1):GND    I43 @BASEBOARD_FAB2_LIB.BASEBOARD_FAB2(SCH_1):PAGE83
   120    GND @BASEBOARD_FAB2_LIB.BASEBOARD_FAB2(SCH_1):GND    I43 @BASEBOARD_FAB2_LIB.BASEBOARD_FAB2(SCH_1):PAGE83
   123    GND @BASEBOARD_FAB2_LIB.BASEBOARD_FAB2(SCH_1):GND    I43 @BASEBOARD_FAB2_LIB.BASEBOARD_FAB2(SCH_1):PAGE83
   125    GND @BASEBOARD_FAB2_LIB.BASEBOARD_FAB2(SCH_1):GND    I43 @BASEBOARD_FAB2_LIB.BASEBOARD_FAB2(SCH_1):PAGE83
   127    GND @BASEBOARD_FAB2_LIB.BASEBOARD_FAB2(SCH_1):GND    I43 @BASEBOARD_FAB2_LIB.BASEBOARD_FAB2(SCH_1):PAGE83
   129    GND @BASEBOARD_FAB2_LIB.BASEBOARD_FAB2(SCH_1):GND    I43 @BASEBOARD_FAB2_LIB.BASEBOARD_FAB2(SCH_1):PAGE83
   131    GND @BASEBOARD_FAB2_LIB.BASEBOARD_FAB2(SCH_1):GND    I43 @BASEBOARD_FAB2_LIB.BASEBOARD_FAB2(SCH_1):PAGE83
   134    GND @BASEBOARD_FAB2_LIB.BASEBOARD_FAB2(SCH_1):GND    I43 @BASEBOARD_FAB2_LIB.BASEBOARD_FAB2(SCH_1):PAGE83
   136    GND @BASEBOARD_FAB2_LIB.BASEBOARD_FAB2(SCH_1):GND    I43 @BASEBOARD_FAB2_LIB.BASEBOARD_FAB2(SCH_1):PAGE83
   138    GND @BASEBOARD_FAB2_LIB.BASEBOARD_FAB2(SCH_1):GND    I43 @BASEBOARD_FAB2_LIB.BASEBOARD_FAB2(SCH_1):PAGE83
   147    GND @BASEBOARD_FAB2_LIB.BASEBOARD_FAB2(SCH_1):GND    I43 @BASEBOARD_FAB2_LIB.BASEBOARD_FAB2(SCH_1):PAGE83
   149    GND @BASEBOARD_FAB2_LIB.BASEBOARD_FAB2(SCH_1):GND    I43 @BASEBOARD_FAB2_LIB.BASEBOARD_FAB2(SCH_1):PAGE83
   151    GND @BASEBOARD_FAB2_LIB.BASEBOARD_FAB2(SCH_1):GND    I43 @BASEBOARD_FAB2_LIB.BASEBOARD_FAB2(SCH_1):PAGE83
   154    GND @BASEBOARD_FAB2_LIB.BASEBOARD_FAB2(SCH_1):GND    I43 @BASEBOARD_FAB2_LIB.BASEBOARD_FAB2(SCH_1):PAGE83
   156    GND @BASEBOARD_FAB2_LIB.BASEBOARD_FAB2(SCH_1):GND    I43 @BASEBOARD_FAB2_LIB.BASEBOARD_FAB2(SCH_1):PAGE83
   158    GND @BASEBOARD_FAB2_LIB.BASEBOARD_FAB2(SCH_1):GND    I43 @BASEBOARD_FAB2_LIB.BASEBOARD_FAB2(SCH_1):PAGE83
   160    GND @BASEBOARD_FAB2_LIB.BASEBOARD_FAB2(SCH_1):GND    I43 @BASEBOARD_FAB2_LIB.BASEBOARD_FAB2(SCH_1):PAGE83
   162    GND @BASEBOARD_FAB2_LIB.BASEBOARD_FAB2(SCH_1):GND    I43 @BASEBOARD_FAB2_LIB.BASEBOARD_FAB2(SCH_1):PAGE83
   165    GND @BASEBOARD_FAB2_LIB.BASEBOARD_FAB2(SCH_1):GND    I43 @BASEBOARD_FAB2_LIB.BASEBOARD_FAB2(SCH_1):PAGE83
   167    GND @BASEBOARD_FAB2_LIB.BASEBOARD_FAB2(SCH_1):GND    I43 @BASEBOARD_FAB2_LIB.BASEBOARD_FAB2(SCH_1):PAGE83
   169    GND @BASEBOARD_FAB2_LIB.BASEBOARD_FAB2(SCH_1):GND    I43 @BASEBOARD_FAB2_LIB.BASEBOARD_FAB2(SCH_1):PAGE83
   171    GND @BASEBOARD_FAB2_LIB.BASEBOARD_FAB2(SCH_1):GND    I43 @BASEBOARD_FAB2_LIB.BASEBOARD_FAB2(SCH_1):PAGE83
   173    GND @BASEBOARD_FAB2_LIB.BASEBOARD_FAB2(SCH_1):GND    I43 @BASEBOARD_FAB2_LIB.BASEBOARD_FAB2(SCH_1):PAGE83
   176    GND @BASEBOARD_FAB2_LIB.BASEBOARD_FAB2(SCH_1):GND    I43 @BASEBOARD_FAB2_LIB.BASEBOARD_FAB2(SCH_1):PAGE83
   178    GND @BASEBOARD_FAB2_LIB.BASEBOARD_FAB2(SCH_1):GND    I43 @BASEBOARD_FAB2_LIB.BASEBOARD_FAB2(SCH_1):PAGE83
   180    GND @BASEBOARD_FAB2_LIB.BASEBOARD_FAB2(SCH_1):GND    I43 @BASEBOARD_FAB2_LIB.BASEBOARD_FAB2(SCH_1):PAGE83
   182    GND @BASEBOARD_FAB2_LIB.BASEBOARD_FAB2(SCH_1):GND    I43 @BASEBOARD_FAB2_LIB.BASEBOARD_FAB2(SCH_1):PAGE83
   184    GND @BASEBOARD_FAB2_LIB.BASEBOARD_FAB2(SCH_1):GND    I43 @BASEBOARD_FAB2_LIB.BASEBOARD_FAB2(SCH_1):PAGE83
   187    GND @BASEBOARD_FAB2_LIB.BASEBOARD_FAB2(SCH_1):GND    I43 @BASEBOARD_FAB2_LIB.BASEBOARD_FAB2(SCH_1):PAGE83
   189    GND @BASEBOARD_FAB2_LIB.BASEBOARD_FAB2(SCH_1):GND    I43 @BASEBOARD_FAB2_LIB.BASEBOARD_FAB2(SCH_1):PAGE83
   191    GND @BASEBOARD_FAB2_LIB.BASEBOARD_FAB2(SCH_1):GND    I43 @BASEBOARD_FAB2_LIB.BASEBOARD_FAB2(SCH_1):PAGE83
   193    GND @BASEBOARD_FAB2_LIB.BASEBOARD_FAB2(SCH_1):GND    I43 @BASEBOARD_FAB2_LIB.BASEBOARD_FAB2(SCH_1):PAGE83
   195    GND @BASEBOARD_FAB2_LIB.BASEBOARD_FAB2(SCH_1):GND    I43 @BASEBOARD_FAB2_LIB.BASEBOARD_FAB2(SCH_1):PAGE83
   198    GND @BASEBOARD_FAB2_LIB.BASEBOARD_FAB2(SCH_1):GND    I43 @BASEBOARD_FAB2_LIB.BASEBOARD_FAB2(SCH_1):PAGE83
   200    GND @BASEBOARD_FAB2_LIB.BASEBOARD_FAB2(SCH_1):GND    I43 @BASEBOARD_FAB2_LIB.BASEBOARD_FAB2(SCH_1):PAGE83
   202    GND @BASEBOARD_FAB2_LIB.BASEBOARD_FAB2(SCH_1):GND    I43 @BASEBOARD_FAB2_LIB.BASEBOARD_FAB2(SCH_1):PAGE83
   239    GND @BASEBOARD_FAB2_LIB.BASEBOARD_FAB2(SCH_1):GND    I43 @BASEBOARD_FAB2_LIB.BASEBOARD_FAB2(SCH_1):PAGE83
   241    GND @BASEBOARD_FAB2_LIB.BASEBOARD_FAB2(SCH_1):GND    I43 @BASEBOARD_FAB2_LIB.BASEBOARD_FAB2(SCH_1):PAGE83
   243    GND @BASEBOARD_FAB2_LIB.BASEBOARD_FAB2(SCH_1):GND    I43 @BASEBOARD_FAB2_LIB.BASEBOARD_FAB2(SCH_1):PAGE83
   246    GND @BASEBOARD_FAB2_LIB.BASEBOARD_FAB2(SCH_1):GND    I43 @BASEBOARD_FAB2_LIB.BASEBOARD_FAB2(SCH_1):PAGE83
   248    GND @BASEBOARD_FAB2_LIB.BASEBOARD_FAB2(SCH_1):GND    I43 @BASEBOARD_FAB2_LIB.BASEBOARD_FAB2(SCH_1):PAGE83
   250    GND @BASEBOARD_FAB2_LIB.BASEBOARD_FAB2(SCH_1):GND    I43 @BASEBOARD_FAB2_LIB.BASEBOARD_FAB2(SCH_1):PAGE83
   252    GND @BASEBOARD_FAB2_LIB.BASEBOARD_FAB2(SCH_1):GND    I43 @BASEBOARD_FAB2_LIB.BASEBOARD_FAB2(SCH_1):PAGE83
   254    GND @BASEBOARD_FAB2_LIB.BASEBOARD_FAB2(SCH_1):GND    I43 @BASEBOARD_FAB2_LIB.BASEBOARD_FAB2(SCH_1):PAGE83
   257    GND @BASEBOARD_FAB2_LIB.BASEBOARD_FAB2(SCH_1):GND    I43 @BASEBOARD_FAB2_LIB.BASEBOARD_FAB2(SCH_1):PAGE83
   259    GND @BASEBOARD_FAB2_LIB.BASEBOARD_FAB2(SCH_1):GND    I43 @BASEBOARD_FAB2_LIB.BASEBOARD_FAB2(SCH_1):PAGE83
   261    GND @BASEBOARD_FAB2_LIB.BASEBOARD_FAB2(SCH_1):GND    I43 @BASEBOARD_FAB2_LIB.BASEBOARD_FAB2(SCH_1):PAGE83
   263    GND @BASEBOARD_FAB2_LIB.BASEBOARD_FAB2(SCH_1):GND    I43 @BASEBOARD_FAB2_LIB.BASEBOARD_FAB2(SCH_1):PAGE83
   265    GND @BASEBOARD_FAB2_LIB.BASEBOARD_FAB2(SCH_1):GND    I43 @BASEBOARD_FAB2_LIB.BASEBOARD_FAB2(SCH_1):PAGE83
   268    GND @BASEBOARD_FAB2_LIB.BASEBOARD_FAB2(SCH_1):GND    I43 @BASEBOARD_FAB2_LIB.BASEBOARD_FAB2(SCH_1):PAGE83
   270    GND @BASEBOARD_FAB2_LIB.BASEBOARD_FAB2(SCH_1):GND    I43 @BASEBOARD_FAB2_LIB.BASEBOARD_FAB2(SCH_1):PAGE83
   272    GND @BASEBOARD_FAB2_LIB.BASEBOARD_FAB2(SCH_1):GND    I43 @BASEBOARD_FAB2_LIB.BASEBOARD_FAB2(SCH_1):PAGE83
   274    GND @BASEBOARD_FAB2_LIB.BASEBOARD_FAB2(SCH_1):GND    I43 @BASEBOARD_FAB2_LIB.BASEBOARD_FAB2(SCH_1):PAGE83
   276    GND @BASEBOARD_FAB2_LIB.BASEBOARD_FAB2(SCH_1):GND    I43 @BASEBOARD_FAB2_LIB.BASEBOARD_FAB2(SCH_1):PAGE83
   279    GND @BASEBOARD_FAB2_LIB.BASEBOARD_FAB2(SCH_1):GND    I43 @BASEBOARD_FAB2_LIB.BASEBOARD_FAB2(SCH_1):PAGE83
   281    GND @BASEBOARD_FAB2_LIB.BASEBOARD_FAB2(SCH_1):GND    I43 @BASEBOARD_FAB2_LIB.BASEBOARD_FAB2(SCH_1):PAGE83
   283    GND @BASEBOARD_FAB2_LIB.BASEBOARD_FAB2(SCH_1):GND    I43 @BASEBOARD_FAB2_LIB.BASEBOARD_FAB2(SCH_1):PAGE83
     1 P12V_NVDIMM_KLM @BASEBOARD_FAB2_LIB.BASEBOARD_FAB2(SCH_1):P12V_NVDIMM_KLM   I167 @BASEBOARD_FAB2_LIB.BASEBOARD_FAB2(SCH_1):PAGE83
   145 P12V_NVDIMM_KLM @BASEBOARD_FAB2_LIB.BASEBOARD_FAB2(SCH_1):P12V_NVDIMM_KLM   I167 @BASEBOARD_FAB2_LIB.BASEBOARD_FAB2(SCH_1):PAGE83
    59 PVDDQ_KLM @BASEBOARD_FAB2_LIB.BASEBOARD_FAB2(SCH_1):PVDDQ_KLM   I167 @BASEBOARD_FAB2_LIB.BASEBOARD_FAB2(SCH_1):PAGE83
    61 PVDDQ_KLM @BASEBOARD_FAB2_LIB.BASEBOARD_FAB2(SCH_1):PVDDQ_KLM   I167 @BASEBOARD_FAB2_LIB.BASEBOARD_FAB2(SCH_1):PAGE83
    64 PVDDQ_KLM @BASEBOARD_FAB2_LIB.BASEBOARD_FAB2(SCH_1):PVDDQ_KLM   I167 @BASEBOARD_FAB2_LIB.BASEBOARD_FAB2(SCH_1):PAGE83
    67 PVDDQ_KLM @BASEBOARD_FAB2_LIB.BASEBOARD_FAB2(SCH_1):PVDDQ_KLM   I167 @BASEBOARD_FAB2_LIB.BASEBOARD_FAB2(SCH_1):PAGE83
    70 PVDDQ_KLM @BASEBOARD_FAB2_LIB.BASEBOARD_FAB2(SCH_1):PVDDQ_KLM   I167 @BASEBOARD_FAB2_LIB.BASEBOARD_FAB2(SCH_1):PAGE83
    73 PVDDQ_KLM @BASEBOARD_FAB2_LIB.BASEBOARD_FAB2(SCH_1):PVDDQ_KLM   I167 @BASEBOARD_FAB2_LIB.BASEBOARD_FAB2(SCH_1):PAGE83
    76 PVDDQ_KLM @BASEBOARD_FAB2_LIB.BASEBOARD_FAB2(SCH_1):PVDDQ_KLM   I167 @BASEBOARD_FAB2_LIB.BASEBOARD_FAB2(SCH_1):PAGE83
    80 PVDDQ_KLM @BASEBOARD_FAB2_LIB.BASEBOARD_FAB2(SCH_1):PVDDQ_KLM   I167 @BASEBOARD_FAB2_LIB.BASEBOARD_FAB2(SCH_1):PAGE83
    83 PVDDQ_KLM @BASEBOARD_FAB2_LIB.BASEBOARD_FAB2(SCH_1):PVDDQ_KLM   I167 @BASEBOARD_FAB2_LIB.BASEBOARD_FAB2(SCH_1):PAGE83
    85 PVDDQ_KLM @BASEBOARD_FAB2_LIB.BASEBOARD_FAB2(SCH_1):PVDDQ_KLM   I167 @BASEBOARD_FAB2_LIB.BASEBOARD_FAB2(SCH_1):PAGE83
    88 PVDDQ_KLM @BASEBOARD_FAB2_LIB.BASEBOARD_FAB2(SCH_1):PVDDQ_KLM   I167 @BASEBOARD_FAB2_LIB.BASEBOARD_FAB2(SCH_1):PAGE83
    90 PVDDQ_KLM @BASEBOARD_FAB2_LIB.BASEBOARD_FAB2(SCH_1):PVDDQ_KLM   I167 @BASEBOARD_FAB2_LIB.BASEBOARD_FAB2(SCH_1):PAGE83
    92 PVDDQ_KLM @BASEBOARD_FAB2_LIB.BASEBOARD_FAB2(SCH_1):PVDDQ_KLM   I167 @BASEBOARD_FAB2_LIB.BASEBOARD_FAB2(SCH_1):PAGE83
   204 PVDDQ_KLM @BASEBOARD_FAB2_LIB.BASEBOARD_FAB2(SCH_1):PVDDQ_KLM   I167 @BASEBOARD_FAB2_LIB.BASEBOARD_FAB2(SCH_1):PAGE83
   206 PVDDQ_KLM @BASEBOARD_FAB2_LIB.BASEBOARD_FAB2(SCH_1):PVDDQ_KLM   I167 @BASEBOARD_FAB2_LIB.BASEBOARD_FAB2(SCH_1):PAGE83
   209 PVDDQ_KLM @BASEBOARD_FAB2_LIB.BASEBOARD_FAB2(SCH_1):PVDDQ_KLM   I167 @BASEBOARD_FAB2_LIB.BASEBOARD_FAB2(SCH_1):PAGE83
   212 PVDDQ_KLM @BASEBOARD_FAB2_LIB.BASEBOARD_FAB2(SCH_1):PVDDQ_KLM   I167 @BASEBOARD_FAB2_LIB.BASEBOARD_FAB2(SCH_1):PAGE83
   215 PVDDQ_KLM @BASEBOARD_FAB2_LIB.BASEBOARD_FAB2(SCH_1):PVDDQ_KLM   I167 @BASEBOARD_FAB2_LIB.BASEBOARD_FAB2(SCH_1):PAGE83
   217 PVDDQ_KLM @BASEBOARD_FAB2_LIB.BASEBOARD_FAB2(SCH_1):PVDDQ_KLM   I167 @BASEBOARD_FAB2_LIB.BASEBOARD_FAB2(SCH_1):PAGE83
   220 PVDDQ_KLM @BASEBOARD_FAB2_LIB.BASEBOARD_FAB2(SCH_1):PVDDQ_KLM   I167 @BASEBOARD_FAB2_LIB.BASEBOARD_FAB2(SCH_1):PAGE83
   223 PVDDQ_KLM @BASEBOARD_FAB2_LIB.BASEBOARD_FAB2(SCH_1):PVDDQ_KLM   I167 @BASEBOARD_FAB2_LIB.BASEBOARD_FAB2(SCH_1):PAGE83
   226 PVDDQ_KLM @BASEBOARD_FAB2_LIB.BASEBOARD_FAB2(SCH_1):PVDDQ_KLM   I167 @BASEBOARD_FAB2_LIB.BASEBOARD_FAB2(SCH_1):PAGE83
   229 PVDDQ_KLM @BASEBOARD_FAB2_LIB.BASEBOARD_FAB2(SCH_1):PVDDQ_KLM   I167 @BASEBOARD_FAB2_LIB.BASEBOARD_FAB2(SCH_1):PAGE83
   231 PVDDQ_KLM @BASEBOARD_FAB2_LIB.BASEBOARD_FAB2(SCH_1):PVDDQ_KLM   I167 @BASEBOARD_FAB2_LIB.BASEBOARD_FAB2(SCH_1):PAGE83
   233 PVDDQ_KLM @BASEBOARD_FAB2_LIB.BASEBOARD_FAB2(SCH_1):PVDDQ_KLM   I167 @BASEBOARD_FAB2_LIB.BASEBOARD_FAB2(SCH_1):PAGE83
   236 PVDDQ_KLM @BASEBOARD_FAB2_LIB.BASEBOARD_FAB2(SCH_1):PVDDQ_KLM   I167 @BASEBOARD_FAB2_LIB.BASEBOARD_FAB2(SCH_1):PAGE83
   142 PVPP_KLM @BASEBOARD_FAB2_LIB.BASEBOARD_FAB2(SCH_1):PVPP_KLM   I167 @BASEBOARD_FAB2_LIB.BASEBOARD_FAB2(SCH_1):PAGE83
   143 PVPP_KLM @BASEBOARD_FAB2_LIB.BASEBOARD_FAB2(SCH_1):PVPP_KLM   I167 @BASEBOARD_FAB2_LIB.BASEBOARD_FAB2(SCH_1):PAGE83
   288 PVPP_KLM @BASEBOARD_FAB2_LIB.BASEBOARD_FAB2(SCH_1):PVPP_KLM   I167 @BASEBOARD_FAB2_LIB.BASEBOARD_FAB2(SCH_1):PAGE83
   286 PVPP_KLM @BASEBOARD_FAB2_LIB.BASEBOARD_FAB2(SCH_1):PVPP_KLM   I167 @BASEBOARD_FAB2_LIB.BASEBOARD_FAB2(SCH_1):PAGE83
   287 PVPP_KLM @BASEBOARD_FAB2_LIB.BASEBOARD_FAB2(SCH_1):PVPP_KLM   I167 @BASEBOARD_FAB2_LIB.BASEBOARD_FAB2(SCH_1):PAGE83
    77 PVTT_KLM @BASEBOARD_FAB2_LIB.BASEBOARD_FAB2(SCH_1):PVTT_KLM   I167 @BASEBOARD_FAB2_LIB.BASEBOARD_FAB2(SCH_1):PAGE83
   221 PVTT_KLM @BASEBOARD_FAB2_LIB.BASEBOARD_FAB2(SCH_1):PVTT_KLM   I167 @BASEBOARD_FAB2_LIB.BASEBOARD_FAB2(SCH_1):PAGE83

J1B2 CONN6_C74770005_PIP-HDR,C74770A
     1    GND @BASEBOARD_FAB2_LIB.BASEBOARD_FAB2(SCH_1):GND    I32 @BASEBOARD_FAB2_LIB.BASEBOARD_FAB2(SCH_1):PAGE161
     2 P12V_FAN @BASEBOARD_FAB2_LIB.BASEBOARD_FAB2(SCH_1):P12V_FAN    I32 @BASEBOARD_FAB2_LIB.BASEBOARD_FAB2(SCH_1):PAGE161
     3 FAN_TACH2_CPU1_D1 @BASEBOARD_FAB2_LIB.BASEBOARD_FAB2(SCH_1):FAN_TACH2_CPU1_D1    I32 @BASEBOARD_FAB2_LIB.BASEBOARD_FAB2(SCH_1):PAGE161
     4 FAN_PWM_OUT_SYS1_R @BASEBOARD_FAB2_LIB.BASEBOARD_FAB2(SCH_1):FAN_PWM_OUT_SYS1_R    I32 @BASEBOARD_FAB2_LIB.BASEBOARD_FAB2(SCH_1):PAGE161
     5 FAN_TACH3_CPU1_D1 @BASEBOARD_FAB2_LIB.BASEBOARD_FAB2(SCH_1):FAN_TACH3_CPU1_D1    I32 @BASEBOARD_FAB2_LIB.BASEBOARD_FAB2(SCH_1):PAGE161
     6 TP_FAN_1 @BASEBOARD_FAB2_LIB.BASEBOARD_FAB2(SCH_1):TP_FAN_1    I32 @BASEBOARD_FAB2_LIB.BASEBOARD_FAB2(SCH_1):PAGE161

J1B3 CONN3_C95678002_PIP-CONN,C9567A
     1 A_HSC_HIGH_EN @BASEBOARD_FAB2_LIB.BASEBOARD_FAB2(SCH_1):A_HSC_HIGH_EN   I123 @BASEBOARD_FAB2_LIB.BASEBOARD_FAB2(SCH_1):PAGE199
     2 A_HSC_OCP_SEL @BASEBOARD_FAB2_LIB.BASEBOARD_FAB2(SCH_1):A_HSC_OCP_SEL   I123 @BASEBOARD_FAB2_LIB.BASEBOARD_FAB2(SCH_1):PAGE199
     3 A_HSC_LOW_EN @BASEBOARD_FAB2_LIB.BASEBOARD_FAB2(SCH_1):A_HSC_LOW_EN   I123 @BASEBOARD_FAB2_LIB.BASEBOARD_FAB2(SCH_1):PAGE199

J1B4 SCONN3_D53458001_SM-EMPTY,D534A
     1 A_HSC_HIGH_EN @BASEBOARD_FAB2_LIB.BASEBOARD_FAB2(SCH_1):A_HSC_HIGH_EN   I124 @BASEBOARD_FAB2_LIB.BASEBOARD_FAB2(SCH_1):PAGE199
     2 A_HSC_OCP_SEL @BASEBOARD_FAB2_LIB.BASEBOARD_FAB2(SCH_1):A_HSC_OCP_SEL   I124 @BASEBOARD_FAB2_LIB.BASEBOARD_FAB2(SCH_1):PAGE199
     3 A_HSC_LOW_EN @BASEBOARD_FAB2_LIB.BASEBOARD_FAB2(SCH_1):A_HSC_LOW_EN   I124 @BASEBOARD_FAB2_LIB.BASEBOARD_FAB2(SCH_1):PAGE199

J1C1 CONN76_H22707001_THMT1-CONN,H2A
    A2    GND @BASEBOARD_FAB2_LIB.BASEBOARD_FAB2(SCH_1):GND    I18 @BASEBOARD_FAB2_LIB.BASEBOARD_FAB2(SCH_1):PAGE182
    A4    GND @BASEBOARD_FAB2_LIB.BASEBOARD_FAB2(SCH_1):GND    I18 @BASEBOARD_FAB2_LIB.BASEBOARD_FAB2(SCH_1):PAGE182
    A6    GND @BASEBOARD_FAB2_LIB.BASEBOARD_FAB2(SCH_1):GND    I18 @BASEBOARD_FAB2_LIB.BASEBOARD_FAB2(SCH_1):PAGE182
    A8    GND @BASEBOARD_FAB2_LIB.BASEBOARD_FAB2(SCH_1):GND    I18 @BASEBOARD_FAB2_LIB.BASEBOARD_FAB2(SCH_1):PAGE182
    C1    GND @BASEBOARD_FAB2_LIB.BASEBOARD_FAB2(SCH_1):GND    I18 @BASEBOARD_FAB2_LIB.BASEBOARD_FAB2(SCH_1):PAGE182
    C3    GND @BASEBOARD_FAB2_LIB.BASEBOARD_FAB2(SCH_1):GND    I18 @BASEBOARD_FAB2_LIB.BASEBOARD_FAB2(SCH_1):PAGE182
    C5    GND @BASEBOARD_FAB2_LIB.BASEBOARD_FAB2(SCH_1):GND    I18 @BASEBOARD_FAB2_LIB.BASEBOARD_FAB2(SCH_1):PAGE182
    C7    GND @BASEBOARD_FAB2_LIB.BASEBOARD_FAB2(SCH_1):GND    I18 @BASEBOARD_FAB2_LIB.BASEBOARD_FAB2(SCH_1):PAGE182
    D2    GND @BASEBOARD_FAB2_LIB.BASEBOARD_FAB2(SCH_1):GND    I18 @BASEBOARD_FAB2_LIB.BASEBOARD_FAB2(SCH_1):PAGE182
    D4    GND @BASEBOARD_FAB2_LIB.BASEBOARD_FAB2(SCH_1):GND    I18 @BASEBOARD_FAB2_LIB.BASEBOARD_FAB2(SCH_1):PAGE182
    D6    GND @BASEBOARD_FAB2_LIB.BASEBOARD_FAB2(SCH_1):GND    I18 @BASEBOARD_FAB2_LIB.BASEBOARD_FAB2(SCH_1):PAGE182
    D8    GND @BASEBOARD_FAB2_LIB.BASEBOARD_FAB2(SCH_1):GND    I18 @BASEBOARD_FAB2_LIB.BASEBOARD_FAB2(SCH_1):PAGE182
    F1    GND @BASEBOARD_FAB2_LIB.BASEBOARD_FAB2(SCH_1):GND    I18 @BASEBOARD_FAB2_LIB.BASEBOARD_FAB2(SCH_1):PAGE182
    F3    GND @BASEBOARD_FAB2_LIB.BASEBOARD_FAB2(SCH_1):GND    I18 @BASEBOARD_FAB2_LIB.BASEBOARD_FAB2(SCH_1):PAGE182
    F5    GND @BASEBOARD_FAB2_LIB.BASEBOARD_FAB2(SCH_1):GND    I18 @BASEBOARD_FAB2_LIB.BASEBOARD_FAB2(SCH_1):PAGE182
    F7    GND @BASEBOARD_FAB2_LIB.BASEBOARD_FAB2(SCH_1):GND    I18 @BASEBOARD_FAB2_LIB.BASEBOARD_FAB2(SCH_1):PAGE182
    G2    GND @BASEBOARD_FAB2_LIB.BASEBOARD_FAB2(SCH_1):GND    I18 @BASEBOARD_FAB2_LIB.BASEBOARD_FAB2(SCH_1):PAGE182
    G4    GND @BASEBOARD_FAB2_LIB.BASEBOARD_FAB2(SCH_1):GND    I18 @BASEBOARD_FAB2_LIB.BASEBOARD_FAB2(SCH_1):PAGE182
    G6    GND @BASEBOARD_FAB2_LIB.BASEBOARD_FAB2(SCH_1):GND    I18 @BASEBOARD_FAB2_LIB.BASEBOARD_FAB2(SCH_1):PAGE182
    G8    GND @BASEBOARD_FAB2_LIB.BASEBOARD_FAB2(SCH_1):GND    I18 @BASEBOARD_FAB2_LIB.BASEBOARD_FAB2(SCH_1):PAGE182
    I1    GND @BASEBOARD_FAB2_LIB.BASEBOARD_FAB2(SCH_1):GND    I18 @BASEBOARD_FAB2_LIB.BASEBOARD_FAB2(SCH_1):PAGE182
    I3    GND @BASEBOARD_FAB2_LIB.BASEBOARD_FAB2(SCH_1):GND    I18 @BASEBOARD_FAB2_LIB.BASEBOARD_FAB2(SCH_1):PAGE182
    I5    GND @BASEBOARD_FAB2_LIB.BASEBOARD_FAB2(SCH_1):GND    I18 @BASEBOARD_FAB2_LIB.BASEBOARD_FAB2(SCH_1):PAGE182
    I7    GND @BASEBOARD_FAB2_LIB.BASEBOARD_FAB2(SCH_1):GND    I18 @BASEBOARD_FAB2_LIB.BASEBOARD_FAB2(SCH_1):PAGE182
    J2    GND @BASEBOARD_FAB2_LIB.BASEBOARD_FAB2(SCH_1):GND    I18 @BASEBOARD_FAB2_LIB.BASEBOARD_FAB2(SCH_1):PAGE182
    J4    GND @BASEBOARD_FAB2_LIB.BASEBOARD_FAB2(SCH_1):GND    I18 @BASEBOARD_FAB2_LIB.BASEBOARD_FAB2(SCH_1):PAGE182
    J6    GND @BASEBOARD_FAB2_LIB.BASEBOARD_FAB2(SCH_1):GND    I18 @BASEBOARD_FAB2_LIB.BASEBOARD_FAB2(SCH_1):PAGE182
    J8    GND @BASEBOARD_FAB2_LIB.BASEBOARD_FAB2(SCH_1):GND    I18 @BASEBOARD_FAB2_LIB.BASEBOARD_FAB2(SCH_1):PAGE182
    A1 P3E_CPU1_PE3_MP_RXN<8> @BASEBOARD_FAB2_LIB.BASEBOARD_FAB2(SCH_1):P3E_CPU1_PE3_MP_RXN(8)    I18 @BASEBOARD_FAB2_LIB.BASEBOARD_FAB2(SCH_1):PAGE182
    A3 P3E_CPU1_PE3_MP_RXP<14> @BASEBOARD_FAB2_LIB.BASEBOARD_FAB2(SCH_1):P3E_CPU1_PE3_MP_RXP(14)    I18 @BASEBOARD_FAB2_LIB.BASEBOARD_FAB2(SCH_1):PAGE182
    A5 TP_IOA5 @BASEBOARD_FAB2_LIB.BASEBOARD_FAB2(SCH_1):TP_IOA5    I18 @BASEBOARD_FAB2_LIB.BASEBOARD_FAB2(SCH_1):PAGE182
    A7 P3E_CPU1_PE3_MP_C_TXN<11> @BASEBOARD_FAB2_LIB.BASEBOARD_FAB2(SCH_1):P3E_CPU1_PE3_MP_C_TXN(11)    I18 @BASEBOARD_FAB2_LIB.BASEBOARD_FAB2(SCH_1):PAGE182
    B1 P3E_CPU1_PE3_MP_RXP<8> @BASEBOARD_FAB2_LIB.BASEBOARD_FAB2(SCH_1):P3E_CPU1_PE3_MP_RXP(8)    I18 @BASEBOARD_FAB2_LIB.BASEBOARD_FAB2(SCH_1):PAGE182
    B2 P3E_CPU1_PE3_MP_RXN<11> @BASEBOARD_FAB2_LIB.BASEBOARD_FAB2(SCH_1):P3E_CPU1_PE3_MP_RXN(11)    I18 @BASEBOARD_FAB2_LIB.BASEBOARD_FAB2(SCH_1):PAGE182
    B3 P3E_CPU1_PE3_MP_RXN<14> @BASEBOARD_FAB2_LIB.BASEBOARD_FAB2(SCH_1):P3E_CPU1_PE3_MP_RXN(14)    I18 @BASEBOARD_FAB2_LIB.BASEBOARD_FAB2(SCH_1):PAGE182
    B4 TP_FM_WAKE_N @BASEBOARD_FAB2_LIB.BASEBOARD_FAB2(SCH_1):TP_FM_WAKE_N    I18 @BASEBOARD_FAB2_LIB.BASEBOARD_FAB2(SCH_1):PAGE182
    B5 IRQ_BOARD_BMC_ALERT_N @BASEBOARD_FAB2_LIB.BASEBOARD_FAB2(SCH_1):IRQ_BOARD_BMC_ALERT_N    I18 @BASEBOARD_FAB2_LIB.BASEBOARD_FAB2(SCH_1):PAGE182
    B6 SMB_PEHPCPU1_STBY_LVC3_SDA @BASEBOARD_FAB2_LIB.BASEBOARD_FAB2(SCH_1):SMB_PEHPCPU1_STBY_LVC3_SDA    I18 @BASEBOARD_FAB2_LIB.BASEBOARD_FAB2(SCH_1):PAGE182
    B7 P3E_CPU1_PE3_MP_C_TXP<11> @BASEBOARD_FAB2_LIB.BASEBOARD_FAB2(SCH_1):P3E_CPU1_PE3_MP_C_TXP(11)    I18 @BASEBOARD_FAB2_LIB.BASEBOARD_FAB2(SCH_1):PAGE182
    B8 P3E_CPU1_PE3_MP_C_TXN<8> @BASEBOARD_FAB2_LIB.BASEBOARD_FAB2(SCH_1):P3E_CPU1_PE3_MP_C_TXN(8)    I18 @BASEBOARD_FAB2_LIB.BASEBOARD_FAB2(SCH_1):PAGE182
    C2 P3E_CPU1_PE3_MP_RXP<11> @BASEBOARD_FAB2_LIB.BASEBOARD_FAB2(SCH_1):P3E_CPU1_PE3_MP_RXP(11)    I18 @BASEBOARD_FAB2_LIB.BASEBOARD_FAB2(SCH_1):PAGE182
    C4 FM_BB_BMC_MP_GPIO @BASEBOARD_FAB2_LIB.BASEBOARD_FAB2(SCH_1):FM_BB_BMC_MP_GPIO    I18 @BASEBOARD_FAB2_LIB.BASEBOARD_FAB2(SCH_1):PAGE182
    C6 SMB_PEHPCPU1_STBY_LVC3_SCL @BASEBOARD_FAB2_LIB.BASEBOARD_FAB2(SCH_1):SMB_PEHPCPU1_STBY_LVC3_SCL    I18 @BASEBOARD_FAB2_LIB.BASEBOARD_FAB2(SCH_1):PAGE182
    C8 P3E_CPU1_PE3_MP_C_TXP<8> @BASEBOARD_FAB2_LIB.BASEBOARD_FAB2(SCH_1):P3E_CPU1_PE3_MP_C_TXP(8)    I18 @BASEBOARD_FAB2_LIB.BASEBOARD_FAB2(SCH_1):PAGE182
    D1 P3E_CPU1_PE3_MP_RXN<9> @BASEBOARD_FAB2_LIB.BASEBOARD_FAB2(SCH_1):P3E_CPU1_PE3_MP_RXN(9)    I18 @BASEBOARD_FAB2_LIB.BASEBOARD_FAB2(SCH_1):PAGE182
    D3 P3E_CPU1_PE3_MP_RXN<15> @BASEBOARD_FAB2_LIB.BASEBOARD_FAB2(SCH_1):P3E_CPU1_PE3_MP_RXN(15)    I18 @BASEBOARD_FAB2_LIB.BASEBOARD_FAB2(SCH_1):PAGE182
    D5 SMB_LAN_STBY_LVC3_SDA @BASEBOARD_FAB2_LIB.BASEBOARD_FAB2(SCH_1):SMB_LAN_STBY_LVC3_SDA    I18 @BASEBOARD_FAB2_LIB.BASEBOARD_FAB2(SCH_1):PAGE182
    D7 P3E_CPU1_PE3_MP_C_TXN<12> @BASEBOARD_FAB2_LIB.BASEBOARD_FAB2(SCH_1):P3E_CPU1_PE3_MP_C_TXN(12)    I18 @BASEBOARD_FAB2_LIB.BASEBOARD_FAB2(SCH_1):PAGE182
    E1 P3E_CPU1_PE3_MP_RXP<9> @BASEBOARD_FAB2_LIB.BASEBOARD_FAB2(SCH_1):P3E_CPU1_PE3_MP_RXP(9)    I18 @BASEBOARD_FAB2_LIB.BASEBOARD_FAB2(SCH_1):PAGE182
    E2 P3E_CPU1_PE3_MP_RXN<12> @BASEBOARD_FAB2_LIB.BASEBOARD_FAB2(SCH_1):P3E_CPU1_PE3_MP_RXN(12)    I18 @BASEBOARD_FAB2_LIB.BASEBOARD_FAB2(SCH_1):PAGE182
    E3 P3E_CPU1_PE3_MP_RXP<15> @BASEBOARD_FAB2_LIB.BASEBOARD_FAB2(SCH_1):P3E_CPU1_PE3_MP_RXP(15)    I18 @BASEBOARD_FAB2_LIB.BASEBOARD_FAB2(SCH_1):PAGE182
    E4 TP_IOE4 @BASEBOARD_FAB2_LIB.BASEBOARD_FAB2(SCH_1):TP_IOE4    I18 @BASEBOARD_FAB2_LIB.BASEBOARD_FAB2(SCH_1):PAGE182
    E5 SMB_LAN_STBY_LVC3_SCL @BASEBOARD_FAB2_LIB.BASEBOARD_FAB2(SCH_1):SMB_LAN_STBY_LVC3_SCL    I18 @BASEBOARD_FAB2_LIB.BASEBOARD_FAB2(SCH_1):PAGE182
    E6 P3E_CPU1_PE3_MP_C_TXN<14> @BASEBOARD_FAB2_LIB.BASEBOARD_FAB2(SCH_1):P3E_CPU1_PE3_MP_C_TXN(14)    I18 @BASEBOARD_FAB2_LIB.BASEBOARD_FAB2(SCH_1):PAGE182
    E7 P3E_CPU1_PE3_MP_C_TXP<12> @BASEBOARD_FAB2_LIB.BASEBOARD_FAB2(SCH_1):P3E_CPU1_PE3_MP_C_TXP(12)    I18 @BASEBOARD_FAB2_LIB.BASEBOARD_FAB2(SCH_1):PAGE182
    E8 P3E_CPU1_PE3_MP_C_TXN<9> @BASEBOARD_FAB2_LIB.BASEBOARD_FAB2(SCH_1):P3E_CPU1_PE3_MP_C_TXN(9)    I18 @BASEBOARD_FAB2_LIB.BASEBOARD_FAB2(SCH_1):PAGE182
    F2 P3E_CPU1_PE3_MP_RXP<12> @BASEBOARD_FAB2_LIB.BASEBOARD_FAB2(SCH_1):P3E_CPU1_PE3_MP_RXP(12)    I18 @BASEBOARD_FAB2_LIB.BASEBOARD_FAB2(SCH_1):PAGE182
    F4 TP_IOF4 @BASEBOARD_FAB2_LIB.BASEBOARD_FAB2(SCH_1):TP_IOF4    I18 @BASEBOARD_FAB2_LIB.BASEBOARD_FAB2(SCH_1):PAGE182
    F6 P3E_CPU1_PE3_MP_C_TXP<14> @BASEBOARD_FAB2_LIB.BASEBOARD_FAB2(SCH_1):P3E_CPU1_PE3_MP_C_TXP(14)    I18 @BASEBOARD_FAB2_LIB.BASEBOARD_FAB2(SCH_1):PAGE182
    F8 P3E_CPU1_PE3_MP_C_TXP<9> @BASEBOARD_FAB2_LIB.BASEBOARD_FAB2(SCH_1):P3E_CPU1_PE3_MP_C_TXP(9)    I18 @BASEBOARD_FAB2_LIB.BASEBOARD_FAB2(SCH_1):PAGE182
    G1 P3E_CPU1_PE3_MP_RXP<10> @BASEBOARD_FAB2_LIB.BASEBOARD_FAB2(SCH_1):P3E_CPU1_PE3_MP_RXP(10)    I18 @BASEBOARD_FAB2_LIB.BASEBOARD_FAB2(SCH_1):PAGE182
    G3 TP_IOG3 @BASEBOARD_FAB2_LIB.BASEBOARD_FAB2(SCH_1):TP_IOG3    I18 @BASEBOARD_FAB2_LIB.BASEBOARD_FAB2(SCH_1):PAGE182
    G5 FM_XRC_PRESENT_N @BASEBOARD_FAB2_LIB.BASEBOARD_FAB2(SCH_1):FM_XRC_PRESENT_N    I18 @BASEBOARD_FAB2_LIB.BASEBOARD_FAB2(SCH_1):PAGE182
    G7 P3E_CPU1_PE3_MP_C_TXN<13> @BASEBOARD_FAB2_LIB.BASEBOARD_FAB2(SCH_1):P3E_CPU1_PE3_MP_C_TXN(13)    I18 @BASEBOARD_FAB2_LIB.BASEBOARD_FAB2(SCH_1):PAGE182
    H1 P3E_CPU1_PE3_MP_RXN<10> @BASEBOARD_FAB2_LIB.BASEBOARD_FAB2(SCH_1):P3E_CPU1_PE3_MP_RXN(10)    I18 @BASEBOARD_FAB2_LIB.BASEBOARD_FAB2(SCH_1):PAGE182
    H2 P3E_CPU1_PE3_MP_RXP<13> @BASEBOARD_FAB2_LIB.BASEBOARD_FAB2(SCH_1):P3E_CPU1_PE3_MP_RXP(13)    I18 @BASEBOARD_FAB2_LIB.BASEBOARD_FAB2(SCH_1):PAGE182
    H3 TP_IOH3 @BASEBOARD_FAB2_LIB.BASEBOARD_FAB2(SCH_1):TP_IOH3    I18 @BASEBOARD_FAB2_LIB.BASEBOARD_FAB2(SCH_1):PAGE182
    H4 TP_IOH4 @BASEBOARD_FAB2_LIB.BASEBOARD_FAB2(SCH_1):TP_IOH4    I18 @BASEBOARD_FAB2_LIB.BASEBOARD_FAB2(SCH_1):PAGE182
    H5 FM_XRC_READY_N @BASEBOARD_FAB2_LIB.BASEBOARD_FAB2(SCH_1):FM_XRC_READY_N    I18 @BASEBOARD_FAB2_LIB.BASEBOARD_FAB2(SCH_1):PAGE182
    H6 P3E_CPU1_PE3_MP_C_TXN<15> @BASEBOARD_FAB2_LIB.BASEBOARD_FAB2(SCH_1):P3E_CPU1_PE3_MP_C_TXN(15)    I18 @BASEBOARD_FAB2_LIB.BASEBOARD_FAB2(SCH_1):PAGE182
    H7 P3E_CPU1_PE3_MP_C_TXP<13> @BASEBOARD_FAB2_LIB.BASEBOARD_FAB2(SCH_1):P3E_CPU1_PE3_MP_C_TXP(13)    I18 @BASEBOARD_FAB2_LIB.BASEBOARD_FAB2(SCH_1):PAGE182
    H8 P3E_CPU1_PE3_MP_C_TXP<10> @BASEBOARD_FAB2_LIB.BASEBOARD_FAB2(SCH_1):P3E_CPU1_PE3_MP_C_TXP(10)    I18 @BASEBOARD_FAB2_LIB.BASEBOARD_FAB2(SCH_1):PAGE182
    I2 P3E_CPU1_PE3_MP_RXN<13> @BASEBOARD_FAB2_LIB.BASEBOARD_FAB2(SCH_1):P3E_CPU1_PE3_MP_RXN(13)    I18 @BASEBOARD_FAB2_LIB.BASEBOARD_FAB2(SCH_1):PAGE182
    I4 TP_IOI4 @BASEBOARD_FAB2_LIB.BASEBOARD_FAB2(SCH_1):TP_IOI4    I18 @BASEBOARD_FAB2_LIB.BASEBOARD_FAB2(SCH_1):PAGE182
    I6 P3E_CPU1_PE3_MP_C_TXP<15> @BASEBOARD_FAB2_LIB.BASEBOARD_FAB2(SCH_1):P3E_CPU1_PE3_MP_C_TXP(15)    I18 @BASEBOARD_FAB2_LIB.BASEBOARD_FAB2(SCH_1):PAGE182
    I8 P3E_CPU1_PE3_MP_C_TXN<10> @BASEBOARD_FAB2_LIB.BASEBOARD_FAB2(SCH_1):P3E_CPU1_PE3_MP_C_TXN(10)    I18 @BASEBOARD_FAB2_LIB.BASEBOARD_FAB2(SCH_1):PAGE182

J1D1 CONN12_G98257001_THMT-CONN,G98A
    A1 P12V_PSU @BASEBOARD_FAB2_LIB.BASEBOARD_FAB2(SCH_1):P12V_PSU    I78 @BASEBOARD_FAB2_LIB.BASEBOARD_FAB2(SCH_1):PAGE195
    A2 P12V_PSU @BASEBOARD_FAB2_LIB.BASEBOARD_FAB2(SCH_1):P12V_PSU    I78 @BASEBOARD_FAB2_LIB.BASEBOARD_FAB2(SCH_1):PAGE195
    A3 P12V_PSU @BASEBOARD_FAB2_LIB.BASEBOARD_FAB2(SCH_1):P12V_PSU    I78 @BASEBOARD_FAB2_LIB.BASEBOARD_FAB2(SCH_1):PAGE195
    B1 P12V_PSU @BASEBOARD_FAB2_LIB.BASEBOARD_FAB2(SCH_1):P12V_PSU    I78 @BASEBOARD_FAB2_LIB.BASEBOARD_FAB2(SCH_1):PAGE195
    B2 P12V_PSU @BASEBOARD_FAB2_LIB.BASEBOARD_FAB2(SCH_1):P12V_PSU    I78 @BASEBOARD_FAB2_LIB.BASEBOARD_FAB2(SCH_1):PAGE195
    B3 P12V_PSU @BASEBOARD_FAB2_LIB.BASEBOARD_FAB2(SCH_1):P12V_PSU    I78 @BASEBOARD_FAB2_LIB.BASEBOARD_FAB2(SCH_1):PAGE195
    C1    GND @BASEBOARD_FAB2_LIB.BASEBOARD_FAB2(SCH_1):GND    I78 @BASEBOARD_FAB2_LIB.BASEBOARD_FAB2(SCH_1):PAGE195
    C2    GND @BASEBOARD_FAB2_LIB.BASEBOARD_FAB2(SCH_1):GND    I78 @BASEBOARD_FAB2_LIB.BASEBOARD_FAB2(SCH_1):PAGE195
    C3    GND @BASEBOARD_FAB2_LIB.BASEBOARD_FAB2(SCH_1):GND    I78 @BASEBOARD_FAB2_LIB.BASEBOARD_FAB2(SCH_1):PAGE195
    D1    GND @BASEBOARD_FAB2_LIB.BASEBOARD_FAB2(SCH_1):GND    I78 @BASEBOARD_FAB2_LIB.BASEBOARD_FAB2(SCH_1):PAGE195
    D2    GND @BASEBOARD_FAB2_LIB.BASEBOARD_FAB2(SCH_1):GND    I78 @BASEBOARD_FAB2_LIB.BASEBOARD_FAB2(SCH_1):PAGE195
    D3    GND @BASEBOARD_FAB2_LIB.BASEBOARD_FAB2(SCH_1):GND    I78 @BASEBOARD_FAB2_LIB.BASEBOARD_FAB2(SCH_1):PAGE195

J1E1 CONN12_G98257001_THMT-CONN,G98A
    A1 P12V_PSU @BASEBOARD_FAB2_LIB.BASEBOARD_FAB2(SCH_1):P12V_PSU    I29 @BASEBOARD_FAB2_LIB.BASEBOARD_FAB2(SCH_1):PAGE195
    A2 P12V_PSU @BASEBOARD_FAB2_LIB.BASEBOARD_FAB2(SCH_1):P12V_PSU    I29 @BASEBOARD_FAB2_LIB.BASEBOARD_FAB2(SCH_1):PAGE195
    A3 P12V_PSU @BASEBOARD_FAB2_LIB.BASEBOARD_FAB2(SCH_1):P12V_PSU    I29 @BASEBOARD_FAB2_LIB.BASEBOARD_FAB2(SCH_1):PAGE195
    B1 P12V_PSU @BASEBOARD_FAB2_LIB.BASEBOARD_FAB2(SCH_1):P12V_PSU    I29 @BASEBOARD_FAB2_LIB.BASEBOARD_FAB2(SCH_1):PAGE195
    B2 P12V_PSU @BASEBOARD_FAB2_LIB.BASEBOARD_FAB2(SCH_1):P12V_PSU    I29 @BASEBOARD_FAB2_LIB.BASEBOARD_FAB2(SCH_1):PAGE195
    B3 P12V_PSU @BASEBOARD_FAB2_LIB.BASEBOARD_FAB2(SCH_1):P12V_PSU    I29 @BASEBOARD_FAB2_LIB.BASEBOARD_FAB2(SCH_1):PAGE195
    C1    GND @BASEBOARD_FAB2_LIB.BASEBOARD_FAB2(SCH_1):GND    I29 @BASEBOARD_FAB2_LIB.BASEBOARD_FAB2(SCH_1):PAGE195
    C2    GND @BASEBOARD_FAB2_LIB.BASEBOARD_FAB2(SCH_1):GND    I29 @BASEBOARD_FAB2_LIB.BASEBOARD_FAB2(SCH_1):PAGE195
    C3    GND @BASEBOARD_FAB2_LIB.BASEBOARD_FAB2(SCH_1):GND    I29 @BASEBOARD_FAB2_LIB.BASEBOARD_FAB2(SCH_1):PAGE195
    D1    GND @BASEBOARD_FAB2_LIB.BASEBOARD_FAB2(SCH_1):GND    I29 @BASEBOARD_FAB2_LIB.BASEBOARD_FAB2(SCH_1):PAGE195
    D2    GND @BASEBOARD_FAB2_LIB.BASEBOARD_FAB2(SCH_1):GND    I29 @BASEBOARD_FAB2_LIB.BASEBOARD_FAB2(SCH_1):PAGE195
    D3    GND @BASEBOARD_FAB2_LIB.BASEBOARD_FAB2(SCH_1):GND    I29 @BASEBOARD_FAB2_LIB.BASEBOARD_FAB2(SCH_1):PAGE195

J1F1 CONN76_H22707001_THMT1-CONN,H2A
    A2    GND @BASEBOARD_FAB2_LIB.BASEBOARD_FAB2(SCH_1):GND   I111 @BASEBOARD_FAB2_LIB.BASEBOARD_FAB2(SCH_1):PAGE181
    A4 FAN_TACH3_R @BASEBOARD_FAB2_LIB.BASEBOARD_FAB2(SCH_1):FAN_TACH3_R   I111 @BASEBOARD_FAB2_LIB.BASEBOARD_FAB2(SCH_1):PAGE181
    A6 IRQ_SML1_PMBUS_ALERT_R_N @BASEBOARD_FAB2_LIB.BASEBOARD_FAB2(SCH_1):IRQ_SML1_PMBUS_ALERT_R_N   I111 @BASEBOARD_FAB2_LIB.BASEBOARD_FAB2(SCH_1):PAGE181
    A8    GND @BASEBOARD_FAB2_LIB.BASEBOARD_FAB2(SCH_1):GND   I111 @BASEBOARD_FAB2_LIB.BASEBOARD_FAB2(SCH_1):PAGE181
    C1    GND @BASEBOARD_FAB2_LIB.BASEBOARD_FAB2(SCH_1):GND   I111 @BASEBOARD_FAB2_LIB.BASEBOARD_FAB2(SCH_1):PAGE181
    C3    GND @BASEBOARD_FAB2_LIB.BASEBOARD_FAB2(SCH_1):GND   I111 @BASEBOARD_FAB2_LIB.BASEBOARD_FAB2(SCH_1):PAGE181
    C5    GND @BASEBOARD_FAB2_LIB.BASEBOARD_FAB2(SCH_1):GND   I111 @BASEBOARD_FAB2_LIB.BASEBOARD_FAB2(SCH_1):PAGE181
    C7    GND @BASEBOARD_FAB2_LIB.BASEBOARD_FAB2(SCH_1):GND   I111 @BASEBOARD_FAB2_LIB.BASEBOARD_FAB2(SCH_1):PAGE181
    D2    GND @BASEBOARD_FAB2_LIB.BASEBOARD_FAB2(SCH_1):GND   I111 @BASEBOARD_FAB2_LIB.BASEBOARD_FAB2(SCH_1):PAGE181
    D4 FAN_TACH0_R @BASEBOARD_FAB2_LIB.BASEBOARD_FAB2(SCH_1):FAN_TACH0_R   I111 @BASEBOARD_FAB2_LIB.BASEBOARD_FAB2(SCH_1):PAGE181
    D6    GND @BASEBOARD_FAB2_LIB.BASEBOARD_FAB2(SCH_1):GND   I111 @BASEBOARD_FAB2_LIB.BASEBOARD_FAB2(SCH_1):PAGE181
    D8    GND @BASEBOARD_FAB2_LIB.BASEBOARD_FAB2(SCH_1):GND   I111 @BASEBOARD_FAB2_LIB.BASEBOARD_FAB2(SCH_1):PAGE181
    F1    GND @BASEBOARD_FAB2_LIB.BASEBOARD_FAB2(SCH_1):GND   I111 @BASEBOARD_FAB2_LIB.BASEBOARD_FAB2(SCH_1):PAGE181
    F3    GND @BASEBOARD_FAB2_LIB.BASEBOARD_FAB2(SCH_1):GND   I111 @BASEBOARD_FAB2_LIB.BASEBOARD_FAB2(SCH_1):PAGE181
    F5 FM_MB_SLOT_ID0 @BASEBOARD_FAB2_LIB.BASEBOARD_FAB2(SCH_1):FM_MB_SLOT_ID0   I111 @BASEBOARD_FAB2_LIB.BASEBOARD_FAB2(SCH_1):PAGE181
    F7    GND @BASEBOARD_FAB2_LIB.BASEBOARD_FAB2(SCH_1):GND   I111 @BASEBOARD_FAB2_LIB.BASEBOARD_FAB2(SCH_1):PAGE181
    G2    GND @BASEBOARD_FAB2_LIB.BASEBOARD_FAB2(SCH_1):GND   I111 @BASEBOARD_FAB2_LIB.BASEBOARD_FAB2(SCH_1):PAGE181
    G4    GND @BASEBOARD_FAB2_LIB.BASEBOARD_FAB2(SCH_1):GND   I111 @BASEBOARD_FAB2_LIB.BASEBOARD_FAB2(SCH_1):PAGE181
    G6    GND @BASEBOARD_FAB2_LIB.BASEBOARD_FAB2(SCH_1):GND   I111 @BASEBOARD_FAB2_LIB.BASEBOARD_FAB2(SCH_1):PAGE181
    G8    GND @BASEBOARD_FAB2_LIB.BASEBOARD_FAB2(SCH_1):GND   I111 @BASEBOARD_FAB2_LIB.BASEBOARD_FAB2(SCH_1):PAGE181
    I1    GND @BASEBOARD_FAB2_LIB.BASEBOARD_FAB2(SCH_1):GND   I111 @BASEBOARD_FAB2_LIB.BASEBOARD_FAB2(SCH_1):PAGE181
    I3 FM_ENABLE_FAN_POWER @BASEBOARD_FAB2_LIB.BASEBOARD_FAB2(SCH_1):FM_ENABLE_FAN_POWER   I111 @BASEBOARD_FAB2_LIB.BASEBOARD_FAB2(SCH_1):PAGE181
    I5 RST_PCIE_MIDPLANE_N @BASEBOARD_FAB2_LIB.BASEBOARD_FAB2(SCH_1):RST_PCIE_MIDPLANE_N   I111 @BASEBOARD_FAB2_LIB.BASEBOARD_FAB2(SCH_1):PAGE181
    I7    GND @BASEBOARD_FAB2_LIB.BASEBOARD_FAB2(SCH_1):GND   I111 @BASEBOARD_FAB2_LIB.BASEBOARD_FAB2(SCH_1):PAGE181
    J2    GND @BASEBOARD_FAB2_LIB.BASEBOARD_FAB2(SCH_1):GND   I111 @BASEBOARD_FAB2_LIB.BASEBOARD_FAB2(SCH_1):PAGE181
    J4    GND @BASEBOARD_FAB2_LIB.BASEBOARD_FAB2(SCH_1):GND   I111 @BASEBOARD_FAB2_LIB.BASEBOARD_FAB2(SCH_1):PAGE181
    J6    GND @BASEBOARD_FAB2_LIB.BASEBOARD_FAB2(SCH_1):GND   I111 @BASEBOARD_FAB2_LIB.BASEBOARD_FAB2(SCH_1):PAGE181
    J8    GND @BASEBOARD_FAB2_LIB.BASEBOARD_FAB2(SCH_1):GND   I111 @BASEBOARD_FAB2_LIB.BASEBOARD_FAB2(SCH_1):PAGE181
    A1 P3E_CPU1_PE3_MP_RXN<0> @BASEBOARD_FAB2_LIB.BASEBOARD_FAB2(SCH_1):P3E_CPU1_PE3_MP_RXN(0)   I111 @BASEBOARD_FAB2_LIB.BASEBOARD_FAB2(SCH_1):PAGE181
    A3 P3E_CPU1_PE3_MP_RXP<6> @BASEBOARD_FAB2_LIB.BASEBOARD_FAB2(SCH_1):P3E_CPU1_PE3_MP_RXP(6)   I111 @BASEBOARD_FAB2_LIB.BASEBOARD_FAB2(SCH_1):PAGE181
    A5 NIC_MDI_MNG_TX_DP @BASEBOARD_FAB2_LIB.BASEBOARD_FAB2(SCH_1):NIC_MDI_MNG_TX_DP   I111 @BASEBOARD_FAB2_LIB.BASEBOARD_FAB2(SCH_1):PAGE181
    A7 P3E_CPU1_PE3_MP_C_TXN<3> @BASEBOARD_FAB2_LIB.BASEBOARD_FAB2(SCH_1):P3E_CPU1_PE3_MP_C_TXN(3)   I111 @BASEBOARD_FAB2_LIB.BASEBOARD_FAB2(SCH_1):PAGE181
    B1 P3E_CPU1_PE3_MP_RXP<0> @BASEBOARD_FAB2_LIB.BASEBOARD_FAB2(SCH_1):P3E_CPU1_PE3_MP_RXP(0)   I111 @BASEBOARD_FAB2_LIB.BASEBOARD_FAB2(SCH_1):PAGE181
    B2 P3E_CPU1_PE3_MP_RXN<3> @BASEBOARD_FAB2_LIB.BASEBOARD_FAB2(SCH_1):P3E_CPU1_PE3_MP_RXN(3)   I111 @BASEBOARD_FAB2_LIB.BASEBOARD_FAB2(SCH_1):PAGE181
    B3 P3E_CPU1_PE3_MP_RXN<6> @BASEBOARD_FAB2_LIB.BASEBOARD_FAB2(SCH_1):P3E_CPU1_PE3_MP_RXN(6)   I111 @BASEBOARD_FAB2_LIB.BASEBOARD_FAB2(SCH_1):PAGE181
    B4 FAN_TACH2_R @BASEBOARD_FAB2_LIB.BASEBOARD_FAB2(SCH_1):FAN_TACH2_R   I111 @BASEBOARD_FAB2_LIB.BASEBOARD_FAB2(SCH_1):PAGE181
    B5 NIC_MDI_MNG_TX_DN @BASEBOARD_FAB2_LIB.BASEBOARD_FAB2(SCH_1):NIC_MDI_MNG_TX_DN   I111 @BASEBOARD_FAB2_LIB.BASEBOARD_FAB2(SCH_1):PAGE181
    B6 SMB_BMC_PMBUS_STBY_LVC3_SDA @BASEBOARD_FAB2_LIB.BASEBOARD_FAB2(SCH_1):SMB_BMC_PMBUS_STBY_LVC3_SDA   I111 @BASEBOARD_FAB2_LIB.BASEBOARD_FAB2(SCH_1):PAGE181
    B7 P3E_CPU1_PE3_MP_C_TXP<3> @BASEBOARD_FAB2_LIB.BASEBOARD_FAB2(SCH_1):P3E_CPU1_PE3_MP_C_TXP(3)   I111 @BASEBOARD_FAB2_LIB.BASEBOARD_FAB2(SCH_1):PAGE181
    B8 P3E_CPU1_PE3_MP_C_TXN<0> @BASEBOARD_FAB2_LIB.BASEBOARD_FAB2(SCH_1):P3E_CPU1_PE3_MP_C_TXN(0)   I111 @BASEBOARD_FAB2_LIB.BASEBOARD_FAB2(SCH_1):PAGE181
    C2 P3E_CPU1_PE3_MP_RXP<3> @BASEBOARD_FAB2_LIB.BASEBOARD_FAB2(SCH_1):P3E_CPU1_PE3_MP_RXP(3)   I111 @BASEBOARD_FAB2_LIB.BASEBOARD_FAB2(SCH_1):PAGE181
    C4 FAN_TACH1_R @BASEBOARD_FAB2_LIB.BASEBOARD_FAB2(SCH_1):FAN_TACH1_R   I111 @BASEBOARD_FAB2_LIB.BASEBOARD_FAB2(SCH_1):PAGE181
    C6 SMB_BMC_PMBUS_STBY_LVC3_SCL @BASEBOARD_FAB2_LIB.BASEBOARD_FAB2(SCH_1):SMB_BMC_PMBUS_STBY_LVC3_SCL   I111 @BASEBOARD_FAB2_LIB.BASEBOARD_FAB2(SCH_1):PAGE181
    C8 P3E_CPU1_PE3_MP_C_TXP<0> @BASEBOARD_FAB2_LIB.BASEBOARD_FAB2(SCH_1):P3E_CPU1_PE3_MP_C_TXP(0)   I111 @BASEBOARD_FAB2_LIB.BASEBOARD_FAB2(SCH_1):PAGE181
    D1 P3E_CPU1_PE3_MP_RXN<1> @BASEBOARD_FAB2_LIB.BASEBOARD_FAB2(SCH_1):P3E_CPU1_PE3_MP_RXN(1)   I111 @BASEBOARD_FAB2_LIB.BASEBOARD_FAB2(SCH_1):PAGE181
    D3 P3E_CPU1_PE3_MP_RXN<7> @BASEBOARD_FAB2_LIB.BASEBOARD_FAB2(SCH_1):P3E_CPU1_PE3_MP_RXN(7)   I111 @BASEBOARD_FAB2_LIB.BASEBOARD_FAB2(SCH_1):PAGE181
    D5 NIC_MDI_MNG_RX_DP @BASEBOARD_FAB2_LIB.BASEBOARD_FAB2(SCH_1):NIC_MDI_MNG_RX_DP   I111 @BASEBOARD_FAB2_LIB.BASEBOARD_FAB2(SCH_1):PAGE181
    D7 P3E_CPU1_PE3_MP_C_TXN<4> @BASEBOARD_FAB2_LIB.BASEBOARD_FAB2(SCH_1):P3E_CPU1_PE3_MP_C_TXN(4)   I111 @BASEBOARD_FAB2_LIB.BASEBOARD_FAB2(SCH_1):PAGE181
    E1 P3E_CPU1_PE3_MP_RXP<1> @BASEBOARD_FAB2_LIB.BASEBOARD_FAB2(SCH_1):P3E_CPU1_PE3_MP_RXP(1)   I111 @BASEBOARD_FAB2_LIB.BASEBOARD_FAB2(SCH_1):PAGE181
    E2 P3E_CPU1_PE3_MP_RXN<4> @BASEBOARD_FAB2_LIB.BASEBOARD_FAB2(SCH_1):P3E_CPU1_PE3_MP_RXN(4)   I111 @BASEBOARD_FAB2_LIB.BASEBOARD_FAB2(SCH_1):PAGE181
    E3 P3E_CPU1_PE3_MP_RXP<7> @BASEBOARD_FAB2_LIB.BASEBOARD_FAB2(SCH_1):P3E_CPU1_PE3_MP_RXP(7)   I111 @BASEBOARD_FAB2_LIB.BASEBOARD_FAB2(SCH_1):PAGE181
    E4 FM_MATED_IN_N @BASEBOARD_FAB2_LIB.BASEBOARD_FAB2(SCH_1):FM_MATED_IN_N   I111 @BASEBOARD_FAB2_LIB.BASEBOARD_FAB2(SCH_1):PAGE181
    E5 NIC_MDI_MNG_RX_DN @BASEBOARD_FAB2_LIB.BASEBOARD_FAB2(SCH_1):NIC_MDI_MNG_RX_DN   I111 @BASEBOARD_FAB2_LIB.BASEBOARD_FAB2(SCH_1):PAGE181
    E6 P3E_CPU1_PE3_MP_C_TXN<6> @BASEBOARD_FAB2_LIB.BASEBOARD_FAB2(SCH_1):P3E_CPU1_PE3_MP_C_TXN(6)   I111 @BASEBOARD_FAB2_LIB.BASEBOARD_FAB2(SCH_1):PAGE181
    E7 P3E_CPU1_PE3_MP_C_TXP<4> @BASEBOARD_FAB2_LIB.BASEBOARD_FAB2(SCH_1):P3E_CPU1_PE3_MP_C_TXP(4)   I111 @BASEBOARD_FAB2_LIB.BASEBOARD_FAB2(SCH_1):PAGE181
    E8 P3E_CPU1_PE3_MP_C_TXN<1> @BASEBOARD_FAB2_LIB.BASEBOARD_FAB2(SCH_1):P3E_CPU1_PE3_MP_C_TXN(1)   I111 @BASEBOARD_FAB2_LIB.BASEBOARD_FAB2(SCH_1):PAGE181
    F2 P3E_CPU1_PE3_MP_RXP<4> @BASEBOARD_FAB2_LIB.BASEBOARD_FAB2(SCH_1):P3E_CPU1_PE3_MP_RXP(4)   I111 @BASEBOARD_FAB2_LIB.BASEBOARD_FAB2(SCH_1):PAGE181
    F4 FAN_PWM_OUT_SYS0_R1 @BASEBOARD_FAB2_LIB.BASEBOARD_FAB2(SCH_1):FAN_PWM_OUT_SYS0_R1   I111 @BASEBOARD_FAB2_LIB.BASEBOARD_FAB2(SCH_1):PAGE181
    F6 P3E_CPU1_PE3_MP_C_TXP<6> @BASEBOARD_FAB2_LIB.BASEBOARD_FAB2(SCH_1):P3E_CPU1_PE3_MP_C_TXP(6)   I111 @BASEBOARD_FAB2_LIB.BASEBOARD_FAB2(SCH_1):PAGE181
    F8 P3E_CPU1_PE3_MP_C_TXP<1> @BASEBOARD_FAB2_LIB.BASEBOARD_FAB2(SCH_1):P3E_CPU1_PE3_MP_C_TXP(1)   I111 @BASEBOARD_FAB2_LIB.BASEBOARD_FAB2(SCH_1):PAGE181
    G1 P3E_CPU1_PE3_MP_RXP<2> @BASEBOARD_FAB2_LIB.BASEBOARD_FAB2(SCH_1):P3E_CPU1_PE3_MP_RXP(2)   I111 @BASEBOARD_FAB2_LIB.BASEBOARD_FAB2(SCH_1):PAGE181
    G3 SPA_MID_DBG_TX_R @BASEBOARD_FAB2_LIB.BASEBOARD_FAB2(SCH_1):SPA_MID_DBG_TX_R   I111 @BASEBOARD_FAB2_LIB.BASEBOARD_FAB2(SCH_1):PAGE181
    G5 FM_MB_SLOT_ID1 @BASEBOARD_FAB2_LIB.BASEBOARD_FAB2(SCH_1):FM_MB_SLOT_ID1   I111 @BASEBOARD_FAB2_LIB.BASEBOARD_FAB2(SCH_1):PAGE181
    G7 P3E_CPU1_PE3_MP_C_TXP<5> @BASEBOARD_FAB2_LIB.BASEBOARD_FAB2(SCH_1):P3E_CPU1_PE3_MP_C_TXP(5)   I111 @BASEBOARD_FAB2_LIB.BASEBOARD_FAB2(SCH_1):PAGE181
    H1 P3E_CPU1_PE3_MP_RXN<2> @BASEBOARD_FAB2_LIB.BASEBOARD_FAB2(SCH_1):P3E_CPU1_PE3_MP_RXN(2)   I111 @BASEBOARD_FAB2_LIB.BASEBOARD_FAB2(SCH_1):PAGE181
    H2 P3E_CPU1_PE3_MP_RXP<5> @BASEBOARD_FAB2_LIB.BASEBOARD_FAB2(SCH_1):P3E_CPU1_PE3_MP_RXP(5)   I111 @BASEBOARD_FAB2_LIB.BASEBOARD_FAB2(SCH_1):PAGE181
    H3 SPA_MID_DBG_RX_R @BASEBOARD_FAB2_LIB.BASEBOARD_FAB2(SCH_1):SPA_MID_DBG_RX_R   I111 @BASEBOARD_FAB2_LIB.BASEBOARD_FAB2(SCH_1):PAGE181
    H4 CLK_100M_AIRMAX8_PE1_DP @BASEBOARD_FAB2_LIB.BASEBOARD_FAB2(SCH_1):CLK_100M_AIRMAX8_PE1_DP   I111 @BASEBOARD_FAB2_LIB.BASEBOARD_FAB2(SCH_1):PAGE181
    H5 FM_MB_SLOT_ID2 @BASEBOARD_FAB2_LIB.BASEBOARD_FAB2(SCH_1):FM_MB_SLOT_ID2   I111 @BASEBOARD_FAB2_LIB.BASEBOARD_FAB2(SCH_1):PAGE181
    H6 P3E_CPU1_PE3_MP_C_TXP<7> @BASEBOARD_FAB2_LIB.BASEBOARD_FAB2(SCH_1):P3E_CPU1_PE3_MP_C_TXP(7)   I111 @BASEBOARD_FAB2_LIB.BASEBOARD_FAB2(SCH_1):PAGE181
    H7 P3E_CPU1_PE3_MP_C_TXN<5> @BASEBOARD_FAB2_LIB.BASEBOARD_FAB2(SCH_1):P3E_CPU1_PE3_MP_C_TXN(5)   I111 @BASEBOARD_FAB2_LIB.BASEBOARD_FAB2(SCH_1):PAGE181
    H8 P3E_CPU1_PE3_MP_C_TXN<2> @BASEBOARD_FAB2_LIB.BASEBOARD_FAB2(SCH_1):P3E_CPU1_PE3_MP_C_TXN(2)   I111 @BASEBOARD_FAB2_LIB.BASEBOARD_FAB2(SCH_1):PAGE181
    I2 P3E_CPU1_PE3_MP_RXN<5> @BASEBOARD_FAB2_LIB.BASEBOARD_FAB2(SCH_1):P3E_CPU1_PE3_MP_RXN(5)   I111 @BASEBOARD_FAB2_LIB.BASEBOARD_FAB2(SCH_1):PAGE181
    I4 CLK_100M_AIRMAX8_PE1_DN @BASEBOARD_FAB2_LIB.BASEBOARD_FAB2(SCH_1):CLK_100M_AIRMAX8_PE1_DN   I111 @BASEBOARD_FAB2_LIB.BASEBOARD_FAB2(SCH_1):PAGE181
    I6 P3E_CPU1_PE3_MP_C_TXN<7> @BASEBOARD_FAB2_LIB.BASEBOARD_FAB2(SCH_1):P3E_CPU1_PE3_MP_C_TXN(7)   I111 @BASEBOARD_FAB2_LIB.BASEBOARD_FAB2(SCH_1):PAGE181
    I8 P3E_CPU1_PE3_MP_C_TXP<2> @BASEBOARD_FAB2_LIB.BASEBOARD_FAB2(SCH_1):P3E_CPU1_PE3_MP_C_TXP(2)   I111 @BASEBOARD_FAB2_LIB.BASEBOARD_FAB2(SCH_1):PAGE181

J1F2 CONN6_C74770005_PIP-HDR,C74770A
     1    GND @BASEBOARD_FAB2_LIB.BASEBOARD_FAB2(SCH_1):GND     I1 @BASEBOARD_FAB2_LIB.BASEBOARD_FAB2(SCH_1):PAGE161
     2 P12V_FAN @BASEBOARD_FAB2_LIB.BASEBOARD_FAB2(SCH_1):P12V_FAN     I1 @BASEBOARD_FAB2_LIB.BASEBOARD_FAB2(SCH_1):PAGE161
     3 FAN_TACH0_CPU0_D1 @BASEBOARD_FAB2_LIB.BASEBOARD_FAB2(SCH_1):FAN_TACH0_CPU0_D1     I1 @BASEBOARD_FAB2_LIB.BASEBOARD_FAB2(SCH_1):PAGE161
     4 FAN_PWM_OUT_SYS0_R @BASEBOARD_FAB2_LIB.BASEBOARD_FAB2(SCH_1):FAN_PWM_OUT_SYS0_R     I1 @BASEBOARD_FAB2_LIB.BASEBOARD_FAB2(SCH_1):PAGE161
     5 FAN_TACH1_CPU1_D1 @BASEBOARD_FAB2_LIB.BASEBOARD_FAB2(SCH_1):FAN_TACH1_CPU1_D1     I1 @BASEBOARD_FAB2_LIB.BASEBOARD_FAB2(SCH_1):PAGE161
     6 TP_FAN_0 @BASEBOARD_FAB2_LIB.BASEBOARD_FAB2(SCH_1):TP_FAN_0     I1 @BASEBOARD_FAB2_LIB.BASEBOARD_FAB2(SCH_1):PAGE161

J1F3 CONN8_H62179001_PIP-CONN,H6217A
     1 P3V3_STBY @BASEBOARD_FAB2_LIB.BASEBOARD_FAB2(SCH_1):P3V3_STBY   I189 @BASEBOARD_FAB2_LIB.BASEBOARD_FAB2(SCH_1):PAGE181
     2 FM_MP_PS_REDUNDANT_LOST_N @BASEBOARD_FAB2_LIB.BASEBOARD_FAB2(SCH_1):FM_MP_PS_REDUNDANT_LOST_N   I189 @BASEBOARD_FAB2_LIB.BASEBOARD_FAB2(SCH_1):PAGE181
     3 FM_MP_PS_FAIL_N @BASEBOARD_FAB2_LIB.BASEBOARD_FAB2(SCH_1):FM_MP_PS_FAIL_N   I189 @BASEBOARD_FAB2_LIB.BASEBOARD_FAB2(SCH_1):PAGE181
     4 FM_MATED_IN_N @BASEBOARD_FAB2_LIB.BASEBOARD_FAB2(SCH_1):FM_MATED_IN_N   I189 @BASEBOARD_FAB2_LIB.BASEBOARD_FAB2(SCH_1):PAGE181
     5 IRQ_SML1_PMBUS_ALERT_R_N @BASEBOARD_FAB2_LIB.BASEBOARD_FAB2(SCH_1):IRQ_SML1_PMBUS_ALERT_R_N   I189 @BASEBOARD_FAB2_LIB.BASEBOARD_FAB2(SCH_1):PAGE181
     6 SMB_BMC_PMBUS_STBY_LVC3_SDA @BASEBOARD_FAB2_LIB.BASEBOARD_FAB2(SCH_1):SMB_BMC_PMBUS_STBY_LVC3_SDA   I189 @BASEBOARD_FAB2_LIB.BASEBOARD_FAB2(SCH_1):PAGE181
     7 SMB_BMC_PMBUS_STBY_LVC3_SCL @BASEBOARD_FAB2_LIB.BASEBOARD_FAB2(SCH_1):SMB_BMC_PMBUS_STBY_LVC3_SCL   I189 @BASEBOARD_FAB2_LIB.BASEBOARD_FAB2(SCH_1):PAGE181
     8    GND @BASEBOARD_FAB2_LIB.BASEBOARD_FAB2(SCH_1):GND   I189 @BASEBOARD_FAB2_LIB.BASEBOARD_FAB2(SCH_1):PAGE181

J1G1 SCONN288_H44441004_PIP-SCONN,HA
    79 M_G_MA<0> @BASEBOARD_FAB2_LIB.BASEBOARD_FAB2(SCH_1):M_G_MA(0)   I111 @BASEBOARD_FAB2_LIB.BASEBOARD_FAB2(SCH_1):PAGE77
    72 M_G_MA<1> @BASEBOARD_FAB2_LIB.BASEBOARD_FAB2(SCH_1):M_G_MA(1)   I111 @BASEBOARD_FAB2_LIB.BASEBOARD_FAB2(SCH_1):PAGE77
   225 M_G_MA<10> @BASEBOARD_FAB2_LIB.BASEBOARD_FAB2(SCH_1):M_G_MA(10)   I111 @BASEBOARD_FAB2_LIB.BASEBOARD_FAB2(SCH_1):PAGE77
   210 M_G_MA<11> @BASEBOARD_FAB2_LIB.BASEBOARD_FAB2(SCH_1):M_G_MA(11)   I111 @BASEBOARD_FAB2_LIB.BASEBOARD_FAB2(SCH_1):PAGE77
    65 M_G_MA<12> @BASEBOARD_FAB2_LIB.BASEBOARD_FAB2(SCH_1):M_G_MA(12)   I111 @BASEBOARD_FAB2_LIB.BASEBOARD_FAB2(SCH_1):PAGE77
   232 M_G_MA<13> @BASEBOARD_FAB2_LIB.BASEBOARD_FAB2(SCH_1):M_G_MA(13)   I111 @BASEBOARD_FAB2_LIB.BASEBOARD_FAB2(SCH_1):PAGE77
   228 M_G_MA<14> @BASEBOARD_FAB2_LIB.BASEBOARD_FAB2(SCH_1):M_G_MA(14)   I111 @BASEBOARD_FAB2_LIB.BASEBOARD_FAB2(SCH_1):PAGE77
    86 M_G_MA<15> @BASEBOARD_FAB2_LIB.BASEBOARD_FAB2(SCH_1):M_G_MA(15)   I111 @BASEBOARD_FAB2_LIB.BASEBOARD_FAB2(SCH_1):PAGE77
    82 M_G_MA<16> @BASEBOARD_FAB2_LIB.BASEBOARD_FAB2(SCH_1):M_G_MA(16)   I111 @BASEBOARD_FAB2_LIB.BASEBOARD_FAB2(SCH_1):PAGE77
   234 M_G_MA<17> @BASEBOARD_FAB2_LIB.BASEBOARD_FAB2(SCH_1):M_G_MA(17)   I111 @BASEBOARD_FAB2_LIB.BASEBOARD_FAB2(SCH_1):PAGE77
   216 M_G_MA<2> @BASEBOARD_FAB2_LIB.BASEBOARD_FAB2(SCH_1):M_G_MA(2)   I111 @BASEBOARD_FAB2_LIB.BASEBOARD_FAB2(SCH_1):PAGE77
    71 M_G_MA<3> @BASEBOARD_FAB2_LIB.BASEBOARD_FAB2(SCH_1):M_G_MA(3)   I111 @BASEBOARD_FAB2_LIB.BASEBOARD_FAB2(SCH_1):PAGE77
   214 M_G_MA<4> @BASEBOARD_FAB2_LIB.BASEBOARD_FAB2(SCH_1):M_G_MA(4)   I111 @BASEBOARD_FAB2_LIB.BASEBOARD_FAB2(SCH_1):PAGE77
   213 M_G_MA<5> @BASEBOARD_FAB2_LIB.BASEBOARD_FAB2(SCH_1):M_G_MA(5)   I111 @BASEBOARD_FAB2_LIB.BASEBOARD_FAB2(SCH_1):PAGE77
    69 M_G_MA<6> @BASEBOARD_FAB2_LIB.BASEBOARD_FAB2(SCH_1):M_G_MA(6)   I111 @BASEBOARD_FAB2_LIB.BASEBOARD_FAB2(SCH_1):PAGE77
   211 M_G_MA<7> @BASEBOARD_FAB2_LIB.BASEBOARD_FAB2(SCH_1):M_G_MA(7)   I111 @BASEBOARD_FAB2_LIB.BASEBOARD_FAB2(SCH_1):PAGE77
    68 M_G_MA<8> @BASEBOARD_FAB2_LIB.BASEBOARD_FAB2(SCH_1):M_G_MA(8)   I111 @BASEBOARD_FAB2_LIB.BASEBOARD_FAB2(SCH_1):PAGE77
    66 M_G_MA<9> @BASEBOARD_FAB2_LIB.BASEBOARD_FAB2(SCH_1):M_G_MA(9)   I111 @BASEBOARD_FAB2_LIB.BASEBOARD_FAB2(SCH_1):PAGE77
    62 M_G_ACT_N @BASEBOARD_FAB2_LIB.BASEBOARD_FAB2(SCH_1):M_G_ACT_N   I111 @BASEBOARD_FAB2_LIB.BASEBOARD_FAB2(SCH_1):PAGE77
   208 M_G_ALERT_N @BASEBOARD_FAB2_LIB.BASEBOARD_FAB2(SCH_1):M_G_ALERT_N   I111 @BASEBOARD_FAB2_LIB.BASEBOARD_FAB2(SCH_1):PAGE77
   224 M_G_BA<1> @BASEBOARD_FAB2_LIB.BASEBOARD_FAB2(SCH_1):M_G_BA(1)   I111 @BASEBOARD_FAB2_LIB.BASEBOARD_FAB2(SCH_1):PAGE77
    81 M_G_BA<0> @BASEBOARD_FAB2_LIB.BASEBOARD_FAB2(SCH_1):M_G_BA(0)   I111 @BASEBOARD_FAB2_LIB.BASEBOARD_FAB2(SCH_1):PAGE77
   207 M_G_BG<1> @BASEBOARD_FAB2_LIB.BASEBOARD_FAB2(SCH_1):M_G_BG(1)   I111 @BASEBOARD_FAB2_LIB.BASEBOARD_FAB2(SCH_1):PAGE77
    63 M_G_BG<0> @BASEBOARD_FAB2_LIB.BASEBOARD_FAB2(SCH_1):M_G_BG(0)   I111 @BASEBOARD_FAB2_LIB.BASEBOARD_FAB2(SCH_1):PAGE77
   235 M_G_C<2> @BASEBOARD_FAB2_LIB.BASEBOARD_FAB2(SCH_1):M_G_C(2)   I111 @BASEBOARD_FAB2_LIB.BASEBOARD_FAB2(SCH_1):PAGE77
   199 M_G_ECC<6> @BASEBOARD_FAB2_LIB.BASEBOARD_FAB2(SCH_1):M_G_ECC(6)   I111 @BASEBOARD_FAB2_LIB.BASEBOARD_FAB2(SCH_1):PAGE77
    54 M_G_ECC<7> @BASEBOARD_FAB2_LIB.BASEBOARD_FAB2(SCH_1):M_G_ECC(7)   I111 @BASEBOARD_FAB2_LIB.BASEBOARD_FAB2(SCH_1):PAGE77
   192 M_G_ECC<4> @BASEBOARD_FAB2_LIB.BASEBOARD_FAB2(SCH_1):M_G_ECC(4)   I111 @BASEBOARD_FAB2_LIB.BASEBOARD_FAB2(SCH_1):PAGE77
    47 M_G_ECC<5> @BASEBOARD_FAB2_LIB.BASEBOARD_FAB2(SCH_1):M_G_ECC(5)   I111 @BASEBOARD_FAB2_LIB.BASEBOARD_FAB2(SCH_1):PAGE77
   201 M_G_ECC<2> @BASEBOARD_FAB2_LIB.BASEBOARD_FAB2(SCH_1):M_G_ECC(2)   I111 @BASEBOARD_FAB2_LIB.BASEBOARD_FAB2(SCH_1):PAGE77
    56 M_G_ECC<3> @BASEBOARD_FAB2_LIB.BASEBOARD_FAB2(SCH_1):M_G_ECC(3)   I111 @BASEBOARD_FAB2_LIB.BASEBOARD_FAB2(SCH_1):PAGE77
   194 M_G_ECC<0> @BASEBOARD_FAB2_LIB.BASEBOARD_FAB2(SCH_1):M_G_ECC(0)   I111 @BASEBOARD_FAB2_LIB.BASEBOARD_FAB2(SCH_1):PAGE77
    49 M_G_ECC<1> @BASEBOARD_FAB2_LIB.BASEBOARD_FAB2(SCH_1):M_G_ECC(1)   I111 @BASEBOARD_FAB2_LIB.BASEBOARD_FAB2(SCH_1):PAGE77
    75 M_G_CLK_DN<0> @BASEBOARD_FAB2_LIB.BASEBOARD_FAB2(SCH_1):M_G_CLK_DN(0)   I111 @BASEBOARD_FAB2_LIB.BASEBOARD_FAB2(SCH_1):PAGE77
    74 M_G_CLK_DP<0> @BASEBOARD_FAB2_LIB.BASEBOARD_FAB2(SCH_1):M_G_CLK_DP(0)   I111 @BASEBOARD_FAB2_LIB.BASEBOARD_FAB2(SCH_1):PAGE77
   219 M_G_CLK_DN<1> @BASEBOARD_FAB2_LIB.BASEBOARD_FAB2(SCH_1):M_G_CLK_DN(1)   I111 @BASEBOARD_FAB2_LIB.BASEBOARD_FAB2(SCH_1):PAGE77
   218 M_G_CLK_DP<1> @BASEBOARD_FAB2_LIB.BASEBOARD_FAB2(SCH_1):M_G_CLK_DP(1)   I111 @BASEBOARD_FAB2_LIB.BASEBOARD_FAB2(SCH_1):PAGE77
   203 M_G_CKE<1> @BASEBOARD_FAB2_LIB.BASEBOARD_FAB2(SCH_1):M_G_CKE(1)   I111 @BASEBOARD_FAB2_LIB.BASEBOARD_FAB2(SCH_1):PAGE77
    60 M_G_CKE<0> @BASEBOARD_FAB2_LIB.BASEBOARD_FAB2(SCH_1):M_G_CKE(0)   I111 @BASEBOARD_FAB2_LIB.BASEBOARD_FAB2(SCH_1):PAGE77
   280 M_G_DQ<62> @BASEBOARD_FAB2_LIB.BASEBOARD_FAB2(SCH_1):M_G_DQ(62)   I111 @BASEBOARD_FAB2_LIB.BASEBOARD_FAB2(SCH_1):PAGE77
   135 M_G_DQ<63> @BASEBOARD_FAB2_LIB.BASEBOARD_FAB2(SCH_1):M_G_DQ(63)   I111 @BASEBOARD_FAB2_LIB.BASEBOARD_FAB2(SCH_1):PAGE77
   273 M_G_DQ<60> @BASEBOARD_FAB2_LIB.BASEBOARD_FAB2(SCH_1):M_G_DQ(60)   I111 @BASEBOARD_FAB2_LIB.BASEBOARD_FAB2(SCH_1):PAGE77
   128 M_G_DQ<61> @BASEBOARD_FAB2_LIB.BASEBOARD_FAB2(SCH_1):M_G_DQ(61)   I111 @BASEBOARD_FAB2_LIB.BASEBOARD_FAB2(SCH_1):PAGE77
   282 M_G_DQ<58> @BASEBOARD_FAB2_LIB.BASEBOARD_FAB2(SCH_1):M_G_DQ(58)   I111 @BASEBOARD_FAB2_LIB.BASEBOARD_FAB2(SCH_1):PAGE77
   137 M_G_DQ<59> @BASEBOARD_FAB2_LIB.BASEBOARD_FAB2(SCH_1):M_G_DQ(59)   I111 @BASEBOARD_FAB2_LIB.BASEBOARD_FAB2(SCH_1):PAGE77
   275 M_G_DQ<56> @BASEBOARD_FAB2_LIB.BASEBOARD_FAB2(SCH_1):M_G_DQ(56)   I111 @BASEBOARD_FAB2_LIB.BASEBOARD_FAB2(SCH_1):PAGE77
   130 M_G_DQ<57> @BASEBOARD_FAB2_LIB.BASEBOARD_FAB2(SCH_1):M_G_DQ(57)   I111 @BASEBOARD_FAB2_LIB.BASEBOARD_FAB2(SCH_1):PAGE77
   269 M_G_DQ<54> @BASEBOARD_FAB2_LIB.BASEBOARD_FAB2(SCH_1):M_G_DQ(54)   I111 @BASEBOARD_FAB2_LIB.BASEBOARD_FAB2(SCH_1):PAGE77
   124 M_G_DQ<55> @BASEBOARD_FAB2_LIB.BASEBOARD_FAB2(SCH_1):M_G_DQ(55)   I111 @BASEBOARD_FAB2_LIB.BASEBOARD_FAB2(SCH_1):PAGE77
   262 M_G_DQ<52> @BASEBOARD_FAB2_LIB.BASEBOARD_FAB2(SCH_1):M_G_DQ(52)   I111 @BASEBOARD_FAB2_LIB.BASEBOARD_FAB2(SCH_1):PAGE77
   117 M_G_DQ<53> @BASEBOARD_FAB2_LIB.BASEBOARD_FAB2(SCH_1):M_G_DQ(53)   I111 @BASEBOARD_FAB2_LIB.BASEBOARD_FAB2(SCH_1):PAGE77
   271 M_G_DQ<50> @BASEBOARD_FAB2_LIB.BASEBOARD_FAB2(SCH_1):M_G_DQ(50)   I111 @BASEBOARD_FAB2_LIB.BASEBOARD_FAB2(SCH_1):PAGE77
   126 M_G_DQ<51> @BASEBOARD_FAB2_LIB.BASEBOARD_FAB2(SCH_1):M_G_DQ(51)   I111 @BASEBOARD_FAB2_LIB.BASEBOARD_FAB2(SCH_1):PAGE77
   264 M_G_DQ<48> @BASEBOARD_FAB2_LIB.BASEBOARD_FAB2(SCH_1):M_G_DQ(48)   I111 @BASEBOARD_FAB2_LIB.BASEBOARD_FAB2(SCH_1):PAGE77
   119 M_G_DQ<49> @BASEBOARD_FAB2_LIB.BASEBOARD_FAB2(SCH_1):M_G_DQ(49)   I111 @BASEBOARD_FAB2_LIB.BASEBOARD_FAB2(SCH_1):PAGE77
   258 M_G_DQ<46> @BASEBOARD_FAB2_LIB.BASEBOARD_FAB2(SCH_1):M_G_DQ(46)   I111 @BASEBOARD_FAB2_LIB.BASEBOARD_FAB2(SCH_1):PAGE77
   113 M_G_DQ<47> @BASEBOARD_FAB2_LIB.BASEBOARD_FAB2(SCH_1):M_G_DQ(47)   I111 @BASEBOARD_FAB2_LIB.BASEBOARD_FAB2(SCH_1):PAGE77
   251 M_G_DQ<44> @BASEBOARD_FAB2_LIB.BASEBOARD_FAB2(SCH_1):M_G_DQ(44)   I111 @BASEBOARD_FAB2_LIB.BASEBOARD_FAB2(SCH_1):PAGE77
   106 M_G_DQ<45> @BASEBOARD_FAB2_LIB.BASEBOARD_FAB2(SCH_1):M_G_DQ(45)   I111 @BASEBOARD_FAB2_LIB.BASEBOARD_FAB2(SCH_1):PAGE77
   260 M_G_DQ<42> @BASEBOARD_FAB2_LIB.BASEBOARD_FAB2(SCH_1):M_G_DQ(42)   I111 @BASEBOARD_FAB2_LIB.BASEBOARD_FAB2(SCH_1):PAGE77
   115 M_G_DQ<43> @BASEBOARD_FAB2_LIB.BASEBOARD_FAB2(SCH_1):M_G_DQ(43)   I111 @BASEBOARD_FAB2_LIB.BASEBOARD_FAB2(SCH_1):PAGE77
   253 M_G_DQ<40> @BASEBOARD_FAB2_LIB.BASEBOARD_FAB2(SCH_1):M_G_DQ(40)   I111 @BASEBOARD_FAB2_LIB.BASEBOARD_FAB2(SCH_1):PAGE77
   108 M_G_DQ<41> @BASEBOARD_FAB2_LIB.BASEBOARD_FAB2(SCH_1):M_G_DQ(41)   I111 @BASEBOARD_FAB2_LIB.BASEBOARD_FAB2(SCH_1):PAGE77
   247 M_G_DQ<38> @BASEBOARD_FAB2_LIB.BASEBOARD_FAB2(SCH_1):M_G_DQ(38)   I111 @BASEBOARD_FAB2_LIB.BASEBOARD_FAB2(SCH_1):PAGE77
   102 M_G_DQ<39> @BASEBOARD_FAB2_LIB.BASEBOARD_FAB2(SCH_1):M_G_DQ(39)   I111 @BASEBOARD_FAB2_LIB.BASEBOARD_FAB2(SCH_1):PAGE77
   240 M_G_DQ<36> @BASEBOARD_FAB2_LIB.BASEBOARD_FAB2(SCH_1):M_G_DQ(36)   I111 @BASEBOARD_FAB2_LIB.BASEBOARD_FAB2(SCH_1):PAGE77
    95 M_G_DQ<37> @BASEBOARD_FAB2_LIB.BASEBOARD_FAB2(SCH_1):M_G_DQ(37)   I111 @BASEBOARD_FAB2_LIB.BASEBOARD_FAB2(SCH_1):PAGE77
   249 M_G_DQ<34> @BASEBOARD_FAB2_LIB.BASEBOARD_FAB2(SCH_1):M_G_DQ(34)   I111 @BASEBOARD_FAB2_LIB.BASEBOARD_FAB2(SCH_1):PAGE77
   104 M_G_DQ<35> @BASEBOARD_FAB2_LIB.BASEBOARD_FAB2(SCH_1):M_G_DQ(35)   I111 @BASEBOARD_FAB2_LIB.BASEBOARD_FAB2(SCH_1):PAGE77
   242 M_G_DQ<32> @BASEBOARD_FAB2_LIB.BASEBOARD_FAB2(SCH_1):M_G_DQ(32)   I111 @BASEBOARD_FAB2_LIB.BASEBOARD_FAB2(SCH_1):PAGE77
    97 M_G_DQ<33> @BASEBOARD_FAB2_LIB.BASEBOARD_FAB2(SCH_1):M_G_DQ(33)   I111 @BASEBOARD_FAB2_LIB.BASEBOARD_FAB2(SCH_1):PAGE77
   188 M_G_DQ<30> @BASEBOARD_FAB2_LIB.BASEBOARD_FAB2(SCH_1):M_G_DQ(30)   I111 @BASEBOARD_FAB2_LIB.BASEBOARD_FAB2(SCH_1):PAGE77
    43 M_G_DQ<31> @BASEBOARD_FAB2_LIB.BASEBOARD_FAB2(SCH_1):M_G_DQ(31)   I111 @BASEBOARD_FAB2_LIB.BASEBOARD_FAB2(SCH_1):PAGE77
   181 M_G_DQ<28> @BASEBOARD_FAB2_LIB.BASEBOARD_FAB2(SCH_1):M_G_DQ(28)   I111 @BASEBOARD_FAB2_LIB.BASEBOARD_FAB2(SCH_1):PAGE77
    36 M_G_DQ<29> @BASEBOARD_FAB2_LIB.BASEBOARD_FAB2(SCH_1):M_G_DQ(29)   I111 @BASEBOARD_FAB2_LIB.BASEBOARD_FAB2(SCH_1):PAGE77
   190 M_G_DQ<26> @BASEBOARD_FAB2_LIB.BASEBOARD_FAB2(SCH_1):M_G_DQ(26)   I111 @BASEBOARD_FAB2_LIB.BASEBOARD_FAB2(SCH_1):PAGE77
    45 M_G_DQ<27> @BASEBOARD_FAB2_LIB.BASEBOARD_FAB2(SCH_1):M_G_DQ(27)   I111 @BASEBOARD_FAB2_LIB.BASEBOARD_FAB2(SCH_1):PAGE77
   183 M_G_DQ<24> @BASEBOARD_FAB2_LIB.BASEBOARD_FAB2(SCH_1):M_G_DQ(24)   I111 @BASEBOARD_FAB2_LIB.BASEBOARD_FAB2(SCH_1):PAGE77
    38 M_G_DQ<25> @BASEBOARD_FAB2_LIB.BASEBOARD_FAB2(SCH_1):M_G_DQ(25)   I111 @BASEBOARD_FAB2_LIB.BASEBOARD_FAB2(SCH_1):PAGE77
   177 M_G_DQ<22> @BASEBOARD_FAB2_LIB.BASEBOARD_FAB2(SCH_1):M_G_DQ(22)   I111 @BASEBOARD_FAB2_LIB.BASEBOARD_FAB2(SCH_1):PAGE77
    32 M_G_DQ<23> @BASEBOARD_FAB2_LIB.BASEBOARD_FAB2(SCH_1):M_G_DQ(23)   I111 @BASEBOARD_FAB2_LIB.BASEBOARD_FAB2(SCH_1):PAGE77
   170 M_G_DQ<20> @BASEBOARD_FAB2_LIB.BASEBOARD_FAB2(SCH_1):M_G_DQ(20)   I111 @BASEBOARD_FAB2_LIB.BASEBOARD_FAB2(SCH_1):PAGE77
    25 M_G_DQ<21> @BASEBOARD_FAB2_LIB.BASEBOARD_FAB2(SCH_1):M_G_DQ(21)   I111 @BASEBOARD_FAB2_LIB.BASEBOARD_FAB2(SCH_1):PAGE77
   179 M_G_DQ<18> @BASEBOARD_FAB2_LIB.BASEBOARD_FAB2(SCH_1):M_G_DQ(18)   I111 @BASEBOARD_FAB2_LIB.BASEBOARD_FAB2(SCH_1):PAGE77
    34 M_G_DQ<19> @BASEBOARD_FAB2_LIB.BASEBOARD_FAB2(SCH_1):M_G_DQ(19)   I111 @BASEBOARD_FAB2_LIB.BASEBOARD_FAB2(SCH_1):PAGE77
   172 M_G_DQ<16> @BASEBOARD_FAB2_LIB.BASEBOARD_FAB2(SCH_1):M_G_DQ(16)   I111 @BASEBOARD_FAB2_LIB.BASEBOARD_FAB2(SCH_1):PAGE77
    27 M_G_DQ<17> @BASEBOARD_FAB2_LIB.BASEBOARD_FAB2(SCH_1):M_G_DQ(17)   I111 @BASEBOARD_FAB2_LIB.BASEBOARD_FAB2(SCH_1):PAGE77
   166 M_G_DQ<14> @BASEBOARD_FAB2_LIB.BASEBOARD_FAB2(SCH_1):M_G_DQ(14)   I111 @BASEBOARD_FAB2_LIB.BASEBOARD_FAB2(SCH_1):PAGE77
    21 M_G_DQ<15> @BASEBOARD_FAB2_LIB.BASEBOARD_FAB2(SCH_1):M_G_DQ(15)   I111 @BASEBOARD_FAB2_LIB.BASEBOARD_FAB2(SCH_1):PAGE77
   159 M_G_DQ<12> @BASEBOARD_FAB2_LIB.BASEBOARD_FAB2(SCH_1):M_G_DQ(12)   I111 @BASEBOARD_FAB2_LIB.BASEBOARD_FAB2(SCH_1):PAGE77
    14 M_G_DQ<13> @BASEBOARD_FAB2_LIB.BASEBOARD_FAB2(SCH_1):M_G_DQ(13)   I111 @BASEBOARD_FAB2_LIB.BASEBOARD_FAB2(SCH_1):PAGE77
   168 M_G_DQ<10> @BASEBOARD_FAB2_LIB.BASEBOARD_FAB2(SCH_1):M_G_DQ(10)   I111 @BASEBOARD_FAB2_LIB.BASEBOARD_FAB2(SCH_1):PAGE77
    23 M_G_DQ<11> @BASEBOARD_FAB2_LIB.BASEBOARD_FAB2(SCH_1):M_G_DQ(11)   I111 @BASEBOARD_FAB2_LIB.BASEBOARD_FAB2(SCH_1):PAGE77
   161 M_G_DQ<8> @BASEBOARD_FAB2_LIB.BASEBOARD_FAB2(SCH_1):M_G_DQ(8)   I111 @BASEBOARD_FAB2_LIB.BASEBOARD_FAB2(SCH_1):PAGE77
    16 M_G_DQ<9> @BASEBOARD_FAB2_LIB.BASEBOARD_FAB2(SCH_1):M_G_DQ(9)   I111 @BASEBOARD_FAB2_LIB.BASEBOARD_FAB2(SCH_1):PAGE77
   155 M_G_DQ<6> @BASEBOARD_FAB2_LIB.BASEBOARD_FAB2(SCH_1):M_G_DQ(6)   I111 @BASEBOARD_FAB2_LIB.BASEBOARD_FAB2(SCH_1):PAGE77
    10 M_G_DQ<7> @BASEBOARD_FAB2_LIB.BASEBOARD_FAB2(SCH_1):M_G_DQ(7)   I111 @BASEBOARD_FAB2_LIB.BASEBOARD_FAB2(SCH_1):PAGE77
   148 M_G_DQ<4> @BASEBOARD_FAB2_LIB.BASEBOARD_FAB2(SCH_1):M_G_DQ(4)   I111 @BASEBOARD_FAB2_LIB.BASEBOARD_FAB2(SCH_1):PAGE77
     3 M_G_DQ<5> @BASEBOARD_FAB2_LIB.BASEBOARD_FAB2(SCH_1):M_G_DQ(5)   I111 @BASEBOARD_FAB2_LIB.BASEBOARD_FAB2(SCH_1):PAGE77
   157 M_G_DQ<2> @BASEBOARD_FAB2_LIB.BASEBOARD_FAB2(SCH_1):M_G_DQ(2)   I111 @BASEBOARD_FAB2_LIB.BASEBOARD_FAB2(SCH_1):PAGE77
    12 M_G_DQ<3> @BASEBOARD_FAB2_LIB.BASEBOARD_FAB2(SCH_1):M_G_DQ(3)   I111 @BASEBOARD_FAB2_LIB.BASEBOARD_FAB2(SCH_1):PAGE77
   150 M_G_DQ<0> @BASEBOARD_FAB2_LIB.BASEBOARD_FAB2(SCH_1):M_G_DQ(0)   I111 @BASEBOARD_FAB2_LIB.BASEBOARD_FAB2(SCH_1):PAGE77
     5 M_G_DQ<1> @BASEBOARD_FAB2_LIB.BASEBOARD_FAB2(SCH_1):M_G_DQ(1)   I111 @BASEBOARD_FAB2_LIB.BASEBOARD_FAB2(SCH_1):PAGE77
    78 FM_DIMM_EVENT_COD_N @BASEBOARD_FAB2_LIB.BASEBOARD_FAB2(SCH_1):FM_DIMM_EVENT_COD_N   I111 @BASEBOARD_FAB2_LIB.BASEBOARD_FAB2(SCH_1):PAGE77
    91 M_G_ODT<1> @BASEBOARD_FAB2_LIB.BASEBOARD_FAB2(SCH_1):M_G_ODT(1)   I111 @BASEBOARD_FAB2_LIB.BASEBOARD_FAB2(SCH_1):PAGE77
    87 M_G_ODT<0> @BASEBOARD_FAB2_LIB.BASEBOARD_FAB2(SCH_1):M_G_ODT(0)   I111 @BASEBOARD_FAB2_LIB.BASEBOARD_FAB2(SCH_1):PAGE77
   222 M_G_PAR @BASEBOARD_FAB2_LIB.BASEBOARD_FAB2(SCH_1):M_G_PAR   I111 @BASEBOARD_FAB2_LIB.BASEBOARD_FAB2(SCH_1):PAGE77
    58 M_GHJ_RST_N @BASEBOARD_FAB2_LIB.BASEBOARD_FAB2(SCH_1):M_GHJ_RST_N   I111 @BASEBOARD_FAB2_LIB.BASEBOARD_FAB2(SCH_1):PAGE77
   144 TP_CH_G_DIMM_G0_RFU_2 @BASEBOARD_FAB2_LIB.BASEBOARD_FAB2(SCH_1):TP_CH_G_DIMM_G0_RFU_2   I111 @BASEBOARD_FAB2_LIB.BASEBOARD_FAB2(SCH_1):PAGE77
   227 TP_CH_G_DIMM_G0_RFU_1 @BASEBOARD_FAB2_LIB.BASEBOARD_FAB2(SCH_1):TP_CH_G_DIMM_G0_RFU_1   I111 @BASEBOARD_FAB2_LIB.BASEBOARD_FAB2(SCH_1):PAGE77
   205 TP_CH_G_DIMM_G0_RFU_0 @BASEBOARD_FAB2_LIB.BASEBOARD_FAB2(SCH_1):TP_CH_G_DIMM_G0_RFU_0   I111 @BASEBOARD_FAB2_LIB.BASEBOARD_FAB2(SCH_1):PAGE77
    84 M_G_CS_N<0> @BASEBOARD_FAB2_LIB.BASEBOARD_FAB2(SCH_1):M_G_CS_N(0)   I111 @BASEBOARD_FAB2_LIB.BASEBOARD_FAB2(SCH_1):PAGE77
    89 M_G_CS_N<1> @BASEBOARD_FAB2_LIB.BASEBOARD_FAB2(SCH_1):M_G_CS_N(1)   I111 @BASEBOARD_FAB2_LIB.BASEBOARD_FAB2(SCH_1):PAGE77
    93 M_G_CS_N<2> @BASEBOARD_FAB2_LIB.BASEBOARD_FAB2(SCH_1):M_G_CS_N(2)   I111 @BASEBOARD_FAB2_LIB.BASEBOARD_FAB2(SCH_1):PAGE77
   237 M_G_CS_N<3> @BASEBOARD_FAB2_LIB.BASEBOARD_FAB2(SCH_1):M_G_CS_N(3)   I111 @BASEBOARD_FAB2_LIB.BASEBOARD_FAB2(SCH_1):PAGE77
   238    GND @BASEBOARD_FAB2_LIB.BASEBOARD_FAB2(SCH_1):GND   I111 @BASEBOARD_FAB2_LIB.BASEBOARD_FAB2(SCH_1):PAGE77
   140    GND @BASEBOARD_FAB2_LIB.BASEBOARD_FAB2(SCH_1):GND   I111 @BASEBOARD_FAB2_LIB.BASEBOARD_FAB2(SCH_1):PAGE77
   139    GND @BASEBOARD_FAB2_LIB.BASEBOARD_FAB2(SCH_1):GND   I111 @BASEBOARD_FAB2_LIB.BASEBOARD_FAB2(SCH_1):PAGE77
   230 FM_ADR_COMPLETE_GHJ_N @BASEBOARD_FAB2_LIB.BASEBOARD_FAB2(SCH_1):FM_ADR_COMPLETE_GHJ_N   I111 @BASEBOARD_FAB2_LIB.BASEBOARD_FAB2(SCH_1):PAGE77
   141 SMB_DDR_GHJ_VPP_SCL @BASEBOARD_FAB2_LIB.BASEBOARD_FAB2(SCH_1):SMB_DDR_GHJ_VPP_SCL   I111 @BASEBOARD_FAB2_LIB.BASEBOARD_FAB2(SCH_1):PAGE77
   285 SMB_DDR_GHJ_VPP_SDA @BASEBOARD_FAB2_LIB.BASEBOARD_FAB2(SCH_1):SMB_DDR_GHJ_VPP_SDA   I111 @BASEBOARD_FAB2_LIB.BASEBOARD_FAB2(SCH_1):PAGE77
   284 PVPP_GHJ @BASEBOARD_FAB2_LIB.BASEBOARD_FAB2(SCH_1):PVPP_GHJ   I111 @BASEBOARD_FAB2_LIB.BASEBOARD_FAB2(SCH_1):PAGE77
   146 M_G_VREF @BASEBOARD_FAB2_LIB.BASEBOARD_FAB2(SCH_1):M_G_VREF   I111 @BASEBOARD_FAB2_LIB.BASEBOARD_FAB2(SCH_1):PAGE77
   152 M_G_DQS_DN<0> @BASEBOARD_FAB2_LIB.BASEBOARD_FAB2(SCH_1):M_G_DQS_DN(0)    I66 @BASEBOARD_FAB2_LIB.BASEBOARD_FAB2(SCH_1):PAGE77
   153 M_G_DQS_DP<0> @BASEBOARD_FAB2_LIB.BASEBOARD_FAB2(SCH_1):M_G_DQS_DP(0)    I66 @BASEBOARD_FAB2_LIB.BASEBOARD_FAB2(SCH_1):PAGE77
    19 M_G_DQS_DN<10> @BASEBOARD_FAB2_LIB.BASEBOARD_FAB2(SCH_1):M_G_DQS_DN(10)    I66 @BASEBOARD_FAB2_LIB.BASEBOARD_FAB2(SCH_1):PAGE77
    18 M_G_DQS_DP<10> @BASEBOARD_FAB2_LIB.BASEBOARD_FAB2(SCH_1):M_G_DQS_DP(10)    I66 @BASEBOARD_FAB2_LIB.BASEBOARD_FAB2(SCH_1):PAGE77
    30 M_G_DQS_DN<11> @BASEBOARD_FAB2_LIB.BASEBOARD_FAB2(SCH_1):M_G_DQS_DN(11)    I66 @BASEBOARD_FAB2_LIB.BASEBOARD_FAB2(SCH_1):PAGE77
    29 M_G_DQS_DP<11> @BASEBOARD_FAB2_LIB.BASEBOARD_FAB2(SCH_1):M_G_DQS_DP(11)    I66 @BASEBOARD_FAB2_LIB.BASEBOARD_FAB2(SCH_1):PAGE77
    41 M_G_DQS_DN<12> @BASEBOARD_FAB2_LIB.BASEBOARD_FAB2(SCH_1):M_G_DQS_DN(12)    I66 @BASEBOARD_FAB2_LIB.BASEBOARD_FAB2(SCH_1):PAGE77
    40 M_G_DQS_DP<12> @BASEBOARD_FAB2_LIB.BASEBOARD_FAB2(SCH_1):M_G_DQS_DP(12)    I66 @BASEBOARD_FAB2_LIB.BASEBOARD_FAB2(SCH_1):PAGE77
   100 M_G_DQS_DN<13> @BASEBOARD_FAB2_LIB.BASEBOARD_FAB2(SCH_1):M_G_DQS_DN(13)    I66 @BASEBOARD_FAB2_LIB.BASEBOARD_FAB2(SCH_1):PAGE77
    99 M_G_DQS_DP<13> @BASEBOARD_FAB2_LIB.BASEBOARD_FAB2(SCH_1):M_G_DQS_DP(13)    I66 @BASEBOARD_FAB2_LIB.BASEBOARD_FAB2(SCH_1):PAGE77
   111 M_G_DQS_DN<14> @BASEBOARD_FAB2_LIB.BASEBOARD_FAB2(SCH_1):M_G_DQS_DN(14)    I66 @BASEBOARD_FAB2_LIB.BASEBOARD_FAB2(SCH_1):PAGE77
   110 M_G_DQS_DP<14> @BASEBOARD_FAB2_LIB.BASEBOARD_FAB2(SCH_1):M_G_DQS_DP(14)    I66 @BASEBOARD_FAB2_LIB.BASEBOARD_FAB2(SCH_1):PAGE77
   122 M_G_DQS_DN<15> @BASEBOARD_FAB2_LIB.BASEBOARD_FAB2(SCH_1):M_G_DQS_DN(15)    I66 @BASEBOARD_FAB2_LIB.BASEBOARD_FAB2(SCH_1):PAGE77
   121 M_G_DQS_DP<15> @BASEBOARD_FAB2_LIB.BASEBOARD_FAB2(SCH_1):M_G_DQS_DP(15)    I66 @BASEBOARD_FAB2_LIB.BASEBOARD_FAB2(SCH_1):PAGE77
   133 M_G_DQS_DN<16> @BASEBOARD_FAB2_LIB.BASEBOARD_FAB2(SCH_1):M_G_DQS_DN(16)    I66 @BASEBOARD_FAB2_LIB.BASEBOARD_FAB2(SCH_1):PAGE77
   132 M_G_DQS_DP<16> @BASEBOARD_FAB2_LIB.BASEBOARD_FAB2(SCH_1):M_G_DQS_DP(16)    I66 @BASEBOARD_FAB2_LIB.BASEBOARD_FAB2(SCH_1):PAGE77
    52 M_G_DQS_DN<17> @BASEBOARD_FAB2_LIB.BASEBOARD_FAB2(SCH_1):M_G_DQS_DN(17)    I66 @BASEBOARD_FAB2_LIB.BASEBOARD_FAB2(SCH_1):PAGE77
    51 M_G_DQS_DP<17> @BASEBOARD_FAB2_LIB.BASEBOARD_FAB2(SCH_1):M_G_DQS_DP(17)    I66 @BASEBOARD_FAB2_LIB.BASEBOARD_FAB2(SCH_1):PAGE77
   163 M_G_DQS_DN<1> @BASEBOARD_FAB2_LIB.BASEBOARD_FAB2(SCH_1):M_G_DQS_DN(1)    I66 @BASEBOARD_FAB2_LIB.BASEBOARD_FAB2(SCH_1):PAGE77
   164 M_G_DQS_DP<1> @BASEBOARD_FAB2_LIB.BASEBOARD_FAB2(SCH_1):M_G_DQS_DP(1)    I66 @BASEBOARD_FAB2_LIB.BASEBOARD_FAB2(SCH_1):PAGE77
   174 M_G_DQS_DN<2> @BASEBOARD_FAB2_LIB.BASEBOARD_FAB2(SCH_1):M_G_DQS_DN(2)    I66 @BASEBOARD_FAB2_LIB.BASEBOARD_FAB2(SCH_1):PAGE77
   175 M_G_DQS_DP<2> @BASEBOARD_FAB2_LIB.BASEBOARD_FAB2(SCH_1):M_G_DQS_DP(2)    I66 @BASEBOARD_FAB2_LIB.BASEBOARD_FAB2(SCH_1):PAGE77
   185 M_G_DQS_DN<3> @BASEBOARD_FAB2_LIB.BASEBOARD_FAB2(SCH_1):M_G_DQS_DN(3)    I66 @BASEBOARD_FAB2_LIB.BASEBOARD_FAB2(SCH_1):PAGE77
   186 M_G_DQS_DP<3> @BASEBOARD_FAB2_LIB.BASEBOARD_FAB2(SCH_1):M_G_DQS_DP(3)    I66 @BASEBOARD_FAB2_LIB.BASEBOARD_FAB2(SCH_1):PAGE77
   244 M_G_DQS_DN<4> @BASEBOARD_FAB2_LIB.BASEBOARD_FAB2(SCH_1):M_G_DQS_DN(4)    I66 @BASEBOARD_FAB2_LIB.BASEBOARD_FAB2(SCH_1):PAGE77
   245 M_G_DQS_DP<4> @BASEBOARD_FAB2_LIB.BASEBOARD_FAB2(SCH_1):M_G_DQS_DP(4)    I66 @BASEBOARD_FAB2_LIB.BASEBOARD_FAB2(SCH_1):PAGE77
   255 M_G_DQS_DN<5> @BASEBOARD_FAB2_LIB.BASEBOARD_FAB2(SCH_1):M_G_DQS_DN(5)    I66 @BASEBOARD_FAB2_LIB.BASEBOARD_FAB2(SCH_1):PAGE77
   256 M_G_DQS_DP<5> @BASEBOARD_FAB2_LIB.BASEBOARD_FAB2(SCH_1):M_G_DQS_DP(5)    I66 @BASEBOARD_FAB2_LIB.BASEBOARD_FAB2(SCH_1):PAGE77
   266 M_G_DQS_DN<6> @BASEBOARD_FAB2_LIB.BASEBOARD_FAB2(SCH_1):M_G_DQS_DN(6)    I66 @BASEBOARD_FAB2_LIB.BASEBOARD_FAB2(SCH_1):PAGE77
   267 M_G_DQS_DP<6> @BASEBOARD_FAB2_LIB.BASEBOARD_FAB2(SCH_1):M_G_DQS_DP(6)    I66 @BASEBOARD_FAB2_LIB.BASEBOARD_FAB2(SCH_1):PAGE77
   277 M_G_DQS_DN<7> @BASEBOARD_FAB2_LIB.BASEBOARD_FAB2(SCH_1):M_G_DQS_DN(7)    I66 @BASEBOARD_FAB2_LIB.BASEBOARD_FAB2(SCH_1):PAGE77
   278 M_G_DQS_DP<7> @BASEBOARD_FAB2_LIB.BASEBOARD_FAB2(SCH_1):M_G_DQS_DP(7)    I66 @BASEBOARD_FAB2_LIB.BASEBOARD_FAB2(SCH_1):PAGE77
   196 M_G_DQS_DN<8> @BASEBOARD_FAB2_LIB.BASEBOARD_FAB2(SCH_1):M_G_DQS_DN(8)    I66 @BASEBOARD_FAB2_LIB.BASEBOARD_FAB2(SCH_1):PAGE77
   197 M_G_DQS_DP<8> @BASEBOARD_FAB2_LIB.BASEBOARD_FAB2(SCH_1):M_G_DQS_DP(8)    I66 @BASEBOARD_FAB2_LIB.BASEBOARD_FAB2(SCH_1):PAGE77
     8 M_G_DQS_DN<9> @BASEBOARD_FAB2_LIB.BASEBOARD_FAB2(SCH_1):M_G_DQS_DN(9)    I66 @BASEBOARD_FAB2_LIB.BASEBOARD_FAB2(SCH_1):PAGE77
     7 M_G_DQS_DP<9> @BASEBOARD_FAB2_LIB.BASEBOARD_FAB2(SCH_1):M_G_DQS_DP(9)    I66 @BASEBOARD_FAB2_LIB.BASEBOARD_FAB2(SCH_1):PAGE77
     2    GND @BASEBOARD_FAB2_LIB.BASEBOARD_FAB2(SCH_1):GND    I43 @BASEBOARD_FAB2_LIB.BASEBOARD_FAB2(SCH_1):PAGE77
     4    GND @BASEBOARD_FAB2_LIB.BASEBOARD_FAB2(SCH_1):GND    I43 @BASEBOARD_FAB2_LIB.BASEBOARD_FAB2(SCH_1):PAGE77
     6    GND @BASEBOARD_FAB2_LIB.BASEBOARD_FAB2(SCH_1):GND    I43 @BASEBOARD_FAB2_LIB.BASEBOARD_FAB2(SCH_1):PAGE77
     9    GND @BASEBOARD_FAB2_LIB.BASEBOARD_FAB2(SCH_1):GND    I43 @BASEBOARD_FAB2_LIB.BASEBOARD_FAB2(SCH_1):PAGE77
    11    GND @BASEBOARD_FAB2_LIB.BASEBOARD_FAB2(SCH_1):GND    I43 @BASEBOARD_FAB2_LIB.BASEBOARD_FAB2(SCH_1):PAGE77
    13    GND @BASEBOARD_FAB2_LIB.BASEBOARD_FAB2(SCH_1):GND    I43 @BASEBOARD_FAB2_LIB.BASEBOARD_FAB2(SCH_1):PAGE77
    15    GND @BASEBOARD_FAB2_LIB.BASEBOARD_FAB2(SCH_1):GND    I43 @BASEBOARD_FAB2_LIB.BASEBOARD_FAB2(SCH_1):PAGE77
    17    GND @BASEBOARD_FAB2_LIB.BASEBOARD_FAB2(SCH_1):GND    I43 @BASEBOARD_FAB2_LIB.BASEBOARD_FAB2(SCH_1):PAGE77
    20    GND @BASEBOARD_FAB2_LIB.BASEBOARD_FAB2(SCH_1):GND    I43 @BASEBOARD_FAB2_LIB.BASEBOARD_FAB2(SCH_1):PAGE77
    22    GND @BASEBOARD_FAB2_LIB.BASEBOARD_FAB2(SCH_1):GND    I43 @BASEBOARD_FAB2_LIB.BASEBOARD_FAB2(SCH_1):PAGE77
    24    GND @BASEBOARD_FAB2_LIB.BASEBOARD_FAB2(SCH_1):GND    I43 @BASEBOARD_FAB2_LIB.BASEBOARD_FAB2(SCH_1):PAGE77
    26    GND @BASEBOARD_FAB2_LIB.BASEBOARD_FAB2(SCH_1):GND    I43 @BASEBOARD_FAB2_LIB.BASEBOARD_FAB2(SCH_1):PAGE77
    28    GND @BASEBOARD_FAB2_LIB.BASEBOARD_FAB2(SCH_1):GND    I43 @BASEBOARD_FAB2_LIB.BASEBOARD_FAB2(SCH_1):PAGE77
    31    GND @BASEBOARD_FAB2_LIB.BASEBOARD_FAB2(SCH_1):GND    I43 @BASEBOARD_FAB2_LIB.BASEBOARD_FAB2(SCH_1):PAGE77
    33    GND @BASEBOARD_FAB2_LIB.BASEBOARD_FAB2(SCH_1):GND    I43 @BASEBOARD_FAB2_LIB.BASEBOARD_FAB2(SCH_1):PAGE77
    35    GND @BASEBOARD_FAB2_LIB.BASEBOARD_FAB2(SCH_1):GND    I43 @BASEBOARD_FAB2_LIB.BASEBOARD_FAB2(SCH_1):PAGE77
    37    GND @BASEBOARD_FAB2_LIB.BASEBOARD_FAB2(SCH_1):GND    I43 @BASEBOARD_FAB2_LIB.BASEBOARD_FAB2(SCH_1):PAGE77
    39    GND @BASEBOARD_FAB2_LIB.BASEBOARD_FAB2(SCH_1):GND    I43 @BASEBOARD_FAB2_LIB.BASEBOARD_FAB2(SCH_1):PAGE77
    42    GND @BASEBOARD_FAB2_LIB.BASEBOARD_FAB2(SCH_1):GND    I43 @BASEBOARD_FAB2_LIB.BASEBOARD_FAB2(SCH_1):PAGE77
    44    GND @BASEBOARD_FAB2_LIB.BASEBOARD_FAB2(SCH_1):GND    I43 @BASEBOARD_FAB2_LIB.BASEBOARD_FAB2(SCH_1):PAGE77
    46    GND @BASEBOARD_FAB2_LIB.BASEBOARD_FAB2(SCH_1):GND    I43 @BASEBOARD_FAB2_LIB.BASEBOARD_FAB2(SCH_1):PAGE77
    48    GND @BASEBOARD_FAB2_LIB.BASEBOARD_FAB2(SCH_1):GND    I43 @BASEBOARD_FAB2_LIB.BASEBOARD_FAB2(SCH_1):PAGE77
    50    GND @BASEBOARD_FAB2_LIB.BASEBOARD_FAB2(SCH_1):GND    I43 @BASEBOARD_FAB2_LIB.BASEBOARD_FAB2(SCH_1):PAGE77
    53    GND @BASEBOARD_FAB2_LIB.BASEBOARD_FAB2(SCH_1):GND    I43 @BASEBOARD_FAB2_LIB.BASEBOARD_FAB2(SCH_1):PAGE77
    55    GND @BASEBOARD_FAB2_LIB.BASEBOARD_FAB2(SCH_1):GND    I43 @BASEBOARD_FAB2_LIB.BASEBOARD_FAB2(SCH_1):PAGE77
    57    GND @BASEBOARD_FAB2_LIB.BASEBOARD_FAB2(SCH_1):GND    I43 @BASEBOARD_FAB2_LIB.BASEBOARD_FAB2(SCH_1):PAGE77
    94    GND @BASEBOARD_FAB2_LIB.BASEBOARD_FAB2(SCH_1):GND    I43 @BASEBOARD_FAB2_LIB.BASEBOARD_FAB2(SCH_1):PAGE77
    96    GND @BASEBOARD_FAB2_LIB.BASEBOARD_FAB2(SCH_1):GND    I43 @BASEBOARD_FAB2_LIB.BASEBOARD_FAB2(SCH_1):PAGE77
    98    GND @BASEBOARD_FAB2_LIB.BASEBOARD_FAB2(SCH_1):GND    I43 @BASEBOARD_FAB2_LIB.BASEBOARD_FAB2(SCH_1):PAGE77
   101    GND @BASEBOARD_FAB2_LIB.BASEBOARD_FAB2(SCH_1):GND    I43 @BASEBOARD_FAB2_LIB.BASEBOARD_FAB2(SCH_1):PAGE77
   103    GND @BASEBOARD_FAB2_LIB.BASEBOARD_FAB2(SCH_1):GND    I43 @BASEBOARD_FAB2_LIB.BASEBOARD_FAB2(SCH_1):PAGE77
   105    GND @BASEBOARD_FAB2_LIB.BASEBOARD_FAB2(SCH_1):GND    I43 @BASEBOARD_FAB2_LIB.BASEBOARD_FAB2(SCH_1):PAGE77
   107    GND @BASEBOARD_FAB2_LIB.BASEBOARD_FAB2(SCH_1):GND    I43 @BASEBOARD_FAB2_LIB.BASEBOARD_FAB2(SCH_1):PAGE77
   109    GND @BASEBOARD_FAB2_LIB.BASEBOARD_FAB2(SCH_1):GND    I43 @BASEBOARD_FAB2_LIB.BASEBOARD_FAB2(SCH_1):PAGE77
   112    GND @BASEBOARD_FAB2_LIB.BASEBOARD_FAB2(SCH_1):GND    I43 @BASEBOARD_FAB2_LIB.BASEBOARD_FAB2(SCH_1):PAGE77
   114    GND @BASEBOARD_FAB2_LIB.BASEBOARD_FAB2(SCH_1):GND    I43 @BASEBOARD_FAB2_LIB.BASEBOARD_FAB2(SCH_1):PAGE77
   116    GND @BASEBOARD_FAB2_LIB.BASEBOARD_FAB2(SCH_1):GND    I43 @BASEBOARD_FAB2_LIB.BASEBOARD_FAB2(SCH_1):PAGE77
   118    GND @BASEBOARD_FAB2_LIB.BASEBOARD_FAB2(SCH_1):GND    I43 @BASEBOARD_FAB2_LIB.BASEBOARD_FAB2(SCH_1):PAGE77
   120    GND @BASEBOARD_FAB2_LIB.BASEBOARD_FAB2(SCH_1):GND    I43 @BASEBOARD_FAB2_LIB.BASEBOARD_FAB2(SCH_1):PAGE77
   123    GND @BASEBOARD_FAB2_LIB.BASEBOARD_FAB2(SCH_1):GND    I43 @BASEBOARD_FAB2_LIB.BASEBOARD_FAB2(SCH_1):PAGE77
   125    GND @BASEBOARD_FAB2_LIB.BASEBOARD_FAB2(SCH_1):GND    I43 @BASEBOARD_FAB2_LIB.BASEBOARD_FAB2(SCH_1):PAGE77
   127    GND @BASEBOARD_FAB2_LIB.BASEBOARD_FAB2(SCH_1):GND    I43 @BASEBOARD_FAB2_LIB.BASEBOARD_FAB2(SCH_1):PAGE77
   129    GND @BASEBOARD_FAB2_LIB.BASEBOARD_FAB2(SCH_1):GND    I43 @BASEBOARD_FAB2_LIB.BASEBOARD_FAB2(SCH_1):PAGE77
   131    GND @BASEBOARD_FAB2_LIB.BASEBOARD_FAB2(SCH_1):GND    I43 @BASEBOARD_FAB2_LIB.BASEBOARD_FAB2(SCH_1):PAGE77
   134    GND @BASEBOARD_FAB2_LIB.BASEBOARD_FAB2(SCH_1):GND    I43 @BASEBOARD_FAB2_LIB.BASEBOARD_FAB2(SCH_1):PAGE77
   136    GND @BASEBOARD_FAB2_LIB.BASEBOARD_FAB2(SCH_1):GND    I43 @BASEBOARD_FAB2_LIB.BASEBOARD_FAB2(SCH_1):PAGE77
   138    GND @BASEBOARD_FAB2_LIB.BASEBOARD_FAB2(SCH_1):GND    I43 @BASEBOARD_FAB2_LIB.BASEBOARD_FAB2(SCH_1):PAGE77
   147    GND @BASEBOARD_FAB2_LIB.BASEBOARD_FAB2(SCH_1):GND    I43 @BASEBOARD_FAB2_LIB.BASEBOARD_FAB2(SCH_1):PAGE77
   149    GND @BASEBOARD_FAB2_LIB.BASEBOARD_FAB2(SCH_1):GND    I43 @BASEBOARD_FAB2_LIB.BASEBOARD_FAB2(SCH_1):PAGE77
   151    GND @BASEBOARD_FAB2_LIB.BASEBOARD_FAB2(SCH_1):GND    I43 @BASEBOARD_FAB2_LIB.BASEBOARD_FAB2(SCH_1):PAGE77
   154    GND @BASEBOARD_FAB2_LIB.BASEBOARD_FAB2(SCH_1):GND    I43 @BASEBOARD_FAB2_LIB.BASEBOARD_FAB2(SCH_1):PAGE77
   156    GND @BASEBOARD_FAB2_LIB.BASEBOARD_FAB2(SCH_1):GND    I43 @BASEBOARD_FAB2_LIB.BASEBOARD_FAB2(SCH_1):PAGE77
   158    GND @BASEBOARD_FAB2_LIB.BASEBOARD_FAB2(SCH_1):GND    I43 @BASEBOARD_FAB2_LIB.BASEBOARD_FAB2(SCH_1):PAGE77
   160    GND @BASEBOARD_FAB2_LIB.BASEBOARD_FAB2(SCH_1):GND    I43 @BASEBOARD_FAB2_LIB.BASEBOARD_FAB2(SCH_1):PAGE77
   162    GND @BASEBOARD_FAB2_LIB.BASEBOARD_FAB2(SCH_1):GND    I43 @BASEBOARD_FAB2_LIB.BASEBOARD_FAB2(SCH_1):PAGE77
   165    GND @BASEBOARD_FAB2_LIB.BASEBOARD_FAB2(SCH_1):GND    I43 @BASEBOARD_FAB2_LIB.BASEBOARD_FAB2(SCH_1):PAGE77
   167    GND @BASEBOARD_FAB2_LIB.BASEBOARD_FAB2(SCH_1):GND    I43 @BASEBOARD_FAB2_LIB.BASEBOARD_FAB2(SCH_1):PAGE77
   169    GND @BASEBOARD_FAB2_LIB.BASEBOARD_FAB2(SCH_1):GND    I43 @BASEBOARD_FAB2_LIB.BASEBOARD_FAB2(SCH_1):PAGE77
   171    GND @BASEBOARD_FAB2_LIB.BASEBOARD_FAB2(SCH_1):GND    I43 @BASEBOARD_FAB2_LIB.BASEBOARD_FAB2(SCH_1):PAGE77
   173    GND @BASEBOARD_FAB2_LIB.BASEBOARD_FAB2(SCH_1):GND    I43 @BASEBOARD_FAB2_LIB.BASEBOARD_FAB2(SCH_1):PAGE77
   176    GND @BASEBOARD_FAB2_LIB.BASEBOARD_FAB2(SCH_1):GND    I43 @BASEBOARD_FAB2_LIB.BASEBOARD_FAB2(SCH_1):PAGE77
   178    GND @BASEBOARD_FAB2_LIB.BASEBOARD_FAB2(SCH_1):GND    I43 @BASEBOARD_FAB2_LIB.BASEBOARD_FAB2(SCH_1):PAGE77
   180    GND @BASEBOARD_FAB2_LIB.BASEBOARD_FAB2(SCH_1):GND    I43 @BASEBOARD_FAB2_LIB.BASEBOARD_FAB2(SCH_1):PAGE77
   182    GND @BASEBOARD_FAB2_LIB.BASEBOARD_FAB2(SCH_1):GND    I43 @BASEBOARD_FAB2_LIB.BASEBOARD_FAB2(SCH_1):PAGE77
   184    GND @BASEBOARD_FAB2_LIB.BASEBOARD_FAB2(SCH_1):GND    I43 @BASEBOARD_FAB2_LIB.BASEBOARD_FAB2(SCH_1):PAGE77
   187    GND @BASEBOARD_FAB2_LIB.BASEBOARD_FAB2(SCH_1):GND    I43 @BASEBOARD_FAB2_LIB.BASEBOARD_FAB2(SCH_1):PAGE77
   189    GND @BASEBOARD_FAB2_LIB.BASEBOARD_FAB2(SCH_1):GND    I43 @BASEBOARD_FAB2_LIB.BASEBOARD_FAB2(SCH_1):PAGE77
   191    GND @BASEBOARD_FAB2_LIB.BASEBOARD_FAB2(SCH_1):GND    I43 @BASEBOARD_FAB2_LIB.BASEBOARD_FAB2(SCH_1):PAGE77
   193    GND @BASEBOARD_FAB2_LIB.BASEBOARD_FAB2(SCH_1):GND    I43 @BASEBOARD_FAB2_LIB.BASEBOARD_FAB2(SCH_1):PAGE77
   195    GND @BASEBOARD_FAB2_LIB.BASEBOARD_FAB2(SCH_1):GND    I43 @BASEBOARD_FAB2_LIB.BASEBOARD_FAB2(SCH_1):PAGE77
   198    GND @BASEBOARD_FAB2_LIB.BASEBOARD_FAB2(SCH_1):GND    I43 @BASEBOARD_FAB2_LIB.BASEBOARD_FAB2(SCH_1):PAGE77
   200    GND @BASEBOARD_FAB2_LIB.BASEBOARD_FAB2(SCH_1):GND    I43 @BASEBOARD_FAB2_LIB.BASEBOARD_FAB2(SCH_1):PAGE77
   202    GND @BASEBOARD_FAB2_LIB.BASEBOARD_FAB2(SCH_1):GND    I43 @BASEBOARD_FAB2_LIB.BASEBOARD_FAB2(SCH_1):PAGE77
   239    GND @BASEBOARD_FAB2_LIB.BASEBOARD_FAB2(SCH_1):GND    I43 @BASEBOARD_FAB2_LIB.BASEBOARD_FAB2(SCH_1):PAGE77
   241    GND @BASEBOARD_FAB2_LIB.BASEBOARD_FAB2(SCH_1):GND    I43 @BASEBOARD_FAB2_LIB.BASEBOARD_FAB2(SCH_1):PAGE77
   243    GND @BASEBOARD_FAB2_LIB.BASEBOARD_FAB2(SCH_1):GND    I43 @BASEBOARD_FAB2_LIB.BASEBOARD_FAB2(SCH_1):PAGE77
   246    GND @BASEBOARD_FAB2_LIB.BASEBOARD_FAB2(SCH_1):GND    I43 @BASEBOARD_FAB2_LIB.BASEBOARD_FAB2(SCH_1):PAGE77
   248    GND @BASEBOARD_FAB2_LIB.BASEBOARD_FAB2(SCH_1):GND    I43 @BASEBOARD_FAB2_LIB.BASEBOARD_FAB2(SCH_1):PAGE77
   250    GND @BASEBOARD_FAB2_LIB.BASEBOARD_FAB2(SCH_1):GND    I43 @BASEBOARD_FAB2_LIB.BASEBOARD_FAB2(SCH_1):PAGE77
   252    GND @BASEBOARD_FAB2_LIB.BASEBOARD_FAB2(SCH_1):GND    I43 @BASEBOARD_FAB2_LIB.BASEBOARD_FAB2(SCH_1):PAGE77
   254    GND @BASEBOARD_FAB2_LIB.BASEBOARD_FAB2(SCH_1):GND    I43 @BASEBOARD_FAB2_LIB.BASEBOARD_FAB2(SCH_1):PAGE77
   257    GND @BASEBOARD_FAB2_LIB.BASEBOARD_FAB2(SCH_1):GND    I43 @BASEBOARD_FAB2_LIB.BASEBOARD_FAB2(SCH_1):PAGE77
   259    GND @BASEBOARD_FAB2_LIB.BASEBOARD_FAB2(SCH_1):GND    I43 @BASEBOARD_FAB2_LIB.BASEBOARD_FAB2(SCH_1):PAGE77
   261    GND @BASEBOARD_FAB2_LIB.BASEBOARD_FAB2(SCH_1):GND    I43 @BASEBOARD_FAB2_LIB.BASEBOARD_FAB2(SCH_1):PAGE77
   263    GND @BASEBOARD_FAB2_LIB.BASEBOARD_FAB2(SCH_1):GND    I43 @BASEBOARD_FAB2_LIB.BASEBOARD_FAB2(SCH_1):PAGE77
   265    GND @BASEBOARD_FAB2_LIB.BASEBOARD_FAB2(SCH_1):GND    I43 @BASEBOARD_FAB2_LIB.BASEBOARD_FAB2(SCH_1):PAGE77
   268    GND @BASEBOARD_FAB2_LIB.BASEBOARD_FAB2(SCH_1):GND    I43 @BASEBOARD_FAB2_LIB.BASEBOARD_FAB2(SCH_1):PAGE77
   270    GND @BASEBOARD_FAB2_LIB.BASEBOARD_FAB2(SCH_1):GND    I43 @BASEBOARD_FAB2_LIB.BASEBOARD_FAB2(SCH_1):PAGE77
   272    GND @BASEBOARD_FAB2_LIB.BASEBOARD_FAB2(SCH_1):GND    I43 @BASEBOARD_FAB2_LIB.BASEBOARD_FAB2(SCH_1):PAGE77
   274    GND @BASEBOARD_FAB2_LIB.BASEBOARD_FAB2(SCH_1):GND    I43 @BASEBOARD_FAB2_LIB.BASEBOARD_FAB2(SCH_1):PAGE77
   276    GND @BASEBOARD_FAB2_LIB.BASEBOARD_FAB2(SCH_1):GND    I43 @BASEBOARD_FAB2_LIB.BASEBOARD_FAB2(SCH_1):PAGE77
   279    GND @BASEBOARD_FAB2_LIB.BASEBOARD_FAB2(SCH_1):GND    I43 @BASEBOARD_FAB2_LIB.BASEBOARD_FAB2(SCH_1):PAGE77
   281    GND @BASEBOARD_FAB2_LIB.BASEBOARD_FAB2(SCH_1):GND    I43 @BASEBOARD_FAB2_LIB.BASEBOARD_FAB2(SCH_1):PAGE77
   283    GND @BASEBOARD_FAB2_LIB.BASEBOARD_FAB2(SCH_1):GND    I43 @BASEBOARD_FAB2_LIB.BASEBOARD_FAB2(SCH_1):PAGE77
     1 P12V_NVDIMM_GHJ @BASEBOARD_FAB2_LIB.BASEBOARD_FAB2(SCH_1):P12V_NVDIMM_GHJ   I171 @BASEBOARD_FAB2_LIB.BASEBOARD_FAB2(SCH_1):PAGE77
   145 P12V_NVDIMM_GHJ @BASEBOARD_FAB2_LIB.BASEBOARD_FAB2(SCH_1):P12V_NVDIMM_GHJ   I171 @BASEBOARD_FAB2_LIB.BASEBOARD_FAB2(SCH_1):PAGE77
    59 PVDDQ_GHJ @BASEBOARD_FAB2_LIB.BASEBOARD_FAB2(SCH_1):PVDDQ_GHJ   I171 @BASEBOARD_FAB2_LIB.BASEBOARD_FAB2(SCH_1):PAGE77
    61 PVDDQ_GHJ @BASEBOARD_FAB2_LIB.BASEBOARD_FAB2(SCH_1):PVDDQ_GHJ   I171 @BASEBOARD_FAB2_LIB.BASEBOARD_FAB2(SCH_1):PAGE77
    64 PVDDQ_GHJ @BASEBOARD_FAB2_LIB.BASEBOARD_FAB2(SCH_1):PVDDQ_GHJ   I171 @BASEBOARD_FAB2_LIB.BASEBOARD_FAB2(SCH_1):PAGE77
    67 PVDDQ_GHJ @BASEBOARD_FAB2_LIB.BASEBOARD_FAB2(SCH_1):PVDDQ_GHJ   I171 @BASEBOARD_FAB2_LIB.BASEBOARD_FAB2(SCH_1):PAGE77
    70 PVDDQ_GHJ @BASEBOARD_FAB2_LIB.BASEBOARD_FAB2(SCH_1):PVDDQ_GHJ   I171 @BASEBOARD_FAB2_LIB.BASEBOARD_FAB2(SCH_1):PAGE77
    73 PVDDQ_GHJ @BASEBOARD_FAB2_LIB.BASEBOARD_FAB2(SCH_1):PVDDQ_GHJ   I171 @BASEBOARD_FAB2_LIB.BASEBOARD_FAB2(SCH_1):PAGE77
    76 PVDDQ_GHJ @BASEBOARD_FAB2_LIB.BASEBOARD_FAB2(SCH_1):PVDDQ_GHJ   I171 @BASEBOARD_FAB2_LIB.BASEBOARD_FAB2(SCH_1):PAGE77
    80 PVDDQ_GHJ @BASEBOARD_FAB2_LIB.BASEBOARD_FAB2(SCH_1):PVDDQ_GHJ   I171 @BASEBOARD_FAB2_LIB.BASEBOARD_FAB2(SCH_1):PAGE77
    83 PVDDQ_GHJ @BASEBOARD_FAB2_LIB.BASEBOARD_FAB2(SCH_1):PVDDQ_GHJ   I171 @BASEBOARD_FAB2_LIB.BASEBOARD_FAB2(SCH_1):PAGE77
    85 PVDDQ_GHJ @BASEBOARD_FAB2_LIB.BASEBOARD_FAB2(SCH_1):PVDDQ_GHJ   I171 @BASEBOARD_FAB2_LIB.BASEBOARD_FAB2(SCH_1):PAGE77
    88 PVDDQ_GHJ @BASEBOARD_FAB2_LIB.BASEBOARD_FAB2(SCH_1):PVDDQ_GHJ   I171 @BASEBOARD_FAB2_LIB.BASEBOARD_FAB2(SCH_1):PAGE77
    90 PVDDQ_GHJ @BASEBOARD_FAB2_LIB.BASEBOARD_FAB2(SCH_1):PVDDQ_GHJ   I171 @BASEBOARD_FAB2_LIB.BASEBOARD_FAB2(SCH_1):PAGE77
    92 PVDDQ_GHJ @BASEBOARD_FAB2_LIB.BASEBOARD_FAB2(SCH_1):PVDDQ_GHJ   I171 @BASEBOARD_FAB2_LIB.BASEBOARD_FAB2(SCH_1):PAGE77
   204 PVDDQ_GHJ @BASEBOARD_FAB2_LIB.BASEBOARD_FAB2(SCH_1):PVDDQ_GHJ   I171 @BASEBOARD_FAB2_LIB.BASEBOARD_FAB2(SCH_1):PAGE77
   206 PVDDQ_GHJ @BASEBOARD_FAB2_LIB.BASEBOARD_FAB2(SCH_1):PVDDQ_GHJ   I171 @BASEBOARD_FAB2_LIB.BASEBOARD_FAB2(SCH_1):PAGE77
   209 PVDDQ_GHJ @BASEBOARD_FAB2_LIB.BASEBOARD_FAB2(SCH_1):PVDDQ_GHJ   I171 @BASEBOARD_FAB2_LIB.BASEBOARD_FAB2(SCH_1):PAGE77
   212 PVDDQ_GHJ @BASEBOARD_FAB2_LIB.BASEBOARD_FAB2(SCH_1):PVDDQ_GHJ   I171 @BASEBOARD_FAB2_LIB.BASEBOARD_FAB2(SCH_1):PAGE77
   215 PVDDQ_GHJ @BASEBOARD_FAB2_LIB.BASEBOARD_FAB2(SCH_1):PVDDQ_GHJ   I171 @BASEBOARD_FAB2_LIB.BASEBOARD_FAB2(SCH_1):PAGE77
   217 PVDDQ_GHJ @BASEBOARD_FAB2_LIB.BASEBOARD_FAB2(SCH_1):PVDDQ_GHJ   I171 @BASEBOARD_FAB2_LIB.BASEBOARD_FAB2(SCH_1):PAGE77
   220 PVDDQ_GHJ @BASEBOARD_FAB2_LIB.BASEBOARD_FAB2(SCH_1):PVDDQ_GHJ   I171 @BASEBOARD_FAB2_LIB.BASEBOARD_FAB2(SCH_1):PAGE77
   223 PVDDQ_GHJ @BASEBOARD_FAB2_LIB.BASEBOARD_FAB2(SCH_1):PVDDQ_GHJ   I171 @BASEBOARD_FAB2_LIB.BASEBOARD_FAB2(SCH_1):PAGE77
   226 PVDDQ_GHJ @BASEBOARD_FAB2_LIB.BASEBOARD_FAB2(SCH_1):PVDDQ_GHJ   I171 @BASEBOARD_FAB2_LIB.BASEBOARD_FAB2(SCH_1):PAGE77
   229 PVDDQ_GHJ @BASEBOARD_FAB2_LIB.BASEBOARD_FAB2(SCH_1):PVDDQ_GHJ   I171 @BASEBOARD_FAB2_LIB.BASEBOARD_FAB2(SCH_1):PAGE77
   231 PVDDQ_GHJ @BASEBOARD_FAB2_LIB.BASEBOARD_FAB2(SCH_1):PVDDQ_GHJ   I171 @BASEBOARD_FAB2_LIB.BASEBOARD_FAB2(SCH_1):PAGE77
   233 PVDDQ_GHJ @BASEBOARD_FAB2_LIB.BASEBOARD_FAB2(SCH_1):PVDDQ_GHJ   I171 @BASEBOARD_FAB2_LIB.BASEBOARD_FAB2(SCH_1):PAGE77
   236 PVDDQ_GHJ @BASEBOARD_FAB2_LIB.BASEBOARD_FAB2(SCH_1):PVDDQ_GHJ   I171 @BASEBOARD_FAB2_LIB.BASEBOARD_FAB2(SCH_1):PAGE77
   142 PVPP_GHJ @BASEBOARD_FAB2_LIB.BASEBOARD_FAB2(SCH_1):PVPP_GHJ   I171 @BASEBOARD_FAB2_LIB.BASEBOARD_FAB2(SCH_1):PAGE77
   143 PVPP_GHJ @BASEBOARD_FAB2_LIB.BASEBOARD_FAB2(SCH_1):PVPP_GHJ   I171 @BASEBOARD_FAB2_LIB.BASEBOARD_FAB2(SCH_1):PAGE77
   288 PVPP_GHJ @BASEBOARD_FAB2_LIB.BASEBOARD_FAB2(SCH_1):PVPP_GHJ   I171 @BASEBOARD_FAB2_LIB.BASEBOARD_FAB2(SCH_1):PAGE77
   286 PVPP_GHJ @BASEBOARD_FAB2_LIB.BASEBOARD_FAB2(SCH_1):PVPP_GHJ   I171 @BASEBOARD_FAB2_LIB.BASEBOARD_FAB2(SCH_1):PAGE77
   287 PVPP_GHJ @BASEBOARD_FAB2_LIB.BASEBOARD_FAB2(SCH_1):PVPP_GHJ   I171 @BASEBOARD_FAB2_LIB.BASEBOARD_FAB2(SCH_1):PAGE77
    77 PVTT_GHJ @BASEBOARD_FAB2_LIB.BASEBOARD_FAB2(SCH_1):PVTT_GHJ   I171 @BASEBOARD_FAB2_LIB.BASEBOARD_FAB2(SCH_1):PAGE77
   221 PVTT_GHJ @BASEBOARD_FAB2_LIB.BASEBOARD_FAB2(SCH_1):PVTT_GHJ   I171 @BASEBOARD_FAB2_LIB.BASEBOARD_FAB2(SCH_1):PAGE77

J1G2 SCONN288_H44441004_PIP-SCONN,HA
    79 M_H_MA<0> @BASEBOARD_FAB2_LIB.BASEBOARD_FAB2(SCH_1):M_H_MA(0)   I111 @BASEBOARD_FAB2_LIB.BASEBOARD_FAB2(SCH_1):PAGE79
    72 M_H_MA<1> @BASEBOARD_FAB2_LIB.BASEBOARD_FAB2(SCH_1):M_H_MA(1)   I111 @BASEBOARD_FAB2_LIB.BASEBOARD_FAB2(SCH_1):PAGE79
   225 M_H_MA<10> @BASEBOARD_FAB2_LIB.BASEBOARD_FAB2(SCH_1):M_H_MA(10)   I111 @BASEBOARD_FAB2_LIB.BASEBOARD_FAB2(SCH_1):PAGE79
   210 M_H_MA<11> @BASEBOARD_FAB2_LIB.BASEBOARD_FAB2(SCH_1):M_H_MA(11)   I111 @BASEBOARD_FAB2_LIB.BASEBOARD_FAB2(SCH_1):PAGE79
    65 M_H_MA<12> @BASEBOARD_FAB2_LIB.BASEBOARD_FAB2(SCH_1):M_H_MA(12)   I111 @BASEBOARD_FAB2_LIB.BASEBOARD_FAB2(SCH_1):PAGE79
   232 M_H_MA<13> @BASEBOARD_FAB2_LIB.BASEBOARD_FAB2(SCH_1):M_H_MA(13)   I111 @BASEBOARD_FAB2_LIB.BASEBOARD_FAB2(SCH_1):PAGE79
   228 M_H_MA<14> @BASEBOARD_FAB2_LIB.BASEBOARD_FAB2(SCH_1):M_H_MA(14)   I111 @BASEBOARD_FAB2_LIB.BASEBOARD_FAB2(SCH_1):PAGE79
    86 M_H_MA<15> @BASEBOARD_FAB2_LIB.BASEBOARD_FAB2(SCH_1):M_H_MA(15)   I111 @BASEBOARD_FAB2_LIB.BASEBOARD_FAB2(SCH_1):PAGE79
    82 M_H_MA<16> @BASEBOARD_FAB2_LIB.BASEBOARD_FAB2(SCH_1):M_H_MA(16)   I111 @BASEBOARD_FAB2_LIB.BASEBOARD_FAB2(SCH_1):PAGE79
   234 M_H_MA<17> @BASEBOARD_FAB2_LIB.BASEBOARD_FAB2(SCH_1):M_H_MA(17)   I111 @BASEBOARD_FAB2_LIB.BASEBOARD_FAB2(SCH_1):PAGE79
   216 M_H_MA<2> @BASEBOARD_FAB2_LIB.BASEBOARD_FAB2(SCH_1):M_H_MA(2)   I111 @BASEBOARD_FAB2_LIB.BASEBOARD_FAB2(SCH_1):PAGE79
    71 M_H_MA<3> @BASEBOARD_FAB2_LIB.BASEBOARD_FAB2(SCH_1):M_H_MA(3)   I111 @BASEBOARD_FAB2_LIB.BASEBOARD_FAB2(SCH_1):PAGE79
   214 M_H_MA<4> @BASEBOARD_FAB2_LIB.BASEBOARD_FAB2(SCH_1):M_H_MA(4)   I111 @BASEBOARD_FAB2_LIB.BASEBOARD_FAB2(SCH_1):PAGE79
   213 M_H_MA<5> @BASEBOARD_FAB2_LIB.BASEBOARD_FAB2(SCH_1):M_H_MA(5)   I111 @BASEBOARD_FAB2_LIB.BASEBOARD_FAB2(SCH_1):PAGE79
    69 M_H_MA<6> @BASEBOARD_FAB2_LIB.BASEBOARD_FAB2(SCH_1):M_H_MA(6)   I111 @BASEBOARD_FAB2_LIB.BASEBOARD_FAB2(SCH_1):PAGE79
   211 M_H_MA<7> @BASEBOARD_FAB2_LIB.BASEBOARD_FAB2(SCH_1):M_H_MA(7)   I111 @BASEBOARD_FAB2_LIB.BASEBOARD_FAB2(SCH_1):PAGE79
    68 M_H_MA<8> @BASEBOARD_FAB2_LIB.BASEBOARD_FAB2(SCH_1):M_H_MA(8)   I111 @BASEBOARD_FAB2_LIB.BASEBOARD_FAB2(SCH_1):PAGE79
    66 M_H_MA<9> @BASEBOARD_FAB2_LIB.BASEBOARD_FAB2(SCH_1):M_H_MA(9)   I111 @BASEBOARD_FAB2_LIB.BASEBOARD_FAB2(SCH_1):PAGE79
    62 M_H_ACT_N @BASEBOARD_FAB2_LIB.BASEBOARD_FAB2(SCH_1):M_H_ACT_N   I111 @BASEBOARD_FAB2_LIB.BASEBOARD_FAB2(SCH_1):PAGE79
   208 M_H_ALERT_N @BASEBOARD_FAB2_LIB.BASEBOARD_FAB2(SCH_1):M_H_ALERT_N   I111 @BASEBOARD_FAB2_LIB.BASEBOARD_FAB2(SCH_1):PAGE79
   224 M_H_BA<1> @BASEBOARD_FAB2_LIB.BASEBOARD_FAB2(SCH_1):M_H_BA(1)   I111 @BASEBOARD_FAB2_LIB.BASEBOARD_FAB2(SCH_1):PAGE79
    81 M_H_BA<0> @BASEBOARD_FAB2_LIB.BASEBOARD_FAB2(SCH_1):M_H_BA(0)   I111 @BASEBOARD_FAB2_LIB.BASEBOARD_FAB2(SCH_1):PAGE79
   207 M_H_BG<1> @BASEBOARD_FAB2_LIB.BASEBOARD_FAB2(SCH_1):M_H_BG(1)   I111 @BASEBOARD_FAB2_LIB.BASEBOARD_FAB2(SCH_1):PAGE79
    63 M_H_BG<0> @BASEBOARD_FAB2_LIB.BASEBOARD_FAB2(SCH_1):M_H_BG(0)   I111 @BASEBOARD_FAB2_LIB.BASEBOARD_FAB2(SCH_1):PAGE79
   235 M_H_C<2> @BASEBOARD_FAB2_LIB.BASEBOARD_FAB2(SCH_1):M_H_C(2)   I111 @BASEBOARD_FAB2_LIB.BASEBOARD_FAB2(SCH_1):PAGE79
   199 M_H_ECC<6> @BASEBOARD_FAB2_LIB.BASEBOARD_FAB2(SCH_1):M_H_ECC(6)   I111 @BASEBOARD_FAB2_LIB.BASEBOARD_FAB2(SCH_1):PAGE79
    54 M_H_ECC<7> @BASEBOARD_FAB2_LIB.BASEBOARD_FAB2(SCH_1):M_H_ECC(7)   I111 @BASEBOARD_FAB2_LIB.BASEBOARD_FAB2(SCH_1):PAGE79
   192 M_H_ECC<4> @BASEBOARD_FAB2_LIB.BASEBOARD_FAB2(SCH_1):M_H_ECC(4)   I111 @BASEBOARD_FAB2_LIB.BASEBOARD_FAB2(SCH_1):PAGE79
    47 M_H_ECC<5> @BASEBOARD_FAB2_LIB.BASEBOARD_FAB2(SCH_1):M_H_ECC(5)   I111 @BASEBOARD_FAB2_LIB.BASEBOARD_FAB2(SCH_1):PAGE79
   201 M_H_ECC<2> @BASEBOARD_FAB2_LIB.BASEBOARD_FAB2(SCH_1):M_H_ECC(2)   I111 @BASEBOARD_FAB2_LIB.BASEBOARD_FAB2(SCH_1):PAGE79
    56 M_H_ECC<3> @BASEBOARD_FAB2_LIB.BASEBOARD_FAB2(SCH_1):M_H_ECC(3)   I111 @BASEBOARD_FAB2_LIB.BASEBOARD_FAB2(SCH_1):PAGE79
   194 M_H_ECC<0> @BASEBOARD_FAB2_LIB.BASEBOARD_FAB2(SCH_1):M_H_ECC(0)   I111 @BASEBOARD_FAB2_LIB.BASEBOARD_FAB2(SCH_1):PAGE79
    49 M_H_ECC<1> @BASEBOARD_FAB2_LIB.BASEBOARD_FAB2(SCH_1):M_H_ECC(1)   I111 @BASEBOARD_FAB2_LIB.BASEBOARD_FAB2(SCH_1):PAGE79
    75 M_H_CLK_DN<0> @BASEBOARD_FAB2_LIB.BASEBOARD_FAB2(SCH_1):M_H_CLK_DN(0)   I111 @BASEBOARD_FAB2_LIB.BASEBOARD_FAB2(SCH_1):PAGE79
    74 M_H_CLK_DP<0> @BASEBOARD_FAB2_LIB.BASEBOARD_FAB2(SCH_1):M_H_CLK_DP(0)   I111 @BASEBOARD_FAB2_LIB.BASEBOARD_FAB2(SCH_1):PAGE79
   219 M_H_CLK_DN<1> @BASEBOARD_FAB2_LIB.BASEBOARD_FAB2(SCH_1):M_H_CLK_DN(1)   I111 @BASEBOARD_FAB2_LIB.BASEBOARD_FAB2(SCH_1):PAGE79
   218 M_H_CLK_DP<1> @BASEBOARD_FAB2_LIB.BASEBOARD_FAB2(SCH_1):M_H_CLK_DP(1)   I111 @BASEBOARD_FAB2_LIB.BASEBOARD_FAB2(SCH_1):PAGE79
   203 M_H_CKE<1> @BASEBOARD_FAB2_LIB.BASEBOARD_FAB2(SCH_1):M_H_CKE(1)   I111 @BASEBOARD_FAB2_LIB.BASEBOARD_FAB2(SCH_1):PAGE79
    60 M_H_CKE<0> @BASEBOARD_FAB2_LIB.BASEBOARD_FAB2(SCH_1):M_H_CKE(0)   I111 @BASEBOARD_FAB2_LIB.BASEBOARD_FAB2(SCH_1):PAGE79
   280 M_H_DQ<62> @BASEBOARD_FAB2_LIB.BASEBOARD_FAB2(SCH_1):M_H_DQ(62)   I111 @BASEBOARD_FAB2_LIB.BASEBOARD_FAB2(SCH_1):PAGE79
   135 M_H_DQ<63> @BASEBOARD_FAB2_LIB.BASEBOARD_FAB2(SCH_1):M_H_DQ(63)   I111 @BASEBOARD_FAB2_LIB.BASEBOARD_FAB2(SCH_1):PAGE79
   273 M_H_DQ<60> @BASEBOARD_FAB2_LIB.BASEBOARD_FAB2(SCH_1):M_H_DQ(60)   I111 @BASEBOARD_FAB2_LIB.BASEBOARD_FAB2(SCH_1):PAGE79
   128 M_H_DQ<61> @BASEBOARD_FAB2_LIB.BASEBOARD_FAB2(SCH_1):M_H_DQ(61)   I111 @BASEBOARD_FAB2_LIB.BASEBOARD_FAB2(SCH_1):PAGE79
   282 M_H_DQ<58> @BASEBOARD_FAB2_LIB.BASEBOARD_FAB2(SCH_1):M_H_DQ(58)   I111 @BASEBOARD_FAB2_LIB.BASEBOARD_FAB2(SCH_1):PAGE79
   137 M_H_DQ<59> @BASEBOARD_FAB2_LIB.BASEBOARD_FAB2(SCH_1):M_H_DQ(59)   I111 @BASEBOARD_FAB2_LIB.BASEBOARD_FAB2(SCH_1):PAGE79
   275 M_H_DQ<56> @BASEBOARD_FAB2_LIB.BASEBOARD_FAB2(SCH_1):M_H_DQ(56)   I111 @BASEBOARD_FAB2_LIB.BASEBOARD_FAB2(SCH_1):PAGE79
   130 M_H_DQ<57> @BASEBOARD_FAB2_LIB.BASEBOARD_FAB2(SCH_1):M_H_DQ(57)   I111 @BASEBOARD_FAB2_LIB.BASEBOARD_FAB2(SCH_1):PAGE79
   269 M_H_DQ<54> @BASEBOARD_FAB2_LIB.BASEBOARD_FAB2(SCH_1):M_H_DQ(54)   I111 @BASEBOARD_FAB2_LIB.BASEBOARD_FAB2(SCH_1):PAGE79
   124 M_H_DQ<55> @BASEBOARD_FAB2_LIB.BASEBOARD_FAB2(SCH_1):M_H_DQ(55)   I111 @BASEBOARD_FAB2_LIB.BASEBOARD_FAB2(SCH_1):PAGE79
   262 M_H_DQ<52> @BASEBOARD_FAB2_LIB.BASEBOARD_FAB2(SCH_1):M_H_DQ(52)   I111 @BASEBOARD_FAB2_LIB.BASEBOARD_FAB2(SCH_1):PAGE79
   117 M_H_DQ<53> @BASEBOARD_FAB2_LIB.BASEBOARD_FAB2(SCH_1):M_H_DQ(53)   I111 @BASEBOARD_FAB2_LIB.BASEBOARD_FAB2(SCH_1):PAGE79
   271 M_H_DQ<50> @BASEBOARD_FAB2_LIB.BASEBOARD_FAB2(SCH_1):M_H_DQ(50)   I111 @BASEBOARD_FAB2_LIB.BASEBOARD_FAB2(SCH_1):PAGE79
   126 M_H_DQ<51> @BASEBOARD_FAB2_LIB.BASEBOARD_FAB2(SCH_1):M_H_DQ(51)   I111 @BASEBOARD_FAB2_LIB.BASEBOARD_FAB2(SCH_1):PAGE79
   264 M_H_DQ<48> @BASEBOARD_FAB2_LIB.BASEBOARD_FAB2(SCH_1):M_H_DQ(48)   I111 @BASEBOARD_FAB2_LIB.BASEBOARD_FAB2(SCH_1):PAGE79
   119 M_H_DQ<49> @BASEBOARD_FAB2_LIB.BASEBOARD_FAB2(SCH_1):M_H_DQ(49)   I111 @BASEBOARD_FAB2_LIB.BASEBOARD_FAB2(SCH_1):PAGE79
   258 M_H_DQ<46> @BASEBOARD_FAB2_LIB.BASEBOARD_FAB2(SCH_1):M_H_DQ(46)   I111 @BASEBOARD_FAB2_LIB.BASEBOARD_FAB2(SCH_1):PAGE79
   113 M_H_DQ<47> @BASEBOARD_FAB2_LIB.BASEBOARD_FAB2(SCH_1):M_H_DQ(47)   I111 @BASEBOARD_FAB2_LIB.BASEBOARD_FAB2(SCH_1):PAGE79
   251 M_H_DQ<44> @BASEBOARD_FAB2_LIB.BASEBOARD_FAB2(SCH_1):M_H_DQ(44)   I111 @BASEBOARD_FAB2_LIB.BASEBOARD_FAB2(SCH_1):PAGE79
   106 M_H_DQ<45> @BASEBOARD_FAB2_LIB.BASEBOARD_FAB2(SCH_1):M_H_DQ(45)   I111 @BASEBOARD_FAB2_LIB.BASEBOARD_FAB2(SCH_1):PAGE79
   260 M_H_DQ<42> @BASEBOARD_FAB2_LIB.BASEBOARD_FAB2(SCH_1):M_H_DQ(42)   I111 @BASEBOARD_FAB2_LIB.BASEBOARD_FAB2(SCH_1):PAGE79
   115 M_H_DQ<43> @BASEBOARD_FAB2_LIB.BASEBOARD_FAB2(SCH_1):M_H_DQ(43)   I111 @BASEBOARD_FAB2_LIB.BASEBOARD_FAB2(SCH_1):PAGE79
   253 M_H_DQ<40> @BASEBOARD_FAB2_LIB.BASEBOARD_FAB2(SCH_1):M_H_DQ(40)   I111 @BASEBOARD_FAB2_LIB.BASEBOARD_FAB2(SCH_1):PAGE79
   108 M_H_DQ<41> @BASEBOARD_FAB2_LIB.BASEBOARD_FAB2(SCH_1):M_H_DQ(41)   I111 @BASEBOARD_FAB2_LIB.BASEBOARD_FAB2(SCH_1):PAGE79
   247 M_H_DQ<38> @BASEBOARD_FAB2_LIB.BASEBOARD_FAB2(SCH_1):M_H_DQ(38)   I111 @BASEBOARD_FAB2_LIB.BASEBOARD_FAB2(SCH_1):PAGE79
   102 M_H_DQ<39> @BASEBOARD_FAB2_LIB.BASEBOARD_FAB2(SCH_1):M_H_DQ(39)   I111 @BASEBOARD_FAB2_LIB.BASEBOARD_FAB2(SCH_1):PAGE79
   240 M_H_DQ<36> @BASEBOARD_FAB2_LIB.BASEBOARD_FAB2(SCH_1):M_H_DQ(36)   I111 @BASEBOARD_FAB2_LIB.BASEBOARD_FAB2(SCH_1):PAGE79
    95 M_H_DQ<37> @BASEBOARD_FAB2_LIB.BASEBOARD_FAB2(SCH_1):M_H_DQ(37)   I111 @BASEBOARD_FAB2_LIB.BASEBOARD_FAB2(SCH_1):PAGE79
   249 M_H_DQ<34> @BASEBOARD_FAB2_LIB.BASEBOARD_FAB2(SCH_1):M_H_DQ(34)   I111 @BASEBOARD_FAB2_LIB.BASEBOARD_FAB2(SCH_1):PAGE79
   104 M_H_DQ<35> @BASEBOARD_FAB2_LIB.BASEBOARD_FAB2(SCH_1):M_H_DQ(35)   I111 @BASEBOARD_FAB2_LIB.BASEBOARD_FAB2(SCH_1):PAGE79
   242 M_H_DQ<32> @BASEBOARD_FAB2_LIB.BASEBOARD_FAB2(SCH_1):M_H_DQ(32)   I111 @BASEBOARD_FAB2_LIB.BASEBOARD_FAB2(SCH_1):PAGE79
    97 M_H_DQ<33> @BASEBOARD_FAB2_LIB.BASEBOARD_FAB2(SCH_1):M_H_DQ(33)   I111 @BASEBOARD_FAB2_LIB.BASEBOARD_FAB2(SCH_1):PAGE79
   188 M_H_DQ<30> @BASEBOARD_FAB2_LIB.BASEBOARD_FAB2(SCH_1):M_H_DQ(30)   I111 @BASEBOARD_FAB2_LIB.BASEBOARD_FAB2(SCH_1):PAGE79
    43 M_H_DQ<31> @BASEBOARD_FAB2_LIB.BASEBOARD_FAB2(SCH_1):M_H_DQ(31)   I111 @BASEBOARD_FAB2_LIB.BASEBOARD_FAB2(SCH_1):PAGE79
   181 M_H_DQ<28> @BASEBOARD_FAB2_LIB.BASEBOARD_FAB2(SCH_1):M_H_DQ(28)   I111 @BASEBOARD_FAB2_LIB.BASEBOARD_FAB2(SCH_1):PAGE79
    36 M_H_DQ<29> @BASEBOARD_FAB2_LIB.BASEBOARD_FAB2(SCH_1):M_H_DQ(29)   I111 @BASEBOARD_FAB2_LIB.BASEBOARD_FAB2(SCH_1):PAGE79
   190 M_H_DQ<26> @BASEBOARD_FAB2_LIB.BASEBOARD_FAB2(SCH_1):M_H_DQ(26)   I111 @BASEBOARD_FAB2_LIB.BASEBOARD_FAB2(SCH_1):PAGE79
    45 M_H_DQ<27> @BASEBOARD_FAB2_LIB.BASEBOARD_FAB2(SCH_1):M_H_DQ(27)   I111 @BASEBOARD_FAB2_LIB.BASEBOARD_FAB2(SCH_1):PAGE79
   183 M_H_DQ<24> @BASEBOARD_FAB2_LIB.BASEBOARD_FAB2(SCH_1):M_H_DQ(24)   I111 @BASEBOARD_FAB2_LIB.BASEBOARD_FAB2(SCH_1):PAGE79
    38 M_H_DQ<25> @BASEBOARD_FAB2_LIB.BASEBOARD_FAB2(SCH_1):M_H_DQ(25)   I111 @BASEBOARD_FAB2_LIB.BASEBOARD_FAB2(SCH_1):PAGE79
   177 M_H_DQ<22> @BASEBOARD_FAB2_LIB.BASEBOARD_FAB2(SCH_1):M_H_DQ(22)   I111 @BASEBOARD_FAB2_LIB.BASEBOARD_FAB2(SCH_1):PAGE79
    32 M_H_DQ<23> @BASEBOARD_FAB2_LIB.BASEBOARD_FAB2(SCH_1):M_H_DQ(23)   I111 @BASEBOARD_FAB2_LIB.BASEBOARD_FAB2(SCH_1):PAGE79
   170 M_H_DQ<20> @BASEBOARD_FAB2_LIB.BASEBOARD_FAB2(SCH_1):M_H_DQ(20)   I111 @BASEBOARD_FAB2_LIB.BASEBOARD_FAB2(SCH_1):PAGE79
    25 M_H_DQ<21> @BASEBOARD_FAB2_LIB.BASEBOARD_FAB2(SCH_1):M_H_DQ(21)   I111 @BASEBOARD_FAB2_LIB.BASEBOARD_FAB2(SCH_1):PAGE79
   179 M_H_DQ<18> @BASEBOARD_FAB2_LIB.BASEBOARD_FAB2(SCH_1):M_H_DQ(18)   I111 @BASEBOARD_FAB2_LIB.BASEBOARD_FAB2(SCH_1):PAGE79
    34 M_H_DQ<19> @BASEBOARD_FAB2_LIB.BASEBOARD_FAB2(SCH_1):M_H_DQ(19)   I111 @BASEBOARD_FAB2_LIB.BASEBOARD_FAB2(SCH_1):PAGE79
   172 M_H_DQ<16> @BASEBOARD_FAB2_LIB.BASEBOARD_FAB2(SCH_1):M_H_DQ(16)   I111 @BASEBOARD_FAB2_LIB.BASEBOARD_FAB2(SCH_1):PAGE79
    27 M_H_DQ<17> @BASEBOARD_FAB2_LIB.BASEBOARD_FAB2(SCH_1):M_H_DQ(17)   I111 @BASEBOARD_FAB2_LIB.BASEBOARD_FAB2(SCH_1):PAGE79
   166 M_H_DQ<14> @BASEBOARD_FAB2_LIB.BASEBOARD_FAB2(SCH_1):M_H_DQ(14)   I111 @BASEBOARD_FAB2_LIB.BASEBOARD_FAB2(SCH_1):PAGE79
    21 M_H_DQ<15> @BASEBOARD_FAB2_LIB.BASEBOARD_FAB2(SCH_1):M_H_DQ(15)   I111 @BASEBOARD_FAB2_LIB.BASEBOARD_FAB2(SCH_1):PAGE79
   159 M_H_DQ<12> @BASEBOARD_FAB2_LIB.BASEBOARD_FAB2(SCH_1):M_H_DQ(12)   I111 @BASEBOARD_FAB2_LIB.BASEBOARD_FAB2(SCH_1):PAGE79
    14 M_H_DQ<13> @BASEBOARD_FAB2_LIB.BASEBOARD_FAB2(SCH_1):M_H_DQ(13)   I111 @BASEBOARD_FAB2_LIB.BASEBOARD_FAB2(SCH_1):PAGE79
   168 M_H_DQ<10> @BASEBOARD_FAB2_LIB.BASEBOARD_FAB2(SCH_1):M_H_DQ(10)   I111 @BASEBOARD_FAB2_LIB.BASEBOARD_FAB2(SCH_1):PAGE79
    23 M_H_DQ<11> @BASEBOARD_FAB2_LIB.BASEBOARD_FAB2(SCH_1):M_H_DQ(11)   I111 @BASEBOARD_FAB2_LIB.BASEBOARD_FAB2(SCH_1):PAGE79
   161 M_H_DQ<8> @BASEBOARD_FAB2_LIB.BASEBOARD_FAB2(SCH_1):M_H_DQ(8)   I111 @BASEBOARD_FAB2_LIB.BASEBOARD_FAB2(SCH_1):PAGE79
    16 M_H_DQ<9> @BASEBOARD_FAB2_LIB.BASEBOARD_FAB2(SCH_1):M_H_DQ(9)   I111 @BASEBOARD_FAB2_LIB.BASEBOARD_FAB2(SCH_1):PAGE79
   155 M_H_DQ<6> @BASEBOARD_FAB2_LIB.BASEBOARD_FAB2(SCH_1):M_H_DQ(6)   I111 @BASEBOARD_FAB2_LIB.BASEBOARD_FAB2(SCH_1):PAGE79
    10 M_H_DQ<7> @BASEBOARD_FAB2_LIB.BASEBOARD_FAB2(SCH_1):M_H_DQ(7)   I111 @BASEBOARD_FAB2_LIB.BASEBOARD_FAB2(SCH_1):PAGE79
   148 M_H_DQ<4> @BASEBOARD_FAB2_LIB.BASEBOARD_FAB2(SCH_1):M_H_DQ(4)   I111 @BASEBOARD_FAB2_LIB.BASEBOARD_FAB2(SCH_1):PAGE79
     3 M_H_DQ<5> @BASEBOARD_FAB2_LIB.BASEBOARD_FAB2(SCH_1):M_H_DQ(5)   I111 @BASEBOARD_FAB2_LIB.BASEBOARD_FAB2(SCH_1):PAGE79
   157 M_H_DQ<2> @BASEBOARD_FAB2_LIB.BASEBOARD_FAB2(SCH_1):M_H_DQ(2)   I111 @BASEBOARD_FAB2_LIB.BASEBOARD_FAB2(SCH_1):PAGE79
    12 M_H_DQ<3> @BASEBOARD_FAB2_LIB.BASEBOARD_FAB2(SCH_1):M_H_DQ(3)   I111 @BASEBOARD_FAB2_LIB.BASEBOARD_FAB2(SCH_1):PAGE79
   150 M_H_DQ<0> @BASEBOARD_FAB2_LIB.BASEBOARD_FAB2(SCH_1):M_H_DQ(0)   I111 @BASEBOARD_FAB2_LIB.BASEBOARD_FAB2(SCH_1):PAGE79
     5 M_H_DQ<1> @BASEBOARD_FAB2_LIB.BASEBOARD_FAB2(SCH_1):M_H_DQ(1)   I111 @BASEBOARD_FAB2_LIB.BASEBOARD_FAB2(SCH_1):PAGE79
    78 FM_DIMM_EVENT_COD_N @BASEBOARD_FAB2_LIB.BASEBOARD_FAB2(SCH_1):FM_DIMM_EVENT_COD_N   I111 @BASEBOARD_FAB2_LIB.BASEBOARD_FAB2(SCH_1):PAGE79
    91 M_H_ODT<1> @BASEBOARD_FAB2_LIB.BASEBOARD_FAB2(SCH_1):M_H_ODT(1)   I111 @BASEBOARD_FAB2_LIB.BASEBOARD_FAB2(SCH_1):PAGE79
    87 M_H_ODT<0> @BASEBOARD_FAB2_LIB.BASEBOARD_FAB2(SCH_1):M_H_ODT(0)   I111 @BASEBOARD_FAB2_LIB.BASEBOARD_FAB2(SCH_1):PAGE79
   222 M_H_PAR @BASEBOARD_FAB2_LIB.BASEBOARD_FAB2(SCH_1):M_H_PAR   I111 @BASEBOARD_FAB2_LIB.BASEBOARD_FAB2(SCH_1):PAGE79
    58 M_GHJ_RST_N @BASEBOARD_FAB2_LIB.BASEBOARD_FAB2(SCH_1):M_GHJ_RST_N   I111 @BASEBOARD_FAB2_LIB.BASEBOARD_FAB2(SCH_1):PAGE79
   144 TP_CH_H_DIMM_H0_RFU_2 @BASEBOARD_FAB2_LIB.BASEBOARD_FAB2(SCH_1):TP_CH_H_DIMM_H0_RFU_2   I111 @BASEBOARD_FAB2_LIB.BASEBOARD_FAB2(SCH_1):PAGE79
   227 TP_CH_H_DIMM_H0_RFU_1 @BASEBOARD_FAB2_LIB.BASEBOARD_FAB2(SCH_1):TP_CH_H_DIMM_H0_RFU_1   I111 @BASEBOARD_FAB2_LIB.BASEBOARD_FAB2(SCH_1):PAGE79
   205 TP_CH_H_DIMM_H0_RFU_0 @BASEBOARD_FAB2_LIB.BASEBOARD_FAB2(SCH_1):TP_CH_H_DIMM_H0_RFU_0   I111 @BASEBOARD_FAB2_LIB.BASEBOARD_FAB2(SCH_1):PAGE79
    84 M_H_CS_N<0> @BASEBOARD_FAB2_LIB.BASEBOARD_FAB2(SCH_1):M_H_CS_N(0)   I111 @BASEBOARD_FAB2_LIB.BASEBOARD_FAB2(SCH_1):PAGE79
    89 M_H_CS_N<1> @BASEBOARD_FAB2_LIB.BASEBOARD_FAB2(SCH_1):M_H_CS_N(1)   I111 @BASEBOARD_FAB2_LIB.BASEBOARD_FAB2(SCH_1):PAGE79
    93 M_H_CS_N<2> @BASEBOARD_FAB2_LIB.BASEBOARD_FAB2(SCH_1):M_H_CS_N(2)   I111 @BASEBOARD_FAB2_LIB.BASEBOARD_FAB2(SCH_1):PAGE79
   237 M_H_CS_N<3> @BASEBOARD_FAB2_LIB.BASEBOARD_FAB2(SCH_1):M_H_CS_N(3)   I111 @BASEBOARD_FAB2_LIB.BASEBOARD_FAB2(SCH_1):PAGE79
   238    GND @BASEBOARD_FAB2_LIB.BASEBOARD_FAB2(SCH_1):GND   I111 @BASEBOARD_FAB2_LIB.BASEBOARD_FAB2(SCH_1):PAGE79
   140 PVPP_GHJ @BASEBOARD_FAB2_LIB.BASEBOARD_FAB2(SCH_1):PVPP_GHJ   I111 @BASEBOARD_FAB2_LIB.BASEBOARD_FAB2(SCH_1):PAGE79
   139    GND @BASEBOARD_FAB2_LIB.BASEBOARD_FAB2(SCH_1):GND   I111 @BASEBOARD_FAB2_LIB.BASEBOARD_FAB2(SCH_1):PAGE79
   230 FM_ADR_COMPLETE_GHJ_N @BASEBOARD_FAB2_LIB.BASEBOARD_FAB2(SCH_1):FM_ADR_COMPLETE_GHJ_N   I111 @BASEBOARD_FAB2_LIB.BASEBOARD_FAB2(SCH_1):PAGE79
   141 SMB_DDR_GHJ_VPP_SCL @BASEBOARD_FAB2_LIB.BASEBOARD_FAB2(SCH_1):SMB_DDR_GHJ_VPP_SCL   I111 @BASEBOARD_FAB2_LIB.BASEBOARD_FAB2(SCH_1):PAGE79
   285 SMB_DDR_GHJ_VPP_SDA @BASEBOARD_FAB2_LIB.BASEBOARD_FAB2(SCH_1):SMB_DDR_GHJ_VPP_SDA   I111 @BASEBOARD_FAB2_LIB.BASEBOARD_FAB2(SCH_1):PAGE79
   284 PVPP_GHJ @BASEBOARD_FAB2_LIB.BASEBOARD_FAB2(SCH_1):PVPP_GHJ   I111 @BASEBOARD_FAB2_LIB.BASEBOARD_FAB2(SCH_1):PAGE79
   146 M_H_VREF @BASEBOARD_FAB2_LIB.BASEBOARD_FAB2(SCH_1):M_H_VREF   I111 @BASEBOARD_FAB2_LIB.BASEBOARD_FAB2(SCH_1):PAGE79
   152 M_H_DQS_DN<0> @BASEBOARD_FAB2_LIB.BASEBOARD_FAB2(SCH_1):M_H_DQS_DN(0)    I64 @BASEBOARD_FAB2_LIB.BASEBOARD_FAB2(SCH_1):PAGE79
   153 M_H_DQS_DP<0> @BASEBOARD_FAB2_LIB.BASEBOARD_FAB2(SCH_1):M_H_DQS_DP(0)    I64 @BASEBOARD_FAB2_LIB.BASEBOARD_FAB2(SCH_1):PAGE79
    19 M_H_DQS_DN<10> @BASEBOARD_FAB2_LIB.BASEBOARD_FAB2(SCH_1):M_H_DQS_DN(10)    I64 @BASEBOARD_FAB2_LIB.BASEBOARD_FAB2(SCH_1):PAGE79
    18 M_H_DQS_DP<10> @BASEBOARD_FAB2_LIB.BASEBOARD_FAB2(SCH_1):M_H_DQS_DP(10)    I64 @BASEBOARD_FAB2_LIB.BASEBOARD_FAB2(SCH_1):PAGE79
    30 M_H_DQS_DN<11> @BASEBOARD_FAB2_LIB.BASEBOARD_FAB2(SCH_1):M_H_DQS_DN(11)    I64 @BASEBOARD_FAB2_LIB.BASEBOARD_FAB2(SCH_1):PAGE79
    29 M_H_DQS_DP<11> @BASEBOARD_FAB2_LIB.BASEBOARD_FAB2(SCH_1):M_H_DQS_DP(11)    I64 @BASEBOARD_FAB2_LIB.BASEBOARD_FAB2(SCH_1):PAGE79
    41 M_H_DQS_DN<12> @BASEBOARD_FAB2_LIB.BASEBOARD_FAB2(SCH_1):M_H_DQS_DN(12)    I64 @BASEBOARD_FAB2_LIB.BASEBOARD_FAB2(SCH_1):PAGE79
    40 M_H_DQS_DP<12> @BASEBOARD_FAB2_LIB.BASEBOARD_FAB2(SCH_1):M_H_DQS_DP(12)    I64 @BASEBOARD_FAB2_LIB.BASEBOARD_FAB2(SCH_1):PAGE79
   100 M_H_DQS_DN<13> @BASEBOARD_FAB2_LIB.BASEBOARD_FAB2(SCH_1):M_H_DQS_DN(13)    I64 @BASEBOARD_FAB2_LIB.BASEBOARD_FAB2(SCH_1):PAGE79
    99 M_H_DQS_DP<13> @BASEBOARD_FAB2_LIB.BASEBOARD_FAB2(SCH_1):M_H_DQS_DP(13)    I64 @BASEBOARD_FAB2_LIB.BASEBOARD_FAB2(SCH_1):PAGE79
   111 M_H_DQS_DN<14> @BASEBOARD_FAB2_LIB.BASEBOARD_FAB2(SCH_1):M_H_DQS_DN(14)    I64 @BASEBOARD_FAB2_LIB.BASEBOARD_FAB2(SCH_1):PAGE79
   110 M_H_DQS_DP<14> @BASEBOARD_FAB2_LIB.BASEBOARD_FAB2(SCH_1):M_H_DQS_DP(14)    I64 @BASEBOARD_FAB2_LIB.BASEBOARD_FAB2(SCH_1):PAGE79
   122 M_H_DQS_DN<15> @BASEBOARD_FAB2_LIB.BASEBOARD_FAB2(SCH_1):M_H_DQS_DN(15)    I64 @BASEBOARD_FAB2_LIB.BASEBOARD_FAB2(SCH_1):PAGE79
   121 M_H_DQS_DP<15> @BASEBOARD_FAB2_LIB.BASEBOARD_FAB2(SCH_1):M_H_DQS_DP(15)    I64 @BASEBOARD_FAB2_LIB.BASEBOARD_FAB2(SCH_1):PAGE79
   133 M_H_DQS_DN<16> @BASEBOARD_FAB2_LIB.BASEBOARD_FAB2(SCH_1):M_H_DQS_DN(16)    I64 @BASEBOARD_FAB2_LIB.BASEBOARD_FAB2(SCH_1):PAGE79
   132 M_H_DQS_DP<16> @BASEBOARD_FAB2_LIB.BASEBOARD_FAB2(SCH_1):M_H_DQS_DP(16)    I64 @BASEBOARD_FAB2_LIB.BASEBOARD_FAB2(SCH_1):PAGE79
    52 M_H_DQS_DN<17> @BASEBOARD_FAB2_LIB.BASEBOARD_FAB2(SCH_1):M_H_DQS_DN(17)    I64 @BASEBOARD_FAB2_LIB.BASEBOARD_FAB2(SCH_1):PAGE79
    51 M_H_DQS_DP<17> @BASEBOARD_FAB2_LIB.BASEBOARD_FAB2(SCH_1):M_H_DQS_DP(17)    I64 @BASEBOARD_FAB2_LIB.BASEBOARD_FAB2(SCH_1):PAGE79
   163 M_H_DQS_DN<1> @BASEBOARD_FAB2_LIB.BASEBOARD_FAB2(SCH_1):M_H_DQS_DN(1)    I64 @BASEBOARD_FAB2_LIB.BASEBOARD_FAB2(SCH_1):PAGE79
   164 M_H_DQS_DP<1> @BASEBOARD_FAB2_LIB.BASEBOARD_FAB2(SCH_1):M_H_DQS_DP(1)    I64 @BASEBOARD_FAB2_LIB.BASEBOARD_FAB2(SCH_1):PAGE79
   174 M_H_DQS_DN<2> @BASEBOARD_FAB2_LIB.BASEBOARD_FAB2(SCH_1):M_H_DQS_DN(2)    I64 @BASEBOARD_FAB2_LIB.BASEBOARD_FAB2(SCH_1):PAGE79
   175 M_H_DQS_DP<2> @BASEBOARD_FAB2_LIB.BASEBOARD_FAB2(SCH_1):M_H_DQS_DP(2)    I64 @BASEBOARD_FAB2_LIB.BASEBOARD_FAB2(SCH_1):PAGE79
   185 M_H_DQS_DN<3> @BASEBOARD_FAB2_LIB.BASEBOARD_FAB2(SCH_1):M_H_DQS_DN(3)    I64 @BASEBOARD_FAB2_LIB.BASEBOARD_FAB2(SCH_1):PAGE79
   186 M_H_DQS_DP<3> @BASEBOARD_FAB2_LIB.BASEBOARD_FAB2(SCH_1):M_H_DQS_DP(3)    I64 @BASEBOARD_FAB2_LIB.BASEBOARD_FAB2(SCH_1):PAGE79
   244 M_H_DQS_DN<4> @BASEBOARD_FAB2_LIB.BASEBOARD_FAB2(SCH_1):M_H_DQS_DN(4)    I64 @BASEBOARD_FAB2_LIB.BASEBOARD_FAB2(SCH_1):PAGE79
   245 M_H_DQS_DP<4> @BASEBOARD_FAB2_LIB.BASEBOARD_FAB2(SCH_1):M_H_DQS_DP(4)    I64 @BASEBOARD_FAB2_LIB.BASEBOARD_FAB2(SCH_1):PAGE79
   255 M_H_DQS_DN<5> @BASEBOARD_FAB2_LIB.BASEBOARD_FAB2(SCH_1):M_H_DQS_DN(5)    I64 @BASEBOARD_FAB2_LIB.BASEBOARD_FAB2(SCH_1):PAGE79
   256 M_H_DQS_DP<5> @BASEBOARD_FAB2_LIB.BASEBOARD_FAB2(SCH_1):M_H_DQS_DP(5)    I64 @BASEBOARD_FAB2_LIB.BASEBOARD_FAB2(SCH_1):PAGE79
   266 M_H_DQS_DN<6> @BASEBOARD_FAB2_LIB.BASEBOARD_FAB2(SCH_1):M_H_DQS_DN(6)    I64 @BASEBOARD_FAB2_LIB.BASEBOARD_FAB2(SCH_1):PAGE79
   267 M_H_DQS_DP<6> @BASEBOARD_FAB2_LIB.BASEBOARD_FAB2(SCH_1):M_H_DQS_DP(6)    I64 @BASEBOARD_FAB2_LIB.BASEBOARD_FAB2(SCH_1):PAGE79
   277 M_H_DQS_DN<7> @BASEBOARD_FAB2_LIB.BASEBOARD_FAB2(SCH_1):M_H_DQS_DN(7)    I64 @BASEBOARD_FAB2_LIB.BASEBOARD_FAB2(SCH_1):PAGE79
   278 M_H_DQS_DP<7> @BASEBOARD_FAB2_LIB.BASEBOARD_FAB2(SCH_1):M_H_DQS_DP(7)    I64 @BASEBOARD_FAB2_LIB.BASEBOARD_FAB2(SCH_1):PAGE79
   196 M_H_DQS_DN<8> @BASEBOARD_FAB2_LIB.BASEBOARD_FAB2(SCH_1):M_H_DQS_DN(8)    I64 @BASEBOARD_FAB2_LIB.BASEBOARD_FAB2(SCH_1):PAGE79
   197 M_H_DQS_DP<8> @BASEBOARD_FAB2_LIB.BASEBOARD_FAB2(SCH_1):M_H_DQS_DP(8)    I64 @BASEBOARD_FAB2_LIB.BASEBOARD_FAB2(SCH_1):PAGE79
     8 M_H_DQS_DN<9> @BASEBOARD_FAB2_LIB.BASEBOARD_FAB2(SCH_1):M_H_DQS_DN(9)    I64 @BASEBOARD_FAB2_LIB.BASEBOARD_FAB2(SCH_1):PAGE79
     7 M_H_DQS_DP<9> @BASEBOARD_FAB2_LIB.BASEBOARD_FAB2(SCH_1):M_H_DQS_DP(9)    I64 @BASEBOARD_FAB2_LIB.BASEBOARD_FAB2(SCH_1):PAGE79
     2    GND @BASEBOARD_FAB2_LIB.BASEBOARD_FAB2(SCH_1):GND    I43 @BASEBOARD_FAB2_LIB.BASEBOARD_FAB2(SCH_1):PAGE79
     4    GND @BASEBOARD_FAB2_LIB.BASEBOARD_FAB2(SCH_1):GND    I43 @BASEBOARD_FAB2_LIB.BASEBOARD_FAB2(SCH_1):PAGE79
     6    GND @BASEBOARD_FAB2_LIB.BASEBOARD_FAB2(SCH_1):GND    I43 @BASEBOARD_FAB2_LIB.BASEBOARD_FAB2(SCH_1):PAGE79
     9    GND @BASEBOARD_FAB2_LIB.BASEBOARD_FAB2(SCH_1):GND    I43 @BASEBOARD_FAB2_LIB.BASEBOARD_FAB2(SCH_1):PAGE79
    11    GND @BASEBOARD_FAB2_LIB.BASEBOARD_FAB2(SCH_1):GND    I43 @BASEBOARD_FAB2_LIB.BASEBOARD_FAB2(SCH_1):PAGE79
    13    GND @BASEBOARD_FAB2_LIB.BASEBOARD_FAB2(SCH_1):GND    I43 @BASEBOARD_FAB2_LIB.BASEBOARD_FAB2(SCH_1):PAGE79
    15    GND @BASEBOARD_FAB2_LIB.BASEBOARD_FAB2(SCH_1):GND    I43 @BASEBOARD_FAB2_LIB.BASEBOARD_FAB2(SCH_1):PAGE79
    17    GND @BASEBOARD_FAB2_LIB.BASEBOARD_FAB2(SCH_1):GND    I43 @BASEBOARD_FAB2_LIB.BASEBOARD_FAB2(SCH_1):PAGE79
    20    GND @BASEBOARD_FAB2_LIB.BASEBOARD_FAB2(SCH_1):GND    I43 @BASEBOARD_FAB2_LIB.BASEBOARD_FAB2(SCH_1):PAGE79
    22    GND @BASEBOARD_FAB2_LIB.BASEBOARD_FAB2(SCH_1):GND    I43 @BASEBOARD_FAB2_LIB.BASEBOARD_FAB2(SCH_1):PAGE79
    24    GND @BASEBOARD_FAB2_LIB.BASEBOARD_FAB2(SCH_1):GND    I43 @BASEBOARD_FAB2_LIB.BASEBOARD_FAB2(SCH_1):PAGE79
    26    GND @BASEBOARD_FAB2_LIB.BASEBOARD_FAB2(SCH_1):GND    I43 @BASEBOARD_FAB2_LIB.BASEBOARD_FAB2(SCH_1):PAGE79
    28    GND @BASEBOARD_FAB2_LIB.BASEBOARD_FAB2(SCH_1):GND    I43 @BASEBOARD_FAB2_LIB.BASEBOARD_FAB2(SCH_1):PAGE79
    31    GND @BASEBOARD_FAB2_LIB.BASEBOARD_FAB2(SCH_1):GND    I43 @BASEBOARD_FAB2_LIB.BASEBOARD_FAB2(SCH_1):PAGE79
    33    GND @BASEBOARD_FAB2_LIB.BASEBOARD_FAB2(SCH_1):GND    I43 @BASEBOARD_FAB2_LIB.BASEBOARD_FAB2(SCH_1):PAGE79
    35    GND @BASEBOARD_FAB2_LIB.BASEBOARD_FAB2(SCH_1):GND    I43 @BASEBOARD_FAB2_LIB.BASEBOARD_FAB2(SCH_1):PAGE79
    37    GND @BASEBOARD_FAB2_LIB.BASEBOARD_FAB2(SCH_1):GND    I43 @BASEBOARD_FAB2_LIB.BASEBOARD_FAB2(SCH_1):PAGE79
    39    GND @BASEBOARD_FAB2_LIB.BASEBOARD_FAB2(SCH_1):GND    I43 @BASEBOARD_FAB2_LIB.BASEBOARD_FAB2(SCH_1):PAGE79
    42    GND @BASEBOARD_FAB2_LIB.BASEBOARD_FAB2(SCH_1):GND    I43 @BASEBOARD_FAB2_LIB.BASEBOARD_FAB2(SCH_1):PAGE79
    44    GND @BASEBOARD_FAB2_LIB.BASEBOARD_FAB2(SCH_1):GND    I43 @BASEBOARD_FAB2_LIB.BASEBOARD_FAB2(SCH_1):PAGE79
    46    GND @BASEBOARD_FAB2_LIB.BASEBOARD_FAB2(SCH_1):GND    I43 @BASEBOARD_FAB2_LIB.BASEBOARD_FAB2(SCH_1):PAGE79
    48    GND @BASEBOARD_FAB2_LIB.BASEBOARD_FAB2(SCH_1):GND    I43 @BASEBOARD_FAB2_LIB.BASEBOARD_FAB2(SCH_1):PAGE79
    50    GND @BASEBOARD_FAB2_LIB.BASEBOARD_FAB2(SCH_1):GND    I43 @BASEBOARD_FAB2_LIB.BASEBOARD_FAB2(SCH_1):PAGE79
    53    GND @BASEBOARD_FAB2_LIB.BASEBOARD_FAB2(SCH_1):GND    I43 @BASEBOARD_FAB2_LIB.BASEBOARD_FAB2(SCH_1):PAGE79
    55    GND @BASEBOARD_FAB2_LIB.BASEBOARD_FAB2(SCH_1):GND    I43 @BASEBOARD_FAB2_LIB.BASEBOARD_FAB2(SCH_1):PAGE79
    57    GND @BASEBOARD_FAB2_LIB.BASEBOARD_FAB2(SCH_1):GND    I43 @BASEBOARD_FAB2_LIB.BASEBOARD_FAB2(SCH_1):PAGE79
    94    GND @BASEBOARD_FAB2_LIB.BASEBOARD_FAB2(SCH_1):GND    I43 @BASEBOARD_FAB2_LIB.BASEBOARD_FAB2(SCH_1):PAGE79
    96    GND @BASEBOARD_FAB2_LIB.BASEBOARD_FAB2(SCH_1):GND    I43 @BASEBOARD_FAB2_LIB.BASEBOARD_FAB2(SCH_1):PAGE79
    98    GND @BASEBOARD_FAB2_LIB.BASEBOARD_FAB2(SCH_1):GND    I43 @BASEBOARD_FAB2_LIB.BASEBOARD_FAB2(SCH_1):PAGE79
   101    GND @BASEBOARD_FAB2_LIB.BASEBOARD_FAB2(SCH_1):GND    I43 @BASEBOARD_FAB2_LIB.BASEBOARD_FAB2(SCH_1):PAGE79
   103    GND @BASEBOARD_FAB2_LIB.BASEBOARD_FAB2(SCH_1):GND    I43 @BASEBOARD_FAB2_LIB.BASEBOARD_FAB2(SCH_1):PAGE79
   105    GND @BASEBOARD_FAB2_LIB.BASEBOARD_FAB2(SCH_1):GND    I43 @BASEBOARD_FAB2_LIB.BASEBOARD_FAB2(SCH_1):PAGE79
   107    GND @BASEBOARD_FAB2_LIB.BASEBOARD_FAB2(SCH_1):GND    I43 @BASEBOARD_FAB2_LIB.BASEBOARD_FAB2(SCH_1):PAGE79
   109    GND @BASEBOARD_FAB2_LIB.BASEBOARD_FAB2(SCH_1):GND    I43 @BASEBOARD_FAB2_LIB.BASEBOARD_FAB2(SCH_1):PAGE79
   112    GND @BASEBOARD_FAB2_LIB.BASEBOARD_FAB2(SCH_1):GND    I43 @BASEBOARD_FAB2_LIB.BASEBOARD_FAB2(SCH_1):PAGE79
   114    GND @BASEBOARD_FAB2_LIB.BASEBOARD_FAB2(SCH_1):GND    I43 @BASEBOARD_FAB2_LIB.BASEBOARD_FAB2(SCH_1):PAGE79
   116    GND @BASEBOARD_FAB2_LIB.BASEBOARD_FAB2(SCH_1):GND    I43 @BASEBOARD_FAB2_LIB.BASEBOARD_FAB2(SCH_1):PAGE79
   118    GND @BASEBOARD_FAB2_LIB.BASEBOARD_FAB2(SCH_1):GND    I43 @BASEBOARD_FAB2_LIB.BASEBOARD_FAB2(SCH_1):PAGE79
   120    GND @BASEBOARD_FAB2_LIB.BASEBOARD_FAB2(SCH_1):GND    I43 @BASEBOARD_FAB2_LIB.BASEBOARD_FAB2(SCH_1):PAGE79
   123    GND @BASEBOARD_FAB2_LIB.BASEBOARD_FAB2(SCH_1):GND    I43 @BASEBOARD_FAB2_LIB.BASEBOARD_FAB2(SCH_1):PAGE79
   125    GND @BASEBOARD_FAB2_LIB.BASEBOARD_FAB2(SCH_1):GND    I43 @BASEBOARD_FAB2_LIB.BASEBOARD_FAB2(SCH_1):PAGE79
   127    GND @BASEBOARD_FAB2_LIB.BASEBOARD_FAB2(SCH_1):GND    I43 @BASEBOARD_FAB2_LIB.BASEBOARD_FAB2(SCH_1):PAGE79
   129    GND @BASEBOARD_FAB2_LIB.BASEBOARD_FAB2(SCH_1):GND    I43 @BASEBOARD_FAB2_LIB.BASEBOARD_FAB2(SCH_1):PAGE79
   131    GND @BASEBOARD_FAB2_LIB.BASEBOARD_FAB2(SCH_1):GND    I43 @BASEBOARD_FAB2_LIB.BASEBOARD_FAB2(SCH_1):PAGE79
   134    GND @BASEBOARD_FAB2_LIB.BASEBOARD_FAB2(SCH_1):GND    I43 @BASEBOARD_FAB2_LIB.BASEBOARD_FAB2(SCH_1):PAGE79
   136    GND @BASEBOARD_FAB2_LIB.BASEBOARD_FAB2(SCH_1):GND    I43 @BASEBOARD_FAB2_LIB.BASEBOARD_FAB2(SCH_1):PAGE79
   138    GND @BASEBOARD_FAB2_LIB.BASEBOARD_FAB2(SCH_1):GND    I43 @BASEBOARD_FAB2_LIB.BASEBOARD_FAB2(SCH_1):PAGE79
   147    GND @BASEBOARD_FAB2_LIB.BASEBOARD_FAB2(SCH_1):GND    I43 @BASEBOARD_FAB2_LIB.BASEBOARD_FAB2(SCH_1):PAGE79
   149    GND @BASEBOARD_FAB2_LIB.BASEBOARD_FAB2(SCH_1):GND    I43 @BASEBOARD_FAB2_LIB.BASEBOARD_FAB2(SCH_1):PAGE79
   151    GND @BASEBOARD_FAB2_LIB.BASEBOARD_FAB2(SCH_1):GND    I43 @BASEBOARD_FAB2_LIB.BASEBOARD_FAB2(SCH_1):PAGE79
   154    GND @BASEBOARD_FAB2_LIB.BASEBOARD_FAB2(SCH_1):GND    I43 @BASEBOARD_FAB2_LIB.BASEBOARD_FAB2(SCH_1):PAGE79
   156    GND @BASEBOARD_FAB2_LIB.BASEBOARD_FAB2(SCH_1):GND    I43 @BASEBOARD_FAB2_LIB.BASEBOARD_FAB2(SCH_1):PAGE79
   158    GND @BASEBOARD_FAB2_LIB.BASEBOARD_FAB2(SCH_1):GND    I43 @BASEBOARD_FAB2_LIB.BASEBOARD_FAB2(SCH_1):PAGE79
   160    GND @BASEBOARD_FAB2_LIB.BASEBOARD_FAB2(SCH_1):GND    I43 @BASEBOARD_FAB2_LIB.BASEBOARD_FAB2(SCH_1):PAGE79
   162    GND @BASEBOARD_FAB2_LIB.BASEBOARD_FAB2(SCH_1):GND    I43 @BASEBOARD_FAB2_LIB.BASEBOARD_FAB2(SCH_1):PAGE79
   165    GND @BASEBOARD_FAB2_LIB.BASEBOARD_FAB2(SCH_1):GND    I43 @BASEBOARD_FAB2_LIB.BASEBOARD_FAB2(SCH_1):PAGE79
   167    GND @BASEBOARD_FAB2_LIB.BASEBOARD_FAB2(SCH_1):GND    I43 @BASEBOARD_FAB2_LIB.BASEBOARD_FAB2(SCH_1):PAGE79
   169    GND @BASEBOARD_FAB2_LIB.BASEBOARD_FAB2(SCH_1):GND    I43 @BASEBOARD_FAB2_LIB.BASEBOARD_FAB2(SCH_1):PAGE79
   171    GND @BASEBOARD_FAB2_LIB.BASEBOARD_FAB2(SCH_1):GND    I43 @BASEBOARD_FAB2_LIB.BASEBOARD_FAB2(SCH_1):PAGE79
   173    GND @BASEBOARD_FAB2_LIB.BASEBOARD_FAB2(SCH_1):GND    I43 @BASEBOARD_FAB2_LIB.BASEBOARD_FAB2(SCH_1):PAGE79
   176    GND @BASEBOARD_FAB2_LIB.BASEBOARD_FAB2(SCH_1):GND    I43 @BASEBOARD_FAB2_LIB.BASEBOARD_FAB2(SCH_1):PAGE79
   178    GND @BASEBOARD_FAB2_LIB.BASEBOARD_FAB2(SCH_1):GND    I43 @BASEBOARD_FAB2_LIB.BASEBOARD_FAB2(SCH_1):PAGE79
   180    GND @BASEBOARD_FAB2_LIB.BASEBOARD_FAB2(SCH_1):GND    I43 @BASEBOARD_FAB2_LIB.BASEBOARD_FAB2(SCH_1):PAGE79
   182    GND @BASEBOARD_FAB2_LIB.BASEBOARD_FAB2(SCH_1):GND    I43 @BASEBOARD_FAB2_LIB.BASEBOARD_FAB2(SCH_1):PAGE79
   184    GND @BASEBOARD_FAB2_LIB.BASEBOARD_FAB2(SCH_1):GND    I43 @BASEBOARD_FAB2_LIB.BASEBOARD_FAB2(SCH_1):PAGE79
   187    GND @BASEBOARD_FAB2_LIB.BASEBOARD_FAB2(SCH_1):GND    I43 @BASEBOARD_FAB2_LIB.BASEBOARD_FAB2(SCH_1):PAGE79
   189    GND @BASEBOARD_FAB2_LIB.BASEBOARD_FAB2(SCH_1):GND    I43 @BASEBOARD_FAB2_LIB.BASEBOARD_FAB2(SCH_1):PAGE79
   191    GND @BASEBOARD_FAB2_LIB.BASEBOARD_FAB2(SCH_1):GND    I43 @BASEBOARD_FAB2_LIB.BASEBOARD_FAB2(SCH_1):PAGE79
   193    GND @BASEBOARD_FAB2_LIB.BASEBOARD_FAB2(SCH_1):GND    I43 @BASEBOARD_FAB2_LIB.BASEBOARD_FAB2(SCH_1):PAGE79
   195    GND @BASEBOARD_FAB2_LIB.BASEBOARD_FAB2(SCH_1):GND    I43 @BASEBOARD_FAB2_LIB.BASEBOARD_FAB2(SCH_1):PAGE79
   198    GND @BASEBOARD_FAB2_LIB.BASEBOARD_FAB2(SCH_1):GND    I43 @BASEBOARD_FAB2_LIB.BASEBOARD_FAB2(SCH_1):PAGE79
   200    GND @BASEBOARD_FAB2_LIB.BASEBOARD_FAB2(SCH_1):GND    I43 @BASEBOARD_FAB2_LIB.BASEBOARD_FAB2(SCH_1):PAGE79
   202    GND @BASEBOARD_FAB2_LIB.BASEBOARD_FAB2(SCH_1):GND    I43 @BASEBOARD_FAB2_LIB.BASEBOARD_FAB2(SCH_1):PAGE79
   239    GND @BASEBOARD_FAB2_LIB.BASEBOARD_FAB2(SCH_1):GND    I43 @BASEBOARD_FAB2_LIB.BASEBOARD_FAB2(SCH_1):PAGE79
   241    GND @BASEBOARD_FAB2_LIB.BASEBOARD_FAB2(SCH_1):GND    I43 @BASEBOARD_FAB2_LIB.BASEBOARD_FAB2(SCH_1):PAGE79
   243    GND @BASEBOARD_FAB2_LIB.BASEBOARD_FAB2(SCH_1):GND    I43 @BASEBOARD_FAB2_LIB.BASEBOARD_FAB2(SCH_1):PAGE79
   246    GND @BASEBOARD_FAB2_LIB.BASEBOARD_FAB2(SCH_1):GND    I43 @BASEBOARD_FAB2_LIB.BASEBOARD_FAB2(SCH_1):PAGE79
   248    GND @BASEBOARD_FAB2_LIB.BASEBOARD_FAB2(SCH_1):GND    I43 @BASEBOARD_FAB2_LIB.BASEBOARD_FAB2(SCH_1):PAGE79
   250    GND @BASEBOARD_FAB2_LIB.BASEBOARD_FAB2(SCH_1):GND    I43 @BASEBOARD_FAB2_LIB.BASEBOARD_FAB2(SCH_1):PAGE79
   252    GND @BASEBOARD_FAB2_LIB.BASEBOARD_FAB2(SCH_1):GND    I43 @BASEBOARD_FAB2_LIB.BASEBOARD_FAB2(SCH_1):PAGE79
   254    GND @BASEBOARD_FAB2_LIB.BASEBOARD_FAB2(SCH_1):GND    I43 @BASEBOARD_FAB2_LIB.BASEBOARD_FAB2(SCH_1):PAGE79
   257    GND @BASEBOARD_FAB2_LIB.BASEBOARD_FAB2(SCH_1):GND    I43 @BASEBOARD_FAB2_LIB.BASEBOARD_FAB2(SCH_1):PAGE79
   259    GND @BASEBOARD_FAB2_LIB.BASEBOARD_FAB2(SCH_1):GND    I43 @BASEBOARD_FAB2_LIB.BASEBOARD_FAB2(SCH_1):PAGE79
   261    GND @BASEBOARD_FAB2_LIB.BASEBOARD_FAB2(SCH_1):GND    I43 @BASEBOARD_FAB2_LIB.BASEBOARD_FAB2(SCH_1):PAGE79
   263    GND @BASEBOARD_FAB2_LIB.BASEBOARD_FAB2(SCH_1):GND    I43 @BASEBOARD_FAB2_LIB.BASEBOARD_FAB2(SCH_1):PAGE79
   265    GND @BASEBOARD_FAB2_LIB.BASEBOARD_FAB2(SCH_1):GND    I43 @BASEBOARD_FAB2_LIB.BASEBOARD_FAB2(SCH_1):PAGE79
   268    GND @BASEBOARD_FAB2_LIB.BASEBOARD_FAB2(SCH_1):GND    I43 @BASEBOARD_FAB2_LIB.BASEBOARD_FAB2(SCH_1):PAGE79
   270    GND @BASEBOARD_FAB2_LIB.BASEBOARD_FAB2(SCH_1):GND    I43 @BASEBOARD_FAB2_LIB.BASEBOARD_FAB2(SCH_1):PAGE79
   272    GND @BASEBOARD_FAB2_LIB.BASEBOARD_FAB2(SCH_1):GND    I43 @BASEBOARD_FAB2_LIB.BASEBOARD_FAB2(SCH_1):PAGE79
   274    GND @BASEBOARD_FAB2_LIB.BASEBOARD_FAB2(SCH_1):GND    I43 @BASEBOARD_FAB2_LIB.BASEBOARD_FAB2(SCH_1):PAGE79
   276    GND @BASEBOARD_FAB2_LIB.BASEBOARD_FAB2(SCH_1):GND    I43 @BASEBOARD_FAB2_LIB.BASEBOARD_FAB2(SCH_1):PAGE79
   279    GND @BASEBOARD_FAB2_LIB.BASEBOARD_FAB2(SCH_1):GND    I43 @BASEBOARD_FAB2_LIB.BASEBOARD_FAB2(SCH_1):PAGE79
   281    GND @BASEBOARD_FAB2_LIB.BASEBOARD_FAB2(SCH_1):GND    I43 @BASEBOARD_FAB2_LIB.BASEBOARD_FAB2(SCH_1):PAGE79
   283    GND @BASEBOARD_FAB2_LIB.BASEBOARD_FAB2(SCH_1):GND    I43 @BASEBOARD_FAB2_LIB.BASEBOARD_FAB2(SCH_1):PAGE79
     1 P12V_NVDIMM_GHJ @BASEBOARD_FAB2_LIB.BASEBOARD_FAB2(SCH_1):P12V_NVDIMM_GHJ   I169 @BASEBOARD_FAB2_LIB.BASEBOARD_FAB2(SCH_1):PAGE79
   145 P12V_NVDIMM_GHJ @BASEBOARD_FAB2_LIB.BASEBOARD_FAB2(SCH_1):P12V_NVDIMM_GHJ   I169 @BASEBOARD_FAB2_LIB.BASEBOARD_FAB2(SCH_1):PAGE79
    59 PVDDQ_GHJ @BASEBOARD_FAB2_LIB.BASEBOARD_FAB2(SCH_1):PVDDQ_GHJ   I169 @BASEBOARD_FAB2_LIB.BASEBOARD_FAB2(SCH_1):PAGE79
    61 PVDDQ_GHJ @BASEBOARD_FAB2_LIB.BASEBOARD_FAB2(SCH_1):PVDDQ_GHJ   I169 @BASEBOARD_FAB2_LIB.BASEBOARD_FAB2(SCH_1):PAGE79
    64 PVDDQ_GHJ @BASEBOARD_FAB2_LIB.BASEBOARD_FAB2(SCH_1):PVDDQ_GHJ   I169 @BASEBOARD_FAB2_LIB.BASEBOARD_FAB2(SCH_1):PAGE79
    67 PVDDQ_GHJ @BASEBOARD_FAB2_LIB.BASEBOARD_FAB2(SCH_1):PVDDQ_GHJ   I169 @BASEBOARD_FAB2_LIB.BASEBOARD_FAB2(SCH_1):PAGE79
    70 PVDDQ_GHJ @BASEBOARD_FAB2_LIB.BASEBOARD_FAB2(SCH_1):PVDDQ_GHJ   I169 @BASEBOARD_FAB2_LIB.BASEBOARD_FAB2(SCH_1):PAGE79
    73 PVDDQ_GHJ @BASEBOARD_FAB2_LIB.BASEBOARD_FAB2(SCH_1):PVDDQ_GHJ   I169 @BASEBOARD_FAB2_LIB.BASEBOARD_FAB2(SCH_1):PAGE79
    76 PVDDQ_GHJ @BASEBOARD_FAB2_LIB.BASEBOARD_FAB2(SCH_1):PVDDQ_GHJ   I169 @BASEBOARD_FAB2_LIB.BASEBOARD_FAB2(SCH_1):PAGE79
    80 PVDDQ_GHJ @BASEBOARD_FAB2_LIB.BASEBOARD_FAB2(SCH_1):PVDDQ_GHJ   I169 @BASEBOARD_FAB2_LIB.BASEBOARD_FAB2(SCH_1):PAGE79
    83 PVDDQ_GHJ @BASEBOARD_FAB2_LIB.BASEBOARD_FAB2(SCH_1):PVDDQ_GHJ   I169 @BASEBOARD_FAB2_LIB.BASEBOARD_FAB2(SCH_1):PAGE79
    85 PVDDQ_GHJ @BASEBOARD_FAB2_LIB.BASEBOARD_FAB2(SCH_1):PVDDQ_GHJ   I169 @BASEBOARD_FAB2_LIB.BASEBOARD_FAB2(SCH_1):PAGE79
    88 PVDDQ_GHJ @BASEBOARD_FAB2_LIB.BASEBOARD_FAB2(SCH_1):PVDDQ_GHJ   I169 @BASEBOARD_FAB2_LIB.BASEBOARD_FAB2(SCH_1):PAGE79
    90 PVDDQ_GHJ @BASEBOARD_FAB2_LIB.BASEBOARD_FAB2(SCH_1):PVDDQ_GHJ   I169 @BASEBOARD_FAB2_LIB.BASEBOARD_FAB2(SCH_1):PAGE79
    92 PVDDQ_GHJ @BASEBOARD_FAB2_LIB.BASEBOARD_FAB2(SCH_1):PVDDQ_GHJ   I169 @BASEBOARD_FAB2_LIB.BASEBOARD_FAB2(SCH_1):PAGE79
   204 PVDDQ_GHJ @BASEBOARD_FAB2_LIB.BASEBOARD_FAB2(SCH_1):PVDDQ_GHJ   I169 @BASEBOARD_FAB2_LIB.BASEBOARD_FAB2(SCH_1):PAGE79
   206 PVDDQ_GHJ @BASEBOARD_FAB2_LIB.BASEBOARD_FAB2(SCH_1):PVDDQ_GHJ   I169 @BASEBOARD_FAB2_LIB.BASEBOARD_FAB2(SCH_1):PAGE79
   209 PVDDQ_GHJ @BASEBOARD_FAB2_LIB.BASEBOARD_FAB2(SCH_1):PVDDQ_GHJ   I169 @BASEBOARD_FAB2_LIB.BASEBOARD_FAB2(SCH_1):PAGE79
   212 PVDDQ_GHJ @BASEBOARD_FAB2_LIB.BASEBOARD_FAB2(SCH_1):PVDDQ_GHJ   I169 @BASEBOARD_FAB2_LIB.BASEBOARD_FAB2(SCH_1):PAGE79
   215 PVDDQ_GHJ @BASEBOARD_FAB2_LIB.BASEBOARD_FAB2(SCH_1):PVDDQ_GHJ   I169 @BASEBOARD_FAB2_LIB.BASEBOARD_FAB2(SCH_1):PAGE79
   217 PVDDQ_GHJ @BASEBOARD_FAB2_LIB.BASEBOARD_FAB2(SCH_1):PVDDQ_GHJ   I169 @BASEBOARD_FAB2_LIB.BASEBOARD_FAB2(SCH_1):PAGE79
   220 PVDDQ_GHJ @BASEBOARD_FAB2_LIB.BASEBOARD_FAB2(SCH_1):PVDDQ_GHJ   I169 @BASEBOARD_FAB2_LIB.BASEBOARD_FAB2(SCH_1):PAGE79
   223 PVDDQ_GHJ @BASEBOARD_FAB2_LIB.BASEBOARD_FAB2(SCH_1):PVDDQ_GHJ   I169 @BASEBOARD_FAB2_LIB.BASEBOARD_FAB2(SCH_1):PAGE79
   226 PVDDQ_GHJ @BASEBOARD_FAB2_LIB.BASEBOARD_FAB2(SCH_1):PVDDQ_GHJ   I169 @BASEBOARD_FAB2_LIB.BASEBOARD_FAB2(SCH_1):PAGE79
   229 PVDDQ_GHJ @BASEBOARD_FAB2_LIB.BASEBOARD_FAB2(SCH_1):PVDDQ_GHJ   I169 @BASEBOARD_FAB2_LIB.BASEBOARD_FAB2(SCH_1):PAGE79
   231 PVDDQ_GHJ @BASEBOARD_FAB2_LIB.BASEBOARD_FAB2(SCH_1):PVDDQ_GHJ   I169 @BASEBOARD_FAB2_LIB.BASEBOARD_FAB2(SCH_1):PAGE79
   233 PVDDQ_GHJ @BASEBOARD_FAB2_LIB.BASEBOARD_FAB2(SCH_1):PVDDQ_GHJ   I169 @BASEBOARD_FAB2_LIB.BASEBOARD_FAB2(SCH_1):PAGE79
   236 PVDDQ_GHJ @BASEBOARD_FAB2_LIB.BASEBOARD_FAB2(SCH_1):PVDDQ_GHJ   I169 @BASEBOARD_FAB2_LIB.BASEBOARD_FAB2(SCH_1):PAGE79
   142 PVPP_GHJ @BASEBOARD_FAB2_LIB.BASEBOARD_FAB2(SCH_1):PVPP_GHJ   I169 @BASEBOARD_FAB2_LIB.BASEBOARD_FAB2(SCH_1):PAGE79
   143 PVPP_GHJ @BASEBOARD_FAB2_LIB.BASEBOARD_FAB2(SCH_1):PVPP_GHJ   I169 @BASEBOARD_FAB2_LIB.BASEBOARD_FAB2(SCH_1):PAGE79
   288 PVPP_GHJ @BASEBOARD_FAB2_LIB.BASEBOARD_FAB2(SCH_1):PVPP_GHJ   I169 @BASEBOARD_FAB2_LIB.BASEBOARD_FAB2(SCH_1):PAGE79
   286 PVPP_GHJ @BASEBOARD_FAB2_LIB.BASEBOARD_FAB2(SCH_1):PVPP_GHJ   I169 @BASEBOARD_FAB2_LIB.BASEBOARD_FAB2(SCH_1):PAGE79
   287 PVPP_GHJ @BASEBOARD_FAB2_LIB.BASEBOARD_FAB2(SCH_1):PVPP_GHJ   I169 @BASEBOARD_FAB2_LIB.BASEBOARD_FAB2(SCH_1):PAGE79
    77 PVTT_GHJ @BASEBOARD_FAB2_LIB.BASEBOARD_FAB2(SCH_1):PVTT_GHJ   I169 @BASEBOARD_FAB2_LIB.BASEBOARD_FAB2(SCH_1):PAGE79
   221 PVTT_GHJ @BASEBOARD_FAB2_LIB.BASEBOARD_FAB2(SCH_1):PVTT_GHJ   I169 @BASEBOARD_FAB2_LIB.BASEBOARD_FAB2(SCH_1):PAGE79

J1G3 SCONN288_H44441004_PIP-SCONN,HA
    79 M_J_MA<0> @BASEBOARD_FAB2_LIB.BASEBOARD_FAB2(SCH_1):M_J_MA(0)   I186 @BASEBOARD_FAB2_LIB.BASEBOARD_FAB2(SCH_1):PAGE81
    72 M_J_MA<1> @BASEBOARD_FAB2_LIB.BASEBOARD_FAB2(SCH_1):M_J_MA(1)   I186 @BASEBOARD_FAB2_LIB.BASEBOARD_FAB2(SCH_1):PAGE81
   225 M_J_MA<10> @BASEBOARD_FAB2_LIB.BASEBOARD_FAB2(SCH_1):M_J_MA(10)   I186 @BASEBOARD_FAB2_LIB.BASEBOARD_FAB2(SCH_1):PAGE81
   210 M_J_MA<11> @BASEBOARD_FAB2_LIB.BASEBOARD_FAB2(SCH_1):M_J_MA(11)   I186 @BASEBOARD_FAB2_LIB.BASEBOARD_FAB2(SCH_1):PAGE81
    65 M_J_MA<12> @BASEBOARD_FAB2_LIB.BASEBOARD_FAB2(SCH_1):M_J_MA(12)   I186 @BASEBOARD_FAB2_LIB.BASEBOARD_FAB2(SCH_1):PAGE81
   232 M_J_MA<13> @BASEBOARD_FAB2_LIB.BASEBOARD_FAB2(SCH_1):M_J_MA(13)   I186 @BASEBOARD_FAB2_LIB.BASEBOARD_FAB2(SCH_1):PAGE81
   228 M_J_MA<14> @BASEBOARD_FAB2_LIB.BASEBOARD_FAB2(SCH_1):M_J_MA(14)   I186 @BASEBOARD_FAB2_LIB.BASEBOARD_FAB2(SCH_1):PAGE81
    86 M_J_MA<15> @BASEBOARD_FAB2_LIB.BASEBOARD_FAB2(SCH_1):M_J_MA(15)   I186 @BASEBOARD_FAB2_LIB.BASEBOARD_FAB2(SCH_1):PAGE81
    82 M_J_MA<16> @BASEBOARD_FAB2_LIB.BASEBOARD_FAB2(SCH_1):M_J_MA(16)   I186 @BASEBOARD_FAB2_LIB.BASEBOARD_FAB2(SCH_1):PAGE81
   234 M_J_MA<17> @BASEBOARD_FAB2_LIB.BASEBOARD_FAB2(SCH_1):M_J_MA(17)   I186 @BASEBOARD_FAB2_LIB.BASEBOARD_FAB2(SCH_1):PAGE81
   216 M_J_MA<2> @BASEBOARD_FAB2_LIB.BASEBOARD_FAB2(SCH_1):M_J_MA(2)   I186 @BASEBOARD_FAB2_LIB.BASEBOARD_FAB2(SCH_1):PAGE81
    71 M_J_MA<3> @BASEBOARD_FAB2_LIB.BASEBOARD_FAB2(SCH_1):M_J_MA(3)   I186 @BASEBOARD_FAB2_LIB.BASEBOARD_FAB2(SCH_1):PAGE81
   214 M_J_MA<4> @BASEBOARD_FAB2_LIB.BASEBOARD_FAB2(SCH_1):M_J_MA(4)   I186 @BASEBOARD_FAB2_LIB.BASEBOARD_FAB2(SCH_1):PAGE81
   213 M_J_MA<5> @BASEBOARD_FAB2_LIB.BASEBOARD_FAB2(SCH_1):M_J_MA(5)   I186 @BASEBOARD_FAB2_LIB.BASEBOARD_FAB2(SCH_1):PAGE81
    69 M_J_MA<6> @BASEBOARD_FAB2_LIB.BASEBOARD_FAB2(SCH_1):M_J_MA(6)   I186 @BASEBOARD_FAB2_LIB.BASEBOARD_FAB2(SCH_1):PAGE81
   211 M_J_MA<7> @BASEBOARD_FAB2_LIB.BASEBOARD_FAB2(SCH_1):M_J_MA(7)   I186 @BASEBOARD_FAB2_LIB.BASEBOARD_FAB2(SCH_1):PAGE81
    68 M_J_MA<8> @BASEBOARD_FAB2_LIB.BASEBOARD_FAB2(SCH_1):M_J_MA(8)   I186 @BASEBOARD_FAB2_LIB.BASEBOARD_FAB2(SCH_1):PAGE81
    66 M_J_MA<9> @BASEBOARD_FAB2_LIB.BASEBOARD_FAB2(SCH_1):M_J_MA(9)   I186 @BASEBOARD_FAB2_LIB.BASEBOARD_FAB2(SCH_1):PAGE81
    62 M_J_ACT_N @BASEBOARD_FAB2_LIB.BASEBOARD_FAB2(SCH_1):M_J_ACT_N   I186 @BASEBOARD_FAB2_LIB.BASEBOARD_FAB2(SCH_1):PAGE81
   208 M_J_ALERT_N @BASEBOARD_FAB2_LIB.BASEBOARD_FAB2(SCH_1):M_J_ALERT_N   I186 @BASEBOARD_FAB2_LIB.BASEBOARD_FAB2(SCH_1):PAGE81
   224 M_J_BA<1> @BASEBOARD_FAB2_LIB.BASEBOARD_FAB2(SCH_1):M_J_BA(1)   I186 @BASEBOARD_FAB2_LIB.BASEBOARD_FAB2(SCH_1):PAGE81
    81 M_J_BA<0> @BASEBOARD_FAB2_LIB.BASEBOARD_FAB2(SCH_1):M_J_BA(0)   I186 @BASEBOARD_FAB2_LIB.BASEBOARD_FAB2(SCH_1):PAGE81
   207 M_J_BG<1> @BASEBOARD_FAB2_LIB.BASEBOARD_FAB2(SCH_1):M_J_BG(1)   I186 @BASEBOARD_FAB2_LIB.BASEBOARD_FAB2(SCH_1):PAGE81
    63 M_J_BG<0> @BASEBOARD_FAB2_LIB.BASEBOARD_FAB2(SCH_1):M_J_BG(0)   I186 @BASEBOARD_FAB2_LIB.BASEBOARD_FAB2(SCH_1):PAGE81
   235 M_J_C<2> @BASEBOARD_FAB2_LIB.BASEBOARD_FAB2(SCH_1):M_J_C(2)   I186 @BASEBOARD_FAB2_LIB.BASEBOARD_FAB2(SCH_1):PAGE81
   199 M_J_ECC<6> @BASEBOARD_FAB2_LIB.BASEBOARD_FAB2(SCH_1):M_J_ECC(6)   I186 @BASEBOARD_FAB2_LIB.BASEBOARD_FAB2(SCH_1):PAGE81
    54 M_J_ECC<7> @BASEBOARD_FAB2_LIB.BASEBOARD_FAB2(SCH_1):M_J_ECC(7)   I186 @BASEBOARD_FAB2_LIB.BASEBOARD_FAB2(SCH_1):PAGE81
   192 M_J_ECC<4> @BASEBOARD_FAB2_LIB.BASEBOARD_FAB2(SCH_1):M_J_ECC(4)   I186 @BASEBOARD_FAB2_LIB.BASEBOARD_FAB2(SCH_1):PAGE81
    47 M_J_ECC<5> @BASEBOARD_FAB2_LIB.BASEBOARD_FAB2(SCH_1):M_J_ECC(5)   I186 @BASEBOARD_FAB2_LIB.BASEBOARD_FAB2(SCH_1):PAGE81
   201 M_J_ECC<2> @BASEBOARD_FAB2_LIB.BASEBOARD_FAB2(SCH_1):M_J_ECC(2)   I186 @BASEBOARD_FAB2_LIB.BASEBOARD_FAB2(SCH_1):PAGE81
    56 M_J_ECC<3> @BASEBOARD_FAB2_LIB.BASEBOARD_FAB2(SCH_1):M_J_ECC(3)   I186 @BASEBOARD_FAB2_LIB.BASEBOARD_FAB2(SCH_1):PAGE81
   194 M_J_ECC<0> @BASEBOARD_FAB2_LIB.BASEBOARD_FAB2(SCH_1):M_J_ECC(0)   I186 @BASEBOARD_FAB2_LIB.BASEBOARD_FAB2(SCH_1):PAGE81
    49 M_J_ECC<1> @BASEBOARD_FAB2_LIB.BASEBOARD_FAB2(SCH_1):M_J_ECC(1)   I186 @BASEBOARD_FAB2_LIB.BASEBOARD_FAB2(SCH_1):PAGE81
    75 M_J_CLK_DN<0> @BASEBOARD_FAB2_LIB.BASEBOARD_FAB2(SCH_1):M_J_CLK_DN(0)   I186 @BASEBOARD_FAB2_LIB.BASEBOARD_FAB2(SCH_1):PAGE81
    74 M_J_CLK_DP<0> @BASEBOARD_FAB2_LIB.BASEBOARD_FAB2(SCH_1):M_J_CLK_DP(0)   I186 @BASEBOARD_FAB2_LIB.BASEBOARD_FAB2(SCH_1):PAGE81
   219 M_J_CLK_DN<1> @BASEBOARD_FAB2_LIB.BASEBOARD_FAB2(SCH_1):M_J_CLK_DN(1)   I186 @BASEBOARD_FAB2_LIB.BASEBOARD_FAB2(SCH_1):PAGE81
   218 M_J_CLK_DP<1> @BASEBOARD_FAB2_LIB.BASEBOARD_FAB2(SCH_1):M_J_CLK_DP(1)   I186 @BASEBOARD_FAB2_LIB.BASEBOARD_FAB2(SCH_1):PAGE81
   203 M_J_CKE<1> @BASEBOARD_FAB2_LIB.BASEBOARD_FAB2(SCH_1):M_J_CKE(1)   I186 @BASEBOARD_FAB2_LIB.BASEBOARD_FAB2(SCH_1):PAGE81
    60 M_J_CKE<0> @BASEBOARD_FAB2_LIB.BASEBOARD_FAB2(SCH_1):M_J_CKE(0)   I186 @BASEBOARD_FAB2_LIB.BASEBOARD_FAB2(SCH_1):PAGE81
   280 M_J_DQ<62> @BASEBOARD_FAB2_LIB.BASEBOARD_FAB2(SCH_1):M_J_DQ(62)   I186 @BASEBOARD_FAB2_LIB.BASEBOARD_FAB2(SCH_1):PAGE81
   135 M_J_DQ<63> @BASEBOARD_FAB2_LIB.BASEBOARD_FAB2(SCH_1):M_J_DQ(63)   I186 @BASEBOARD_FAB2_LIB.BASEBOARD_FAB2(SCH_1):PAGE81
   273 M_J_DQ<60> @BASEBOARD_FAB2_LIB.BASEBOARD_FAB2(SCH_1):M_J_DQ(60)   I186 @BASEBOARD_FAB2_LIB.BASEBOARD_FAB2(SCH_1):PAGE81
   128 M_J_DQ<61> @BASEBOARD_FAB2_LIB.BASEBOARD_FAB2(SCH_1):M_J_DQ(61)   I186 @BASEBOARD_FAB2_LIB.BASEBOARD_FAB2(SCH_1):PAGE81
   282 M_J_DQ<58> @BASEBOARD_FAB2_LIB.BASEBOARD_FAB2(SCH_1):M_J_DQ(58)   I186 @BASEBOARD_FAB2_LIB.BASEBOARD_FAB2(SCH_1):PAGE81
   137 M_J_DQ<59> @BASEBOARD_FAB2_LIB.BASEBOARD_FAB2(SCH_1):M_J_DQ(59)   I186 @BASEBOARD_FAB2_LIB.BASEBOARD_FAB2(SCH_1):PAGE81
   275 M_J_DQ<56> @BASEBOARD_FAB2_LIB.BASEBOARD_FAB2(SCH_1):M_J_DQ(56)   I186 @BASEBOARD_FAB2_LIB.BASEBOARD_FAB2(SCH_1):PAGE81
   130 M_J_DQ<57> @BASEBOARD_FAB2_LIB.BASEBOARD_FAB2(SCH_1):M_J_DQ(57)   I186 @BASEBOARD_FAB2_LIB.BASEBOARD_FAB2(SCH_1):PAGE81
   269 M_J_DQ<54> @BASEBOARD_FAB2_LIB.BASEBOARD_FAB2(SCH_1):M_J_DQ(54)   I186 @BASEBOARD_FAB2_LIB.BASEBOARD_FAB2(SCH_1):PAGE81
   124 M_J_DQ<55> @BASEBOARD_FAB2_LIB.BASEBOARD_FAB2(SCH_1):M_J_DQ(55)   I186 @BASEBOARD_FAB2_LIB.BASEBOARD_FAB2(SCH_1):PAGE81
   262 M_J_DQ<52> @BASEBOARD_FAB2_LIB.BASEBOARD_FAB2(SCH_1):M_J_DQ(52)   I186 @BASEBOARD_FAB2_LIB.BASEBOARD_FAB2(SCH_1):PAGE81
   117 M_J_DQ<53> @BASEBOARD_FAB2_LIB.BASEBOARD_FAB2(SCH_1):M_J_DQ(53)   I186 @BASEBOARD_FAB2_LIB.BASEBOARD_FAB2(SCH_1):PAGE81
   271 M_J_DQ<50> @BASEBOARD_FAB2_LIB.BASEBOARD_FAB2(SCH_1):M_J_DQ(50)   I186 @BASEBOARD_FAB2_LIB.BASEBOARD_FAB2(SCH_1):PAGE81
   126 M_J_DQ<51> @BASEBOARD_FAB2_LIB.BASEBOARD_FAB2(SCH_1):M_J_DQ(51)   I186 @BASEBOARD_FAB2_LIB.BASEBOARD_FAB2(SCH_1):PAGE81
   264 M_J_DQ<48> @BASEBOARD_FAB2_LIB.BASEBOARD_FAB2(SCH_1):M_J_DQ(48)   I186 @BASEBOARD_FAB2_LIB.BASEBOARD_FAB2(SCH_1):PAGE81
   119 M_J_DQ<49> @BASEBOARD_FAB2_LIB.BASEBOARD_FAB2(SCH_1):M_J_DQ(49)   I186 @BASEBOARD_FAB2_LIB.BASEBOARD_FAB2(SCH_1):PAGE81
   258 M_J_DQ<46> @BASEBOARD_FAB2_LIB.BASEBOARD_FAB2(SCH_1):M_J_DQ(46)   I186 @BASEBOARD_FAB2_LIB.BASEBOARD_FAB2(SCH_1):PAGE81
   113 M_J_DQ<47> @BASEBOARD_FAB2_LIB.BASEBOARD_FAB2(SCH_1):M_J_DQ(47)   I186 @BASEBOARD_FAB2_LIB.BASEBOARD_FAB2(SCH_1):PAGE81
   251 M_J_DQ<44> @BASEBOARD_FAB2_LIB.BASEBOARD_FAB2(SCH_1):M_J_DQ(44)   I186 @BASEBOARD_FAB2_LIB.BASEBOARD_FAB2(SCH_1):PAGE81
   106 M_J_DQ<45> @BASEBOARD_FAB2_LIB.BASEBOARD_FAB2(SCH_1):M_J_DQ(45)   I186 @BASEBOARD_FAB2_LIB.BASEBOARD_FAB2(SCH_1):PAGE81
   260 M_J_DQ<42> @BASEBOARD_FAB2_LIB.BASEBOARD_FAB2(SCH_1):M_J_DQ(42)   I186 @BASEBOARD_FAB2_LIB.BASEBOARD_FAB2(SCH_1):PAGE81
   115 M_J_DQ<43> @BASEBOARD_FAB2_LIB.BASEBOARD_FAB2(SCH_1):M_J_DQ(43)   I186 @BASEBOARD_FAB2_LIB.BASEBOARD_FAB2(SCH_1):PAGE81
   253 M_J_DQ<40> @BASEBOARD_FAB2_LIB.BASEBOARD_FAB2(SCH_1):M_J_DQ(40)   I186 @BASEBOARD_FAB2_LIB.BASEBOARD_FAB2(SCH_1):PAGE81
   108 M_J_DQ<41> @BASEBOARD_FAB2_LIB.BASEBOARD_FAB2(SCH_1):M_J_DQ(41)   I186 @BASEBOARD_FAB2_LIB.BASEBOARD_FAB2(SCH_1):PAGE81
   247 M_J_DQ<38> @BASEBOARD_FAB2_LIB.BASEBOARD_FAB2(SCH_1):M_J_DQ(38)   I186 @BASEBOARD_FAB2_LIB.BASEBOARD_FAB2(SCH_1):PAGE81
   102 M_J_DQ<39> @BASEBOARD_FAB2_LIB.BASEBOARD_FAB2(SCH_1):M_J_DQ(39)   I186 @BASEBOARD_FAB2_LIB.BASEBOARD_FAB2(SCH_1):PAGE81
   240 M_J_DQ<36> @BASEBOARD_FAB2_LIB.BASEBOARD_FAB2(SCH_1):M_J_DQ(36)   I186 @BASEBOARD_FAB2_LIB.BASEBOARD_FAB2(SCH_1):PAGE81
    95 M_J_DQ<37> @BASEBOARD_FAB2_LIB.BASEBOARD_FAB2(SCH_1):M_J_DQ(37)   I186 @BASEBOARD_FAB2_LIB.BASEBOARD_FAB2(SCH_1):PAGE81
   249 M_J_DQ<34> @BASEBOARD_FAB2_LIB.BASEBOARD_FAB2(SCH_1):M_J_DQ(34)   I186 @BASEBOARD_FAB2_LIB.BASEBOARD_FAB2(SCH_1):PAGE81
   104 M_J_DQ<35> @BASEBOARD_FAB2_LIB.BASEBOARD_FAB2(SCH_1):M_J_DQ(35)   I186 @BASEBOARD_FAB2_LIB.BASEBOARD_FAB2(SCH_1):PAGE81
   242 M_J_DQ<32> @BASEBOARD_FAB2_LIB.BASEBOARD_FAB2(SCH_1):M_J_DQ(32)   I186 @BASEBOARD_FAB2_LIB.BASEBOARD_FAB2(SCH_1):PAGE81
    97 M_J_DQ<33> @BASEBOARD_FAB2_LIB.BASEBOARD_FAB2(SCH_1):M_J_DQ(33)   I186 @BASEBOARD_FAB2_LIB.BASEBOARD_FAB2(SCH_1):PAGE81
   188 M_J_DQ<30> @BASEBOARD_FAB2_LIB.BASEBOARD_FAB2(SCH_1):M_J_DQ(30)   I186 @BASEBOARD_FAB2_LIB.BASEBOARD_FAB2(SCH_1):PAGE81
    43 M_J_DQ<31> @BASEBOARD_FAB2_LIB.BASEBOARD_FAB2(SCH_1):M_J_DQ(31)   I186 @BASEBOARD_FAB2_LIB.BASEBOARD_FAB2(SCH_1):PAGE81
   181 M_J_DQ<28> @BASEBOARD_FAB2_LIB.BASEBOARD_FAB2(SCH_1):M_J_DQ(28)   I186 @BASEBOARD_FAB2_LIB.BASEBOARD_FAB2(SCH_1):PAGE81
    36 M_J_DQ<29> @BASEBOARD_FAB2_LIB.BASEBOARD_FAB2(SCH_1):M_J_DQ(29)   I186 @BASEBOARD_FAB2_LIB.BASEBOARD_FAB2(SCH_1):PAGE81
   190 M_J_DQ<26> @BASEBOARD_FAB2_LIB.BASEBOARD_FAB2(SCH_1):M_J_DQ(26)   I186 @BASEBOARD_FAB2_LIB.BASEBOARD_FAB2(SCH_1):PAGE81
    45 M_J_DQ<27> @BASEBOARD_FAB2_LIB.BASEBOARD_FAB2(SCH_1):M_J_DQ(27)   I186 @BASEBOARD_FAB2_LIB.BASEBOARD_FAB2(SCH_1):PAGE81
   183 M_J_DQ<24> @BASEBOARD_FAB2_LIB.BASEBOARD_FAB2(SCH_1):M_J_DQ(24)   I186 @BASEBOARD_FAB2_LIB.BASEBOARD_FAB2(SCH_1):PAGE81
    38 M_J_DQ<25> @BASEBOARD_FAB2_LIB.BASEBOARD_FAB2(SCH_1):M_J_DQ(25)   I186 @BASEBOARD_FAB2_LIB.BASEBOARD_FAB2(SCH_1):PAGE81
   177 M_J_DQ<22> @BASEBOARD_FAB2_LIB.BASEBOARD_FAB2(SCH_1):M_J_DQ(22)   I186 @BASEBOARD_FAB2_LIB.BASEBOARD_FAB2(SCH_1):PAGE81
    32 M_J_DQ<23> @BASEBOARD_FAB2_LIB.BASEBOARD_FAB2(SCH_1):M_J_DQ(23)   I186 @BASEBOARD_FAB2_LIB.BASEBOARD_FAB2(SCH_1):PAGE81
   170 M_J_DQ<20> @BASEBOARD_FAB2_LIB.BASEBOARD_FAB2(SCH_1):M_J_DQ(20)   I186 @BASEBOARD_FAB2_LIB.BASEBOARD_FAB2(SCH_1):PAGE81
    25 M_J_DQ<21> @BASEBOARD_FAB2_LIB.BASEBOARD_FAB2(SCH_1):M_J_DQ(21)   I186 @BASEBOARD_FAB2_LIB.BASEBOARD_FAB2(SCH_1):PAGE81
   179 M_J_DQ<18> @BASEBOARD_FAB2_LIB.BASEBOARD_FAB2(SCH_1):M_J_DQ(18)   I186 @BASEBOARD_FAB2_LIB.BASEBOARD_FAB2(SCH_1):PAGE81
    34 M_J_DQ<19> @BASEBOARD_FAB2_LIB.BASEBOARD_FAB2(SCH_1):M_J_DQ(19)   I186 @BASEBOARD_FAB2_LIB.BASEBOARD_FAB2(SCH_1):PAGE81
   172 M_J_DQ<16> @BASEBOARD_FAB2_LIB.BASEBOARD_FAB2(SCH_1):M_J_DQ(16)   I186 @BASEBOARD_FAB2_LIB.BASEBOARD_FAB2(SCH_1):PAGE81
    27 M_J_DQ<17> @BASEBOARD_FAB2_LIB.BASEBOARD_FAB2(SCH_1):M_J_DQ(17)   I186 @BASEBOARD_FAB2_LIB.BASEBOARD_FAB2(SCH_1):PAGE81
   166 M_J_DQ<14> @BASEBOARD_FAB2_LIB.BASEBOARD_FAB2(SCH_1):M_J_DQ(14)   I186 @BASEBOARD_FAB2_LIB.BASEBOARD_FAB2(SCH_1):PAGE81
    21 M_J_DQ<15> @BASEBOARD_FAB2_LIB.BASEBOARD_FAB2(SCH_1):M_J_DQ(15)   I186 @BASEBOARD_FAB2_LIB.BASEBOARD_FAB2(SCH_1):PAGE81
   159 M_J_DQ<12> @BASEBOARD_FAB2_LIB.BASEBOARD_FAB2(SCH_1):M_J_DQ(12)   I186 @BASEBOARD_FAB2_LIB.BASEBOARD_FAB2(SCH_1):PAGE81
    14 M_J_DQ<13> @BASEBOARD_FAB2_LIB.BASEBOARD_FAB2(SCH_1):M_J_DQ(13)   I186 @BASEBOARD_FAB2_LIB.BASEBOARD_FAB2(SCH_1):PAGE81
   168 M_J_DQ<10> @BASEBOARD_FAB2_LIB.BASEBOARD_FAB2(SCH_1):M_J_DQ(10)   I186 @BASEBOARD_FAB2_LIB.BASEBOARD_FAB2(SCH_1):PAGE81
    23 M_J_DQ<11> @BASEBOARD_FAB2_LIB.BASEBOARD_FAB2(SCH_1):M_J_DQ(11)   I186 @BASEBOARD_FAB2_LIB.BASEBOARD_FAB2(SCH_1):PAGE81
   161 M_J_DQ<8> @BASEBOARD_FAB2_LIB.BASEBOARD_FAB2(SCH_1):M_J_DQ(8)   I186 @BASEBOARD_FAB2_LIB.BASEBOARD_FAB2(SCH_1):PAGE81
    16 M_J_DQ<9> @BASEBOARD_FAB2_LIB.BASEBOARD_FAB2(SCH_1):M_J_DQ(9)   I186 @BASEBOARD_FAB2_LIB.BASEBOARD_FAB2(SCH_1):PAGE81
   155 M_J_DQ<6> @BASEBOARD_FAB2_LIB.BASEBOARD_FAB2(SCH_1):M_J_DQ(6)   I186 @BASEBOARD_FAB2_LIB.BASEBOARD_FAB2(SCH_1):PAGE81
    10 M_J_DQ<7> @BASEBOARD_FAB2_LIB.BASEBOARD_FAB2(SCH_1):M_J_DQ(7)   I186 @BASEBOARD_FAB2_LIB.BASEBOARD_FAB2(SCH_1):PAGE81
   148 M_J_DQ<4> @BASEBOARD_FAB2_LIB.BASEBOARD_FAB2(SCH_1):M_J_DQ(4)   I186 @BASEBOARD_FAB2_LIB.BASEBOARD_FAB2(SCH_1):PAGE81
     3 M_J_DQ<5> @BASEBOARD_FAB2_LIB.BASEBOARD_FAB2(SCH_1):M_J_DQ(5)   I186 @BASEBOARD_FAB2_LIB.BASEBOARD_FAB2(SCH_1):PAGE81
   157 M_J_DQ<2> @BASEBOARD_FAB2_LIB.BASEBOARD_FAB2(SCH_1):M_J_DQ(2)   I186 @BASEBOARD_FAB2_LIB.BASEBOARD_FAB2(SCH_1):PAGE81
    12 M_J_DQ<3> @BASEBOARD_FAB2_LIB.BASEBOARD_FAB2(SCH_1):M_J_DQ(3)   I186 @BASEBOARD_FAB2_LIB.BASEBOARD_FAB2(SCH_1):PAGE81
   150 M_J_DQ<0> @BASEBOARD_FAB2_LIB.BASEBOARD_FAB2(SCH_1):M_J_DQ(0)   I186 @BASEBOARD_FAB2_LIB.BASEBOARD_FAB2(SCH_1):PAGE81
     5 M_J_DQ<1> @BASEBOARD_FAB2_LIB.BASEBOARD_FAB2(SCH_1):M_J_DQ(1)   I186 @BASEBOARD_FAB2_LIB.BASEBOARD_FAB2(SCH_1):PAGE81
    78 FM_DIMM_EVENT_COD_N @BASEBOARD_FAB2_LIB.BASEBOARD_FAB2(SCH_1):FM_DIMM_EVENT_COD_N   I186 @BASEBOARD_FAB2_LIB.BASEBOARD_FAB2(SCH_1):PAGE81
    91 M_J_ODT<1> @BASEBOARD_FAB2_LIB.BASEBOARD_FAB2(SCH_1):M_J_ODT(1)   I186 @BASEBOARD_FAB2_LIB.BASEBOARD_FAB2(SCH_1):PAGE81
    87 M_J_ODT<0> @BASEBOARD_FAB2_LIB.BASEBOARD_FAB2(SCH_1):M_J_ODT(0)   I186 @BASEBOARD_FAB2_LIB.BASEBOARD_FAB2(SCH_1):PAGE81
   222 M_J_PAR @BASEBOARD_FAB2_LIB.BASEBOARD_FAB2(SCH_1):M_J_PAR   I186 @BASEBOARD_FAB2_LIB.BASEBOARD_FAB2(SCH_1):PAGE81
    58 M_GHJ_RST_N @BASEBOARD_FAB2_LIB.BASEBOARD_FAB2(SCH_1):M_GHJ_RST_N   I186 @BASEBOARD_FAB2_LIB.BASEBOARD_FAB2(SCH_1):PAGE81
   144 TP_CH_J_DIMM_J0_RFU_2 @BASEBOARD_FAB2_LIB.BASEBOARD_FAB2(SCH_1):TP_CH_J_DIMM_J0_RFU_2   I186 @BASEBOARD_FAB2_LIB.BASEBOARD_FAB2(SCH_1):PAGE81
   227 TP_CH_J_DIMM_J0_RFU_1 @BASEBOARD_FAB2_LIB.BASEBOARD_FAB2(SCH_1):TP_CH_J_DIMM_J0_RFU_1   I186 @BASEBOARD_FAB2_LIB.BASEBOARD_FAB2(SCH_1):PAGE81
   205 TP_CH_J_DIMM_J0_RFU_0 @BASEBOARD_FAB2_LIB.BASEBOARD_FAB2(SCH_1):TP_CH_J_DIMM_J0_RFU_0   I186 @BASEBOARD_FAB2_LIB.BASEBOARD_FAB2(SCH_1):PAGE81
    84 M_J_CS_N<0> @BASEBOARD_FAB2_LIB.BASEBOARD_FAB2(SCH_1):M_J_CS_N(0)   I186 @BASEBOARD_FAB2_LIB.BASEBOARD_FAB2(SCH_1):PAGE81
    89 M_J_CS_N<1> @BASEBOARD_FAB2_LIB.BASEBOARD_FAB2(SCH_1):M_J_CS_N(1)   I186 @BASEBOARD_FAB2_LIB.BASEBOARD_FAB2(SCH_1):PAGE81
    93 M_J_CS_N<2> @BASEBOARD_FAB2_LIB.BASEBOARD_FAB2(SCH_1):M_J_CS_N(2)   I186 @BASEBOARD_FAB2_LIB.BASEBOARD_FAB2(SCH_1):PAGE81
   237 M_J_CS_N<3> @BASEBOARD_FAB2_LIB.BASEBOARD_FAB2(SCH_1):M_J_CS_N(3)   I186 @BASEBOARD_FAB2_LIB.BASEBOARD_FAB2(SCH_1):PAGE81
   238 PVPP_GHJ @BASEBOARD_FAB2_LIB.BASEBOARD_FAB2(SCH_1):PVPP_GHJ   I186 @BASEBOARD_FAB2_LIB.BASEBOARD_FAB2(SCH_1):PAGE81
   140    GND @BASEBOARD_FAB2_LIB.BASEBOARD_FAB2(SCH_1):GND   I186 @BASEBOARD_FAB2_LIB.BASEBOARD_FAB2(SCH_1):PAGE81
   139    GND @BASEBOARD_FAB2_LIB.BASEBOARD_FAB2(SCH_1):GND   I186 @BASEBOARD_FAB2_LIB.BASEBOARD_FAB2(SCH_1):PAGE81
   230 FM_ADR_COMPLETE_GHJ_N @BASEBOARD_FAB2_LIB.BASEBOARD_FAB2(SCH_1):FM_ADR_COMPLETE_GHJ_N   I186 @BASEBOARD_FAB2_LIB.BASEBOARD_FAB2(SCH_1):PAGE81
   141 SMB_DDR_GHJ_VPP_SCL @BASEBOARD_FAB2_LIB.BASEBOARD_FAB2(SCH_1):SMB_DDR_GHJ_VPP_SCL   I186 @BASEBOARD_FAB2_LIB.BASEBOARD_FAB2(SCH_1):PAGE81
   285 SMB_DDR_GHJ_VPP_SDA @BASEBOARD_FAB2_LIB.BASEBOARD_FAB2(SCH_1):SMB_DDR_GHJ_VPP_SDA   I186 @BASEBOARD_FAB2_LIB.BASEBOARD_FAB2(SCH_1):PAGE81
   284 PVPP_GHJ @BASEBOARD_FAB2_LIB.BASEBOARD_FAB2(SCH_1):PVPP_GHJ   I186 @BASEBOARD_FAB2_LIB.BASEBOARD_FAB2(SCH_1):PAGE81
   146 M_J_VREF @BASEBOARD_FAB2_LIB.BASEBOARD_FAB2(SCH_1):M_J_VREF   I186 @BASEBOARD_FAB2_LIB.BASEBOARD_FAB2(SCH_1):PAGE81
   152 M_J_DQS_DN<0> @BASEBOARD_FAB2_LIB.BASEBOARD_FAB2(SCH_1):M_J_DQS_DN(0)    I67 @BASEBOARD_FAB2_LIB.BASEBOARD_FAB2(SCH_1):PAGE81
   153 M_J_DQS_DP<0> @BASEBOARD_FAB2_LIB.BASEBOARD_FAB2(SCH_1):M_J_DQS_DP(0)    I67 @BASEBOARD_FAB2_LIB.BASEBOARD_FAB2(SCH_1):PAGE81
    19 M_J_DQS_DN<10> @BASEBOARD_FAB2_LIB.BASEBOARD_FAB2(SCH_1):M_J_DQS_DN(10)    I67 @BASEBOARD_FAB2_LIB.BASEBOARD_FAB2(SCH_1):PAGE81
    18 M_J_DQS_DP<10> @BASEBOARD_FAB2_LIB.BASEBOARD_FAB2(SCH_1):M_J_DQS_DP(10)    I67 @BASEBOARD_FAB2_LIB.BASEBOARD_FAB2(SCH_1):PAGE81
    30 M_J_DQS_DN<11> @BASEBOARD_FAB2_LIB.BASEBOARD_FAB2(SCH_1):M_J_DQS_DN(11)    I67 @BASEBOARD_FAB2_LIB.BASEBOARD_FAB2(SCH_1):PAGE81
    29 M_J_DQS_DP<11> @BASEBOARD_FAB2_LIB.BASEBOARD_FAB2(SCH_1):M_J_DQS_DP(11)    I67 @BASEBOARD_FAB2_LIB.BASEBOARD_FAB2(SCH_1):PAGE81
    41 M_J_DQS_DN<12> @BASEBOARD_FAB2_LIB.BASEBOARD_FAB2(SCH_1):M_J_DQS_DN(12)    I67 @BASEBOARD_FAB2_LIB.BASEBOARD_FAB2(SCH_1):PAGE81
    40 M_J_DQS_DP<12> @BASEBOARD_FAB2_LIB.BASEBOARD_FAB2(SCH_1):M_J_DQS_DP(12)    I67 @BASEBOARD_FAB2_LIB.BASEBOARD_FAB2(SCH_1):PAGE81
   100 M_J_DQS_DN<13> @BASEBOARD_FAB2_LIB.BASEBOARD_FAB2(SCH_1):M_J_DQS_DN(13)    I67 @BASEBOARD_FAB2_LIB.BASEBOARD_FAB2(SCH_1):PAGE81
    99 M_J_DQS_DP<13> @BASEBOARD_FAB2_LIB.BASEBOARD_FAB2(SCH_1):M_J_DQS_DP(13)    I67 @BASEBOARD_FAB2_LIB.BASEBOARD_FAB2(SCH_1):PAGE81
   111 M_J_DQS_DN<14> @BASEBOARD_FAB2_LIB.BASEBOARD_FAB2(SCH_1):M_J_DQS_DN(14)    I67 @BASEBOARD_FAB2_LIB.BASEBOARD_FAB2(SCH_1):PAGE81
   110 M_J_DQS_DP<14> @BASEBOARD_FAB2_LIB.BASEBOARD_FAB2(SCH_1):M_J_DQS_DP(14)    I67 @BASEBOARD_FAB2_LIB.BASEBOARD_FAB2(SCH_1):PAGE81
   122 M_J_DQS_DN<15> @BASEBOARD_FAB2_LIB.BASEBOARD_FAB2(SCH_1):M_J_DQS_DN(15)    I67 @BASEBOARD_FAB2_LIB.BASEBOARD_FAB2(SCH_1):PAGE81
   121 M_J_DQS_DP<15> @BASEBOARD_FAB2_LIB.BASEBOARD_FAB2(SCH_1):M_J_DQS_DP(15)    I67 @BASEBOARD_FAB2_LIB.BASEBOARD_FAB2(SCH_1):PAGE81
   133 M_J_DQS_DN<16> @BASEBOARD_FAB2_LIB.BASEBOARD_FAB2(SCH_1):M_J_DQS_DN(16)    I67 @BASEBOARD_FAB2_LIB.BASEBOARD_FAB2(SCH_1):PAGE81
   132 M_J_DQS_DP<16> @BASEBOARD_FAB2_LIB.BASEBOARD_FAB2(SCH_1):M_J_DQS_DP(16)    I67 @BASEBOARD_FAB2_LIB.BASEBOARD_FAB2(SCH_1):PAGE81
    52 M_J_DQS_DN<17> @BASEBOARD_FAB2_LIB.BASEBOARD_FAB2(SCH_1):M_J_DQS_DN(17)    I67 @BASEBOARD_FAB2_LIB.BASEBOARD_FAB2(SCH_1):PAGE81
    51 M_J_DQS_DP<17> @BASEBOARD_FAB2_LIB.BASEBOARD_FAB2(SCH_1):M_J_DQS_DP(17)    I67 @BASEBOARD_FAB2_LIB.BASEBOARD_FAB2(SCH_1):PAGE81
   163 M_J_DQS_DN<1> @BASEBOARD_FAB2_LIB.BASEBOARD_FAB2(SCH_1):M_J_DQS_DN(1)    I67 @BASEBOARD_FAB2_LIB.BASEBOARD_FAB2(SCH_1):PAGE81
   164 M_J_DQS_DP<1> @BASEBOARD_FAB2_LIB.BASEBOARD_FAB2(SCH_1):M_J_DQS_DP(1)    I67 @BASEBOARD_FAB2_LIB.BASEBOARD_FAB2(SCH_1):PAGE81
   174 M_J_DQS_DN<2> @BASEBOARD_FAB2_LIB.BASEBOARD_FAB2(SCH_1):M_J_DQS_DN(2)    I67 @BASEBOARD_FAB2_LIB.BASEBOARD_FAB2(SCH_1):PAGE81
   175 M_J_DQS_DP<2> @BASEBOARD_FAB2_LIB.BASEBOARD_FAB2(SCH_1):M_J_DQS_DP(2)    I67 @BASEBOARD_FAB2_LIB.BASEBOARD_FAB2(SCH_1):PAGE81
   185 M_J_DQS_DN<3> @BASEBOARD_FAB2_LIB.BASEBOARD_FAB2(SCH_1):M_J_DQS_DN(3)    I67 @BASEBOARD_FAB2_LIB.BASEBOARD_FAB2(SCH_1):PAGE81
   186 M_J_DQS_DP<3> @BASEBOARD_FAB2_LIB.BASEBOARD_FAB2(SCH_1):M_J_DQS_DP(3)    I67 @BASEBOARD_FAB2_LIB.BASEBOARD_FAB2(SCH_1):PAGE81
   244 M_J_DQS_DN<4> @BASEBOARD_FAB2_LIB.BASEBOARD_FAB2(SCH_1):M_J_DQS_DN(4)    I67 @BASEBOARD_FAB2_LIB.BASEBOARD_FAB2(SCH_1):PAGE81
   245 M_J_DQS_DP<4> @BASEBOARD_FAB2_LIB.BASEBOARD_FAB2(SCH_1):M_J_DQS_DP(4)    I67 @BASEBOARD_FAB2_LIB.BASEBOARD_FAB2(SCH_1):PAGE81
   255 M_J_DQS_DN<5> @BASEBOARD_FAB2_LIB.BASEBOARD_FAB2(SCH_1):M_J_DQS_DN(5)    I67 @BASEBOARD_FAB2_LIB.BASEBOARD_FAB2(SCH_1):PAGE81
   256 M_J_DQS_DP<5> @BASEBOARD_FAB2_LIB.BASEBOARD_FAB2(SCH_1):M_J_DQS_DP(5)    I67 @BASEBOARD_FAB2_LIB.BASEBOARD_FAB2(SCH_1):PAGE81
   266 M_J_DQS_DN<6> @BASEBOARD_FAB2_LIB.BASEBOARD_FAB2(SCH_1):M_J_DQS_DN(6)    I67 @BASEBOARD_FAB2_LIB.BASEBOARD_FAB2(SCH_1):PAGE81
   267 M_J_DQS_DP<6> @BASEBOARD_FAB2_LIB.BASEBOARD_FAB2(SCH_1):M_J_DQS_DP(6)    I67 @BASEBOARD_FAB2_LIB.BASEBOARD_FAB2(SCH_1):PAGE81
   277 M_J_DQS_DN<7> @BASEBOARD_FAB2_LIB.BASEBOARD_FAB2(SCH_1):M_J_DQS_DN(7)    I67 @BASEBOARD_FAB2_LIB.BASEBOARD_FAB2(SCH_1):PAGE81
   278 M_J_DQS_DP<7> @BASEBOARD_FAB2_LIB.BASEBOARD_FAB2(SCH_1):M_J_DQS_DP(7)    I67 @BASEBOARD_FAB2_LIB.BASEBOARD_FAB2(SCH_1):PAGE81
   196 M_J_DQS_DN<8> @BASEBOARD_FAB2_LIB.BASEBOARD_FAB2(SCH_1):M_J_DQS_DN(8)    I67 @BASEBOARD_FAB2_LIB.BASEBOARD_FAB2(SCH_1):PAGE81
   197 M_J_DQS_DP<8> @BASEBOARD_FAB2_LIB.BASEBOARD_FAB2(SCH_1):M_J_DQS_DP(8)    I67 @BASEBOARD_FAB2_LIB.BASEBOARD_FAB2(SCH_1):PAGE81
     8 M_J_DQS_DN<9> @BASEBOARD_FAB2_LIB.BASEBOARD_FAB2(SCH_1):M_J_DQS_DN(9)    I67 @BASEBOARD_FAB2_LIB.BASEBOARD_FAB2(SCH_1):PAGE81
     7 M_J_DQS_DP<9> @BASEBOARD_FAB2_LIB.BASEBOARD_FAB2(SCH_1):M_J_DQS_DP(9)    I67 @BASEBOARD_FAB2_LIB.BASEBOARD_FAB2(SCH_1):PAGE81
     2    GND @BASEBOARD_FAB2_LIB.BASEBOARD_FAB2(SCH_1):GND   I185 @BASEBOARD_FAB2_LIB.BASEBOARD_FAB2(SCH_1):PAGE81
     4    GND @BASEBOARD_FAB2_LIB.BASEBOARD_FAB2(SCH_1):GND   I185 @BASEBOARD_FAB2_LIB.BASEBOARD_FAB2(SCH_1):PAGE81
     6    GND @BASEBOARD_FAB2_LIB.BASEBOARD_FAB2(SCH_1):GND   I185 @BASEBOARD_FAB2_LIB.BASEBOARD_FAB2(SCH_1):PAGE81
     9    GND @BASEBOARD_FAB2_LIB.BASEBOARD_FAB2(SCH_1):GND   I185 @BASEBOARD_FAB2_LIB.BASEBOARD_FAB2(SCH_1):PAGE81
    11    GND @BASEBOARD_FAB2_LIB.BASEBOARD_FAB2(SCH_1):GND   I185 @BASEBOARD_FAB2_LIB.BASEBOARD_FAB2(SCH_1):PAGE81
    13    GND @BASEBOARD_FAB2_LIB.BASEBOARD_FAB2(SCH_1):GND   I185 @BASEBOARD_FAB2_LIB.BASEBOARD_FAB2(SCH_1):PAGE81
    15    GND @BASEBOARD_FAB2_LIB.BASEBOARD_FAB2(SCH_1):GND   I185 @BASEBOARD_FAB2_LIB.BASEBOARD_FAB2(SCH_1):PAGE81
    17    GND @BASEBOARD_FAB2_LIB.BASEBOARD_FAB2(SCH_1):GND   I185 @BASEBOARD_FAB2_LIB.BASEBOARD_FAB2(SCH_1):PAGE81
    20    GND @BASEBOARD_FAB2_LIB.BASEBOARD_FAB2(SCH_1):GND   I185 @BASEBOARD_FAB2_LIB.BASEBOARD_FAB2(SCH_1):PAGE81
    22    GND @BASEBOARD_FAB2_LIB.BASEBOARD_FAB2(SCH_1):GND   I185 @BASEBOARD_FAB2_LIB.BASEBOARD_FAB2(SCH_1):PAGE81
    24    GND @BASEBOARD_FAB2_LIB.BASEBOARD_FAB2(SCH_1):GND   I185 @BASEBOARD_FAB2_LIB.BASEBOARD_FAB2(SCH_1):PAGE81
    26    GND @BASEBOARD_FAB2_LIB.BASEBOARD_FAB2(SCH_1):GND   I185 @BASEBOARD_FAB2_LIB.BASEBOARD_FAB2(SCH_1):PAGE81
    28    GND @BASEBOARD_FAB2_LIB.BASEBOARD_FAB2(SCH_1):GND   I185 @BASEBOARD_FAB2_LIB.BASEBOARD_FAB2(SCH_1):PAGE81
    31    GND @BASEBOARD_FAB2_LIB.BASEBOARD_FAB2(SCH_1):GND   I185 @BASEBOARD_FAB2_LIB.BASEBOARD_FAB2(SCH_1):PAGE81
    33    GND @BASEBOARD_FAB2_LIB.BASEBOARD_FAB2(SCH_1):GND   I185 @BASEBOARD_FAB2_LIB.BASEBOARD_FAB2(SCH_1):PAGE81
    35    GND @BASEBOARD_FAB2_LIB.BASEBOARD_FAB2(SCH_1):GND   I185 @BASEBOARD_FAB2_LIB.BASEBOARD_FAB2(SCH_1):PAGE81
    37    GND @BASEBOARD_FAB2_LIB.BASEBOARD_FAB2(SCH_1):GND   I185 @BASEBOARD_FAB2_LIB.BASEBOARD_FAB2(SCH_1):PAGE81
    39    GND @BASEBOARD_FAB2_LIB.BASEBOARD_FAB2(SCH_1):GND   I185 @BASEBOARD_FAB2_LIB.BASEBOARD_FAB2(SCH_1):PAGE81
    42    GND @BASEBOARD_FAB2_LIB.BASEBOARD_FAB2(SCH_1):GND   I185 @BASEBOARD_FAB2_LIB.BASEBOARD_FAB2(SCH_1):PAGE81
    44    GND @BASEBOARD_FAB2_LIB.BASEBOARD_FAB2(SCH_1):GND   I185 @BASEBOARD_FAB2_LIB.BASEBOARD_FAB2(SCH_1):PAGE81
    46    GND @BASEBOARD_FAB2_LIB.BASEBOARD_FAB2(SCH_1):GND   I185 @BASEBOARD_FAB2_LIB.BASEBOARD_FAB2(SCH_1):PAGE81
    48    GND @BASEBOARD_FAB2_LIB.BASEBOARD_FAB2(SCH_1):GND   I185 @BASEBOARD_FAB2_LIB.BASEBOARD_FAB2(SCH_1):PAGE81
    50    GND @BASEBOARD_FAB2_LIB.BASEBOARD_FAB2(SCH_1):GND   I185 @BASEBOARD_FAB2_LIB.BASEBOARD_FAB2(SCH_1):PAGE81
    53    GND @BASEBOARD_FAB2_LIB.BASEBOARD_FAB2(SCH_1):GND   I185 @BASEBOARD_FAB2_LIB.BASEBOARD_FAB2(SCH_1):PAGE81
    55    GND @BASEBOARD_FAB2_LIB.BASEBOARD_FAB2(SCH_1):GND   I185 @BASEBOARD_FAB2_LIB.BASEBOARD_FAB2(SCH_1):PAGE81
    57    GND @BASEBOARD_FAB2_LIB.BASEBOARD_FAB2(SCH_1):GND   I185 @BASEBOARD_FAB2_LIB.BASEBOARD_FAB2(SCH_1):PAGE81
    94    GND @BASEBOARD_FAB2_LIB.BASEBOARD_FAB2(SCH_1):GND   I185 @BASEBOARD_FAB2_LIB.BASEBOARD_FAB2(SCH_1):PAGE81
    96    GND @BASEBOARD_FAB2_LIB.BASEBOARD_FAB2(SCH_1):GND   I185 @BASEBOARD_FAB2_LIB.BASEBOARD_FAB2(SCH_1):PAGE81
    98    GND @BASEBOARD_FAB2_LIB.BASEBOARD_FAB2(SCH_1):GND   I185 @BASEBOARD_FAB2_LIB.BASEBOARD_FAB2(SCH_1):PAGE81
   101    GND @BASEBOARD_FAB2_LIB.BASEBOARD_FAB2(SCH_1):GND   I185 @BASEBOARD_FAB2_LIB.BASEBOARD_FAB2(SCH_1):PAGE81
   103    GND @BASEBOARD_FAB2_LIB.BASEBOARD_FAB2(SCH_1):GND   I185 @BASEBOARD_FAB2_LIB.BASEBOARD_FAB2(SCH_1):PAGE81
   105    GND @BASEBOARD_FAB2_LIB.BASEBOARD_FAB2(SCH_1):GND   I185 @BASEBOARD_FAB2_LIB.BASEBOARD_FAB2(SCH_1):PAGE81
   107    GND @BASEBOARD_FAB2_LIB.BASEBOARD_FAB2(SCH_1):GND   I185 @BASEBOARD_FAB2_LIB.BASEBOARD_FAB2(SCH_1):PAGE81
   109    GND @BASEBOARD_FAB2_LIB.BASEBOARD_FAB2(SCH_1):GND   I185 @BASEBOARD_FAB2_LIB.BASEBOARD_FAB2(SCH_1):PAGE81
   112    GND @BASEBOARD_FAB2_LIB.BASEBOARD_FAB2(SCH_1):GND   I185 @BASEBOARD_FAB2_LIB.BASEBOARD_FAB2(SCH_1):PAGE81
   114    GND @BASEBOARD_FAB2_LIB.BASEBOARD_FAB2(SCH_1):GND   I185 @BASEBOARD_FAB2_LIB.BASEBOARD_FAB2(SCH_1):PAGE81
   116    GND @BASEBOARD_FAB2_LIB.BASEBOARD_FAB2(SCH_1):GND   I185 @BASEBOARD_FAB2_LIB.BASEBOARD_FAB2(SCH_1):PAGE81
   118    GND @BASEBOARD_FAB2_LIB.BASEBOARD_FAB2(SCH_1):GND   I185 @BASEBOARD_FAB2_LIB.BASEBOARD_FAB2(SCH_1):PAGE81
   120    GND @BASEBOARD_FAB2_LIB.BASEBOARD_FAB2(SCH_1):GND   I185 @BASEBOARD_FAB2_LIB.BASEBOARD_FAB2(SCH_1):PAGE81
   123    GND @BASEBOARD_FAB2_LIB.BASEBOARD_FAB2(SCH_1):GND   I185 @BASEBOARD_FAB2_LIB.BASEBOARD_FAB2(SCH_1):PAGE81
   125    GND @BASEBOARD_FAB2_LIB.BASEBOARD_FAB2(SCH_1):GND   I185 @BASEBOARD_FAB2_LIB.BASEBOARD_FAB2(SCH_1):PAGE81
   127    GND @BASEBOARD_FAB2_LIB.BASEBOARD_FAB2(SCH_1):GND   I185 @BASEBOARD_FAB2_LIB.BASEBOARD_FAB2(SCH_1):PAGE81
   129    GND @BASEBOARD_FAB2_LIB.BASEBOARD_FAB2(SCH_1):GND   I185 @BASEBOARD_FAB2_LIB.BASEBOARD_FAB2(SCH_1):PAGE81
   131    GND @BASEBOARD_FAB2_LIB.BASEBOARD_FAB2(SCH_1):GND   I185 @BASEBOARD_FAB2_LIB.BASEBOARD_FAB2(SCH_1):PAGE81
   134    GND @BASEBOARD_FAB2_LIB.BASEBOARD_FAB2(SCH_1):GND   I185 @BASEBOARD_FAB2_LIB.BASEBOARD_FAB2(SCH_1):PAGE81
   136    GND @BASEBOARD_FAB2_LIB.BASEBOARD_FAB2(SCH_1):GND   I185 @BASEBOARD_FAB2_LIB.BASEBOARD_FAB2(SCH_1):PAGE81
   138    GND @BASEBOARD_FAB2_LIB.BASEBOARD_FAB2(SCH_1):GND   I185 @BASEBOARD_FAB2_LIB.BASEBOARD_FAB2(SCH_1):PAGE81
   147    GND @BASEBOARD_FAB2_LIB.BASEBOARD_FAB2(SCH_1):GND   I185 @BASEBOARD_FAB2_LIB.BASEBOARD_FAB2(SCH_1):PAGE81
   149    GND @BASEBOARD_FAB2_LIB.BASEBOARD_FAB2(SCH_1):GND   I185 @BASEBOARD_FAB2_LIB.BASEBOARD_FAB2(SCH_1):PAGE81
   151    GND @BASEBOARD_FAB2_LIB.BASEBOARD_FAB2(SCH_1):GND   I185 @BASEBOARD_FAB2_LIB.BASEBOARD_FAB2(SCH_1):PAGE81
   154    GND @BASEBOARD_FAB2_LIB.BASEBOARD_FAB2(SCH_1):GND   I185 @BASEBOARD_FAB2_LIB.BASEBOARD_FAB2(SCH_1):PAGE81
   156    GND @BASEBOARD_FAB2_LIB.BASEBOARD_FAB2(SCH_1):GND   I185 @BASEBOARD_FAB2_LIB.BASEBOARD_FAB2(SCH_1):PAGE81
   158    GND @BASEBOARD_FAB2_LIB.BASEBOARD_FAB2(SCH_1):GND   I185 @BASEBOARD_FAB2_LIB.BASEBOARD_FAB2(SCH_1):PAGE81
   160    GND @BASEBOARD_FAB2_LIB.BASEBOARD_FAB2(SCH_1):GND   I185 @BASEBOARD_FAB2_LIB.BASEBOARD_FAB2(SCH_1):PAGE81
   162    GND @BASEBOARD_FAB2_LIB.BASEBOARD_FAB2(SCH_1):GND   I185 @BASEBOARD_FAB2_LIB.BASEBOARD_FAB2(SCH_1):PAGE81
   165    GND @BASEBOARD_FAB2_LIB.BASEBOARD_FAB2(SCH_1):GND   I185 @BASEBOARD_FAB2_LIB.BASEBOARD_FAB2(SCH_1):PAGE81
   167    GND @BASEBOARD_FAB2_LIB.BASEBOARD_FAB2(SCH_1):GND   I185 @BASEBOARD_FAB2_LIB.BASEBOARD_FAB2(SCH_1):PAGE81
   169    GND @BASEBOARD_FAB2_LIB.BASEBOARD_FAB2(SCH_1):GND   I185 @BASEBOARD_FAB2_LIB.BASEBOARD_FAB2(SCH_1):PAGE81
   171    GND @BASEBOARD_FAB2_LIB.BASEBOARD_FAB2(SCH_1):GND   I185 @BASEBOARD_FAB2_LIB.BASEBOARD_FAB2(SCH_1):PAGE81
   173    GND @BASEBOARD_FAB2_LIB.BASEBOARD_FAB2(SCH_1):GND   I185 @BASEBOARD_FAB2_LIB.BASEBOARD_FAB2(SCH_1):PAGE81
   176    GND @BASEBOARD_FAB2_LIB.BASEBOARD_FAB2(SCH_1):GND   I185 @BASEBOARD_FAB2_LIB.BASEBOARD_FAB2(SCH_1):PAGE81
   178    GND @BASEBOARD_FAB2_LIB.BASEBOARD_FAB2(SCH_1):GND   I185 @BASEBOARD_FAB2_LIB.BASEBOARD_FAB2(SCH_1):PAGE81
   180    GND @BASEBOARD_FAB2_LIB.BASEBOARD_FAB2(SCH_1):GND   I185 @BASEBOARD_FAB2_LIB.BASEBOARD_FAB2(SCH_1):PAGE81
   182    GND @BASEBOARD_FAB2_LIB.BASEBOARD_FAB2(SCH_1):GND   I185 @BASEBOARD_FAB2_LIB.BASEBOARD_FAB2(SCH_1):PAGE81
   184    GND @BASEBOARD_FAB2_LIB.BASEBOARD_FAB2(SCH_1):GND   I185 @BASEBOARD_FAB2_LIB.BASEBOARD_FAB2(SCH_1):PAGE81
   187    GND @BASEBOARD_FAB2_LIB.BASEBOARD_FAB2(SCH_1):GND   I185 @BASEBOARD_FAB2_LIB.BASEBOARD_FAB2(SCH_1):PAGE81
   189    GND @BASEBOARD_FAB2_LIB.BASEBOARD_FAB2(SCH_1):GND   I185 @BASEBOARD_FAB2_LIB.BASEBOARD_FAB2(SCH_1):PAGE81
   191    GND @BASEBOARD_FAB2_LIB.BASEBOARD_FAB2(SCH_1):GND   I185 @BASEBOARD_FAB2_LIB.BASEBOARD_FAB2(SCH_1):PAGE81
   193    GND @BASEBOARD_FAB2_LIB.BASEBOARD_FAB2(SCH_1):GND   I185 @BASEBOARD_FAB2_LIB.BASEBOARD_FAB2(SCH_1):PAGE81
   195    GND @BASEBOARD_FAB2_LIB.BASEBOARD_FAB2(SCH_1):GND   I185 @BASEBOARD_FAB2_LIB.BASEBOARD_FAB2(SCH_1):PAGE81
   198    GND @BASEBOARD_FAB2_LIB.BASEBOARD_FAB2(SCH_1):GND   I185 @BASEBOARD_FAB2_LIB.BASEBOARD_FAB2(SCH_1):PAGE81
   200    GND @BASEBOARD_FAB2_LIB.BASEBOARD_FAB2(SCH_1):GND   I185 @BASEBOARD_FAB2_LIB.BASEBOARD_FAB2(SCH_1):PAGE81
   202    GND @BASEBOARD_FAB2_LIB.BASEBOARD_FAB2(SCH_1):GND   I185 @BASEBOARD_FAB2_LIB.BASEBOARD_FAB2(SCH_1):PAGE81
   239    GND @BASEBOARD_FAB2_LIB.BASEBOARD_FAB2(SCH_1):GND   I185 @BASEBOARD_FAB2_LIB.BASEBOARD_FAB2(SCH_1):PAGE81
   241    GND @BASEBOARD_FAB2_LIB.BASEBOARD_FAB2(SCH_1):GND   I185 @BASEBOARD_FAB2_LIB.BASEBOARD_FAB2(SCH_1):PAGE81
   243    GND @BASEBOARD_FAB2_LIB.BASEBOARD_FAB2(SCH_1):GND   I185 @BASEBOARD_FAB2_LIB.BASEBOARD_FAB2(SCH_1):PAGE81
   246    GND @BASEBOARD_FAB2_LIB.BASEBOARD_FAB2(SCH_1):GND   I185 @BASEBOARD_FAB2_LIB.BASEBOARD_FAB2(SCH_1):PAGE81
   248    GND @BASEBOARD_FAB2_LIB.BASEBOARD_FAB2(SCH_1):GND   I185 @BASEBOARD_FAB2_LIB.BASEBOARD_FAB2(SCH_1):PAGE81
   250    GND @BASEBOARD_FAB2_LIB.BASEBOARD_FAB2(SCH_1):GND   I185 @BASEBOARD_FAB2_LIB.BASEBOARD_FAB2(SCH_1):PAGE81
   252    GND @BASEBOARD_FAB2_LIB.BASEBOARD_FAB2(SCH_1):GND   I185 @BASEBOARD_FAB2_LIB.BASEBOARD_FAB2(SCH_1):PAGE81
   254    GND @BASEBOARD_FAB2_LIB.BASEBOARD_FAB2(SCH_1):GND   I185 @BASEBOARD_FAB2_LIB.BASEBOARD_FAB2(SCH_1):PAGE81
   257    GND @BASEBOARD_FAB2_LIB.BASEBOARD_FAB2(SCH_1):GND   I185 @BASEBOARD_FAB2_LIB.BASEBOARD_FAB2(SCH_1):PAGE81
   259    GND @BASEBOARD_FAB2_LIB.BASEBOARD_FAB2(SCH_1):GND   I185 @BASEBOARD_FAB2_LIB.BASEBOARD_FAB2(SCH_1):PAGE81
   261    GND @BASEBOARD_FAB2_LIB.BASEBOARD_FAB2(SCH_1):GND   I185 @BASEBOARD_FAB2_LIB.BASEBOARD_FAB2(SCH_1):PAGE81
   263    GND @BASEBOARD_FAB2_LIB.BASEBOARD_FAB2(SCH_1):GND   I185 @BASEBOARD_FAB2_LIB.BASEBOARD_FAB2(SCH_1):PAGE81
   265    GND @BASEBOARD_FAB2_LIB.BASEBOARD_FAB2(SCH_1):GND   I185 @BASEBOARD_FAB2_LIB.BASEBOARD_FAB2(SCH_1):PAGE81
   268    GND @BASEBOARD_FAB2_LIB.BASEBOARD_FAB2(SCH_1):GND   I185 @BASEBOARD_FAB2_LIB.BASEBOARD_FAB2(SCH_1):PAGE81
   270    GND @BASEBOARD_FAB2_LIB.BASEBOARD_FAB2(SCH_1):GND   I185 @BASEBOARD_FAB2_LIB.BASEBOARD_FAB2(SCH_1):PAGE81
   272    GND @BASEBOARD_FAB2_LIB.BASEBOARD_FAB2(SCH_1):GND   I185 @BASEBOARD_FAB2_LIB.BASEBOARD_FAB2(SCH_1):PAGE81
   274    GND @BASEBOARD_FAB2_LIB.BASEBOARD_FAB2(SCH_1):GND   I185 @BASEBOARD_FAB2_LIB.BASEBOARD_FAB2(SCH_1):PAGE81
   276    GND @BASEBOARD_FAB2_LIB.BASEBOARD_FAB2(SCH_1):GND   I185 @BASEBOARD_FAB2_LIB.BASEBOARD_FAB2(SCH_1):PAGE81
   279    GND @BASEBOARD_FAB2_LIB.BASEBOARD_FAB2(SCH_1):GND   I185 @BASEBOARD_FAB2_LIB.BASEBOARD_FAB2(SCH_1):PAGE81
   281    GND @BASEBOARD_FAB2_LIB.BASEBOARD_FAB2(SCH_1):GND   I185 @BASEBOARD_FAB2_LIB.BASEBOARD_FAB2(SCH_1):PAGE81
   283    GND @BASEBOARD_FAB2_LIB.BASEBOARD_FAB2(SCH_1):GND   I185 @BASEBOARD_FAB2_LIB.BASEBOARD_FAB2(SCH_1):PAGE81
     1 P12V_NVDIMM_GHJ @BASEBOARD_FAB2_LIB.BASEBOARD_FAB2(SCH_1):P12V_NVDIMM_GHJ   I169 @BASEBOARD_FAB2_LIB.BASEBOARD_FAB2(SCH_1):PAGE81
   145 P12V_NVDIMM_GHJ @BASEBOARD_FAB2_LIB.BASEBOARD_FAB2(SCH_1):P12V_NVDIMM_GHJ   I169 @BASEBOARD_FAB2_LIB.BASEBOARD_FAB2(SCH_1):PAGE81
    59 PVDDQ_GHJ @BASEBOARD_FAB2_LIB.BASEBOARD_FAB2(SCH_1):PVDDQ_GHJ   I169 @BASEBOARD_FAB2_LIB.BASEBOARD_FAB2(SCH_1):PAGE81
    61 PVDDQ_GHJ @BASEBOARD_FAB2_LIB.BASEBOARD_FAB2(SCH_1):PVDDQ_GHJ   I169 @BASEBOARD_FAB2_LIB.BASEBOARD_FAB2(SCH_1):PAGE81
    64 PVDDQ_GHJ @BASEBOARD_FAB2_LIB.BASEBOARD_FAB2(SCH_1):PVDDQ_GHJ   I169 @BASEBOARD_FAB2_LIB.BASEBOARD_FAB2(SCH_1):PAGE81
    67 PVDDQ_GHJ @BASEBOARD_FAB2_LIB.BASEBOARD_FAB2(SCH_1):PVDDQ_GHJ   I169 @BASEBOARD_FAB2_LIB.BASEBOARD_FAB2(SCH_1):PAGE81
    70 PVDDQ_GHJ @BASEBOARD_FAB2_LIB.BASEBOARD_FAB2(SCH_1):PVDDQ_GHJ   I169 @BASEBOARD_FAB2_LIB.BASEBOARD_FAB2(SCH_1):PAGE81
    73 PVDDQ_GHJ @BASEBOARD_FAB2_LIB.BASEBOARD_FAB2(SCH_1):PVDDQ_GHJ   I169 @BASEBOARD_FAB2_LIB.BASEBOARD_FAB2(SCH_1):PAGE81
    76 PVDDQ_GHJ @BASEBOARD_FAB2_LIB.BASEBOARD_FAB2(SCH_1):PVDDQ_GHJ   I169 @BASEBOARD_FAB2_LIB.BASEBOARD_FAB2(SCH_1):PAGE81
    80 PVDDQ_GHJ @BASEBOARD_FAB2_LIB.BASEBOARD_FAB2(SCH_1):PVDDQ_GHJ   I169 @BASEBOARD_FAB2_LIB.BASEBOARD_FAB2(SCH_1):PAGE81
    83 PVDDQ_GHJ @BASEBOARD_FAB2_LIB.BASEBOARD_FAB2(SCH_1):PVDDQ_GHJ   I169 @BASEBOARD_FAB2_LIB.BASEBOARD_FAB2(SCH_1):PAGE81
    85 PVDDQ_GHJ @BASEBOARD_FAB2_LIB.BASEBOARD_FAB2(SCH_1):PVDDQ_GHJ   I169 @BASEBOARD_FAB2_LIB.BASEBOARD_FAB2(SCH_1):PAGE81
    88 PVDDQ_GHJ @BASEBOARD_FAB2_LIB.BASEBOARD_FAB2(SCH_1):PVDDQ_GHJ   I169 @BASEBOARD_FAB2_LIB.BASEBOARD_FAB2(SCH_1):PAGE81
    90 PVDDQ_GHJ @BASEBOARD_FAB2_LIB.BASEBOARD_FAB2(SCH_1):PVDDQ_GHJ   I169 @BASEBOARD_FAB2_LIB.BASEBOARD_FAB2(SCH_1):PAGE81
    92 PVDDQ_GHJ @BASEBOARD_FAB2_LIB.BASEBOARD_FAB2(SCH_1):PVDDQ_GHJ   I169 @BASEBOARD_FAB2_LIB.BASEBOARD_FAB2(SCH_1):PAGE81
   204 PVDDQ_GHJ @BASEBOARD_FAB2_LIB.BASEBOARD_FAB2(SCH_1):PVDDQ_GHJ   I169 @BASEBOARD_FAB2_LIB.BASEBOARD_FAB2(SCH_1):PAGE81
   206 PVDDQ_GHJ @BASEBOARD_FAB2_LIB.BASEBOARD_FAB2(SCH_1):PVDDQ_GHJ   I169 @BASEBOARD_FAB2_LIB.BASEBOARD_FAB2(SCH_1):PAGE81
   209 PVDDQ_GHJ @BASEBOARD_FAB2_LIB.BASEBOARD_FAB2(SCH_1):PVDDQ_GHJ   I169 @BASEBOARD_FAB2_LIB.BASEBOARD_FAB2(SCH_1):PAGE81
   212 PVDDQ_GHJ @BASEBOARD_FAB2_LIB.BASEBOARD_FAB2(SCH_1):PVDDQ_GHJ   I169 @BASEBOARD_FAB2_LIB.BASEBOARD_FAB2(SCH_1):PAGE81
   215 PVDDQ_GHJ @BASEBOARD_FAB2_LIB.BASEBOARD_FAB2(SCH_1):PVDDQ_GHJ   I169 @BASEBOARD_FAB2_LIB.BASEBOARD_FAB2(SCH_1):PAGE81
   217 PVDDQ_GHJ @BASEBOARD_FAB2_LIB.BASEBOARD_FAB2(SCH_1):PVDDQ_GHJ   I169 @BASEBOARD_FAB2_LIB.BASEBOARD_FAB2(SCH_1):PAGE81
   220 PVDDQ_GHJ @BASEBOARD_FAB2_LIB.BASEBOARD_FAB2(SCH_1):PVDDQ_GHJ   I169 @BASEBOARD_FAB2_LIB.BASEBOARD_FAB2(SCH_1):PAGE81
   223 PVDDQ_GHJ @BASEBOARD_FAB2_LIB.BASEBOARD_FAB2(SCH_1):PVDDQ_GHJ   I169 @BASEBOARD_FAB2_LIB.BASEBOARD_FAB2(SCH_1):PAGE81
   226 PVDDQ_GHJ @BASEBOARD_FAB2_LIB.BASEBOARD_FAB2(SCH_1):PVDDQ_GHJ   I169 @BASEBOARD_FAB2_LIB.BASEBOARD_FAB2(SCH_1):PAGE81
   229 PVDDQ_GHJ @BASEBOARD_FAB2_LIB.BASEBOARD_FAB2(SCH_1):PVDDQ_GHJ   I169 @BASEBOARD_FAB2_LIB.BASEBOARD_FAB2(SCH_1):PAGE81
   231 PVDDQ_GHJ @BASEBOARD_FAB2_LIB.BASEBOARD_FAB2(SCH_1):PVDDQ_GHJ   I169 @BASEBOARD_FAB2_LIB.BASEBOARD_FAB2(SCH_1):PAGE81
   233 PVDDQ_GHJ @BASEBOARD_FAB2_LIB.BASEBOARD_FAB2(SCH_1):PVDDQ_GHJ   I169 @BASEBOARD_FAB2_LIB.BASEBOARD_FAB2(SCH_1):PAGE81
   236 PVDDQ_GHJ @BASEBOARD_FAB2_LIB.BASEBOARD_FAB2(SCH_1):PVDDQ_GHJ   I169 @BASEBOARD_FAB2_LIB.BASEBOARD_FAB2(SCH_1):PAGE81
   142 PVPP_GHJ @BASEBOARD_FAB2_LIB.BASEBOARD_FAB2(SCH_1):PVPP_GHJ   I169 @BASEBOARD_FAB2_LIB.BASEBOARD_FAB2(SCH_1):PAGE81
   143 PVPP_GHJ @BASEBOARD_FAB2_LIB.BASEBOARD_FAB2(SCH_1):PVPP_GHJ   I169 @BASEBOARD_FAB2_LIB.BASEBOARD_FAB2(SCH_1):PAGE81
   288 PVPP_GHJ @BASEBOARD_FAB2_LIB.BASEBOARD_FAB2(SCH_1):PVPP_GHJ   I169 @BASEBOARD_FAB2_LIB.BASEBOARD_FAB2(SCH_1):PAGE81
   286 PVPP_GHJ @BASEBOARD_FAB2_LIB.BASEBOARD_FAB2(SCH_1):PVPP_GHJ   I169 @BASEBOARD_FAB2_LIB.BASEBOARD_FAB2(SCH_1):PAGE81
   287 PVPP_GHJ @BASEBOARD_FAB2_LIB.BASEBOARD_FAB2(SCH_1):PVPP_GHJ   I169 @BASEBOARD_FAB2_LIB.BASEBOARD_FAB2(SCH_1):PAGE81
    77 PVTT_GHJ @BASEBOARD_FAB2_LIB.BASEBOARD_FAB2(SCH_1):PVTT_GHJ   I169 @BASEBOARD_FAB2_LIB.BASEBOARD_FAB2(SCH_1):PAGE81
   221 PVTT_GHJ @BASEBOARD_FAB2_LIB.BASEBOARD_FAB2(SCH_1):PVTT_GHJ   I169 @BASEBOARD_FAB2_LIB.BASEBOARD_FAB2(SCH_1):PAGE81

J2L1 CONN4_H73295001_PIP-CONN,H7329A
     1 P5V_HDD_SATA @BASEBOARD_FAB2_LIB.BASEBOARD_FAB2(SCH_1):P5V_HDD_SATA    I53 @BASEBOARD_FAB2_LIB.BASEBOARD_FAB2(SCH_1):PAGE172
     2    GND @BASEBOARD_FAB2_LIB.BASEBOARD_FAB2(SCH_1):GND    I53 @BASEBOARD_FAB2_LIB.BASEBOARD_FAB2(SCH_1):PAGE172
     3    GND @BASEBOARD_FAB2_LIB.BASEBOARD_FAB2(SCH_1):GND    I53 @BASEBOARD_FAB2_LIB.BASEBOARD_FAB2(SCH_1):PAGE172
     4 P12V_HDD_SATA @BASEBOARD_FAB2_LIB.BASEBOARD_FAB2(SCH_1):P12V_HDD_SATA    I53 @BASEBOARD_FAB2_LIB.BASEBOARD_FAB2(SCH_1):PAGE172

J2M1 CONN7_E82125014_PIP_TH-CONN,E8A
     1    GND @BASEBOARD_FAB2_LIB.BASEBOARD_FAB2(SCH_1):GND    I52 @BASEBOARD_FAB2_LIB.BASEBOARD_FAB2(SCH_1):PAGE172
     4    GND @BASEBOARD_FAB2_LIB.BASEBOARD_FAB2(SCH_1):GND    I52 @BASEBOARD_FAB2_LIB.BASEBOARD_FAB2(SCH_1):PAGE172
     7    GND @BASEBOARD_FAB2_LIB.BASEBOARD_FAB2(SCH_1):GND    I52 @BASEBOARD_FAB2_LIB.BASEBOARD_FAB2(SCH_1):PAGE172
   MH1    GND @BASEBOARD_FAB2_LIB.BASEBOARD_FAB2(SCH_1):GND    I52 @BASEBOARD_FAB2_LIB.BASEBOARD_FAB2(SCH_1):PAGE172
   MH2    GND @BASEBOARD_FAB2_LIB.BASEBOARD_FAB2(SCH_1):GND    I52 @BASEBOARD_FAB2_LIB.BASEBOARD_FAB2(SCH_1):PAGE172
     5 SATA6G_S1_RX_C_DN @BASEBOARD_FAB2_LIB.BASEBOARD_FAB2(SCH_1):SATA6G_S1_RX_C_DN    I52 @BASEBOARD_FAB2_LIB.BASEBOARD_FAB2(SCH_1):PAGE172
     6 SATA6G_S1_RX_C_DP @BASEBOARD_FAB2_LIB.BASEBOARD_FAB2(SCH_1):SATA6G_S1_RX_C_DP    I52 @BASEBOARD_FAB2_LIB.BASEBOARD_FAB2(SCH_1):PAGE172
     3 SATA6G_S1_TX_C_DN @BASEBOARD_FAB2_LIB.BASEBOARD_FAB2(SCH_1):SATA6G_S1_TX_C_DN    I52 @BASEBOARD_FAB2_LIB.BASEBOARD_FAB2(SCH_1):PAGE172
     2 SATA6G_S1_TX_C_DP @BASEBOARD_FAB2_LIB.BASEBOARD_FAB2(SCH_1):SATA6G_S1_TX_C_DP    I52 @BASEBOARD_FAB2_LIB.BASEBOARD_FAB2(SCH_1):PAGE172

J4A1 SCONN288_H44441004_PIP-SCONN,HA
    79 M_F_MA<0> @BASEBOARD_FAB2_LIB.BASEBOARD_FAB2(SCH_1):M_F_MA(0)   I111 @BASEBOARD_FAB2_LIB.BASEBOARD_FAB2(SCH_1):PAGE53
    72 M_F_MA<1> @BASEBOARD_FAB2_LIB.BASEBOARD_FAB2(SCH_1):M_F_MA(1)   I111 @BASEBOARD_FAB2_LIB.BASEBOARD_FAB2(SCH_1):PAGE53
   225 M_F_MA<10> @BASEBOARD_FAB2_LIB.BASEBOARD_FAB2(SCH_1):M_F_MA(10)   I111 @BASEBOARD_FAB2_LIB.BASEBOARD_FAB2(SCH_1):PAGE53
   210 M_F_MA<11> @BASEBOARD_FAB2_LIB.BASEBOARD_FAB2(SCH_1):M_F_MA(11)   I111 @BASEBOARD_FAB2_LIB.BASEBOARD_FAB2(SCH_1):PAGE53
    65 M_F_MA<12> @BASEBOARD_FAB2_LIB.BASEBOARD_FAB2(SCH_1):M_F_MA(12)   I111 @BASEBOARD_FAB2_LIB.BASEBOARD_FAB2(SCH_1):PAGE53
   232 M_F_MA<13> @BASEBOARD_FAB2_LIB.BASEBOARD_FAB2(SCH_1):M_F_MA(13)   I111 @BASEBOARD_FAB2_LIB.BASEBOARD_FAB2(SCH_1):PAGE53
   228 M_F_MA<14> @BASEBOARD_FAB2_LIB.BASEBOARD_FAB2(SCH_1):M_F_MA(14)   I111 @BASEBOARD_FAB2_LIB.BASEBOARD_FAB2(SCH_1):PAGE53
    86 M_F_MA<15> @BASEBOARD_FAB2_LIB.BASEBOARD_FAB2(SCH_1):M_F_MA(15)   I111 @BASEBOARD_FAB2_LIB.BASEBOARD_FAB2(SCH_1):PAGE53
    82 M_F_MA<16> @BASEBOARD_FAB2_LIB.BASEBOARD_FAB2(SCH_1):M_F_MA(16)   I111 @BASEBOARD_FAB2_LIB.BASEBOARD_FAB2(SCH_1):PAGE53
   234 M_F_MA<17> @BASEBOARD_FAB2_LIB.BASEBOARD_FAB2(SCH_1):M_F_MA(17)   I111 @BASEBOARD_FAB2_LIB.BASEBOARD_FAB2(SCH_1):PAGE53
   216 M_F_MA<2> @BASEBOARD_FAB2_LIB.BASEBOARD_FAB2(SCH_1):M_F_MA(2)   I111 @BASEBOARD_FAB2_LIB.BASEBOARD_FAB2(SCH_1):PAGE53
    71 M_F_MA<3> @BASEBOARD_FAB2_LIB.BASEBOARD_FAB2(SCH_1):M_F_MA(3)   I111 @BASEBOARD_FAB2_LIB.BASEBOARD_FAB2(SCH_1):PAGE53
   214 M_F_MA<4> @BASEBOARD_FAB2_LIB.BASEBOARD_FAB2(SCH_1):M_F_MA(4)   I111 @BASEBOARD_FAB2_LIB.BASEBOARD_FAB2(SCH_1):PAGE53
   213 M_F_MA<5> @BASEBOARD_FAB2_LIB.BASEBOARD_FAB2(SCH_1):M_F_MA(5)   I111 @BASEBOARD_FAB2_LIB.BASEBOARD_FAB2(SCH_1):PAGE53
    69 M_F_MA<6> @BASEBOARD_FAB2_LIB.BASEBOARD_FAB2(SCH_1):M_F_MA(6)   I111 @BASEBOARD_FAB2_LIB.BASEBOARD_FAB2(SCH_1):PAGE53
   211 M_F_MA<7> @BASEBOARD_FAB2_LIB.BASEBOARD_FAB2(SCH_1):M_F_MA(7)   I111 @BASEBOARD_FAB2_LIB.BASEBOARD_FAB2(SCH_1):PAGE53
    68 M_F_MA<8> @BASEBOARD_FAB2_LIB.BASEBOARD_FAB2(SCH_1):M_F_MA(8)   I111 @BASEBOARD_FAB2_LIB.BASEBOARD_FAB2(SCH_1):PAGE53
    66 M_F_MA<9> @BASEBOARD_FAB2_LIB.BASEBOARD_FAB2(SCH_1):M_F_MA(9)   I111 @BASEBOARD_FAB2_LIB.BASEBOARD_FAB2(SCH_1):PAGE53
    62 M_F_ACT_N @BASEBOARD_FAB2_LIB.BASEBOARD_FAB2(SCH_1):M_F_ACT_N   I111 @BASEBOARD_FAB2_LIB.BASEBOARD_FAB2(SCH_1):PAGE53
   208 M_F_ALERT_N @BASEBOARD_FAB2_LIB.BASEBOARD_FAB2(SCH_1):M_F_ALERT_N   I111 @BASEBOARD_FAB2_LIB.BASEBOARD_FAB2(SCH_1):PAGE53
   224 M_F_BA<1> @BASEBOARD_FAB2_LIB.BASEBOARD_FAB2(SCH_1):M_F_BA(1)   I111 @BASEBOARD_FAB2_LIB.BASEBOARD_FAB2(SCH_1):PAGE53
    81 M_F_BA<0> @BASEBOARD_FAB2_LIB.BASEBOARD_FAB2(SCH_1):M_F_BA(0)   I111 @BASEBOARD_FAB2_LIB.BASEBOARD_FAB2(SCH_1):PAGE53
   207 M_F_BG<1> @BASEBOARD_FAB2_LIB.BASEBOARD_FAB2(SCH_1):M_F_BG(1)   I111 @BASEBOARD_FAB2_LIB.BASEBOARD_FAB2(SCH_1):PAGE53
    63 M_F_BG<0> @BASEBOARD_FAB2_LIB.BASEBOARD_FAB2(SCH_1):M_F_BG(0)   I111 @BASEBOARD_FAB2_LIB.BASEBOARD_FAB2(SCH_1):PAGE53
   235 M_F_C<2> @BASEBOARD_FAB2_LIB.BASEBOARD_FAB2(SCH_1):M_F_C(2)   I111 @BASEBOARD_FAB2_LIB.BASEBOARD_FAB2(SCH_1):PAGE53
   199 M_F_ECC<6> @BASEBOARD_FAB2_LIB.BASEBOARD_FAB2(SCH_1):M_F_ECC(6)   I111 @BASEBOARD_FAB2_LIB.BASEBOARD_FAB2(SCH_1):PAGE53
    54 M_F_ECC<7> @BASEBOARD_FAB2_LIB.BASEBOARD_FAB2(SCH_1):M_F_ECC(7)   I111 @BASEBOARD_FAB2_LIB.BASEBOARD_FAB2(SCH_1):PAGE53
   192 M_F_ECC<4> @BASEBOARD_FAB2_LIB.BASEBOARD_FAB2(SCH_1):M_F_ECC(4)   I111 @BASEBOARD_FAB2_LIB.BASEBOARD_FAB2(SCH_1):PAGE53
    47 M_F_ECC<5> @BASEBOARD_FAB2_LIB.BASEBOARD_FAB2(SCH_1):M_F_ECC(5)   I111 @BASEBOARD_FAB2_LIB.BASEBOARD_FAB2(SCH_1):PAGE53
   201 M_F_ECC<2> @BASEBOARD_FAB2_LIB.BASEBOARD_FAB2(SCH_1):M_F_ECC(2)   I111 @BASEBOARD_FAB2_LIB.BASEBOARD_FAB2(SCH_1):PAGE53
    56 M_F_ECC<3> @BASEBOARD_FAB2_LIB.BASEBOARD_FAB2(SCH_1):M_F_ECC(3)   I111 @BASEBOARD_FAB2_LIB.BASEBOARD_FAB2(SCH_1):PAGE53
   194 M_F_ECC<0> @BASEBOARD_FAB2_LIB.BASEBOARD_FAB2(SCH_1):M_F_ECC(0)   I111 @BASEBOARD_FAB2_LIB.BASEBOARD_FAB2(SCH_1):PAGE53
    49 M_F_ECC<1> @BASEBOARD_FAB2_LIB.BASEBOARD_FAB2(SCH_1):M_F_ECC(1)   I111 @BASEBOARD_FAB2_LIB.BASEBOARD_FAB2(SCH_1):PAGE53
    75 M_F_CLK_DN<0> @BASEBOARD_FAB2_LIB.BASEBOARD_FAB2(SCH_1):M_F_CLK_DN(0)   I111 @BASEBOARD_FAB2_LIB.BASEBOARD_FAB2(SCH_1):PAGE53
    74 M_F_CLK_DP<0> @BASEBOARD_FAB2_LIB.BASEBOARD_FAB2(SCH_1):M_F_CLK_DP(0)   I111 @BASEBOARD_FAB2_LIB.BASEBOARD_FAB2(SCH_1):PAGE53
   219 M_F_CLK_DN<1> @BASEBOARD_FAB2_LIB.BASEBOARD_FAB2(SCH_1):M_F_CLK_DN(1)   I111 @BASEBOARD_FAB2_LIB.BASEBOARD_FAB2(SCH_1):PAGE53
   218 M_F_CLK_DP<1> @BASEBOARD_FAB2_LIB.BASEBOARD_FAB2(SCH_1):M_F_CLK_DP(1)   I111 @BASEBOARD_FAB2_LIB.BASEBOARD_FAB2(SCH_1):PAGE53
   203 M_F_CKE<1> @BASEBOARD_FAB2_LIB.BASEBOARD_FAB2(SCH_1):M_F_CKE(1)   I111 @BASEBOARD_FAB2_LIB.BASEBOARD_FAB2(SCH_1):PAGE53
    60 M_F_CKE<0> @BASEBOARD_FAB2_LIB.BASEBOARD_FAB2(SCH_1):M_F_CKE(0)   I111 @BASEBOARD_FAB2_LIB.BASEBOARD_FAB2(SCH_1):PAGE53
   280 M_F_DQ<62> @BASEBOARD_FAB2_LIB.BASEBOARD_FAB2(SCH_1):M_F_DQ(62)   I111 @BASEBOARD_FAB2_LIB.BASEBOARD_FAB2(SCH_1):PAGE53
   135 M_F_DQ<63> @BASEBOARD_FAB2_LIB.BASEBOARD_FAB2(SCH_1):M_F_DQ(63)   I111 @BASEBOARD_FAB2_LIB.BASEBOARD_FAB2(SCH_1):PAGE53
   273 M_F_DQ<60> @BASEBOARD_FAB2_LIB.BASEBOARD_FAB2(SCH_1):M_F_DQ(60)   I111 @BASEBOARD_FAB2_LIB.BASEBOARD_FAB2(SCH_1):PAGE53
   128 M_F_DQ<61> @BASEBOARD_FAB2_LIB.BASEBOARD_FAB2(SCH_1):M_F_DQ(61)   I111 @BASEBOARD_FAB2_LIB.BASEBOARD_FAB2(SCH_1):PAGE53
   282 M_F_DQ<58> @BASEBOARD_FAB2_LIB.BASEBOARD_FAB2(SCH_1):M_F_DQ(58)   I111 @BASEBOARD_FAB2_LIB.BASEBOARD_FAB2(SCH_1):PAGE53
   137 M_F_DQ<59> @BASEBOARD_FAB2_LIB.BASEBOARD_FAB2(SCH_1):M_F_DQ(59)   I111 @BASEBOARD_FAB2_LIB.BASEBOARD_FAB2(SCH_1):PAGE53
   275 M_F_DQ<56> @BASEBOARD_FAB2_LIB.BASEBOARD_FAB2(SCH_1):M_F_DQ(56)   I111 @BASEBOARD_FAB2_LIB.BASEBOARD_FAB2(SCH_1):PAGE53
   130 M_F_DQ<57> @BASEBOARD_FAB2_LIB.BASEBOARD_FAB2(SCH_1):M_F_DQ(57)   I111 @BASEBOARD_FAB2_LIB.BASEBOARD_FAB2(SCH_1):PAGE53
   269 M_F_DQ<54> @BASEBOARD_FAB2_LIB.BASEBOARD_FAB2(SCH_1):M_F_DQ(54)   I111 @BASEBOARD_FAB2_LIB.BASEBOARD_FAB2(SCH_1):PAGE53
   124 M_F_DQ<55> @BASEBOARD_FAB2_LIB.BASEBOARD_FAB2(SCH_1):M_F_DQ(55)   I111 @BASEBOARD_FAB2_LIB.BASEBOARD_FAB2(SCH_1):PAGE53
   262 M_F_DQ<52> @BASEBOARD_FAB2_LIB.BASEBOARD_FAB2(SCH_1):M_F_DQ(52)   I111 @BASEBOARD_FAB2_LIB.BASEBOARD_FAB2(SCH_1):PAGE53
   117 M_F_DQ<53> @BASEBOARD_FAB2_LIB.BASEBOARD_FAB2(SCH_1):M_F_DQ(53)   I111 @BASEBOARD_FAB2_LIB.BASEBOARD_FAB2(SCH_1):PAGE53
   271 M_F_DQ<50> @BASEBOARD_FAB2_LIB.BASEBOARD_FAB2(SCH_1):M_F_DQ(50)   I111 @BASEBOARD_FAB2_LIB.BASEBOARD_FAB2(SCH_1):PAGE53
   126 M_F_DQ<51> @BASEBOARD_FAB2_LIB.BASEBOARD_FAB2(SCH_1):M_F_DQ(51)   I111 @BASEBOARD_FAB2_LIB.BASEBOARD_FAB2(SCH_1):PAGE53
   264 M_F_DQ<48> @BASEBOARD_FAB2_LIB.BASEBOARD_FAB2(SCH_1):M_F_DQ(48)   I111 @BASEBOARD_FAB2_LIB.BASEBOARD_FAB2(SCH_1):PAGE53
   119 M_F_DQ<49> @BASEBOARD_FAB2_LIB.BASEBOARD_FAB2(SCH_1):M_F_DQ(49)   I111 @BASEBOARD_FAB2_LIB.BASEBOARD_FAB2(SCH_1):PAGE53
   258 M_F_DQ<46> @BASEBOARD_FAB2_LIB.BASEBOARD_FAB2(SCH_1):M_F_DQ(46)   I111 @BASEBOARD_FAB2_LIB.BASEBOARD_FAB2(SCH_1):PAGE53
   113 M_F_DQ<47> @BASEBOARD_FAB2_LIB.BASEBOARD_FAB2(SCH_1):M_F_DQ(47)   I111 @BASEBOARD_FAB2_LIB.BASEBOARD_FAB2(SCH_1):PAGE53
   251 M_F_DQ<44> @BASEBOARD_FAB2_LIB.BASEBOARD_FAB2(SCH_1):M_F_DQ(44)   I111 @BASEBOARD_FAB2_LIB.BASEBOARD_FAB2(SCH_1):PAGE53
   106 M_F_DQ<45> @BASEBOARD_FAB2_LIB.BASEBOARD_FAB2(SCH_1):M_F_DQ(45)   I111 @BASEBOARD_FAB2_LIB.BASEBOARD_FAB2(SCH_1):PAGE53
   260 M_F_DQ<42> @BASEBOARD_FAB2_LIB.BASEBOARD_FAB2(SCH_1):M_F_DQ(42)   I111 @BASEBOARD_FAB2_LIB.BASEBOARD_FAB2(SCH_1):PAGE53
   115 M_F_DQ<43> @BASEBOARD_FAB2_LIB.BASEBOARD_FAB2(SCH_1):M_F_DQ(43)   I111 @BASEBOARD_FAB2_LIB.BASEBOARD_FAB2(SCH_1):PAGE53
   253 M_F_DQ<40> @BASEBOARD_FAB2_LIB.BASEBOARD_FAB2(SCH_1):M_F_DQ(40)   I111 @BASEBOARD_FAB2_LIB.BASEBOARD_FAB2(SCH_1):PAGE53
   108 M_F_DQ<41> @BASEBOARD_FAB2_LIB.BASEBOARD_FAB2(SCH_1):M_F_DQ(41)   I111 @BASEBOARD_FAB2_LIB.BASEBOARD_FAB2(SCH_1):PAGE53
   247 M_F_DQ<38> @BASEBOARD_FAB2_LIB.BASEBOARD_FAB2(SCH_1):M_F_DQ(38)   I111 @BASEBOARD_FAB2_LIB.BASEBOARD_FAB2(SCH_1):PAGE53
   102 M_F_DQ<39> @BASEBOARD_FAB2_LIB.BASEBOARD_FAB2(SCH_1):M_F_DQ(39)   I111 @BASEBOARD_FAB2_LIB.BASEBOARD_FAB2(SCH_1):PAGE53
   240 M_F_DQ<36> @BASEBOARD_FAB2_LIB.BASEBOARD_FAB2(SCH_1):M_F_DQ(36)   I111 @BASEBOARD_FAB2_LIB.BASEBOARD_FAB2(SCH_1):PAGE53
    95 M_F_DQ<37> @BASEBOARD_FAB2_LIB.BASEBOARD_FAB2(SCH_1):M_F_DQ(37)   I111 @BASEBOARD_FAB2_LIB.BASEBOARD_FAB2(SCH_1):PAGE53
   249 M_F_DQ<34> @BASEBOARD_FAB2_LIB.BASEBOARD_FAB2(SCH_1):M_F_DQ(34)   I111 @BASEBOARD_FAB2_LIB.BASEBOARD_FAB2(SCH_1):PAGE53
   104 M_F_DQ<35> @BASEBOARD_FAB2_LIB.BASEBOARD_FAB2(SCH_1):M_F_DQ(35)   I111 @BASEBOARD_FAB2_LIB.BASEBOARD_FAB2(SCH_1):PAGE53
   242 M_F_DQ<32> @BASEBOARD_FAB2_LIB.BASEBOARD_FAB2(SCH_1):M_F_DQ(32)   I111 @BASEBOARD_FAB2_LIB.BASEBOARD_FAB2(SCH_1):PAGE53
    97 M_F_DQ<33> @BASEBOARD_FAB2_LIB.BASEBOARD_FAB2(SCH_1):M_F_DQ(33)   I111 @BASEBOARD_FAB2_LIB.BASEBOARD_FAB2(SCH_1):PAGE53
   188 M_F_DQ<30> @BASEBOARD_FAB2_LIB.BASEBOARD_FAB2(SCH_1):M_F_DQ(30)   I111 @BASEBOARD_FAB2_LIB.BASEBOARD_FAB2(SCH_1):PAGE53
    43 M_F_DQ<31> @BASEBOARD_FAB2_LIB.BASEBOARD_FAB2(SCH_1):M_F_DQ(31)   I111 @BASEBOARD_FAB2_LIB.BASEBOARD_FAB2(SCH_1):PAGE53
   181 M_F_DQ<28> @BASEBOARD_FAB2_LIB.BASEBOARD_FAB2(SCH_1):M_F_DQ(28)   I111 @BASEBOARD_FAB2_LIB.BASEBOARD_FAB2(SCH_1):PAGE53
    36 M_F_DQ<29> @BASEBOARD_FAB2_LIB.BASEBOARD_FAB2(SCH_1):M_F_DQ(29)   I111 @BASEBOARD_FAB2_LIB.BASEBOARD_FAB2(SCH_1):PAGE53
   190 M_F_DQ<26> @BASEBOARD_FAB2_LIB.BASEBOARD_FAB2(SCH_1):M_F_DQ(26)   I111 @BASEBOARD_FAB2_LIB.BASEBOARD_FAB2(SCH_1):PAGE53
    45 M_F_DQ<27> @BASEBOARD_FAB2_LIB.BASEBOARD_FAB2(SCH_1):M_F_DQ(27)   I111 @BASEBOARD_FAB2_LIB.BASEBOARD_FAB2(SCH_1):PAGE53
   183 M_F_DQ<24> @BASEBOARD_FAB2_LIB.BASEBOARD_FAB2(SCH_1):M_F_DQ(24)   I111 @BASEBOARD_FAB2_LIB.BASEBOARD_FAB2(SCH_1):PAGE53
    38 M_F_DQ<25> @BASEBOARD_FAB2_LIB.BASEBOARD_FAB2(SCH_1):M_F_DQ(25)   I111 @BASEBOARD_FAB2_LIB.BASEBOARD_FAB2(SCH_1):PAGE53
   177 M_F_DQ<22> @BASEBOARD_FAB2_LIB.BASEBOARD_FAB2(SCH_1):M_F_DQ(22)   I111 @BASEBOARD_FAB2_LIB.BASEBOARD_FAB2(SCH_1):PAGE53
    32 M_F_DQ<23> @BASEBOARD_FAB2_LIB.BASEBOARD_FAB2(SCH_1):M_F_DQ(23)   I111 @BASEBOARD_FAB2_LIB.BASEBOARD_FAB2(SCH_1):PAGE53
   170 M_F_DQ<20> @BASEBOARD_FAB2_LIB.BASEBOARD_FAB2(SCH_1):M_F_DQ(20)   I111 @BASEBOARD_FAB2_LIB.BASEBOARD_FAB2(SCH_1):PAGE53
    25 M_F_DQ<21> @BASEBOARD_FAB2_LIB.BASEBOARD_FAB2(SCH_1):M_F_DQ(21)   I111 @BASEBOARD_FAB2_LIB.BASEBOARD_FAB2(SCH_1):PAGE53
   179 M_F_DQ<18> @BASEBOARD_FAB2_LIB.BASEBOARD_FAB2(SCH_1):M_F_DQ(18)   I111 @BASEBOARD_FAB2_LIB.BASEBOARD_FAB2(SCH_1):PAGE53
    34 M_F_DQ<19> @BASEBOARD_FAB2_LIB.BASEBOARD_FAB2(SCH_1):M_F_DQ(19)   I111 @BASEBOARD_FAB2_LIB.BASEBOARD_FAB2(SCH_1):PAGE53
   172 M_F_DQ<16> @BASEBOARD_FAB2_LIB.BASEBOARD_FAB2(SCH_1):M_F_DQ(16)   I111 @BASEBOARD_FAB2_LIB.BASEBOARD_FAB2(SCH_1):PAGE53
    27 M_F_DQ<17> @BASEBOARD_FAB2_LIB.BASEBOARD_FAB2(SCH_1):M_F_DQ(17)   I111 @BASEBOARD_FAB2_LIB.BASEBOARD_FAB2(SCH_1):PAGE53
   166 M_F_DQ<14> @BASEBOARD_FAB2_LIB.BASEBOARD_FAB2(SCH_1):M_F_DQ(14)   I111 @BASEBOARD_FAB2_LIB.BASEBOARD_FAB2(SCH_1):PAGE53
    21 M_F_DQ<15> @BASEBOARD_FAB2_LIB.BASEBOARD_FAB2(SCH_1):M_F_DQ(15)   I111 @BASEBOARD_FAB2_LIB.BASEBOARD_FAB2(SCH_1):PAGE53
   159 M_F_DQ<12> @BASEBOARD_FAB2_LIB.BASEBOARD_FAB2(SCH_1):M_F_DQ(12)   I111 @BASEBOARD_FAB2_LIB.BASEBOARD_FAB2(SCH_1):PAGE53
    14 M_F_DQ<13> @BASEBOARD_FAB2_LIB.BASEBOARD_FAB2(SCH_1):M_F_DQ(13)   I111 @BASEBOARD_FAB2_LIB.BASEBOARD_FAB2(SCH_1):PAGE53
   168 M_F_DQ<10> @BASEBOARD_FAB2_LIB.BASEBOARD_FAB2(SCH_1):M_F_DQ(10)   I111 @BASEBOARD_FAB2_LIB.BASEBOARD_FAB2(SCH_1):PAGE53
    23 M_F_DQ<11> @BASEBOARD_FAB2_LIB.BASEBOARD_FAB2(SCH_1):M_F_DQ(11)   I111 @BASEBOARD_FAB2_LIB.BASEBOARD_FAB2(SCH_1):PAGE53
   161 M_F_DQ<8> @BASEBOARD_FAB2_LIB.BASEBOARD_FAB2(SCH_1):M_F_DQ(8)   I111 @BASEBOARD_FAB2_LIB.BASEBOARD_FAB2(SCH_1):PAGE53
    16 M_F_DQ<9> @BASEBOARD_FAB2_LIB.BASEBOARD_FAB2(SCH_1):M_F_DQ(9)   I111 @BASEBOARD_FAB2_LIB.BASEBOARD_FAB2(SCH_1):PAGE53
   155 M_F_DQ<6> @BASEBOARD_FAB2_LIB.BASEBOARD_FAB2(SCH_1):M_F_DQ(6)   I111 @BASEBOARD_FAB2_LIB.BASEBOARD_FAB2(SCH_1):PAGE53
    10 M_F_DQ<7> @BASEBOARD_FAB2_LIB.BASEBOARD_FAB2(SCH_1):M_F_DQ(7)   I111 @BASEBOARD_FAB2_LIB.BASEBOARD_FAB2(SCH_1):PAGE53
   148 M_F_DQ<4> @BASEBOARD_FAB2_LIB.BASEBOARD_FAB2(SCH_1):M_F_DQ(4)   I111 @BASEBOARD_FAB2_LIB.BASEBOARD_FAB2(SCH_1):PAGE53
     3 M_F_DQ<5> @BASEBOARD_FAB2_LIB.BASEBOARD_FAB2(SCH_1):M_F_DQ(5)   I111 @BASEBOARD_FAB2_LIB.BASEBOARD_FAB2(SCH_1):PAGE53
   157 M_F_DQ<2> @BASEBOARD_FAB2_LIB.BASEBOARD_FAB2(SCH_1):M_F_DQ(2)   I111 @BASEBOARD_FAB2_LIB.BASEBOARD_FAB2(SCH_1):PAGE53
    12 M_F_DQ<3> @BASEBOARD_FAB2_LIB.BASEBOARD_FAB2(SCH_1):M_F_DQ(3)   I111 @BASEBOARD_FAB2_LIB.BASEBOARD_FAB2(SCH_1):PAGE53
   150 M_F_DQ<0> @BASEBOARD_FAB2_LIB.BASEBOARD_FAB2(SCH_1):M_F_DQ(0)   I111 @BASEBOARD_FAB2_LIB.BASEBOARD_FAB2(SCH_1):PAGE53
     5 M_F_DQ<1> @BASEBOARD_FAB2_LIB.BASEBOARD_FAB2(SCH_1):M_F_DQ(1)   I111 @BASEBOARD_FAB2_LIB.BASEBOARD_FAB2(SCH_1):PAGE53
    78 FM_DIMM_EVENT_COD_N @BASEBOARD_FAB2_LIB.BASEBOARD_FAB2(SCH_1):FM_DIMM_EVENT_COD_N   I111 @BASEBOARD_FAB2_LIB.BASEBOARD_FAB2(SCH_1):PAGE53
    91 M_F_ODT<1> @BASEBOARD_FAB2_LIB.BASEBOARD_FAB2(SCH_1):M_F_ODT(1)   I111 @BASEBOARD_FAB2_LIB.BASEBOARD_FAB2(SCH_1):PAGE53
    87 M_F_ODT<0> @BASEBOARD_FAB2_LIB.BASEBOARD_FAB2(SCH_1):M_F_ODT(0)   I111 @BASEBOARD_FAB2_LIB.BASEBOARD_FAB2(SCH_1):PAGE53
   222 M_F_PAR @BASEBOARD_FAB2_LIB.BASEBOARD_FAB2(SCH_1):M_F_PAR   I111 @BASEBOARD_FAB2_LIB.BASEBOARD_FAB2(SCH_1):PAGE53
    58 M_DEF_RST_N @BASEBOARD_FAB2_LIB.BASEBOARD_FAB2(SCH_1):M_DEF_RST_N   I111 @BASEBOARD_FAB2_LIB.BASEBOARD_FAB2(SCH_1):PAGE53
   144 TP_CH_F_DIMM_F0_RFU_2 @BASEBOARD_FAB2_LIB.BASEBOARD_FAB2(SCH_1):TP_CH_F_DIMM_F0_RFU_2   I111 @BASEBOARD_FAB2_LIB.BASEBOARD_FAB2(SCH_1):PAGE53
   227 TP_CH_F_DIMM_F0_RFU_1 @BASEBOARD_FAB2_LIB.BASEBOARD_FAB2(SCH_1):TP_CH_F_DIMM_F0_RFU_1   I111 @BASEBOARD_FAB2_LIB.BASEBOARD_FAB2(SCH_1):PAGE53
   205 TP_CH_F_DIMM_F0_RFU_0 @BASEBOARD_FAB2_LIB.BASEBOARD_FAB2(SCH_1):TP_CH_F_DIMM_F0_RFU_0   I111 @BASEBOARD_FAB2_LIB.BASEBOARD_FAB2(SCH_1):PAGE53
    84 M_F_CS_N<0> @BASEBOARD_FAB2_LIB.BASEBOARD_FAB2(SCH_1):M_F_CS_N(0)   I111 @BASEBOARD_FAB2_LIB.BASEBOARD_FAB2(SCH_1):PAGE53
    89 M_F_CS_N<1> @BASEBOARD_FAB2_LIB.BASEBOARD_FAB2(SCH_1):M_F_CS_N(1)   I111 @BASEBOARD_FAB2_LIB.BASEBOARD_FAB2(SCH_1):PAGE53
    93 M_F_CS_N<2> @BASEBOARD_FAB2_LIB.BASEBOARD_FAB2(SCH_1):M_F_CS_N(2)   I111 @BASEBOARD_FAB2_LIB.BASEBOARD_FAB2(SCH_1):PAGE53
   237 M_F_CS_N<3> @BASEBOARD_FAB2_LIB.BASEBOARD_FAB2(SCH_1):M_F_CS_N(3)   I111 @BASEBOARD_FAB2_LIB.BASEBOARD_FAB2(SCH_1):PAGE53
   238 PVPP_DEF @BASEBOARD_FAB2_LIB.BASEBOARD_FAB2(SCH_1):PVPP_DEF   I111 @BASEBOARD_FAB2_LIB.BASEBOARD_FAB2(SCH_1):PAGE53
   140    GND @BASEBOARD_FAB2_LIB.BASEBOARD_FAB2(SCH_1):GND   I111 @BASEBOARD_FAB2_LIB.BASEBOARD_FAB2(SCH_1):PAGE53
   139    GND @BASEBOARD_FAB2_LIB.BASEBOARD_FAB2(SCH_1):GND   I111 @BASEBOARD_FAB2_LIB.BASEBOARD_FAB2(SCH_1):PAGE53
   230 FM_ADR_COMPLETE_DEF_N @BASEBOARD_FAB2_LIB.BASEBOARD_FAB2(SCH_1):FM_ADR_COMPLETE_DEF_N   I111 @BASEBOARD_FAB2_LIB.BASEBOARD_FAB2(SCH_1):PAGE53
   141 SMB_DDR_DEF_VPP_SCL @BASEBOARD_FAB2_LIB.BASEBOARD_FAB2(SCH_1):SMB_DDR_DEF_VPP_SCL   I111 @BASEBOARD_FAB2_LIB.BASEBOARD_FAB2(SCH_1):PAGE53
   285 SMB_DDR_DEF_VPP_SDA @BASEBOARD_FAB2_LIB.BASEBOARD_FAB2(SCH_1):SMB_DDR_DEF_VPP_SDA   I111 @BASEBOARD_FAB2_LIB.BASEBOARD_FAB2(SCH_1):PAGE53
   284 PVPP_DEF @BASEBOARD_FAB2_LIB.BASEBOARD_FAB2(SCH_1):PVPP_DEF   I111 @BASEBOARD_FAB2_LIB.BASEBOARD_FAB2(SCH_1):PAGE53
   146 M_F_VREF @BASEBOARD_FAB2_LIB.BASEBOARD_FAB2(SCH_1):M_F_VREF   I111 @BASEBOARD_FAB2_LIB.BASEBOARD_FAB2(SCH_1):PAGE53
   152 M_F_DQS_DN<0> @BASEBOARD_FAB2_LIB.BASEBOARD_FAB2(SCH_1):M_F_DQS_DN(0)    I66 @BASEBOARD_FAB2_LIB.BASEBOARD_FAB2(SCH_1):PAGE53
   153 M_F_DQS_DP<0> @BASEBOARD_FAB2_LIB.BASEBOARD_FAB2(SCH_1):M_F_DQS_DP(0)    I66 @BASEBOARD_FAB2_LIB.BASEBOARD_FAB2(SCH_1):PAGE53
    19 M_F_DQS_DN<10> @BASEBOARD_FAB2_LIB.BASEBOARD_FAB2(SCH_1):M_F_DQS_DN(10)    I66 @BASEBOARD_FAB2_LIB.BASEBOARD_FAB2(SCH_1):PAGE53
    18 M_F_DQS_DP<10> @BASEBOARD_FAB2_LIB.BASEBOARD_FAB2(SCH_1):M_F_DQS_DP(10)    I66 @BASEBOARD_FAB2_LIB.BASEBOARD_FAB2(SCH_1):PAGE53
    30 M_F_DQS_DN<11> @BASEBOARD_FAB2_LIB.BASEBOARD_FAB2(SCH_1):M_F_DQS_DN(11)    I66 @BASEBOARD_FAB2_LIB.BASEBOARD_FAB2(SCH_1):PAGE53
    29 M_F_DQS_DP<11> @BASEBOARD_FAB2_LIB.BASEBOARD_FAB2(SCH_1):M_F_DQS_DP(11)    I66 @BASEBOARD_FAB2_LIB.BASEBOARD_FAB2(SCH_1):PAGE53
    41 M_F_DQS_DN<12> @BASEBOARD_FAB2_LIB.BASEBOARD_FAB2(SCH_1):M_F_DQS_DN(12)    I66 @BASEBOARD_FAB2_LIB.BASEBOARD_FAB2(SCH_1):PAGE53
    40 M_F_DQS_DP<12> @BASEBOARD_FAB2_LIB.BASEBOARD_FAB2(SCH_1):M_F_DQS_DP(12)    I66 @BASEBOARD_FAB2_LIB.BASEBOARD_FAB2(SCH_1):PAGE53
   100 M_F_DQS_DN<13> @BASEBOARD_FAB2_LIB.BASEBOARD_FAB2(SCH_1):M_F_DQS_DN(13)    I66 @BASEBOARD_FAB2_LIB.BASEBOARD_FAB2(SCH_1):PAGE53
    99 M_F_DQS_DP<13> @BASEBOARD_FAB2_LIB.BASEBOARD_FAB2(SCH_1):M_F_DQS_DP(13)    I66 @BASEBOARD_FAB2_LIB.BASEBOARD_FAB2(SCH_1):PAGE53
   111 M_F_DQS_DN<14> @BASEBOARD_FAB2_LIB.BASEBOARD_FAB2(SCH_1):M_F_DQS_DN(14)    I66 @BASEBOARD_FAB2_LIB.BASEBOARD_FAB2(SCH_1):PAGE53
   110 M_F_DQS_DP<14> @BASEBOARD_FAB2_LIB.BASEBOARD_FAB2(SCH_1):M_F_DQS_DP(14)    I66 @BASEBOARD_FAB2_LIB.BASEBOARD_FAB2(SCH_1):PAGE53
   122 M_F_DQS_DN<15> @BASEBOARD_FAB2_LIB.BASEBOARD_FAB2(SCH_1):M_F_DQS_DN(15)    I66 @BASEBOARD_FAB2_LIB.BASEBOARD_FAB2(SCH_1):PAGE53
   121 M_F_DQS_DP<15> @BASEBOARD_FAB2_LIB.BASEBOARD_FAB2(SCH_1):M_F_DQS_DP(15)    I66 @BASEBOARD_FAB2_LIB.BASEBOARD_FAB2(SCH_1):PAGE53
   133 M_F_DQS_DN<16> @BASEBOARD_FAB2_LIB.BASEBOARD_FAB2(SCH_1):M_F_DQS_DN(16)    I66 @BASEBOARD_FAB2_LIB.BASEBOARD_FAB2(SCH_1):PAGE53
   132 M_F_DQS_DP<16> @BASEBOARD_FAB2_LIB.BASEBOARD_FAB2(SCH_1):M_F_DQS_DP(16)    I66 @BASEBOARD_FAB2_LIB.BASEBOARD_FAB2(SCH_1):PAGE53
    52 M_F_DQS_DN<17> @BASEBOARD_FAB2_LIB.BASEBOARD_FAB2(SCH_1):M_F_DQS_DN(17)    I66 @BASEBOARD_FAB2_LIB.BASEBOARD_FAB2(SCH_1):PAGE53
    51 M_F_DQS_DP<17> @BASEBOARD_FAB2_LIB.BASEBOARD_FAB2(SCH_1):M_F_DQS_DP(17)    I66 @BASEBOARD_FAB2_LIB.BASEBOARD_FAB2(SCH_1):PAGE53
   163 M_F_DQS_DN<1> @BASEBOARD_FAB2_LIB.BASEBOARD_FAB2(SCH_1):M_F_DQS_DN(1)    I66 @BASEBOARD_FAB2_LIB.BASEBOARD_FAB2(SCH_1):PAGE53
   164 M_F_DQS_DP<1> @BASEBOARD_FAB2_LIB.BASEBOARD_FAB2(SCH_1):M_F_DQS_DP(1)    I66 @BASEBOARD_FAB2_LIB.BASEBOARD_FAB2(SCH_1):PAGE53
   174 M_F_DQS_DN<2> @BASEBOARD_FAB2_LIB.BASEBOARD_FAB2(SCH_1):M_F_DQS_DN(2)    I66 @BASEBOARD_FAB2_LIB.BASEBOARD_FAB2(SCH_1):PAGE53
   175 M_F_DQS_DP<2> @BASEBOARD_FAB2_LIB.BASEBOARD_FAB2(SCH_1):M_F_DQS_DP(2)    I66 @BASEBOARD_FAB2_LIB.BASEBOARD_FAB2(SCH_1):PAGE53
   185 M_F_DQS_DN<3> @BASEBOARD_FAB2_LIB.BASEBOARD_FAB2(SCH_1):M_F_DQS_DN(3)    I66 @BASEBOARD_FAB2_LIB.BASEBOARD_FAB2(SCH_1):PAGE53
   186 M_F_DQS_DP<3> @BASEBOARD_FAB2_LIB.BASEBOARD_FAB2(SCH_1):M_F_DQS_DP(3)    I66 @BASEBOARD_FAB2_LIB.BASEBOARD_FAB2(SCH_1):PAGE53
   244 M_F_DQS_DN<4> @BASEBOARD_FAB2_LIB.BASEBOARD_FAB2(SCH_1):M_F_DQS_DN(4)    I66 @BASEBOARD_FAB2_LIB.BASEBOARD_FAB2(SCH_1):PAGE53
   245 M_F_DQS_DP<4> @BASEBOARD_FAB2_LIB.BASEBOARD_FAB2(SCH_1):M_F_DQS_DP(4)    I66 @BASEBOARD_FAB2_LIB.BASEBOARD_FAB2(SCH_1):PAGE53
   255 M_F_DQS_DN<5> @BASEBOARD_FAB2_LIB.BASEBOARD_FAB2(SCH_1):M_F_DQS_DN(5)    I66 @BASEBOARD_FAB2_LIB.BASEBOARD_FAB2(SCH_1):PAGE53
   256 M_F_DQS_DP<5> @BASEBOARD_FAB2_LIB.BASEBOARD_FAB2(SCH_1):M_F_DQS_DP(5)    I66 @BASEBOARD_FAB2_LIB.BASEBOARD_FAB2(SCH_1):PAGE53
   266 M_F_DQS_DN<6> @BASEBOARD_FAB2_LIB.BASEBOARD_FAB2(SCH_1):M_F_DQS_DN(6)    I66 @BASEBOARD_FAB2_LIB.BASEBOARD_FAB2(SCH_1):PAGE53
   267 M_F_DQS_DP<6> @BASEBOARD_FAB2_LIB.BASEBOARD_FAB2(SCH_1):M_F_DQS_DP(6)    I66 @BASEBOARD_FAB2_LIB.BASEBOARD_FAB2(SCH_1):PAGE53
   277 M_F_DQS_DN<7> @BASEBOARD_FAB2_LIB.BASEBOARD_FAB2(SCH_1):M_F_DQS_DN(7)    I66 @BASEBOARD_FAB2_LIB.BASEBOARD_FAB2(SCH_1):PAGE53
   278 M_F_DQS_DP<7> @BASEBOARD_FAB2_LIB.BASEBOARD_FAB2(SCH_1):M_F_DQS_DP(7)    I66 @BASEBOARD_FAB2_LIB.BASEBOARD_FAB2(SCH_1):PAGE53
   196 M_F_DQS_DN<8> @BASEBOARD_FAB2_LIB.BASEBOARD_FAB2(SCH_1):M_F_DQS_DN(8)    I66 @BASEBOARD_FAB2_LIB.BASEBOARD_FAB2(SCH_1):PAGE53
   197 M_F_DQS_DP<8> @BASEBOARD_FAB2_LIB.BASEBOARD_FAB2(SCH_1):M_F_DQS_DP(8)    I66 @BASEBOARD_FAB2_LIB.BASEBOARD_FAB2(SCH_1):PAGE53
     8 M_F_DQS_DN<9> @BASEBOARD_FAB2_LIB.BASEBOARD_FAB2(SCH_1):M_F_DQS_DN(9)    I66 @BASEBOARD_FAB2_LIB.BASEBOARD_FAB2(SCH_1):PAGE53
     7 M_F_DQS_DP<9> @BASEBOARD_FAB2_LIB.BASEBOARD_FAB2(SCH_1):M_F_DQS_DP(9)    I66 @BASEBOARD_FAB2_LIB.BASEBOARD_FAB2(SCH_1):PAGE53
     2    GND @BASEBOARD_FAB2_LIB.BASEBOARD_FAB2(SCH_1):GND    I43 @BASEBOARD_FAB2_LIB.BASEBOARD_FAB2(SCH_1):PAGE53
     4    GND @BASEBOARD_FAB2_LIB.BASEBOARD_FAB2(SCH_1):GND    I43 @BASEBOARD_FAB2_LIB.BASEBOARD_FAB2(SCH_1):PAGE53
     6    GND @BASEBOARD_FAB2_LIB.BASEBOARD_FAB2(SCH_1):GND    I43 @BASEBOARD_FAB2_LIB.BASEBOARD_FAB2(SCH_1):PAGE53
     9    GND @BASEBOARD_FAB2_LIB.BASEBOARD_FAB2(SCH_1):GND    I43 @BASEBOARD_FAB2_LIB.BASEBOARD_FAB2(SCH_1):PAGE53
    11    GND @BASEBOARD_FAB2_LIB.BASEBOARD_FAB2(SCH_1):GND    I43 @BASEBOARD_FAB2_LIB.BASEBOARD_FAB2(SCH_1):PAGE53
    13    GND @BASEBOARD_FAB2_LIB.BASEBOARD_FAB2(SCH_1):GND    I43 @BASEBOARD_FAB2_LIB.BASEBOARD_FAB2(SCH_1):PAGE53
    15    GND @BASEBOARD_FAB2_LIB.BASEBOARD_FAB2(SCH_1):GND    I43 @BASEBOARD_FAB2_LIB.BASEBOARD_FAB2(SCH_1):PAGE53
    17    GND @BASEBOARD_FAB2_LIB.BASEBOARD_FAB2(SCH_1):GND    I43 @BASEBOARD_FAB2_LIB.BASEBOARD_FAB2(SCH_1):PAGE53
    20    GND @BASEBOARD_FAB2_LIB.BASEBOARD_FAB2(SCH_1):GND    I43 @BASEBOARD_FAB2_LIB.BASEBOARD_FAB2(SCH_1):PAGE53
    22    GND @BASEBOARD_FAB2_LIB.BASEBOARD_FAB2(SCH_1):GND    I43 @BASEBOARD_FAB2_LIB.BASEBOARD_FAB2(SCH_1):PAGE53
    24    GND @BASEBOARD_FAB2_LIB.BASEBOARD_FAB2(SCH_1):GND    I43 @BASEBOARD_FAB2_LIB.BASEBOARD_FAB2(SCH_1):PAGE53
    26    GND @BASEBOARD_FAB2_LIB.BASEBOARD_FAB2(SCH_1):GND    I43 @BASEBOARD_FAB2_LIB.BASEBOARD_FAB2(SCH_1):PAGE53
    28    GND @BASEBOARD_FAB2_LIB.BASEBOARD_FAB2(SCH_1):GND    I43 @BASEBOARD_FAB2_LIB.BASEBOARD_FAB2(SCH_1):PAGE53
    31    GND @BASEBOARD_FAB2_LIB.BASEBOARD_FAB2(SCH_1):GND    I43 @BASEBOARD_FAB2_LIB.BASEBOARD_FAB2(SCH_1):PAGE53
    33    GND @BASEBOARD_FAB2_LIB.BASEBOARD_FAB2(SCH_1):GND    I43 @BASEBOARD_FAB2_LIB.BASEBOARD_FAB2(SCH_1):PAGE53
    35    GND @BASEBOARD_FAB2_LIB.BASEBOARD_FAB2(SCH_1):GND    I43 @BASEBOARD_FAB2_LIB.BASEBOARD_FAB2(SCH_1):PAGE53
    37    GND @BASEBOARD_FAB2_LIB.BASEBOARD_FAB2(SCH_1):GND    I43 @BASEBOARD_FAB2_LIB.BASEBOARD_FAB2(SCH_1):PAGE53
    39    GND @BASEBOARD_FAB2_LIB.BASEBOARD_FAB2(SCH_1):GND    I43 @BASEBOARD_FAB2_LIB.BASEBOARD_FAB2(SCH_1):PAGE53
    42    GND @BASEBOARD_FAB2_LIB.BASEBOARD_FAB2(SCH_1):GND    I43 @BASEBOARD_FAB2_LIB.BASEBOARD_FAB2(SCH_1):PAGE53
    44    GND @BASEBOARD_FAB2_LIB.BASEBOARD_FAB2(SCH_1):GND    I43 @BASEBOARD_FAB2_LIB.BASEBOARD_FAB2(SCH_1):PAGE53
    46    GND @BASEBOARD_FAB2_LIB.BASEBOARD_FAB2(SCH_1):GND    I43 @BASEBOARD_FAB2_LIB.BASEBOARD_FAB2(SCH_1):PAGE53
    48    GND @BASEBOARD_FAB2_LIB.BASEBOARD_FAB2(SCH_1):GND    I43 @BASEBOARD_FAB2_LIB.BASEBOARD_FAB2(SCH_1):PAGE53
    50    GND @BASEBOARD_FAB2_LIB.BASEBOARD_FAB2(SCH_1):GND    I43 @BASEBOARD_FAB2_LIB.BASEBOARD_FAB2(SCH_1):PAGE53
    53    GND @BASEBOARD_FAB2_LIB.BASEBOARD_FAB2(SCH_1):GND    I43 @BASEBOARD_FAB2_LIB.BASEBOARD_FAB2(SCH_1):PAGE53
    55    GND @BASEBOARD_FAB2_LIB.BASEBOARD_FAB2(SCH_1):GND    I43 @BASEBOARD_FAB2_LIB.BASEBOARD_FAB2(SCH_1):PAGE53
    57    GND @BASEBOARD_FAB2_LIB.BASEBOARD_FAB2(SCH_1):GND    I43 @BASEBOARD_FAB2_LIB.BASEBOARD_FAB2(SCH_1):PAGE53
    94    GND @BASEBOARD_FAB2_LIB.BASEBOARD_FAB2(SCH_1):GND    I43 @BASEBOARD_FAB2_LIB.BASEBOARD_FAB2(SCH_1):PAGE53
    96    GND @BASEBOARD_FAB2_LIB.BASEBOARD_FAB2(SCH_1):GND    I43 @BASEBOARD_FAB2_LIB.BASEBOARD_FAB2(SCH_1):PAGE53
    98    GND @BASEBOARD_FAB2_LIB.BASEBOARD_FAB2(SCH_1):GND    I43 @BASEBOARD_FAB2_LIB.BASEBOARD_FAB2(SCH_1):PAGE53
   101    GND @BASEBOARD_FAB2_LIB.BASEBOARD_FAB2(SCH_1):GND    I43 @BASEBOARD_FAB2_LIB.BASEBOARD_FAB2(SCH_1):PAGE53
   103    GND @BASEBOARD_FAB2_LIB.BASEBOARD_FAB2(SCH_1):GND    I43 @BASEBOARD_FAB2_LIB.BASEBOARD_FAB2(SCH_1):PAGE53
   105    GND @BASEBOARD_FAB2_LIB.BASEBOARD_FAB2(SCH_1):GND    I43 @BASEBOARD_FAB2_LIB.BASEBOARD_FAB2(SCH_1):PAGE53
   107    GND @BASEBOARD_FAB2_LIB.BASEBOARD_FAB2(SCH_1):GND    I43 @BASEBOARD_FAB2_LIB.BASEBOARD_FAB2(SCH_1):PAGE53
   109    GND @BASEBOARD_FAB2_LIB.BASEBOARD_FAB2(SCH_1):GND    I43 @BASEBOARD_FAB2_LIB.BASEBOARD_FAB2(SCH_1):PAGE53
   112    GND @BASEBOARD_FAB2_LIB.BASEBOARD_FAB2(SCH_1):GND    I43 @BASEBOARD_FAB2_LIB.BASEBOARD_FAB2(SCH_1):PAGE53
   114    GND @BASEBOARD_FAB2_LIB.BASEBOARD_FAB2(SCH_1):GND    I43 @BASEBOARD_FAB2_LIB.BASEBOARD_FAB2(SCH_1):PAGE53
   116    GND @BASEBOARD_FAB2_LIB.BASEBOARD_FAB2(SCH_1):GND    I43 @BASEBOARD_FAB2_LIB.BASEBOARD_FAB2(SCH_1):PAGE53
   118    GND @BASEBOARD_FAB2_LIB.BASEBOARD_FAB2(SCH_1):GND    I43 @BASEBOARD_FAB2_LIB.BASEBOARD_FAB2(SCH_1):PAGE53
   120    GND @BASEBOARD_FAB2_LIB.BASEBOARD_FAB2(SCH_1):GND    I43 @BASEBOARD_FAB2_LIB.BASEBOARD_FAB2(SCH_1):PAGE53
   123    GND @BASEBOARD_FAB2_LIB.BASEBOARD_FAB2(SCH_1):GND    I43 @BASEBOARD_FAB2_LIB.BASEBOARD_FAB2(SCH_1):PAGE53
   125    GND @BASEBOARD_FAB2_LIB.BASEBOARD_FAB2(SCH_1):GND    I43 @BASEBOARD_FAB2_LIB.BASEBOARD_FAB2(SCH_1):PAGE53
   127    GND @BASEBOARD_FAB2_LIB.BASEBOARD_FAB2(SCH_1):GND    I43 @BASEBOARD_FAB2_LIB.BASEBOARD_FAB2(SCH_1):PAGE53
   129    GND @BASEBOARD_FAB2_LIB.BASEBOARD_FAB2(SCH_1):GND    I43 @BASEBOARD_FAB2_LIB.BASEBOARD_FAB2(SCH_1):PAGE53
   131    GND @BASEBOARD_FAB2_LIB.BASEBOARD_FAB2(SCH_1):GND    I43 @BASEBOARD_FAB2_LIB.BASEBOARD_FAB2(SCH_1):PAGE53
   134    GND @BASEBOARD_FAB2_LIB.BASEBOARD_FAB2(SCH_1):GND    I43 @BASEBOARD_FAB2_LIB.BASEBOARD_FAB2(SCH_1):PAGE53
   136    GND @BASEBOARD_FAB2_LIB.BASEBOARD_FAB2(SCH_1):GND    I43 @BASEBOARD_FAB2_LIB.BASEBOARD_FAB2(SCH_1):PAGE53
   138    GND @BASEBOARD_FAB2_LIB.BASEBOARD_FAB2(SCH_1):GND    I43 @BASEBOARD_FAB2_LIB.BASEBOARD_FAB2(SCH_1):PAGE53
   147    GND @BASEBOARD_FAB2_LIB.BASEBOARD_FAB2(SCH_1):GND    I43 @BASEBOARD_FAB2_LIB.BASEBOARD_FAB2(SCH_1):PAGE53
   149    GND @BASEBOARD_FAB2_LIB.BASEBOARD_FAB2(SCH_1):GND    I43 @BASEBOARD_FAB2_LIB.BASEBOARD_FAB2(SCH_1):PAGE53
   151    GND @BASEBOARD_FAB2_LIB.BASEBOARD_FAB2(SCH_1):GND    I43 @BASEBOARD_FAB2_LIB.BASEBOARD_FAB2(SCH_1):PAGE53
   154    GND @BASEBOARD_FAB2_LIB.BASEBOARD_FAB2(SCH_1):GND    I43 @BASEBOARD_FAB2_LIB.BASEBOARD_FAB2(SCH_1):PAGE53
   156    GND @BASEBOARD_FAB2_LIB.BASEBOARD_FAB2(SCH_1):GND    I43 @BASEBOARD_FAB2_LIB.BASEBOARD_FAB2(SCH_1):PAGE53
   158    GND @BASEBOARD_FAB2_LIB.BASEBOARD_FAB2(SCH_1):GND    I43 @BASEBOARD_FAB2_LIB.BASEBOARD_FAB2(SCH_1):PAGE53
   160    GND @BASEBOARD_FAB2_LIB.BASEBOARD_FAB2(SCH_1):GND    I43 @BASEBOARD_FAB2_LIB.BASEBOARD_FAB2(SCH_1):PAGE53
   162    GND @BASEBOARD_FAB2_LIB.BASEBOARD_FAB2(SCH_1):GND    I43 @BASEBOARD_FAB2_LIB.BASEBOARD_FAB2(SCH_1):PAGE53
   165    GND @BASEBOARD_FAB2_LIB.BASEBOARD_FAB2(SCH_1):GND    I43 @BASEBOARD_FAB2_LIB.BASEBOARD_FAB2(SCH_1):PAGE53
   167    GND @BASEBOARD_FAB2_LIB.BASEBOARD_FAB2(SCH_1):GND    I43 @BASEBOARD_FAB2_LIB.BASEBOARD_FAB2(SCH_1):PAGE53
   169    GND @BASEBOARD_FAB2_LIB.BASEBOARD_FAB2(SCH_1):GND    I43 @BASEBOARD_FAB2_LIB.BASEBOARD_FAB2(SCH_1):PAGE53
   171    GND @BASEBOARD_FAB2_LIB.BASEBOARD_FAB2(SCH_1):GND    I43 @BASEBOARD_FAB2_LIB.BASEBOARD_FAB2(SCH_1):PAGE53
   173    GND @BASEBOARD_FAB2_LIB.BASEBOARD_FAB2(SCH_1):GND    I43 @BASEBOARD_FAB2_LIB.BASEBOARD_FAB2(SCH_1):PAGE53
   176    GND @BASEBOARD_FAB2_LIB.BASEBOARD_FAB2(SCH_1):GND    I43 @BASEBOARD_FAB2_LIB.BASEBOARD_FAB2(SCH_1):PAGE53
   178    GND @BASEBOARD_FAB2_LIB.BASEBOARD_FAB2(SCH_1):GND    I43 @BASEBOARD_FAB2_LIB.BASEBOARD_FAB2(SCH_1):PAGE53
   180    GND @BASEBOARD_FAB2_LIB.BASEBOARD_FAB2(SCH_1):GND    I43 @BASEBOARD_FAB2_LIB.BASEBOARD_FAB2(SCH_1):PAGE53
   182    GND @BASEBOARD_FAB2_LIB.BASEBOARD_FAB2(SCH_1):GND    I43 @BASEBOARD_FAB2_LIB.BASEBOARD_FAB2(SCH_1):PAGE53
   184    GND @BASEBOARD_FAB2_LIB.BASEBOARD_FAB2(SCH_1):GND    I43 @BASEBOARD_FAB2_LIB.BASEBOARD_FAB2(SCH_1):PAGE53
   187    GND @BASEBOARD_FAB2_LIB.BASEBOARD_FAB2(SCH_1):GND    I43 @BASEBOARD_FAB2_LIB.BASEBOARD_FAB2(SCH_1):PAGE53
   189    GND @BASEBOARD_FAB2_LIB.BASEBOARD_FAB2(SCH_1):GND    I43 @BASEBOARD_FAB2_LIB.BASEBOARD_FAB2(SCH_1):PAGE53
   191    GND @BASEBOARD_FAB2_LIB.BASEBOARD_FAB2(SCH_1):GND    I43 @BASEBOARD_FAB2_LIB.BASEBOARD_FAB2(SCH_1):PAGE53
   193    GND @BASEBOARD_FAB2_LIB.BASEBOARD_FAB2(SCH_1):GND    I43 @BASEBOARD_FAB2_LIB.BASEBOARD_FAB2(SCH_1):PAGE53
   195    GND @BASEBOARD_FAB2_LIB.BASEBOARD_FAB2(SCH_1):GND    I43 @BASEBOARD_FAB2_LIB.BASEBOARD_FAB2(SCH_1):PAGE53
   198    GND @BASEBOARD_FAB2_LIB.BASEBOARD_FAB2(SCH_1):GND    I43 @BASEBOARD_FAB2_LIB.BASEBOARD_FAB2(SCH_1):PAGE53
   200    GND @BASEBOARD_FAB2_LIB.BASEBOARD_FAB2(SCH_1):GND    I43 @BASEBOARD_FAB2_LIB.BASEBOARD_FAB2(SCH_1):PAGE53
   202    GND @BASEBOARD_FAB2_LIB.BASEBOARD_FAB2(SCH_1):GND    I43 @BASEBOARD_FAB2_LIB.BASEBOARD_FAB2(SCH_1):PAGE53
   239    GND @BASEBOARD_FAB2_LIB.BASEBOARD_FAB2(SCH_1):GND    I43 @BASEBOARD_FAB2_LIB.BASEBOARD_FAB2(SCH_1):PAGE53
   241    GND @BASEBOARD_FAB2_LIB.BASEBOARD_FAB2(SCH_1):GND    I43 @BASEBOARD_FAB2_LIB.BASEBOARD_FAB2(SCH_1):PAGE53
   243    GND @BASEBOARD_FAB2_LIB.BASEBOARD_FAB2(SCH_1):GND    I43 @BASEBOARD_FAB2_LIB.BASEBOARD_FAB2(SCH_1):PAGE53
   246    GND @BASEBOARD_FAB2_LIB.BASEBOARD_FAB2(SCH_1):GND    I43 @BASEBOARD_FAB2_LIB.BASEBOARD_FAB2(SCH_1):PAGE53
   248    GND @BASEBOARD_FAB2_LIB.BASEBOARD_FAB2(SCH_1):GND    I43 @BASEBOARD_FAB2_LIB.BASEBOARD_FAB2(SCH_1):PAGE53
   250    GND @BASEBOARD_FAB2_LIB.BASEBOARD_FAB2(SCH_1):GND    I43 @BASEBOARD_FAB2_LIB.BASEBOARD_FAB2(SCH_1):PAGE53
   252    GND @BASEBOARD_FAB2_LIB.BASEBOARD_FAB2(SCH_1):GND    I43 @BASEBOARD_FAB2_LIB.BASEBOARD_FAB2(SCH_1):PAGE53
   254    GND @BASEBOARD_FAB2_LIB.BASEBOARD_FAB2(SCH_1):GND    I43 @BASEBOARD_FAB2_LIB.BASEBOARD_FAB2(SCH_1):PAGE53
   257    GND @BASEBOARD_FAB2_LIB.BASEBOARD_FAB2(SCH_1):GND    I43 @BASEBOARD_FAB2_LIB.BASEBOARD_FAB2(SCH_1):PAGE53
   259    GND @BASEBOARD_FAB2_LIB.BASEBOARD_FAB2(SCH_1):GND    I43 @BASEBOARD_FAB2_LIB.BASEBOARD_FAB2(SCH_1):PAGE53
   261    GND @BASEBOARD_FAB2_LIB.BASEBOARD_FAB2(SCH_1):GND    I43 @BASEBOARD_FAB2_LIB.BASEBOARD_FAB2(SCH_1):PAGE53
   263    GND @BASEBOARD_FAB2_LIB.BASEBOARD_FAB2(SCH_1):GND    I43 @BASEBOARD_FAB2_LIB.BASEBOARD_FAB2(SCH_1):PAGE53
   265    GND @BASEBOARD_FAB2_LIB.BASEBOARD_FAB2(SCH_1):GND    I43 @BASEBOARD_FAB2_LIB.BASEBOARD_FAB2(SCH_1):PAGE53
   268    GND @BASEBOARD_FAB2_LIB.BASEBOARD_FAB2(SCH_1):GND    I43 @BASEBOARD_FAB2_LIB.BASEBOARD_FAB2(SCH_1):PAGE53
   270    GND @BASEBOARD_FAB2_LIB.BASEBOARD_FAB2(SCH_1):GND    I43 @BASEBOARD_FAB2_LIB.BASEBOARD_FAB2(SCH_1):PAGE53
   272    GND @BASEBOARD_FAB2_LIB.BASEBOARD_FAB2(SCH_1):GND    I43 @BASEBOARD_FAB2_LIB.BASEBOARD_FAB2(SCH_1):PAGE53
   274    GND @BASEBOARD_FAB2_LIB.BASEBOARD_FAB2(SCH_1):GND    I43 @BASEBOARD_FAB2_LIB.BASEBOARD_FAB2(SCH_1):PAGE53
   276    GND @BASEBOARD_FAB2_LIB.BASEBOARD_FAB2(SCH_1):GND    I43 @BASEBOARD_FAB2_LIB.BASEBOARD_FAB2(SCH_1):PAGE53
   279    GND @BASEBOARD_FAB2_LIB.BASEBOARD_FAB2(SCH_1):GND    I43 @BASEBOARD_FAB2_LIB.BASEBOARD_FAB2(SCH_1):PAGE53
   281    GND @BASEBOARD_FAB2_LIB.BASEBOARD_FAB2(SCH_1):GND    I43 @BASEBOARD_FAB2_LIB.BASEBOARD_FAB2(SCH_1):PAGE53
   283    GND @BASEBOARD_FAB2_LIB.BASEBOARD_FAB2(SCH_1):GND    I43 @BASEBOARD_FAB2_LIB.BASEBOARD_FAB2(SCH_1):PAGE53
     1 P12V_NVDIMM_DEF @BASEBOARD_FAB2_LIB.BASEBOARD_FAB2(SCH_1):P12V_NVDIMM_DEF   I171 @BASEBOARD_FAB2_LIB.BASEBOARD_FAB2(SCH_1):PAGE53
   145 P12V_NVDIMM_DEF @BASEBOARD_FAB2_LIB.BASEBOARD_FAB2(SCH_1):P12V_NVDIMM_DEF   I171 @BASEBOARD_FAB2_LIB.BASEBOARD_FAB2(SCH_1):PAGE53
    59 PVDDQ_DEF @BASEBOARD_FAB2_LIB.BASEBOARD_FAB2(SCH_1):PVDDQ_DEF   I171 @BASEBOARD_FAB2_LIB.BASEBOARD_FAB2(SCH_1):PAGE53
    61 PVDDQ_DEF @BASEBOARD_FAB2_LIB.BASEBOARD_FAB2(SCH_1):PVDDQ_DEF   I171 @BASEBOARD_FAB2_LIB.BASEBOARD_FAB2(SCH_1):PAGE53
    64 PVDDQ_DEF @BASEBOARD_FAB2_LIB.BASEBOARD_FAB2(SCH_1):PVDDQ_DEF   I171 @BASEBOARD_FAB2_LIB.BASEBOARD_FAB2(SCH_1):PAGE53
    67 PVDDQ_DEF @BASEBOARD_FAB2_LIB.BASEBOARD_FAB2(SCH_1):PVDDQ_DEF   I171 @BASEBOARD_FAB2_LIB.BASEBOARD_FAB2(SCH_1):PAGE53
    70 PVDDQ_DEF @BASEBOARD_FAB2_LIB.BASEBOARD_FAB2(SCH_1):PVDDQ_DEF   I171 @BASEBOARD_FAB2_LIB.BASEBOARD_FAB2(SCH_1):PAGE53
    73 PVDDQ_DEF @BASEBOARD_FAB2_LIB.BASEBOARD_FAB2(SCH_1):PVDDQ_DEF   I171 @BASEBOARD_FAB2_LIB.BASEBOARD_FAB2(SCH_1):PAGE53
    76 PVDDQ_DEF @BASEBOARD_FAB2_LIB.BASEBOARD_FAB2(SCH_1):PVDDQ_DEF   I171 @BASEBOARD_FAB2_LIB.BASEBOARD_FAB2(SCH_1):PAGE53
    80 PVDDQ_DEF @BASEBOARD_FAB2_LIB.BASEBOARD_FAB2(SCH_1):PVDDQ_DEF   I171 @BASEBOARD_FAB2_LIB.BASEBOARD_FAB2(SCH_1):PAGE53
    83 PVDDQ_DEF @BASEBOARD_FAB2_LIB.BASEBOARD_FAB2(SCH_1):PVDDQ_DEF   I171 @BASEBOARD_FAB2_LIB.BASEBOARD_FAB2(SCH_1):PAGE53
    85 PVDDQ_DEF @BASEBOARD_FAB2_LIB.BASEBOARD_FAB2(SCH_1):PVDDQ_DEF   I171 @BASEBOARD_FAB2_LIB.BASEBOARD_FAB2(SCH_1):PAGE53
    88 PVDDQ_DEF @BASEBOARD_FAB2_LIB.BASEBOARD_FAB2(SCH_1):PVDDQ_DEF   I171 @BASEBOARD_FAB2_LIB.BASEBOARD_FAB2(SCH_1):PAGE53
    90 PVDDQ_DEF @BASEBOARD_FAB2_LIB.BASEBOARD_FAB2(SCH_1):PVDDQ_DEF   I171 @BASEBOARD_FAB2_LIB.BASEBOARD_FAB2(SCH_1):PAGE53
    92 PVDDQ_DEF @BASEBOARD_FAB2_LIB.BASEBOARD_FAB2(SCH_1):PVDDQ_DEF   I171 @BASEBOARD_FAB2_LIB.BASEBOARD_FAB2(SCH_1):PAGE53
   204 PVDDQ_DEF @BASEBOARD_FAB2_LIB.BASEBOARD_FAB2(SCH_1):PVDDQ_DEF   I171 @BASEBOARD_FAB2_LIB.BASEBOARD_FAB2(SCH_1):PAGE53
   206 PVDDQ_DEF @BASEBOARD_FAB2_LIB.BASEBOARD_FAB2(SCH_1):PVDDQ_DEF   I171 @BASEBOARD_FAB2_LIB.BASEBOARD_FAB2(SCH_1):PAGE53
   209 PVDDQ_DEF @BASEBOARD_FAB2_LIB.BASEBOARD_FAB2(SCH_1):PVDDQ_DEF   I171 @BASEBOARD_FAB2_LIB.BASEBOARD_FAB2(SCH_1):PAGE53
   212 PVDDQ_DEF @BASEBOARD_FAB2_LIB.BASEBOARD_FAB2(SCH_1):PVDDQ_DEF   I171 @BASEBOARD_FAB2_LIB.BASEBOARD_FAB2(SCH_1):PAGE53
   215 PVDDQ_DEF @BASEBOARD_FAB2_LIB.BASEBOARD_FAB2(SCH_1):PVDDQ_DEF   I171 @BASEBOARD_FAB2_LIB.BASEBOARD_FAB2(SCH_1):PAGE53
   217 PVDDQ_DEF @BASEBOARD_FAB2_LIB.BASEBOARD_FAB2(SCH_1):PVDDQ_DEF   I171 @BASEBOARD_FAB2_LIB.BASEBOARD_FAB2(SCH_1):PAGE53
   220 PVDDQ_DEF @BASEBOARD_FAB2_LIB.BASEBOARD_FAB2(SCH_1):PVDDQ_DEF   I171 @BASEBOARD_FAB2_LIB.BASEBOARD_FAB2(SCH_1):PAGE53
   223 PVDDQ_DEF @BASEBOARD_FAB2_LIB.BASEBOARD_FAB2(SCH_1):PVDDQ_DEF   I171 @BASEBOARD_FAB2_LIB.BASEBOARD_FAB2(SCH_1):PAGE53
   226 PVDDQ_DEF @BASEBOARD_FAB2_LIB.BASEBOARD_FAB2(SCH_1):PVDDQ_DEF   I171 @BASEBOARD_FAB2_LIB.BASEBOARD_FAB2(SCH_1):PAGE53
   229 PVDDQ_DEF @BASEBOARD_FAB2_LIB.BASEBOARD_FAB2(SCH_1):PVDDQ_DEF   I171 @BASEBOARD_FAB2_LIB.BASEBOARD_FAB2(SCH_1):PAGE53
   231 PVDDQ_DEF @BASEBOARD_FAB2_LIB.BASEBOARD_FAB2(SCH_1):PVDDQ_DEF   I171 @BASEBOARD_FAB2_LIB.BASEBOARD_FAB2(SCH_1):PAGE53
   233 PVDDQ_DEF @BASEBOARD_FAB2_LIB.BASEBOARD_FAB2(SCH_1):PVDDQ_DEF   I171 @BASEBOARD_FAB2_LIB.BASEBOARD_FAB2(SCH_1):PAGE53
   236 PVDDQ_DEF @BASEBOARD_FAB2_LIB.BASEBOARD_FAB2(SCH_1):PVDDQ_DEF   I171 @BASEBOARD_FAB2_LIB.BASEBOARD_FAB2(SCH_1):PAGE53
   142 PVPP_DEF @BASEBOARD_FAB2_LIB.BASEBOARD_FAB2(SCH_1):PVPP_DEF   I171 @BASEBOARD_FAB2_LIB.BASEBOARD_FAB2(SCH_1):PAGE53
   143 PVPP_DEF @BASEBOARD_FAB2_LIB.BASEBOARD_FAB2(SCH_1):PVPP_DEF   I171 @BASEBOARD_FAB2_LIB.BASEBOARD_FAB2(SCH_1):PAGE53
   288 PVPP_DEF @BASEBOARD_FAB2_LIB.BASEBOARD_FAB2(SCH_1):PVPP_DEF   I171 @BASEBOARD_FAB2_LIB.BASEBOARD_FAB2(SCH_1):PAGE53
   286 PVPP_DEF @BASEBOARD_FAB2_LIB.BASEBOARD_FAB2(SCH_1):PVPP_DEF   I171 @BASEBOARD_FAB2_LIB.BASEBOARD_FAB2(SCH_1):PAGE53
   287 PVPP_DEF @BASEBOARD_FAB2_LIB.BASEBOARD_FAB2(SCH_1):PVPP_DEF   I171 @BASEBOARD_FAB2_LIB.BASEBOARD_FAB2(SCH_1):PAGE53
    77 PVTT_DEF @BASEBOARD_FAB2_LIB.BASEBOARD_FAB2(SCH_1):PVTT_DEF   I171 @BASEBOARD_FAB2_LIB.BASEBOARD_FAB2(SCH_1):PAGE53
   221 PVTT_DEF @BASEBOARD_FAB2_LIB.BASEBOARD_FAB2(SCH_1):PVTT_DEF   I171 @BASEBOARD_FAB2_LIB.BASEBOARD_FAB2(SCH_1):PAGE53

J4A2 SCONN288_H44441004_PIP-SCONN,HA
    79 M_E_MA<0> @BASEBOARD_FAB2_LIB.BASEBOARD_FAB2(SCH_1):M_E_MA(0)   I111 @BASEBOARD_FAB2_LIB.BASEBOARD_FAB2(SCH_1):PAGE51
    72 M_E_MA<1> @BASEBOARD_FAB2_LIB.BASEBOARD_FAB2(SCH_1):M_E_MA(1)   I111 @BASEBOARD_FAB2_LIB.BASEBOARD_FAB2(SCH_1):PAGE51
   225 M_E_MA<10> @BASEBOARD_FAB2_LIB.BASEBOARD_FAB2(SCH_1):M_E_MA(10)   I111 @BASEBOARD_FAB2_LIB.BASEBOARD_FAB2(SCH_1):PAGE51
   210 M_E_MA<11> @BASEBOARD_FAB2_LIB.BASEBOARD_FAB2(SCH_1):M_E_MA(11)   I111 @BASEBOARD_FAB2_LIB.BASEBOARD_FAB2(SCH_1):PAGE51
    65 M_E_MA<12> @BASEBOARD_FAB2_LIB.BASEBOARD_FAB2(SCH_1):M_E_MA(12)   I111 @BASEBOARD_FAB2_LIB.BASEBOARD_FAB2(SCH_1):PAGE51
   232 M_E_MA<13> @BASEBOARD_FAB2_LIB.BASEBOARD_FAB2(SCH_1):M_E_MA(13)   I111 @BASEBOARD_FAB2_LIB.BASEBOARD_FAB2(SCH_1):PAGE51
   228 M_E_MA<14> @BASEBOARD_FAB2_LIB.BASEBOARD_FAB2(SCH_1):M_E_MA(14)   I111 @BASEBOARD_FAB2_LIB.BASEBOARD_FAB2(SCH_1):PAGE51
    86 M_E_MA<15> @BASEBOARD_FAB2_LIB.BASEBOARD_FAB2(SCH_1):M_E_MA(15)   I111 @BASEBOARD_FAB2_LIB.BASEBOARD_FAB2(SCH_1):PAGE51
    82 M_E_MA<16> @BASEBOARD_FAB2_LIB.BASEBOARD_FAB2(SCH_1):M_E_MA(16)   I111 @BASEBOARD_FAB2_LIB.BASEBOARD_FAB2(SCH_1):PAGE51
   234 M_E_MA<17> @BASEBOARD_FAB2_LIB.BASEBOARD_FAB2(SCH_1):M_E_MA(17)   I111 @BASEBOARD_FAB2_LIB.BASEBOARD_FAB2(SCH_1):PAGE51
   216 M_E_MA<2> @BASEBOARD_FAB2_LIB.BASEBOARD_FAB2(SCH_1):M_E_MA(2)   I111 @BASEBOARD_FAB2_LIB.BASEBOARD_FAB2(SCH_1):PAGE51
    71 M_E_MA<3> @BASEBOARD_FAB2_LIB.BASEBOARD_FAB2(SCH_1):M_E_MA(3)   I111 @BASEBOARD_FAB2_LIB.BASEBOARD_FAB2(SCH_1):PAGE51
   214 M_E_MA<4> @BASEBOARD_FAB2_LIB.BASEBOARD_FAB2(SCH_1):M_E_MA(4)   I111 @BASEBOARD_FAB2_LIB.BASEBOARD_FAB2(SCH_1):PAGE51
   213 M_E_MA<5> @BASEBOARD_FAB2_LIB.BASEBOARD_FAB2(SCH_1):M_E_MA(5)   I111 @BASEBOARD_FAB2_LIB.BASEBOARD_FAB2(SCH_1):PAGE51
    69 M_E_MA<6> @BASEBOARD_FAB2_LIB.BASEBOARD_FAB2(SCH_1):M_E_MA(6)   I111 @BASEBOARD_FAB2_LIB.BASEBOARD_FAB2(SCH_1):PAGE51
   211 M_E_MA<7> @BASEBOARD_FAB2_LIB.BASEBOARD_FAB2(SCH_1):M_E_MA(7)   I111 @BASEBOARD_FAB2_LIB.BASEBOARD_FAB2(SCH_1):PAGE51
    68 M_E_MA<8> @BASEBOARD_FAB2_LIB.BASEBOARD_FAB2(SCH_1):M_E_MA(8)   I111 @BASEBOARD_FAB2_LIB.BASEBOARD_FAB2(SCH_1):PAGE51
    66 M_E_MA<9> @BASEBOARD_FAB2_LIB.BASEBOARD_FAB2(SCH_1):M_E_MA(9)   I111 @BASEBOARD_FAB2_LIB.BASEBOARD_FAB2(SCH_1):PAGE51
    62 M_E_ACT_N @BASEBOARD_FAB2_LIB.BASEBOARD_FAB2(SCH_1):M_E_ACT_N   I111 @BASEBOARD_FAB2_LIB.BASEBOARD_FAB2(SCH_1):PAGE51
   208 M_E_ALERT_N @BASEBOARD_FAB2_LIB.BASEBOARD_FAB2(SCH_1):M_E_ALERT_N   I111 @BASEBOARD_FAB2_LIB.BASEBOARD_FAB2(SCH_1):PAGE51
   224 M_E_BA<1> @BASEBOARD_FAB2_LIB.BASEBOARD_FAB2(SCH_1):M_E_BA(1)   I111 @BASEBOARD_FAB2_LIB.BASEBOARD_FAB2(SCH_1):PAGE51
    81 M_E_BA<0> @BASEBOARD_FAB2_LIB.BASEBOARD_FAB2(SCH_1):M_E_BA(0)   I111 @BASEBOARD_FAB2_LIB.BASEBOARD_FAB2(SCH_1):PAGE51
   207 M_E_BG<1> @BASEBOARD_FAB2_LIB.BASEBOARD_FAB2(SCH_1):M_E_BG(1)   I111 @BASEBOARD_FAB2_LIB.BASEBOARD_FAB2(SCH_1):PAGE51
    63 M_E_BG<0> @BASEBOARD_FAB2_LIB.BASEBOARD_FAB2(SCH_1):M_E_BG(0)   I111 @BASEBOARD_FAB2_LIB.BASEBOARD_FAB2(SCH_1):PAGE51
   235 M_E_C<2> @BASEBOARD_FAB2_LIB.BASEBOARD_FAB2(SCH_1):M_E_C(2)   I111 @BASEBOARD_FAB2_LIB.BASEBOARD_FAB2(SCH_1):PAGE51
   199 M_E_ECC<6> @BASEBOARD_FAB2_LIB.BASEBOARD_FAB2(SCH_1):M_E_ECC(6)   I111 @BASEBOARD_FAB2_LIB.BASEBOARD_FAB2(SCH_1):PAGE51
    54 M_E_ECC<7> @BASEBOARD_FAB2_LIB.BASEBOARD_FAB2(SCH_1):M_E_ECC(7)   I111 @BASEBOARD_FAB2_LIB.BASEBOARD_FAB2(SCH_1):PAGE51
   192 M_E_ECC<4> @BASEBOARD_FAB2_LIB.BASEBOARD_FAB2(SCH_1):M_E_ECC(4)   I111 @BASEBOARD_FAB2_LIB.BASEBOARD_FAB2(SCH_1):PAGE51
    47 M_E_ECC<5> @BASEBOARD_FAB2_LIB.BASEBOARD_FAB2(SCH_1):M_E_ECC(5)   I111 @BASEBOARD_FAB2_LIB.BASEBOARD_FAB2(SCH_1):PAGE51
   201 M_E_ECC<2> @BASEBOARD_FAB2_LIB.BASEBOARD_FAB2(SCH_1):M_E_ECC(2)   I111 @BASEBOARD_FAB2_LIB.BASEBOARD_FAB2(SCH_1):PAGE51
    56 M_E_ECC<3> @BASEBOARD_FAB2_LIB.BASEBOARD_FAB2(SCH_1):M_E_ECC(3)   I111 @BASEBOARD_FAB2_LIB.BASEBOARD_FAB2(SCH_1):PAGE51
   194 M_E_ECC<0> @BASEBOARD_FAB2_LIB.BASEBOARD_FAB2(SCH_1):M_E_ECC(0)   I111 @BASEBOARD_FAB2_LIB.BASEBOARD_FAB2(SCH_1):PAGE51
    49 M_E_ECC<1> @BASEBOARD_FAB2_LIB.BASEBOARD_FAB2(SCH_1):M_E_ECC(1)   I111 @BASEBOARD_FAB2_LIB.BASEBOARD_FAB2(SCH_1):PAGE51
    75 M_E_CLK_DN<0> @BASEBOARD_FAB2_LIB.BASEBOARD_FAB2(SCH_1):M_E_CLK_DN(0)   I111 @BASEBOARD_FAB2_LIB.BASEBOARD_FAB2(SCH_1):PAGE51
    74 M_E_CLK_DP<0> @BASEBOARD_FAB2_LIB.BASEBOARD_FAB2(SCH_1):M_E_CLK_DP(0)   I111 @BASEBOARD_FAB2_LIB.BASEBOARD_FAB2(SCH_1):PAGE51
   219 M_E_CLK_DN<1> @BASEBOARD_FAB2_LIB.BASEBOARD_FAB2(SCH_1):M_E_CLK_DN(1)   I111 @BASEBOARD_FAB2_LIB.BASEBOARD_FAB2(SCH_1):PAGE51
   218 M_E_CLK_DP<1> @BASEBOARD_FAB2_LIB.BASEBOARD_FAB2(SCH_1):M_E_CLK_DP(1)   I111 @BASEBOARD_FAB2_LIB.BASEBOARD_FAB2(SCH_1):PAGE51
   203 M_E_CKE<1> @BASEBOARD_FAB2_LIB.BASEBOARD_FAB2(SCH_1):M_E_CKE(1)   I111 @BASEBOARD_FAB2_LIB.BASEBOARD_FAB2(SCH_1):PAGE51
    60 M_E_CKE<0> @BASEBOARD_FAB2_LIB.BASEBOARD_FAB2(SCH_1):M_E_CKE(0)   I111 @BASEBOARD_FAB2_LIB.BASEBOARD_FAB2(SCH_1):PAGE51
   280 M_E_DQ<62> @BASEBOARD_FAB2_LIB.BASEBOARD_FAB2(SCH_1):M_E_DQ(62)   I111 @BASEBOARD_FAB2_LIB.BASEBOARD_FAB2(SCH_1):PAGE51
   135 M_E_DQ<63> @BASEBOARD_FAB2_LIB.BASEBOARD_FAB2(SCH_1):M_E_DQ(63)   I111 @BASEBOARD_FAB2_LIB.BASEBOARD_FAB2(SCH_1):PAGE51
   273 M_E_DQ<60> @BASEBOARD_FAB2_LIB.BASEBOARD_FAB2(SCH_1):M_E_DQ(60)   I111 @BASEBOARD_FAB2_LIB.BASEBOARD_FAB2(SCH_1):PAGE51
   128 M_E_DQ<61> @BASEBOARD_FAB2_LIB.BASEBOARD_FAB2(SCH_1):M_E_DQ(61)   I111 @BASEBOARD_FAB2_LIB.BASEBOARD_FAB2(SCH_1):PAGE51
   282 M_E_DQ<58> @BASEBOARD_FAB2_LIB.BASEBOARD_FAB2(SCH_1):M_E_DQ(58)   I111 @BASEBOARD_FAB2_LIB.BASEBOARD_FAB2(SCH_1):PAGE51
   137 M_E_DQ<59> @BASEBOARD_FAB2_LIB.BASEBOARD_FAB2(SCH_1):M_E_DQ(59)   I111 @BASEBOARD_FAB2_LIB.BASEBOARD_FAB2(SCH_1):PAGE51
   275 M_E_DQ<56> @BASEBOARD_FAB2_LIB.BASEBOARD_FAB2(SCH_1):M_E_DQ(56)   I111 @BASEBOARD_FAB2_LIB.BASEBOARD_FAB2(SCH_1):PAGE51
   130 M_E_DQ<57> @BASEBOARD_FAB2_LIB.BASEBOARD_FAB2(SCH_1):M_E_DQ(57)   I111 @BASEBOARD_FAB2_LIB.BASEBOARD_FAB2(SCH_1):PAGE51
   269 M_E_DQ<54> @BASEBOARD_FAB2_LIB.BASEBOARD_FAB2(SCH_1):M_E_DQ(54)   I111 @BASEBOARD_FAB2_LIB.BASEBOARD_FAB2(SCH_1):PAGE51
   124 M_E_DQ<55> @BASEBOARD_FAB2_LIB.BASEBOARD_FAB2(SCH_1):M_E_DQ(55)   I111 @BASEBOARD_FAB2_LIB.BASEBOARD_FAB2(SCH_1):PAGE51
   262 M_E_DQ<52> @BASEBOARD_FAB2_LIB.BASEBOARD_FAB2(SCH_1):M_E_DQ(52)   I111 @BASEBOARD_FAB2_LIB.BASEBOARD_FAB2(SCH_1):PAGE51
   117 M_E_DQ<53> @BASEBOARD_FAB2_LIB.BASEBOARD_FAB2(SCH_1):M_E_DQ(53)   I111 @BASEBOARD_FAB2_LIB.BASEBOARD_FAB2(SCH_1):PAGE51
   271 M_E_DQ<50> @BASEBOARD_FAB2_LIB.BASEBOARD_FAB2(SCH_1):M_E_DQ(50)   I111 @BASEBOARD_FAB2_LIB.BASEBOARD_FAB2(SCH_1):PAGE51
   126 M_E_DQ<51> @BASEBOARD_FAB2_LIB.BASEBOARD_FAB2(SCH_1):M_E_DQ(51)   I111 @BASEBOARD_FAB2_LIB.BASEBOARD_FAB2(SCH_1):PAGE51
   264 M_E_DQ<48> @BASEBOARD_FAB2_LIB.BASEBOARD_FAB2(SCH_1):M_E_DQ(48)   I111 @BASEBOARD_FAB2_LIB.BASEBOARD_FAB2(SCH_1):PAGE51
   119 M_E_DQ<49> @BASEBOARD_FAB2_LIB.BASEBOARD_FAB2(SCH_1):M_E_DQ(49)   I111 @BASEBOARD_FAB2_LIB.BASEBOARD_FAB2(SCH_1):PAGE51
   258 M_E_DQ<46> @BASEBOARD_FAB2_LIB.BASEBOARD_FAB2(SCH_1):M_E_DQ(46)   I111 @BASEBOARD_FAB2_LIB.BASEBOARD_FAB2(SCH_1):PAGE51
   113 M_E_DQ<47> @BASEBOARD_FAB2_LIB.BASEBOARD_FAB2(SCH_1):M_E_DQ(47)   I111 @BASEBOARD_FAB2_LIB.BASEBOARD_FAB2(SCH_1):PAGE51
   251 M_E_DQ<44> @BASEBOARD_FAB2_LIB.BASEBOARD_FAB2(SCH_1):M_E_DQ(44)   I111 @BASEBOARD_FAB2_LIB.BASEBOARD_FAB2(SCH_1):PAGE51
   106 M_E_DQ<45> @BASEBOARD_FAB2_LIB.BASEBOARD_FAB2(SCH_1):M_E_DQ(45)   I111 @BASEBOARD_FAB2_LIB.BASEBOARD_FAB2(SCH_1):PAGE51
   260 M_E_DQ<42> @BASEBOARD_FAB2_LIB.BASEBOARD_FAB2(SCH_1):M_E_DQ(42)   I111 @BASEBOARD_FAB2_LIB.BASEBOARD_FAB2(SCH_1):PAGE51
   115 M_E_DQ<43> @BASEBOARD_FAB2_LIB.BASEBOARD_FAB2(SCH_1):M_E_DQ(43)   I111 @BASEBOARD_FAB2_LIB.BASEBOARD_FAB2(SCH_1):PAGE51
   253 M_E_DQ<40> @BASEBOARD_FAB2_LIB.BASEBOARD_FAB2(SCH_1):M_E_DQ(40)   I111 @BASEBOARD_FAB2_LIB.BASEBOARD_FAB2(SCH_1):PAGE51
   108 M_E_DQ<41> @BASEBOARD_FAB2_LIB.BASEBOARD_FAB2(SCH_1):M_E_DQ(41)   I111 @BASEBOARD_FAB2_LIB.BASEBOARD_FAB2(SCH_1):PAGE51
   247 M_E_DQ<38> @BASEBOARD_FAB2_LIB.BASEBOARD_FAB2(SCH_1):M_E_DQ(38)   I111 @BASEBOARD_FAB2_LIB.BASEBOARD_FAB2(SCH_1):PAGE51
   102 M_E_DQ<39> @BASEBOARD_FAB2_LIB.BASEBOARD_FAB2(SCH_1):M_E_DQ(39)   I111 @BASEBOARD_FAB2_LIB.BASEBOARD_FAB2(SCH_1):PAGE51
   240 M_E_DQ<36> @BASEBOARD_FAB2_LIB.BASEBOARD_FAB2(SCH_1):M_E_DQ(36)   I111 @BASEBOARD_FAB2_LIB.BASEBOARD_FAB2(SCH_1):PAGE51
    95 M_E_DQ<37> @BASEBOARD_FAB2_LIB.BASEBOARD_FAB2(SCH_1):M_E_DQ(37)   I111 @BASEBOARD_FAB2_LIB.BASEBOARD_FAB2(SCH_1):PAGE51
   249 M_E_DQ<34> @BASEBOARD_FAB2_LIB.BASEBOARD_FAB2(SCH_1):M_E_DQ(34)   I111 @BASEBOARD_FAB2_LIB.BASEBOARD_FAB2(SCH_1):PAGE51
   104 M_E_DQ<35> @BASEBOARD_FAB2_LIB.BASEBOARD_FAB2(SCH_1):M_E_DQ(35)   I111 @BASEBOARD_FAB2_LIB.BASEBOARD_FAB2(SCH_1):PAGE51
   242 M_E_DQ<32> @BASEBOARD_FAB2_LIB.BASEBOARD_FAB2(SCH_1):M_E_DQ(32)   I111 @BASEBOARD_FAB2_LIB.BASEBOARD_FAB2(SCH_1):PAGE51
    97 M_E_DQ<33> @BASEBOARD_FAB2_LIB.BASEBOARD_FAB2(SCH_1):M_E_DQ(33)   I111 @BASEBOARD_FAB2_LIB.BASEBOARD_FAB2(SCH_1):PAGE51
   188 M_E_DQ<30> @BASEBOARD_FAB2_LIB.BASEBOARD_FAB2(SCH_1):M_E_DQ(30)   I111 @BASEBOARD_FAB2_LIB.BASEBOARD_FAB2(SCH_1):PAGE51
    43 M_E_DQ<31> @BASEBOARD_FAB2_LIB.BASEBOARD_FAB2(SCH_1):M_E_DQ(31)   I111 @BASEBOARD_FAB2_LIB.BASEBOARD_FAB2(SCH_1):PAGE51
   181 M_E_DQ<28> @BASEBOARD_FAB2_LIB.BASEBOARD_FAB2(SCH_1):M_E_DQ(28)   I111 @BASEBOARD_FAB2_LIB.BASEBOARD_FAB2(SCH_1):PAGE51
    36 M_E_DQ<29> @BASEBOARD_FAB2_LIB.BASEBOARD_FAB2(SCH_1):M_E_DQ(29)   I111 @BASEBOARD_FAB2_LIB.BASEBOARD_FAB2(SCH_1):PAGE51
   190 M_E_DQ<26> @BASEBOARD_FAB2_LIB.BASEBOARD_FAB2(SCH_1):M_E_DQ(26)   I111 @BASEBOARD_FAB2_LIB.BASEBOARD_FAB2(SCH_1):PAGE51
    45 M_E_DQ<27> @BASEBOARD_FAB2_LIB.BASEBOARD_FAB2(SCH_1):M_E_DQ(27)   I111 @BASEBOARD_FAB2_LIB.BASEBOARD_FAB2(SCH_1):PAGE51
   183 M_E_DQ<24> @BASEBOARD_FAB2_LIB.BASEBOARD_FAB2(SCH_1):M_E_DQ(24)   I111 @BASEBOARD_FAB2_LIB.BASEBOARD_FAB2(SCH_1):PAGE51
    38 M_E_DQ<25> @BASEBOARD_FAB2_LIB.BASEBOARD_FAB2(SCH_1):M_E_DQ(25)   I111 @BASEBOARD_FAB2_LIB.BASEBOARD_FAB2(SCH_1):PAGE51
   177 M_E_DQ<22> @BASEBOARD_FAB2_LIB.BASEBOARD_FAB2(SCH_1):M_E_DQ(22)   I111 @BASEBOARD_FAB2_LIB.BASEBOARD_FAB2(SCH_1):PAGE51
    32 M_E_DQ<23> @BASEBOARD_FAB2_LIB.BASEBOARD_FAB2(SCH_1):M_E_DQ(23)   I111 @BASEBOARD_FAB2_LIB.BASEBOARD_FAB2(SCH_1):PAGE51
   170 M_E_DQ<20> @BASEBOARD_FAB2_LIB.BASEBOARD_FAB2(SCH_1):M_E_DQ(20)   I111 @BASEBOARD_FAB2_LIB.BASEBOARD_FAB2(SCH_1):PAGE51
    25 M_E_DQ<21> @BASEBOARD_FAB2_LIB.BASEBOARD_FAB2(SCH_1):M_E_DQ(21)   I111 @BASEBOARD_FAB2_LIB.BASEBOARD_FAB2(SCH_1):PAGE51
   179 M_E_DQ<18> @BASEBOARD_FAB2_LIB.BASEBOARD_FAB2(SCH_1):M_E_DQ(18)   I111 @BASEBOARD_FAB2_LIB.BASEBOARD_FAB2(SCH_1):PAGE51
    34 M_E_DQ<19> @BASEBOARD_FAB2_LIB.BASEBOARD_FAB2(SCH_1):M_E_DQ(19)   I111 @BASEBOARD_FAB2_LIB.BASEBOARD_FAB2(SCH_1):PAGE51
   172 M_E_DQ<16> @BASEBOARD_FAB2_LIB.BASEBOARD_FAB2(SCH_1):M_E_DQ(16)   I111 @BASEBOARD_FAB2_LIB.BASEBOARD_FAB2(SCH_1):PAGE51
    27 M_E_DQ<17> @BASEBOARD_FAB2_LIB.BASEBOARD_FAB2(SCH_1):M_E_DQ(17)   I111 @BASEBOARD_FAB2_LIB.BASEBOARD_FAB2(SCH_1):PAGE51
   166 M_E_DQ<14> @BASEBOARD_FAB2_LIB.BASEBOARD_FAB2(SCH_1):M_E_DQ(14)   I111 @BASEBOARD_FAB2_LIB.BASEBOARD_FAB2(SCH_1):PAGE51
    21 M_E_DQ<15> @BASEBOARD_FAB2_LIB.BASEBOARD_FAB2(SCH_1):M_E_DQ(15)   I111 @BASEBOARD_FAB2_LIB.BASEBOARD_FAB2(SCH_1):PAGE51
   159 M_E_DQ<12> @BASEBOARD_FAB2_LIB.BASEBOARD_FAB2(SCH_1):M_E_DQ(12)   I111 @BASEBOARD_FAB2_LIB.BASEBOARD_FAB2(SCH_1):PAGE51
    14 M_E_DQ<13> @BASEBOARD_FAB2_LIB.BASEBOARD_FAB2(SCH_1):M_E_DQ(13)   I111 @BASEBOARD_FAB2_LIB.BASEBOARD_FAB2(SCH_1):PAGE51
   168 M_E_DQ<10> @BASEBOARD_FAB2_LIB.BASEBOARD_FAB2(SCH_1):M_E_DQ(10)   I111 @BASEBOARD_FAB2_LIB.BASEBOARD_FAB2(SCH_1):PAGE51
    23 M_E_DQ<11> @BASEBOARD_FAB2_LIB.BASEBOARD_FAB2(SCH_1):M_E_DQ(11)   I111 @BASEBOARD_FAB2_LIB.BASEBOARD_FAB2(SCH_1):PAGE51
   161 M_E_DQ<8> @BASEBOARD_FAB2_LIB.BASEBOARD_FAB2(SCH_1):M_E_DQ(8)   I111 @BASEBOARD_FAB2_LIB.BASEBOARD_FAB2(SCH_1):PAGE51
    16 M_E_DQ<9> @BASEBOARD_FAB2_LIB.BASEBOARD_FAB2(SCH_1):M_E_DQ(9)   I111 @BASEBOARD_FAB2_LIB.BASEBOARD_FAB2(SCH_1):PAGE51
   155 M_E_DQ<6> @BASEBOARD_FAB2_LIB.BASEBOARD_FAB2(SCH_1):M_E_DQ(6)   I111 @BASEBOARD_FAB2_LIB.BASEBOARD_FAB2(SCH_1):PAGE51
    10 M_E_DQ<7> @BASEBOARD_FAB2_LIB.BASEBOARD_FAB2(SCH_1):M_E_DQ(7)   I111 @BASEBOARD_FAB2_LIB.BASEBOARD_FAB2(SCH_1):PAGE51
   148 M_E_DQ<4> @BASEBOARD_FAB2_LIB.BASEBOARD_FAB2(SCH_1):M_E_DQ(4)   I111 @BASEBOARD_FAB2_LIB.BASEBOARD_FAB2(SCH_1):PAGE51
     3 M_E_DQ<5> @BASEBOARD_FAB2_LIB.BASEBOARD_FAB2(SCH_1):M_E_DQ(5)   I111 @BASEBOARD_FAB2_LIB.BASEBOARD_FAB2(SCH_1):PAGE51
   157 M_E_DQ<2> @BASEBOARD_FAB2_LIB.BASEBOARD_FAB2(SCH_1):M_E_DQ(2)   I111 @BASEBOARD_FAB2_LIB.BASEBOARD_FAB2(SCH_1):PAGE51
    12 M_E_DQ<3> @BASEBOARD_FAB2_LIB.BASEBOARD_FAB2(SCH_1):M_E_DQ(3)   I111 @BASEBOARD_FAB2_LIB.BASEBOARD_FAB2(SCH_1):PAGE51
   150 M_E_DQ<0> @BASEBOARD_FAB2_LIB.BASEBOARD_FAB2(SCH_1):M_E_DQ(0)   I111 @BASEBOARD_FAB2_LIB.BASEBOARD_FAB2(SCH_1):PAGE51
     5 M_E_DQ<1> @BASEBOARD_FAB2_LIB.BASEBOARD_FAB2(SCH_1):M_E_DQ(1)   I111 @BASEBOARD_FAB2_LIB.BASEBOARD_FAB2(SCH_1):PAGE51
    78 FM_DIMM_EVENT_COD_N @BASEBOARD_FAB2_LIB.BASEBOARD_FAB2(SCH_1):FM_DIMM_EVENT_COD_N   I111 @BASEBOARD_FAB2_LIB.BASEBOARD_FAB2(SCH_1):PAGE51
    91 M_E_ODT<1> @BASEBOARD_FAB2_LIB.BASEBOARD_FAB2(SCH_1):M_E_ODT(1)   I111 @BASEBOARD_FAB2_LIB.BASEBOARD_FAB2(SCH_1):PAGE51
    87 M_E_ODT<0> @BASEBOARD_FAB2_LIB.BASEBOARD_FAB2(SCH_1):M_E_ODT(0)   I111 @BASEBOARD_FAB2_LIB.BASEBOARD_FAB2(SCH_1):PAGE51
   222 M_E_PAR @BASEBOARD_FAB2_LIB.BASEBOARD_FAB2(SCH_1):M_E_PAR   I111 @BASEBOARD_FAB2_LIB.BASEBOARD_FAB2(SCH_1):PAGE51
    58 M_DEF_RST_N @BASEBOARD_FAB2_LIB.BASEBOARD_FAB2(SCH_1):M_DEF_RST_N   I111 @BASEBOARD_FAB2_LIB.BASEBOARD_FAB2(SCH_1):PAGE51
   144 TP_CH_E_DIMM_E0_RFU_2 @BASEBOARD_FAB2_LIB.BASEBOARD_FAB2(SCH_1):TP_CH_E_DIMM_E0_RFU_2   I111 @BASEBOARD_FAB2_LIB.BASEBOARD_FAB2(SCH_1):PAGE51
   227 TP_CH_E_DIMM_E0_RFU_1 @BASEBOARD_FAB2_LIB.BASEBOARD_FAB2(SCH_1):TP_CH_E_DIMM_E0_RFU_1   I111 @BASEBOARD_FAB2_LIB.BASEBOARD_FAB2(SCH_1):PAGE51
   205 TP_CH_E_DIMM_E0_RFU_0 @BASEBOARD_FAB2_LIB.BASEBOARD_FAB2(SCH_1):TP_CH_E_DIMM_E0_RFU_0   I111 @BASEBOARD_FAB2_LIB.BASEBOARD_FAB2(SCH_1):PAGE51
    84 M_E_CS_N<0> @BASEBOARD_FAB2_LIB.BASEBOARD_FAB2(SCH_1):M_E_CS_N(0)   I111 @BASEBOARD_FAB2_LIB.BASEBOARD_FAB2(SCH_1):PAGE51
    89 M_E_CS_N<1> @BASEBOARD_FAB2_LIB.BASEBOARD_FAB2(SCH_1):M_E_CS_N(1)   I111 @BASEBOARD_FAB2_LIB.BASEBOARD_FAB2(SCH_1):PAGE51
    93 M_E_CS_N<2> @BASEBOARD_FAB2_LIB.BASEBOARD_FAB2(SCH_1):M_E_CS_N(2)   I111 @BASEBOARD_FAB2_LIB.BASEBOARD_FAB2(SCH_1):PAGE51
   237 M_E_CS_N<3> @BASEBOARD_FAB2_LIB.BASEBOARD_FAB2(SCH_1):M_E_CS_N(3)   I111 @BASEBOARD_FAB2_LIB.BASEBOARD_FAB2(SCH_1):PAGE51
   238    GND @BASEBOARD_FAB2_LIB.BASEBOARD_FAB2(SCH_1):GND   I111 @BASEBOARD_FAB2_LIB.BASEBOARD_FAB2(SCH_1):PAGE51
   140 PVPP_DEF @BASEBOARD_FAB2_LIB.BASEBOARD_FAB2(SCH_1):PVPP_DEF   I111 @BASEBOARD_FAB2_LIB.BASEBOARD_FAB2(SCH_1):PAGE51
   139    GND @BASEBOARD_FAB2_LIB.BASEBOARD_FAB2(SCH_1):GND   I111 @BASEBOARD_FAB2_LIB.BASEBOARD_FAB2(SCH_1):PAGE51
   230 FM_ADR_COMPLETE_DEF_N @BASEBOARD_FAB2_LIB.BASEBOARD_FAB2(SCH_1):FM_ADR_COMPLETE_DEF_N   I111 @BASEBOARD_FAB2_LIB.BASEBOARD_FAB2(SCH_1):PAGE51
   141 SMB_DDR_DEF_VPP_SCL @BASEBOARD_FAB2_LIB.BASEBOARD_FAB2(SCH_1):SMB_DDR_DEF_VPP_SCL   I111 @BASEBOARD_FAB2_LIB.BASEBOARD_FAB2(SCH_1):PAGE51
   285 SMB_DDR_DEF_VPP_SDA @BASEBOARD_FAB2_LIB.BASEBOARD_FAB2(SCH_1):SMB_DDR_DEF_VPP_SDA   I111 @BASEBOARD_FAB2_LIB.BASEBOARD_FAB2(SCH_1):PAGE51
   284 PVPP_DEF @BASEBOARD_FAB2_LIB.BASEBOARD_FAB2(SCH_1):PVPP_DEF   I111 @BASEBOARD_FAB2_LIB.BASEBOARD_FAB2(SCH_1):PAGE51
   146 M_E_VREF @BASEBOARD_FAB2_LIB.BASEBOARD_FAB2(SCH_1):M_E_VREF   I111 @BASEBOARD_FAB2_LIB.BASEBOARD_FAB2(SCH_1):PAGE51
   152 M_E_DQS_DN<0> @BASEBOARD_FAB2_LIB.BASEBOARD_FAB2(SCH_1):M_E_DQS_DN(0)    I66 @BASEBOARD_FAB2_LIB.BASEBOARD_FAB2(SCH_1):PAGE51
   153 M_E_DQS_DP<0> @BASEBOARD_FAB2_LIB.BASEBOARD_FAB2(SCH_1):M_E_DQS_DP(0)    I66 @BASEBOARD_FAB2_LIB.BASEBOARD_FAB2(SCH_1):PAGE51
    19 M_E_DQS_DN<10> @BASEBOARD_FAB2_LIB.BASEBOARD_FAB2(SCH_1):M_E_DQS_DN(10)    I66 @BASEBOARD_FAB2_LIB.BASEBOARD_FAB2(SCH_1):PAGE51
    18 M_E_DQS_DP<10> @BASEBOARD_FAB2_LIB.BASEBOARD_FAB2(SCH_1):M_E_DQS_DP(10)    I66 @BASEBOARD_FAB2_LIB.BASEBOARD_FAB2(SCH_1):PAGE51
    30 M_E_DQS_DN<11> @BASEBOARD_FAB2_LIB.BASEBOARD_FAB2(SCH_1):M_E_DQS_DN(11)    I66 @BASEBOARD_FAB2_LIB.BASEBOARD_FAB2(SCH_1):PAGE51
    29 M_E_DQS_DP<11> @BASEBOARD_FAB2_LIB.BASEBOARD_FAB2(SCH_1):M_E_DQS_DP(11)    I66 @BASEBOARD_FAB2_LIB.BASEBOARD_FAB2(SCH_1):PAGE51
    41 M_E_DQS_DN<12> @BASEBOARD_FAB2_LIB.BASEBOARD_FAB2(SCH_1):M_E_DQS_DN(12)    I66 @BASEBOARD_FAB2_LIB.BASEBOARD_FAB2(SCH_1):PAGE51
    40 M_E_DQS_DP<12> @BASEBOARD_FAB2_LIB.BASEBOARD_FAB2(SCH_1):M_E_DQS_DP(12)    I66 @BASEBOARD_FAB2_LIB.BASEBOARD_FAB2(SCH_1):PAGE51
   100 M_E_DQS_DN<13> @BASEBOARD_FAB2_LIB.BASEBOARD_FAB2(SCH_1):M_E_DQS_DN(13)    I66 @BASEBOARD_FAB2_LIB.BASEBOARD_FAB2(SCH_1):PAGE51
    99 M_E_DQS_DP<13> @BASEBOARD_FAB2_LIB.BASEBOARD_FAB2(SCH_1):M_E_DQS_DP(13)    I66 @BASEBOARD_FAB2_LIB.BASEBOARD_FAB2(SCH_1):PAGE51
   111 M_E_DQS_DN<14> @BASEBOARD_FAB2_LIB.BASEBOARD_FAB2(SCH_1):M_E_DQS_DN(14)    I66 @BASEBOARD_FAB2_LIB.BASEBOARD_FAB2(SCH_1):PAGE51
   110 M_E_DQS_DP<14> @BASEBOARD_FAB2_LIB.BASEBOARD_FAB2(SCH_1):M_E_DQS_DP(14)    I66 @BASEBOARD_FAB2_LIB.BASEBOARD_FAB2(SCH_1):PAGE51
   122 M_E_DQS_DN<15> @BASEBOARD_FAB2_LIB.BASEBOARD_FAB2(SCH_1):M_E_DQS_DN(15)    I66 @BASEBOARD_FAB2_LIB.BASEBOARD_FAB2(SCH_1):PAGE51
   121 M_E_DQS_DP<15> @BASEBOARD_FAB2_LIB.BASEBOARD_FAB2(SCH_1):M_E_DQS_DP(15)    I66 @BASEBOARD_FAB2_LIB.BASEBOARD_FAB2(SCH_1):PAGE51
   133 M_E_DQS_DN<16> @BASEBOARD_FAB2_LIB.BASEBOARD_FAB2(SCH_1):M_E_DQS_DN(16)    I66 @BASEBOARD_FAB2_LIB.BASEBOARD_FAB2(SCH_1):PAGE51
   132 M_E_DQS_DP<16> @BASEBOARD_FAB2_LIB.BASEBOARD_FAB2(SCH_1):M_E_DQS_DP(16)    I66 @BASEBOARD_FAB2_LIB.BASEBOARD_FAB2(SCH_1):PAGE51
    52 M_E_DQS_DN<17> @BASEBOARD_FAB2_LIB.BASEBOARD_FAB2(SCH_1):M_E_DQS_DN(17)    I66 @BASEBOARD_FAB2_LIB.BASEBOARD_FAB2(SCH_1):PAGE51
    51 M_E_DQS_DP<17> @BASEBOARD_FAB2_LIB.BASEBOARD_FAB2(SCH_1):M_E_DQS_DP(17)    I66 @BASEBOARD_FAB2_LIB.BASEBOARD_FAB2(SCH_1):PAGE51
   163 M_E_DQS_DN<1> @BASEBOARD_FAB2_LIB.BASEBOARD_FAB2(SCH_1):M_E_DQS_DN(1)    I66 @BASEBOARD_FAB2_LIB.BASEBOARD_FAB2(SCH_1):PAGE51
   164 M_E_DQS_DP<1> @BASEBOARD_FAB2_LIB.BASEBOARD_FAB2(SCH_1):M_E_DQS_DP(1)    I66 @BASEBOARD_FAB2_LIB.BASEBOARD_FAB2(SCH_1):PAGE51
   174 M_E_DQS_DN<2> @BASEBOARD_FAB2_LIB.BASEBOARD_FAB2(SCH_1):M_E_DQS_DN(2)    I66 @BASEBOARD_FAB2_LIB.BASEBOARD_FAB2(SCH_1):PAGE51
   175 M_E_DQS_DP<2> @BASEBOARD_FAB2_LIB.BASEBOARD_FAB2(SCH_1):M_E_DQS_DP(2)    I66 @BASEBOARD_FAB2_LIB.BASEBOARD_FAB2(SCH_1):PAGE51
   185 M_E_DQS_DN<3> @BASEBOARD_FAB2_LIB.BASEBOARD_FAB2(SCH_1):M_E_DQS_DN(3)    I66 @BASEBOARD_FAB2_LIB.BASEBOARD_FAB2(SCH_1):PAGE51
   186 M_E_DQS_DP<3> @BASEBOARD_FAB2_LIB.BASEBOARD_FAB2(SCH_1):M_E_DQS_DP(3)    I66 @BASEBOARD_FAB2_LIB.BASEBOARD_FAB2(SCH_1):PAGE51
   244 M_E_DQS_DN<4> @BASEBOARD_FAB2_LIB.BASEBOARD_FAB2(SCH_1):M_E_DQS_DN(4)    I66 @BASEBOARD_FAB2_LIB.BASEBOARD_FAB2(SCH_1):PAGE51
   245 M_E_DQS_DP<4> @BASEBOARD_FAB2_LIB.BASEBOARD_FAB2(SCH_1):M_E_DQS_DP(4)    I66 @BASEBOARD_FAB2_LIB.BASEBOARD_FAB2(SCH_1):PAGE51
   255 M_E_DQS_DN<5> @BASEBOARD_FAB2_LIB.BASEBOARD_FAB2(SCH_1):M_E_DQS_DN(5)    I66 @BASEBOARD_FAB2_LIB.BASEBOARD_FAB2(SCH_1):PAGE51
   256 M_E_DQS_DP<5> @BASEBOARD_FAB2_LIB.BASEBOARD_FAB2(SCH_1):M_E_DQS_DP(5)    I66 @BASEBOARD_FAB2_LIB.BASEBOARD_FAB2(SCH_1):PAGE51
   266 M_E_DQS_DN<6> @BASEBOARD_FAB2_LIB.BASEBOARD_FAB2(SCH_1):M_E_DQS_DN(6)    I66 @BASEBOARD_FAB2_LIB.BASEBOARD_FAB2(SCH_1):PAGE51
   267 M_E_DQS_DP<6> @BASEBOARD_FAB2_LIB.BASEBOARD_FAB2(SCH_1):M_E_DQS_DP(6)    I66 @BASEBOARD_FAB2_LIB.BASEBOARD_FAB2(SCH_1):PAGE51
   277 M_E_DQS_DN<7> @BASEBOARD_FAB2_LIB.BASEBOARD_FAB2(SCH_1):M_E_DQS_DN(7)    I66 @BASEBOARD_FAB2_LIB.BASEBOARD_FAB2(SCH_1):PAGE51
   278 M_E_DQS_DP<7> @BASEBOARD_FAB2_LIB.BASEBOARD_FAB2(SCH_1):M_E_DQS_DP(7)    I66 @BASEBOARD_FAB2_LIB.BASEBOARD_FAB2(SCH_1):PAGE51
   196 M_E_DQS_DN<8> @BASEBOARD_FAB2_LIB.BASEBOARD_FAB2(SCH_1):M_E_DQS_DN(8)    I66 @BASEBOARD_FAB2_LIB.BASEBOARD_FAB2(SCH_1):PAGE51
   197 M_E_DQS_DP<8> @BASEBOARD_FAB2_LIB.BASEBOARD_FAB2(SCH_1):M_E_DQS_DP(8)    I66 @BASEBOARD_FAB2_LIB.BASEBOARD_FAB2(SCH_1):PAGE51
     8 M_E_DQS_DN<9> @BASEBOARD_FAB2_LIB.BASEBOARD_FAB2(SCH_1):M_E_DQS_DN(9)    I66 @BASEBOARD_FAB2_LIB.BASEBOARD_FAB2(SCH_1):PAGE51
     7 M_E_DQS_DP<9> @BASEBOARD_FAB2_LIB.BASEBOARD_FAB2(SCH_1):M_E_DQS_DP(9)    I66 @BASEBOARD_FAB2_LIB.BASEBOARD_FAB2(SCH_1):PAGE51
     2    GND @BASEBOARD_FAB2_LIB.BASEBOARD_FAB2(SCH_1):GND    I43 @BASEBOARD_FAB2_LIB.BASEBOARD_FAB2(SCH_1):PAGE51
     4    GND @BASEBOARD_FAB2_LIB.BASEBOARD_FAB2(SCH_1):GND    I43 @BASEBOARD_FAB2_LIB.BASEBOARD_FAB2(SCH_1):PAGE51
     6    GND @BASEBOARD_FAB2_LIB.BASEBOARD_FAB2(SCH_1):GND    I43 @BASEBOARD_FAB2_LIB.BASEBOARD_FAB2(SCH_1):PAGE51
     9    GND @BASEBOARD_FAB2_LIB.BASEBOARD_FAB2(SCH_1):GND    I43 @BASEBOARD_FAB2_LIB.BASEBOARD_FAB2(SCH_1):PAGE51
    11    GND @BASEBOARD_FAB2_LIB.BASEBOARD_FAB2(SCH_1):GND    I43 @BASEBOARD_FAB2_LIB.BASEBOARD_FAB2(SCH_1):PAGE51
    13    GND @BASEBOARD_FAB2_LIB.BASEBOARD_FAB2(SCH_1):GND    I43 @BASEBOARD_FAB2_LIB.BASEBOARD_FAB2(SCH_1):PAGE51
    15    GND @BASEBOARD_FAB2_LIB.BASEBOARD_FAB2(SCH_1):GND    I43 @BASEBOARD_FAB2_LIB.BASEBOARD_FAB2(SCH_1):PAGE51
    17    GND @BASEBOARD_FAB2_LIB.BASEBOARD_FAB2(SCH_1):GND    I43 @BASEBOARD_FAB2_LIB.BASEBOARD_FAB2(SCH_1):PAGE51
    20    GND @BASEBOARD_FAB2_LIB.BASEBOARD_FAB2(SCH_1):GND    I43 @BASEBOARD_FAB2_LIB.BASEBOARD_FAB2(SCH_1):PAGE51
    22    GND @BASEBOARD_FAB2_LIB.BASEBOARD_FAB2(SCH_1):GND    I43 @BASEBOARD_FAB2_LIB.BASEBOARD_FAB2(SCH_1):PAGE51
    24    GND @BASEBOARD_FAB2_LIB.BASEBOARD_FAB2(SCH_1):GND    I43 @BASEBOARD_FAB2_LIB.BASEBOARD_FAB2(SCH_1):PAGE51
    26    GND @BASEBOARD_FAB2_LIB.BASEBOARD_FAB2(SCH_1):GND    I43 @BASEBOARD_FAB2_LIB.BASEBOARD_FAB2(SCH_1):PAGE51
    28    GND @BASEBOARD_FAB2_LIB.BASEBOARD_FAB2(SCH_1):GND    I43 @BASEBOARD_FAB2_LIB.BASEBOARD_FAB2(SCH_1):PAGE51
    31    GND @BASEBOARD_FAB2_LIB.BASEBOARD_FAB2(SCH_1):GND    I43 @BASEBOARD_FAB2_LIB.BASEBOARD_FAB2(SCH_1):PAGE51
    33    GND @BASEBOARD_FAB2_LIB.BASEBOARD_FAB2(SCH_1):GND    I43 @BASEBOARD_FAB2_LIB.BASEBOARD_FAB2(SCH_1):PAGE51
    35    GND @BASEBOARD_FAB2_LIB.BASEBOARD_FAB2(SCH_1):GND    I43 @BASEBOARD_FAB2_LIB.BASEBOARD_FAB2(SCH_1):PAGE51
    37    GND @BASEBOARD_FAB2_LIB.BASEBOARD_FAB2(SCH_1):GND    I43 @BASEBOARD_FAB2_LIB.BASEBOARD_FAB2(SCH_1):PAGE51
    39    GND @BASEBOARD_FAB2_LIB.BASEBOARD_FAB2(SCH_1):GND    I43 @BASEBOARD_FAB2_LIB.BASEBOARD_FAB2(SCH_1):PAGE51
    42    GND @BASEBOARD_FAB2_LIB.BASEBOARD_FAB2(SCH_1):GND    I43 @BASEBOARD_FAB2_LIB.BASEBOARD_FAB2(SCH_1):PAGE51
    44    GND @BASEBOARD_FAB2_LIB.BASEBOARD_FAB2(SCH_1):GND    I43 @BASEBOARD_FAB2_LIB.BASEBOARD_FAB2(SCH_1):PAGE51
    46    GND @BASEBOARD_FAB2_LIB.BASEBOARD_FAB2(SCH_1):GND    I43 @BASEBOARD_FAB2_LIB.BASEBOARD_FAB2(SCH_1):PAGE51
    48    GND @BASEBOARD_FAB2_LIB.BASEBOARD_FAB2(SCH_1):GND    I43 @BASEBOARD_FAB2_LIB.BASEBOARD_FAB2(SCH_1):PAGE51
    50    GND @BASEBOARD_FAB2_LIB.BASEBOARD_FAB2(SCH_1):GND    I43 @BASEBOARD_FAB2_LIB.BASEBOARD_FAB2(SCH_1):PAGE51
    53    GND @BASEBOARD_FAB2_LIB.BASEBOARD_FAB2(SCH_1):GND    I43 @BASEBOARD_FAB2_LIB.BASEBOARD_FAB2(SCH_1):PAGE51
    55    GND @BASEBOARD_FAB2_LIB.BASEBOARD_FAB2(SCH_1):GND    I43 @BASEBOARD_FAB2_LIB.BASEBOARD_FAB2(SCH_1):PAGE51
    57    GND @BASEBOARD_FAB2_LIB.BASEBOARD_FAB2(SCH_1):GND    I43 @BASEBOARD_FAB2_LIB.BASEBOARD_FAB2(SCH_1):PAGE51
    94    GND @BASEBOARD_FAB2_LIB.BASEBOARD_FAB2(SCH_1):GND    I43 @BASEBOARD_FAB2_LIB.BASEBOARD_FAB2(SCH_1):PAGE51
    96    GND @BASEBOARD_FAB2_LIB.BASEBOARD_FAB2(SCH_1):GND    I43 @BASEBOARD_FAB2_LIB.BASEBOARD_FAB2(SCH_1):PAGE51
    98    GND @BASEBOARD_FAB2_LIB.BASEBOARD_FAB2(SCH_1):GND    I43 @BASEBOARD_FAB2_LIB.BASEBOARD_FAB2(SCH_1):PAGE51
   101    GND @BASEBOARD_FAB2_LIB.BASEBOARD_FAB2(SCH_1):GND    I43 @BASEBOARD_FAB2_LIB.BASEBOARD_FAB2(SCH_1):PAGE51
   103    GND @BASEBOARD_FAB2_LIB.BASEBOARD_FAB2(SCH_1):GND    I43 @BASEBOARD_FAB2_LIB.BASEBOARD_FAB2(SCH_1):PAGE51
   105    GND @BASEBOARD_FAB2_LIB.BASEBOARD_FAB2(SCH_1):GND    I43 @BASEBOARD_FAB2_LIB.BASEBOARD_FAB2(SCH_1):PAGE51
   107    GND @BASEBOARD_FAB2_LIB.BASEBOARD_FAB2(SCH_1):GND    I43 @BASEBOARD_FAB2_LIB.BASEBOARD_FAB2(SCH_1):PAGE51
   109    GND @BASEBOARD_FAB2_LIB.BASEBOARD_FAB2(SCH_1):GND    I43 @BASEBOARD_FAB2_LIB.BASEBOARD_FAB2(SCH_1):PAGE51
   112    GND @BASEBOARD_FAB2_LIB.BASEBOARD_FAB2(SCH_1):GND    I43 @BASEBOARD_FAB2_LIB.BASEBOARD_FAB2(SCH_1):PAGE51
   114    GND @BASEBOARD_FAB2_LIB.BASEBOARD_FAB2(SCH_1):GND    I43 @BASEBOARD_FAB2_LIB.BASEBOARD_FAB2(SCH_1):PAGE51
   116    GND @BASEBOARD_FAB2_LIB.BASEBOARD_FAB2(SCH_1):GND    I43 @BASEBOARD_FAB2_LIB.BASEBOARD_FAB2(SCH_1):PAGE51
   118    GND @BASEBOARD_FAB2_LIB.BASEBOARD_FAB2(SCH_1):GND    I43 @BASEBOARD_FAB2_LIB.BASEBOARD_FAB2(SCH_1):PAGE51
   120    GND @BASEBOARD_FAB2_LIB.BASEBOARD_FAB2(SCH_1):GND    I43 @BASEBOARD_FAB2_LIB.BASEBOARD_FAB2(SCH_1):PAGE51
   123    GND @BASEBOARD_FAB2_LIB.BASEBOARD_FAB2(SCH_1):GND    I43 @BASEBOARD_FAB2_LIB.BASEBOARD_FAB2(SCH_1):PAGE51
   125    GND @BASEBOARD_FAB2_LIB.BASEBOARD_FAB2(SCH_1):GND    I43 @BASEBOARD_FAB2_LIB.BASEBOARD_FAB2(SCH_1):PAGE51
   127    GND @BASEBOARD_FAB2_LIB.BASEBOARD_FAB2(SCH_1):GND    I43 @BASEBOARD_FAB2_LIB.BASEBOARD_FAB2(SCH_1):PAGE51
   129    GND @BASEBOARD_FAB2_LIB.BASEBOARD_FAB2(SCH_1):GND    I43 @BASEBOARD_FAB2_LIB.BASEBOARD_FAB2(SCH_1):PAGE51
   131    GND @BASEBOARD_FAB2_LIB.BASEBOARD_FAB2(SCH_1):GND    I43 @BASEBOARD_FAB2_LIB.BASEBOARD_FAB2(SCH_1):PAGE51
   134    GND @BASEBOARD_FAB2_LIB.BASEBOARD_FAB2(SCH_1):GND    I43 @BASEBOARD_FAB2_LIB.BASEBOARD_FAB2(SCH_1):PAGE51
   136    GND @BASEBOARD_FAB2_LIB.BASEBOARD_FAB2(SCH_1):GND    I43 @BASEBOARD_FAB2_LIB.BASEBOARD_FAB2(SCH_1):PAGE51
   138    GND @BASEBOARD_FAB2_LIB.BASEBOARD_FAB2(SCH_1):GND    I43 @BASEBOARD_FAB2_LIB.BASEBOARD_FAB2(SCH_1):PAGE51
   147    GND @BASEBOARD_FAB2_LIB.BASEBOARD_FAB2(SCH_1):GND    I43 @BASEBOARD_FAB2_LIB.BASEBOARD_FAB2(SCH_1):PAGE51
   149    GND @BASEBOARD_FAB2_LIB.BASEBOARD_FAB2(SCH_1):GND    I43 @BASEBOARD_FAB2_LIB.BASEBOARD_FAB2(SCH_1):PAGE51
   151    GND @BASEBOARD_FAB2_LIB.BASEBOARD_FAB2(SCH_1):GND    I43 @BASEBOARD_FAB2_LIB.BASEBOARD_FAB2(SCH_1):PAGE51
   154    GND @BASEBOARD_FAB2_LIB.BASEBOARD_FAB2(SCH_1):GND    I43 @BASEBOARD_FAB2_LIB.BASEBOARD_FAB2(SCH_1):PAGE51
   156    GND @BASEBOARD_FAB2_LIB.BASEBOARD_FAB2(SCH_1):GND    I43 @BASEBOARD_FAB2_LIB.BASEBOARD_FAB2(SCH_1):PAGE51
   158    GND @BASEBOARD_FAB2_LIB.BASEBOARD_FAB2(SCH_1):GND    I43 @BASEBOARD_FAB2_LIB.BASEBOARD_FAB2(SCH_1):PAGE51
   160    GND @BASEBOARD_FAB2_LIB.BASEBOARD_FAB2(SCH_1):GND    I43 @BASEBOARD_FAB2_LIB.BASEBOARD_FAB2(SCH_1):PAGE51
   162    GND @BASEBOARD_FAB2_LIB.BASEBOARD_FAB2(SCH_1):GND    I43 @BASEBOARD_FAB2_LIB.BASEBOARD_FAB2(SCH_1):PAGE51
   165    GND @BASEBOARD_FAB2_LIB.BASEBOARD_FAB2(SCH_1):GND    I43 @BASEBOARD_FAB2_LIB.BASEBOARD_FAB2(SCH_1):PAGE51
   167    GND @BASEBOARD_FAB2_LIB.BASEBOARD_FAB2(SCH_1):GND    I43 @BASEBOARD_FAB2_LIB.BASEBOARD_FAB2(SCH_1):PAGE51
   169    GND @BASEBOARD_FAB2_LIB.BASEBOARD_FAB2(SCH_1):GND    I43 @BASEBOARD_FAB2_LIB.BASEBOARD_FAB2(SCH_1):PAGE51
   171    GND @BASEBOARD_FAB2_LIB.BASEBOARD_FAB2(SCH_1):GND    I43 @BASEBOARD_FAB2_LIB.BASEBOARD_FAB2(SCH_1):PAGE51
   173    GND @BASEBOARD_FAB2_LIB.BASEBOARD_FAB2(SCH_1):GND    I43 @BASEBOARD_FAB2_LIB.BASEBOARD_FAB2(SCH_1):PAGE51
   176    GND @BASEBOARD_FAB2_LIB.BASEBOARD_FAB2(SCH_1):GND    I43 @BASEBOARD_FAB2_LIB.BASEBOARD_FAB2(SCH_1):PAGE51
   178    GND @BASEBOARD_FAB2_LIB.BASEBOARD_FAB2(SCH_1):GND    I43 @BASEBOARD_FAB2_LIB.BASEBOARD_FAB2(SCH_1):PAGE51
   180    GND @BASEBOARD_FAB2_LIB.BASEBOARD_FAB2(SCH_1):GND    I43 @BASEBOARD_FAB2_LIB.BASEBOARD_FAB2(SCH_1):PAGE51
   182    GND @BASEBOARD_FAB2_LIB.BASEBOARD_FAB2(SCH_1):GND    I43 @BASEBOARD_FAB2_LIB.BASEBOARD_FAB2(SCH_1):PAGE51
   184    GND @BASEBOARD_FAB2_LIB.BASEBOARD_FAB2(SCH_1):GND    I43 @BASEBOARD_FAB2_LIB.BASEBOARD_FAB2(SCH_1):PAGE51
   187    GND @BASEBOARD_FAB2_LIB.BASEBOARD_FAB2(SCH_1):GND    I43 @BASEBOARD_FAB2_LIB.BASEBOARD_FAB2(SCH_1):PAGE51
   189    GND @BASEBOARD_FAB2_LIB.BASEBOARD_FAB2(SCH_1):GND    I43 @BASEBOARD_FAB2_LIB.BASEBOARD_FAB2(SCH_1):PAGE51
   191    GND @BASEBOARD_FAB2_LIB.BASEBOARD_FAB2(SCH_1):GND    I43 @BASEBOARD_FAB2_LIB.BASEBOARD_FAB2(SCH_1):PAGE51
   193    GND @BASEBOARD_FAB2_LIB.BASEBOARD_FAB2(SCH_1):GND    I43 @BASEBOARD_FAB2_LIB.BASEBOARD_FAB2(SCH_1):PAGE51
   195    GND @BASEBOARD_FAB2_LIB.BASEBOARD_FAB2(SCH_1):GND    I43 @BASEBOARD_FAB2_LIB.BASEBOARD_FAB2(SCH_1):PAGE51
   198    GND @BASEBOARD_FAB2_LIB.BASEBOARD_FAB2(SCH_1):GND    I43 @BASEBOARD_FAB2_LIB.BASEBOARD_FAB2(SCH_1):PAGE51
   200    GND @BASEBOARD_FAB2_LIB.BASEBOARD_FAB2(SCH_1):GND    I43 @BASEBOARD_FAB2_LIB.BASEBOARD_FAB2(SCH_1):PAGE51
   202    GND @BASEBOARD_FAB2_LIB.BASEBOARD_FAB2(SCH_1):GND    I43 @BASEBOARD_FAB2_LIB.BASEBOARD_FAB2(SCH_1):PAGE51
   239    GND @BASEBOARD_FAB2_LIB.BASEBOARD_FAB2(SCH_1):GND    I43 @BASEBOARD_FAB2_LIB.BASEBOARD_FAB2(SCH_1):PAGE51
   241    GND @BASEBOARD_FAB2_LIB.BASEBOARD_FAB2(SCH_1):GND    I43 @BASEBOARD_FAB2_LIB.BASEBOARD_FAB2(SCH_1):PAGE51
   243    GND @BASEBOARD_FAB2_LIB.BASEBOARD_FAB2(SCH_1):GND    I43 @BASEBOARD_FAB2_LIB.BASEBOARD_FAB2(SCH_1):PAGE51
   246    GND @BASEBOARD_FAB2_LIB.BASEBOARD_FAB2(SCH_1):GND    I43 @BASEBOARD_FAB2_LIB.BASEBOARD_FAB2(SCH_1):PAGE51
   248    GND @BASEBOARD_FAB2_LIB.BASEBOARD_FAB2(SCH_1):GND    I43 @BASEBOARD_FAB2_LIB.BASEBOARD_FAB2(SCH_1):PAGE51
   250    GND @BASEBOARD_FAB2_LIB.BASEBOARD_FAB2(SCH_1):GND    I43 @BASEBOARD_FAB2_LIB.BASEBOARD_FAB2(SCH_1):PAGE51
   252    GND @BASEBOARD_FAB2_LIB.BASEBOARD_FAB2(SCH_1):GND    I43 @BASEBOARD_FAB2_LIB.BASEBOARD_FAB2(SCH_1):PAGE51
   254    GND @BASEBOARD_FAB2_LIB.BASEBOARD_FAB2(SCH_1):GND    I43 @BASEBOARD_FAB2_LIB.BASEBOARD_FAB2(SCH_1):PAGE51
   257    GND @BASEBOARD_FAB2_LIB.BASEBOARD_FAB2(SCH_1):GND    I43 @BASEBOARD_FAB2_LIB.BASEBOARD_FAB2(SCH_1):PAGE51
   259    GND @BASEBOARD_FAB2_LIB.BASEBOARD_FAB2(SCH_1):GND    I43 @BASEBOARD_FAB2_LIB.BASEBOARD_FAB2(SCH_1):PAGE51
   261    GND @BASEBOARD_FAB2_LIB.BASEBOARD_FAB2(SCH_1):GND    I43 @BASEBOARD_FAB2_LIB.BASEBOARD_FAB2(SCH_1):PAGE51
   263    GND @BASEBOARD_FAB2_LIB.BASEBOARD_FAB2(SCH_1):GND    I43 @BASEBOARD_FAB2_LIB.BASEBOARD_FAB2(SCH_1):PAGE51
   265    GND @BASEBOARD_FAB2_LIB.BASEBOARD_FAB2(SCH_1):GND    I43 @BASEBOARD_FAB2_LIB.BASEBOARD_FAB2(SCH_1):PAGE51
   268    GND @BASEBOARD_FAB2_LIB.BASEBOARD_FAB2(SCH_1):GND    I43 @BASEBOARD_FAB2_LIB.BASEBOARD_FAB2(SCH_1):PAGE51
   270    GND @BASEBOARD_FAB2_LIB.BASEBOARD_FAB2(SCH_1):GND    I43 @BASEBOARD_FAB2_LIB.BASEBOARD_FAB2(SCH_1):PAGE51
   272    GND @BASEBOARD_FAB2_LIB.BASEBOARD_FAB2(SCH_1):GND    I43 @BASEBOARD_FAB2_LIB.BASEBOARD_FAB2(SCH_1):PAGE51
   274    GND @BASEBOARD_FAB2_LIB.BASEBOARD_FAB2(SCH_1):GND    I43 @BASEBOARD_FAB2_LIB.BASEBOARD_FAB2(SCH_1):PAGE51
   276    GND @BASEBOARD_FAB2_LIB.BASEBOARD_FAB2(SCH_1):GND    I43 @BASEBOARD_FAB2_LIB.BASEBOARD_FAB2(SCH_1):PAGE51
   279    GND @BASEBOARD_FAB2_LIB.BASEBOARD_FAB2(SCH_1):GND    I43 @BASEBOARD_FAB2_LIB.BASEBOARD_FAB2(SCH_1):PAGE51
   281    GND @BASEBOARD_FAB2_LIB.BASEBOARD_FAB2(SCH_1):GND    I43 @BASEBOARD_FAB2_LIB.BASEBOARD_FAB2(SCH_1):PAGE51
   283    GND @BASEBOARD_FAB2_LIB.BASEBOARD_FAB2(SCH_1):GND    I43 @BASEBOARD_FAB2_LIB.BASEBOARD_FAB2(SCH_1):PAGE51
     1 P12V_NVDIMM_DEF @BASEBOARD_FAB2_LIB.BASEBOARD_FAB2(SCH_1):P12V_NVDIMM_DEF   I167 @BASEBOARD_FAB2_LIB.BASEBOARD_FAB2(SCH_1):PAGE51
   145 P12V_NVDIMM_DEF @BASEBOARD_FAB2_LIB.BASEBOARD_FAB2(SCH_1):P12V_NVDIMM_DEF   I167 @BASEBOARD_FAB2_LIB.BASEBOARD_FAB2(SCH_1):PAGE51
    59 PVDDQ_DEF @BASEBOARD_FAB2_LIB.BASEBOARD_FAB2(SCH_1):PVDDQ_DEF   I167 @BASEBOARD_FAB2_LIB.BASEBOARD_FAB2(SCH_1):PAGE51
    61 PVDDQ_DEF @BASEBOARD_FAB2_LIB.BASEBOARD_FAB2(SCH_1):PVDDQ_DEF   I167 @BASEBOARD_FAB2_LIB.BASEBOARD_FAB2(SCH_1):PAGE51
    64 PVDDQ_DEF @BASEBOARD_FAB2_LIB.BASEBOARD_FAB2(SCH_1):PVDDQ_DEF   I167 @BASEBOARD_FAB2_LIB.BASEBOARD_FAB2(SCH_1):PAGE51
    67 PVDDQ_DEF @BASEBOARD_FAB2_LIB.BASEBOARD_FAB2(SCH_1):PVDDQ_DEF   I167 @BASEBOARD_FAB2_LIB.BASEBOARD_FAB2(SCH_1):PAGE51
    70 PVDDQ_DEF @BASEBOARD_FAB2_LIB.BASEBOARD_FAB2(SCH_1):PVDDQ_DEF   I167 @BASEBOARD_FAB2_LIB.BASEBOARD_FAB2(SCH_1):PAGE51
    73 PVDDQ_DEF @BASEBOARD_FAB2_LIB.BASEBOARD_FAB2(SCH_1):PVDDQ_DEF   I167 @BASEBOARD_FAB2_LIB.BASEBOARD_FAB2(SCH_1):PAGE51
    76 PVDDQ_DEF @BASEBOARD_FAB2_LIB.BASEBOARD_FAB2(SCH_1):PVDDQ_DEF   I167 @BASEBOARD_FAB2_LIB.BASEBOARD_FAB2(SCH_1):PAGE51
    80 PVDDQ_DEF @BASEBOARD_FAB2_LIB.BASEBOARD_FAB2(SCH_1):PVDDQ_DEF   I167 @BASEBOARD_FAB2_LIB.BASEBOARD_FAB2(SCH_1):PAGE51
    83 PVDDQ_DEF @BASEBOARD_FAB2_LIB.BASEBOARD_FAB2(SCH_1):PVDDQ_DEF   I167 @BASEBOARD_FAB2_LIB.BASEBOARD_FAB2(SCH_1):PAGE51
    85 PVDDQ_DEF @BASEBOARD_FAB2_LIB.BASEBOARD_FAB2(SCH_1):PVDDQ_DEF   I167 @BASEBOARD_FAB2_LIB.BASEBOARD_FAB2(SCH_1):PAGE51
    88 PVDDQ_DEF @BASEBOARD_FAB2_LIB.BASEBOARD_FAB2(SCH_1):PVDDQ_DEF   I167 @BASEBOARD_FAB2_LIB.BASEBOARD_FAB2(SCH_1):PAGE51
    90 PVDDQ_DEF @BASEBOARD_FAB2_LIB.BASEBOARD_FAB2(SCH_1):PVDDQ_DEF   I167 @BASEBOARD_FAB2_LIB.BASEBOARD_FAB2(SCH_1):PAGE51
    92 PVDDQ_DEF @BASEBOARD_FAB2_LIB.BASEBOARD_FAB2(SCH_1):PVDDQ_DEF   I167 @BASEBOARD_FAB2_LIB.BASEBOARD_FAB2(SCH_1):PAGE51
   204 PVDDQ_DEF @BASEBOARD_FAB2_LIB.BASEBOARD_FAB2(SCH_1):PVDDQ_DEF   I167 @BASEBOARD_FAB2_LIB.BASEBOARD_FAB2(SCH_1):PAGE51
   206 PVDDQ_DEF @BASEBOARD_FAB2_LIB.BASEBOARD_FAB2(SCH_1):PVDDQ_DEF   I167 @BASEBOARD_FAB2_LIB.BASEBOARD_FAB2(SCH_1):PAGE51
   209 PVDDQ_DEF @BASEBOARD_FAB2_LIB.BASEBOARD_FAB2(SCH_1):PVDDQ_DEF   I167 @BASEBOARD_FAB2_LIB.BASEBOARD_FAB2(SCH_1):PAGE51
   212 PVDDQ_DEF @BASEBOARD_FAB2_LIB.BASEBOARD_FAB2(SCH_1):PVDDQ_DEF   I167 @BASEBOARD_FAB2_LIB.BASEBOARD_FAB2(SCH_1):PAGE51
   215 PVDDQ_DEF @BASEBOARD_FAB2_LIB.BASEBOARD_FAB2(SCH_1):PVDDQ_DEF   I167 @BASEBOARD_FAB2_LIB.BASEBOARD_FAB2(SCH_1):PAGE51
   217 PVDDQ_DEF @BASEBOARD_FAB2_LIB.BASEBOARD_FAB2(SCH_1):PVDDQ_DEF   I167 @BASEBOARD_FAB2_LIB.BASEBOARD_FAB2(SCH_1):PAGE51
   220 PVDDQ_DEF @BASEBOARD_FAB2_LIB.BASEBOARD_FAB2(SCH_1):PVDDQ_DEF   I167 @BASEBOARD_FAB2_LIB.BASEBOARD_FAB2(SCH_1):PAGE51
   223 PVDDQ_DEF @BASEBOARD_FAB2_LIB.BASEBOARD_FAB2(SCH_1):PVDDQ_DEF   I167 @BASEBOARD_FAB2_LIB.BASEBOARD_FAB2(SCH_1):PAGE51
   226 PVDDQ_DEF @BASEBOARD_FAB2_LIB.BASEBOARD_FAB2(SCH_1):PVDDQ_DEF   I167 @BASEBOARD_FAB2_LIB.BASEBOARD_FAB2(SCH_1):PAGE51
   229 PVDDQ_DEF @BASEBOARD_FAB2_LIB.BASEBOARD_FAB2(SCH_1):PVDDQ_DEF   I167 @BASEBOARD_FAB2_LIB.BASEBOARD_FAB2(SCH_1):PAGE51
   231 PVDDQ_DEF @BASEBOARD_FAB2_LIB.BASEBOARD_FAB2(SCH_1):PVDDQ_DEF   I167 @BASEBOARD_FAB2_LIB.BASEBOARD_FAB2(SCH_1):PAGE51
   233 PVDDQ_DEF @BASEBOARD_FAB2_LIB.BASEBOARD_FAB2(SCH_1):PVDDQ_DEF   I167 @BASEBOARD_FAB2_LIB.BASEBOARD_FAB2(SCH_1):PAGE51
   236 PVDDQ_DEF @BASEBOARD_FAB2_LIB.BASEBOARD_FAB2(SCH_1):PVDDQ_DEF   I167 @BASEBOARD_FAB2_LIB.BASEBOARD_FAB2(SCH_1):PAGE51
   142 PVPP_DEF @BASEBOARD_FAB2_LIB.BASEBOARD_FAB2(SCH_1):PVPP_DEF   I167 @BASEBOARD_FAB2_LIB.BASEBOARD_FAB2(SCH_1):PAGE51
   143 PVPP_DEF @BASEBOARD_FAB2_LIB.BASEBOARD_FAB2(SCH_1):PVPP_DEF   I167 @BASEBOARD_FAB2_LIB.BASEBOARD_FAB2(SCH_1):PAGE51
   288 PVPP_DEF @BASEBOARD_FAB2_LIB.BASEBOARD_FAB2(SCH_1):PVPP_DEF   I167 @BASEBOARD_FAB2_LIB.BASEBOARD_FAB2(SCH_1):PAGE51
   286 PVPP_DEF @BASEBOARD_FAB2_LIB.BASEBOARD_FAB2(SCH_1):PVPP_DEF   I167 @BASEBOARD_FAB2_LIB.BASEBOARD_FAB2(SCH_1):PAGE51
   287 PVPP_DEF @BASEBOARD_FAB2_LIB.BASEBOARD_FAB2(SCH_1):PVPP_DEF   I167 @BASEBOARD_FAB2_LIB.BASEBOARD_FAB2(SCH_1):PAGE51
    77 PVTT_DEF @BASEBOARD_FAB2_LIB.BASEBOARD_FAB2(SCH_1):PVTT_DEF   I167 @BASEBOARD_FAB2_LIB.BASEBOARD_FAB2(SCH_1):PAGE51
   221 PVTT_DEF @BASEBOARD_FAB2_LIB.BASEBOARD_FAB2(SCH_1):PVTT_DEF   I167 @BASEBOARD_FAB2_LIB.BASEBOARD_FAB2(SCH_1):PAGE51

J4B1 SCONN288_H44441004_PIP-SCONN,HA
    79 M_D_MA<0> @BASEBOARD_FAB2_LIB.BASEBOARD_FAB2(SCH_1):M_D_MA(0)   I111 @BASEBOARD_FAB2_LIB.BASEBOARD_FAB2(SCH_1):PAGE49
    72 M_D_MA<1> @BASEBOARD_FAB2_LIB.BASEBOARD_FAB2(SCH_1):M_D_MA(1)   I111 @BASEBOARD_FAB2_LIB.BASEBOARD_FAB2(SCH_1):PAGE49
   225 M_D_MA<10> @BASEBOARD_FAB2_LIB.BASEBOARD_FAB2(SCH_1):M_D_MA(10)   I111 @BASEBOARD_FAB2_LIB.BASEBOARD_FAB2(SCH_1):PAGE49
   210 M_D_MA<11> @BASEBOARD_FAB2_LIB.BASEBOARD_FAB2(SCH_1):M_D_MA(11)   I111 @BASEBOARD_FAB2_LIB.BASEBOARD_FAB2(SCH_1):PAGE49
    65 M_D_MA<12> @BASEBOARD_FAB2_LIB.BASEBOARD_FAB2(SCH_1):M_D_MA(12)   I111 @BASEBOARD_FAB2_LIB.BASEBOARD_FAB2(SCH_1):PAGE49
   232 M_D_MA<13> @BASEBOARD_FAB2_LIB.BASEBOARD_FAB2(SCH_1):M_D_MA(13)   I111 @BASEBOARD_FAB2_LIB.BASEBOARD_FAB2(SCH_1):PAGE49
   228 M_D_MA<14> @BASEBOARD_FAB2_LIB.BASEBOARD_FAB2(SCH_1):M_D_MA(14)   I111 @BASEBOARD_FAB2_LIB.BASEBOARD_FAB2(SCH_1):PAGE49
    86 M_D_MA<15> @BASEBOARD_FAB2_LIB.BASEBOARD_FAB2(SCH_1):M_D_MA(15)   I111 @BASEBOARD_FAB2_LIB.BASEBOARD_FAB2(SCH_1):PAGE49
    82 M_D_MA<16> @BASEBOARD_FAB2_LIB.BASEBOARD_FAB2(SCH_1):M_D_MA(16)   I111 @BASEBOARD_FAB2_LIB.BASEBOARD_FAB2(SCH_1):PAGE49
   234 M_D_MA<17> @BASEBOARD_FAB2_LIB.BASEBOARD_FAB2(SCH_1):M_D_MA(17)   I111 @BASEBOARD_FAB2_LIB.BASEBOARD_FAB2(SCH_1):PAGE49
   216 M_D_MA<2> @BASEBOARD_FAB2_LIB.BASEBOARD_FAB2(SCH_1):M_D_MA(2)   I111 @BASEBOARD_FAB2_LIB.BASEBOARD_FAB2(SCH_1):PAGE49
    71 M_D_MA<3> @BASEBOARD_FAB2_LIB.BASEBOARD_FAB2(SCH_1):M_D_MA(3)   I111 @BASEBOARD_FAB2_LIB.BASEBOARD_FAB2(SCH_1):PAGE49
   214 M_D_MA<4> @BASEBOARD_FAB2_LIB.BASEBOARD_FAB2(SCH_1):M_D_MA(4)   I111 @BASEBOARD_FAB2_LIB.BASEBOARD_FAB2(SCH_1):PAGE49
   213 M_D_MA<5> @BASEBOARD_FAB2_LIB.BASEBOARD_FAB2(SCH_1):M_D_MA(5)   I111 @BASEBOARD_FAB2_LIB.BASEBOARD_FAB2(SCH_1):PAGE49
    69 M_D_MA<6> @BASEBOARD_FAB2_LIB.BASEBOARD_FAB2(SCH_1):M_D_MA(6)   I111 @BASEBOARD_FAB2_LIB.BASEBOARD_FAB2(SCH_1):PAGE49
   211 M_D_MA<7> @BASEBOARD_FAB2_LIB.BASEBOARD_FAB2(SCH_1):M_D_MA(7)   I111 @BASEBOARD_FAB2_LIB.BASEBOARD_FAB2(SCH_1):PAGE49
    68 M_D_MA<8> @BASEBOARD_FAB2_LIB.BASEBOARD_FAB2(SCH_1):M_D_MA(8)   I111 @BASEBOARD_FAB2_LIB.BASEBOARD_FAB2(SCH_1):PAGE49
    66 M_D_MA<9> @BASEBOARD_FAB2_LIB.BASEBOARD_FAB2(SCH_1):M_D_MA(9)   I111 @BASEBOARD_FAB2_LIB.BASEBOARD_FAB2(SCH_1):PAGE49
    62 M_D_ACT_N @BASEBOARD_FAB2_LIB.BASEBOARD_FAB2(SCH_1):M_D_ACT_N   I111 @BASEBOARD_FAB2_LIB.BASEBOARD_FAB2(SCH_1):PAGE49
   208 M_D_ALERT_N @BASEBOARD_FAB2_LIB.BASEBOARD_FAB2(SCH_1):M_D_ALERT_N   I111 @BASEBOARD_FAB2_LIB.BASEBOARD_FAB2(SCH_1):PAGE49
   224 M_D_BA<1> @BASEBOARD_FAB2_LIB.BASEBOARD_FAB2(SCH_1):M_D_BA(1)   I111 @BASEBOARD_FAB2_LIB.BASEBOARD_FAB2(SCH_1):PAGE49
    81 M_D_BA<0> @BASEBOARD_FAB2_LIB.BASEBOARD_FAB2(SCH_1):M_D_BA(0)   I111 @BASEBOARD_FAB2_LIB.BASEBOARD_FAB2(SCH_1):PAGE49
   207 M_D_BG<1> @BASEBOARD_FAB2_LIB.BASEBOARD_FAB2(SCH_1):M_D_BG(1)   I111 @BASEBOARD_FAB2_LIB.BASEBOARD_FAB2(SCH_1):PAGE49
    63 M_D_BG<0> @BASEBOARD_FAB2_LIB.BASEBOARD_FAB2(SCH_1):M_D_BG(0)   I111 @BASEBOARD_FAB2_LIB.BASEBOARD_FAB2(SCH_1):PAGE49
   235 M_D_C<2> @BASEBOARD_FAB2_LIB.BASEBOARD_FAB2(SCH_1):M_D_C(2)   I111 @BASEBOARD_FAB2_LIB.BASEBOARD_FAB2(SCH_1):PAGE49
   199 M_D_ECC<6> @BASEBOARD_FAB2_LIB.BASEBOARD_FAB2(SCH_1):M_D_ECC(6)   I111 @BASEBOARD_FAB2_LIB.BASEBOARD_FAB2(SCH_1):PAGE49
    54 M_D_ECC<7> @BASEBOARD_FAB2_LIB.BASEBOARD_FAB2(SCH_1):M_D_ECC(7)   I111 @BASEBOARD_FAB2_LIB.BASEBOARD_FAB2(SCH_1):PAGE49
   192 M_D_ECC<4> @BASEBOARD_FAB2_LIB.BASEBOARD_FAB2(SCH_1):M_D_ECC(4)   I111 @BASEBOARD_FAB2_LIB.BASEBOARD_FAB2(SCH_1):PAGE49
    47 M_D_ECC<5> @BASEBOARD_FAB2_LIB.BASEBOARD_FAB2(SCH_1):M_D_ECC(5)   I111 @BASEBOARD_FAB2_LIB.BASEBOARD_FAB2(SCH_1):PAGE49
   201 M_D_ECC<2> @BASEBOARD_FAB2_LIB.BASEBOARD_FAB2(SCH_1):M_D_ECC(2)   I111 @BASEBOARD_FAB2_LIB.BASEBOARD_FAB2(SCH_1):PAGE49
    56 M_D_ECC<3> @BASEBOARD_FAB2_LIB.BASEBOARD_FAB2(SCH_1):M_D_ECC(3)   I111 @BASEBOARD_FAB2_LIB.BASEBOARD_FAB2(SCH_1):PAGE49
   194 M_D_ECC<0> @BASEBOARD_FAB2_LIB.BASEBOARD_FAB2(SCH_1):M_D_ECC(0)   I111 @BASEBOARD_FAB2_LIB.BASEBOARD_FAB2(SCH_1):PAGE49
    49 M_D_ECC<1> @BASEBOARD_FAB2_LIB.BASEBOARD_FAB2(SCH_1):M_D_ECC(1)   I111 @BASEBOARD_FAB2_LIB.BASEBOARD_FAB2(SCH_1):PAGE49
    75 M_D_CLK_DN<0> @BASEBOARD_FAB2_LIB.BASEBOARD_FAB2(SCH_1):M_D_CLK_DN(0)   I111 @BASEBOARD_FAB2_LIB.BASEBOARD_FAB2(SCH_1):PAGE49
    74 M_D_CLK_DP<0> @BASEBOARD_FAB2_LIB.BASEBOARD_FAB2(SCH_1):M_D_CLK_DP(0)   I111 @BASEBOARD_FAB2_LIB.BASEBOARD_FAB2(SCH_1):PAGE49
   219 M_D_CLK_DN<1> @BASEBOARD_FAB2_LIB.BASEBOARD_FAB2(SCH_1):M_D_CLK_DN(1)   I111 @BASEBOARD_FAB2_LIB.BASEBOARD_FAB2(SCH_1):PAGE49
   218 M_D_CLK_DP<1> @BASEBOARD_FAB2_LIB.BASEBOARD_FAB2(SCH_1):M_D_CLK_DP(1)   I111 @BASEBOARD_FAB2_LIB.BASEBOARD_FAB2(SCH_1):PAGE49
   203 M_D_CKE<1> @BASEBOARD_FAB2_LIB.BASEBOARD_FAB2(SCH_1):M_D_CKE(1)   I111 @BASEBOARD_FAB2_LIB.BASEBOARD_FAB2(SCH_1):PAGE49
    60 M_D_CKE<0> @BASEBOARD_FAB2_LIB.BASEBOARD_FAB2(SCH_1):M_D_CKE(0)   I111 @BASEBOARD_FAB2_LIB.BASEBOARD_FAB2(SCH_1):PAGE49
   280 M_D_DQ<62> @BASEBOARD_FAB2_LIB.BASEBOARD_FAB2(SCH_1):M_D_DQ(62)   I111 @BASEBOARD_FAB2_LIB.BASEBOARD_FAB2(SCH_1):PAGE49
   135 M_D_DQ<63> @BASEBOARD_FAB2_LIB.BASEBOARD_FAB2(SCH_1):M_D_DQ(63)   I111 @BASEBOARD_FAB2_LIB.BASEBOARD_FAB2(SCH_1):PAGE49
   273 M_D_DQ<60> @BASEBOARD_FAB2_LIB.BASEBOARD_FAB2(SCH_1):M_D_DQ(60)   I111 @BASEBOARD_FAB2_LIB.BASEBOARD_FAB2(SCH_1):PAGE49
   128 M_D_DQ<61> @BASEBOARD_FAB2_LIB.BASEBOARD_FAB2(SCH_1):M_D_DQ(61)   I111 @BASEBOARD_FAB2_LIB.BASEBOARD_FAB2(SCH_1):PAGE49
   282 M_D_DQ<58> @BASEBOARD_FAB2_LIB.BASEBOARD_FAB2(SCH_1):M_D_DQ(58)   I111 @BASEBOARD_FAB2_LIB.BASEBOARD_FAB2(SCH_1):PAGE49
   137 M_D_DQ<59> @BASEBOARD_FAB2_LIB.BASEBOARD_FAB2(SCH_1):M_D_DQ(59)   I111 @BASEBOARD_FAB2_LIB.BASEBOARD_FAB2(SCH_1):PAGE49
   275 M_D_DQ<56> @BASEBOARD_FAB2_LIB.BASEBOARD_FAB2(SCH_1):M_D_DQ(56)   I111 @BASEBOARD_FAB2_LIB.BASEBOARD_FAB2(SCH_1):PAGE49
   130 M_D_DQ<57> @BASEBOARD_FAB2_LIB.BASEBOARD_FAB2(SCH_1):M_D_DQ(57)   I111 @BASEBOARD_FAB2_LIB.BASEBOARD_FAB2(SCH_1):PAGE49
   269 M_D_DQ<54> @BASEBOARD_FAB2_LIB.BASEBOARD_FAB2(SCH_1):M_D_DQ(54)   I111 @BASEBOARD_FAB2_LIB.BASEBOARD_FAB2(SCH_1):PAGE49
   124 M_D_DQ<55> @BASEBOARD_FAB2_LIB.BASEBOARD_FAB2(SCH_1):M_D_DQ(55)   I111 @BASEBOARD_FAB2_LIB.BASEBOARD_FAB2(SCH_1):PAGE49
   262 M_D_DQ<52> @BASEBOARD_FAB2_LIB.BASEBOARD_FAB2(SCH_1):M_D_DQ(52)   I111 @BASEBOARD_FAB2_LIB.BASEBOARD_FAB2(SCH_1):PAGE49
   117 M_D_DQ<53> @BASEBOARD_FAB2_LIB.BASEBOARD_FAB2(SCH_1):M_D_DQ(53)   I111 @BASEBOARD_FAB2_LIB.BASEBOARD_FAB2(SCH_1):PAGE49
   271 M_D_DQ<50> @BASEBOARD_FAB2_LIB.BASEBOARD_FAB2(SCH_1):M_D_DQ(50)   I111 @BASEBOARD_FAB2_LIB.BASEBOARD_FAB2(SCH_1):PAGE49
   126 M_D_DQ<51> @BASEBOARD_FAB2_LIB.BASEBOARD_FAB2(SCH_1):M_D_DQ(51)   I111 @BASEBOARD_FAB2_LIB.BASEBOARD_FAB2(SCH_1):PAGE49
   264 M_D_DQ<48> @BASEBOARD_FAB2_LIB.BASEBOARD_FAB2(SCH_1):M_D_DQ(48)   I111 @BASEBOARD_FAB2_LIB.BASEBOARD_FAB2(SCH_1):PAGE49
   119 M_D_DQ<49> @BASEBOARD_FAB2_LIB.BASEBOARD_FAB2(SCH_1):M_D_DQ(49)   I111 @BASEBOARD_FAB2_LIB.BASEBOARD_FAB2(SCH_1):PAGE49
   258 M_D_DQ<46> @BASEBOARD_FAB2_LIB.BASEBOARD_FAB2(SCH_1):M_D_DQ(46)   I111 @BASEBOARD_FAB2_LIB.BASEBOARD_FAB2(SCH_1):PAGE49
   113 M_D_DQ<47> @BASEBOARD_FAB2_LIB.BASEBOARD_FAB2(SCH_1):M_D_DQ(47)   I111 @BASEBOARD_FAB2_LIB.BASEBOARD_FAB2(SCH_1):PAGE49
   251 M_D_DQ<44> @BASEBOARD_FAB2_LIB.BASEBOARD_FAB2(SCH_1):M_D_DQ(44)   I111 @BASEBOARD_FAB2_LIB.BASEBOARD_FAB2(SCH_1):PAGE49
   106 M_D_DQ<45> @BASEBOARD_FAB2_LIB.BASEBOARD_FAB2(SCH_1):M_D_DQ(45)   I111 @BASEBOARD_FAB2_LIB.BASEBOARD_FAB2(SCH_1):PAGE49
   260 M_D_DQ<42> @BASEBOARD_FAB2_LIB.BASEBOARD_FAB2(SCH_1):M_D_DQ(42)   I111 @BASEBOARD_FAB2_LIB.BASEBOARD_FAB2(SCH_1):PAGE49
   115 M_D_DQ<43> @BASEBOARD_FAB2_LIB.BASEBOARD_FAB2(SCH_1):M_D_DQ(43)   I111 @BASEBOARD_FAB2_LIB.BASEBOARD_FAB2(SCH_1):PAGE49
   253 M_D_DQ<40> @BASEBOARD_FAB2_LIB.BASEBOARD_FAB2(SCH_1):M_D_DQ(40)   I111 @BASEBOARD_FAB2_LIB.BASEBOARD_FAB2(SCH_1):PAGE49
   108 M_D_DQ<41> @BASEBOARD_FAB2_LIB.BASEBOARD_FAB2(SCH_1):M_D_DQ(41)   I111 @BASEBOARD_FAB2_LIB.BASEBOARD_FAB2(SCH_1):PAGE49
   247 M_D_DQ<38> @BASEBOARD_FAB2_LIB.BASEBOARD_FAB2(SCH_1):M_D_DQ(38)   I111 @BASEBOARD_FAB2_LIB.BASEBOARD_FAB2(SCH_1):PAGE49
   102 M_D_DQ<39> @BASEBOARD_FAB2_LIB.BASEBOARD_FAB2(SCH_1):M_D_DQ(39)   I111 @BASEBOARD_FAB2_LIB.BASEBOARD_FAB2(SCH_1):PAGE49
   240 M_D_DQ<36> @BASEBOARD_FAB2_LIB.BASEBOARD_FAB2(SCH_1):M_D_DQ(36)   I111 @BASEBOARD_FAB2_LIB.BASEBOARD_FAB2(SCH_1):PAGE49
    95 M_D_DQ<37> @BASEBOARD_FAB2_LIB.BASEBOARD_FAB2(SCH_1):M_D_DQ(37)   I111 @BASEBOARD_FAB2_LIB.BASEBOARD_FAB2(SCH_1):PAGE49
   249 M_D_DQ<34> @BASEBOARD_FAB2_LIB.BASEBOARD_FAB2(SCH_1):M_D_DQ(34)   I111 @BASEBOARD_FAB2_LIB.BASEBOARD_FAB2(SCH_1):PAGE49
   104 M_D_DQ<35> @BASEBOARD_FAB2_LIB.BASEBOARD_FAB2(SCH_1):M_D_DQ(35)   I111 @BASEBOARD_FAB2_LIB.BASEBOARD_FAB2(SCH_1):PAGE49
   242 M_D_DQ<32> @BASEBOARD_FAB2_LIB.BASEBOARD_FAB2(SCH_1):M_D_DQ(32)   I111 @BASEBOARD_FAB2_LIB.BASEBOARD_FAB2(SCH_1):PAGE49
    97 M_D_DQ<33> @BASEBOARD_FAB2_LIB.BASEBOARD_FAB2(SCH_1):M_D_DQ(33)   I111 @BASEBOARD_FAB2_LIB.BASEBOARD_FAB2(SCH_1):PAGE49
   188 M_D_DQ<30> @BASEBOARD_FAB2_LIB.BASEBOARD_FAB2(SCH_1):M_D_DQ(30)   I111 @BASEBOARD_FAB2_LIB.BASEBOARD_FAB2(SCH_1):PAGE49
    43 M_D_DQ<31> @BASEBOARD_FAB2_LIB.BASEBOARD_FAB2(SCH_1):M_D_DQ(31)   I111 @BASEBOARD_FAB2_LIB.BASEBOARD_FAB2(SCH_1):PAGE49
   181 M_D_DQ<28> @BASEBOARD_FAB2_LIB.BASEBOARD_FAB2(SCH_1):M_D_DQ(28)   I111 @BASEBOARD_FAB2_LIB.BASEBOARD_FAB2(SCH_1):PAGE49
    36 M_D_DQ<29> @BASEBOARD_FAB2_LIB.BASEBOARD_FAB2(SCH_1):M_D_DQ(29)   I111 @BASEBOARD_FAB2_LIB.BASEBOARD_FAB2(SCH_1):PAGE49
   190 M_D_DQ<26> @BASEBOARD_FAB2_LIB.BASEBOARD_FAB2(SCH_1):M_D_DQ(26)   I111 @BASEBOARD_FAB2_LIB.BASEBOARD_FAB2(SCH_1):PAGE49
    45 M_D_DQ<27> @BASEBOARD_FAB2_LIB.BASEBOARD_FAB2(SCH_1):M_D_DQ(27)   I111 @BASEBOARD_FAB2_LIB.BASEBOARD_FAB2(SCH_1):PAGE49
   183 M_D_DQ<24> @BASEBOARD_FAB2_LIB.BASEBOARD_FAB2(SCH_1):M_D_DQ(24)   I111 @BASEBOARD_FAB2_LIB.BASEBOARD_FAB2(SCH_1):PAGE49
    38 M_D_DQ<25> @BASEBOARD_FAB2_LIB.BASEBOARD_FAB2(SCH_1):M_D_DQ(25)   I111 @BASEBOARD_FAB2_LIB.BASEBOARD_FAB2(SCH_1):PAGE49
   177 M_D_DQ<22> @BASEBOARD_FAB2_LIB.BASEBOARD_FAB2(SCH_1):M_D_DQ(22)   I111 @BASEBOARD_FAB2_LIB.BASEBOARD_FAB2(SCH_1):PAGE49
    32 M_D_DQ<23> @BASEBOARD_FAB2_LIB.BASEBOARD_FAB2(SCH_1):M_D_DQ(23)   I111 @BASEBOARD_FAB2_LIB.BASEBOARD_FAB2(SCH_1):PAGE49
   170 M_D_DQ<20> @BASEBOARD_FAB2_LIB.BASEBOARD_FAB2(SCH_1):M_D_DQ(20)   I111 @BASEBOARD_FAB2_LIB.BASEBOARD_FAB2(SCH_1):PAGE49
    25 M_D_DQ<21> @BASEBOARD_FAB2_LIB.BASEBOARD_FAB2(SCH_1):M_D_DQ(21)   I111 @BASEBOARD_FAB2_LIB.BASEBOARD_FAB2(SCH_1):PAGE49
   179 M_D_DQ<18> @BASEBOARD_FAB2_LIB.BASEBOARD_FAB2(SCH_1):M_D_DQ(18)   I111 @BASEBOARD_FAB2_LIB.BASEBOARD_FAB2(SCH_1):PAGE49
    34 M_D_DQ<19> @BASEBOARD_FAB2_LIB.BASEBOARD_FAB2(SCH_1):M_D_DQ(19)   I111 @BASEBOARD_FAB2_LIB.BASEBOARD_FAB2(SCH_1):PAGE49
   172 M_D_DQ<16> @BASEBOARD_FAB2_LIB.BASEBOARD_FAB2(SCH_1):M_D_DQ(16)   I111 @BASEBOARD_FAB2_LIB.BASEBOARD_FAB2(SCH_1):PAGE49
    27 M_D_DQ<17> @BASEBOARD_FAB2_LIB.BASEBOARD_FAB2(SCH_1):M_D_DQ(17)   I111 @BASEBOARD_FAB2_LIB.BASEBOARD_FAB2(SCH_1):PAGE49
   166 M_D_DQ<14> @BASEBOARD_FAB2_LIB.BASEBOARD_FAB2(SCH_1):M_D_DQ(14)   I111 @BASEBOARD_FAB2_LIB.BASEBOARD_FAB2(SCH_1):PAGE49
    21 M_D_DQ<15> @BASEBOARD_FAB2_LIB.BASEBOARD_FAB2(SCH_1):M_D_DQ(15)   I111 @BASEBOARD_FAB2_LIB.BASEBOARD_FAB2(SCH_1):PAGE49
   159 M_D_DQ<12> @BASEBOARD_FAB2_LIB.BASEBOARD_FAB2(SCH_1):M_D_DQ(12)   I111 @BASEBOARD_FAB2_LIB.BASEBOARD_FAB2(SCH_1):PAGE49
    14 M_D_DQ<13> @BASEBOARD_FAB2_LIB.BASEBOARD_FAB2(SCH_1):M_D_DQ(13)   I111 @BASEBOARD_FAB2_LIB.BASEBOARD_FAB2(SCH_1):PAGE49
   168 M_D_DQ<10> @BASEBOARD_FAB2_LIB.BASEBOARD_FAB2(SCH_1):M_D_DQ(10)   I111 @BASEBOARD_FAB2_LIB.BASEBOARD_FAB2(SCH_1):PAGE49
    23 M_D_DQ<11> @BASEBOARD_FAB2_LIB.BASEBOARD_FAB2(SCH_1):M_D_DQ(11)   I111 @BASEBOARD_FAB2_LIB.BASEBOARD_FAB2(SCH_1):PAGE49
   161 M_D_DQ<8> @BASEBOARD_FAB2_LIB.BASEBOARD_FAB2(SCH_1):M_D_DQ(8)   I111 @BASEBOARD_FAB2_LIB.BASEBOARD_FAB2(SCH_1):PAGE49
    16 M_D_DQ<9> @BASEBOARD_FAB2_LIB.BASEBOARD_FAB2(SCH_1):M_D_DQ(9)   I111 @BASEBOARD_FAB2_LIB.BASEBOARD_FAB2(SCH_1):PAGE49
   155 M_D_DQ<6> @BASEBOARD_FAB2_LIB.BASEBOARD_FAB2(SCH_1):M_D_DQ(6)   I111 @BASEBOARD_FAB2_LIB.BASEBOARD_FAB2(SCH_1):PAGE49
    10 M_D_DQ<7> @BASEBOARD_FAB2_LIB.BASEBOARD_FAB2(SCH_1):M_D_DQ(7)   I111 @BASEBOARD_FAB2_LIB.BASEBOARD_FAB2(SCH_1):PAGE49
   148 M_D_DQ<4> @BASEBOARD_FAB2_LIB.BASEBOARD_FAB2(SCH_1):M_D_DQ(4)   I111 @BASEBOARD_FAB2_LIB.BASEBOARD_FAB2(SCH_1):PAGE49
     3 M_D_DQ<5> @BASEBOARD_FAB2_LIB.BASEBOARD_FAB2(SCH_1):M_D_DQ(5)   I111 @BASEBOARD_FAB2_LIB.BASEBOARD_FAB2(SCH_1):PAGE49
   157 M_D_DQ<2> @BASEBOARD_FAB2_LIB.BASEBOARD_FAB2(SCH_1):M_D_DQ(2)   I111 @BASEBOARD_FAB2_LIB.BASEBOARD_FAB2(SCH_1):PAGE49
    12 M_D_DQ<3> @BASEBOARD_FAB2_LIB.BASEBOARD_FAB2(SCH_1):M_D_DQ(3)   I111 @BASEBOARD_FAB2_LIB.BASEBOARD_FAB2(SCH_1):PAGE49
   150 M_D_DQ<0> @BASEBOARD_FAB2_LIB.BASEBOARD_FAB2(SCH_1):M_D_DQ(0)   I111 @BASEBOARD_FAB2_LIB.BASEBOARD_FAB2(SCH_1):PAGE49
     5 M_D_DQ<1> @BASEBOARD_FAB2_LIB.BASEBOARD_FAB2(SCH_1):M_D_DQ(1)   I111 @BASEBOARD_FAB2_LIB.BASEBOARD_FAB2(SCH_1):PAGE49
    78 FM_DIMM_EVENT_COD_N @BASEBOARD_FAB2_LIB.BASEBOARD_FAB2(SCH_1):FM_DIMM_EVENT_COD_N   I111 @BASEBOARD_FAB2_LIB.BASEBOARD_FAB2(SCH_1):PAGE49
    91 M_D_ODT<1> @BASEBOARD_FAB2_LIB.BASEBOARD_FAB2(SCH_1):M_D_ODT(1)   I111 @BASEBOARD_FAB2_LIB.BASEBOARD_FAB2(SCH_1):PAGE49
    87 M_D_ODT<0> @BASEBOARD_FAB2_LIB.BASEBOARD_FAB2(SCH_1):M_D_ODT(0)   I111 @BASEBOARD_FAB2_LIB.BASEBOARD_FAB2(SCH_1):PAGE49
   222 M_D_PAR @BASEBOARD_FAB2_LIB.BASEBOARD_FAB2(SCH_1):M_D_PAR   I111 @BASEBOARD_FAB2_LIB.BASEBOARD_FAB2(SCH_1):PAGE49
    58 M_DEF_RST_N @BASEBOARD_FAB2_LIB.BASEBOARD_FAB2(SCH_1):M_DEF_RST_N   I111 @BASEBOARD_FAB2_LIB.BASEBOARD_FAB2(SCH_1):PAGE49
   144 TP_CH_D_DIMM_D0_RFU_2 @BASEBOARD_FAB2_LIB.BASEBOARD_FAB2(SCH_1):TP_CH_D_DIMM_D0_RFU_2   I111 @BASEBOARD_FAB2_LIB.BASEBOARD_FAB2(SCH_1):PAGE49
   227 TP_CH_D_DIMM_D0_RFU_1 @BASEBOARD_FAB2_LIB.BASEBOARD_FAB2(SCH_1):TP_CH_D_DIMM_D0_RFU_1   I111 @BASEBOARD_FAB2_LIB.BASEBOARD_FAB2(SCH_1):PAGE49
   205 TP_CH_D_DIMM_D0_RFU_0 @BASEBOARD_FAB2_LIB.BASEBOARD_FAB2(SCH_1):TP_CH_D_DIMM_D0_RFU_0   I111 @BASEBOARD_FAB2_LIB.BASEBOARD_FAB2(SCH_1):PAGE49
    84 M_D_CS_N<0> @BASEBOARD_FAB2_LIB.BASEBOARD_FAB2(SCH_1):M_D_CS_N(0)   I111 @BASEBOARD_FAB2_LIB.BASEBOARD_FAB2(SCH_1):PAGE49
    89 M_D_CS_N<1> @BASEBOARD_FAB2_LIB.BASEBOARD_FAB2(SCH_1):M_D_CS_N(1)   I111 @BASEBOARD_FAB2_LIB.BASEBOARD_FAB2(SCH_1):PAGE49
    93 M_D_CS_N<2> @BASEBOARD_FAB2_LIB.BASEBOARD_FAB2(SCH_1):M_D_CS_N(2)   I111 @BASEBOARD_FAB2_LIB.BASEBOARD_FAB2(SCH_1):PAGE49
   237 M_D_CS_N<3> @BASEBOARD_FAB2_LIB.BASEBOARD_FAB2(SCH_1):M_D_CS_N(3)   I111 @BASEBOARD_FAB2_LIB.BASEBOARD_FAB2(SCH_1):PAGE49
   238    GND @BASEBOARD_FAB2_LIB.BASEBOARD_FAB2(SCH_1):GND   I111 @BASEBOARD_FAB2_LIB.BASEBOARD_FAB2(SCH_1):PAGE49
   140    GND @BASEBOARD_FAB2_LIB.BASEBOARD_FAB2(SCH_1):GND   I111 @BASEBOARD_FAB2_LIB.BASEBOARD_FAB2(SCH_1):PAGE49
   139    GND @BASEBOARD_FAB2_LIB.BASEBOARD_FAB2(SCH_1):GND   I111 @BASEBOARD_FAB2_LIB.BASEBOARD_FAB2(SCH_1):PAGE49
   230 FM_ADR_COMPLETE_DEF_N @BASEBOARD_FAB2_LIB.BASEBOARD_FAB2(SCH_1):FM_ADR_COMPLETE_DEF_N   I111 @BASEBOARD_FAB2_LIB.BASEBOARD_FAB2(SCH_1):PAGE49
   141 SMB_DDR_DEF_VPP_SCL @BASEBOARD_FAB2_LIB.BASEBOARD_FAB2(SCH_1):SMB_DDR_DEF_VPP_SCL   I111 @BASEBOARD_FAB2_LIB.BASEBOARD_FAB2(SCH_1):PAGE49
   285 SMB_DDR_DEF_VPP_SDA @BASEBOARD_FAB2_LIB.BASEBOARD_FAB2(SCH_1):SMB_DDR_DEF_VPP_SDA   I111 @BASEBOARD_FAB2_LIB.BASEBOARD_FAB2(SCH_1):PAGE49
   284 PVPP_DEF @BASEBOARD_FAB2_LIB.BASEBOARD_FAB2(SCH_1):PVPP_DEF   I111 @BASEBOARD_FAB2_LIB.BASEBOARD_FAB2(SCH_1):PAGE49
   146 M_D_VREF @BASEBOARD_FAB2_LIB.BASEBOARD_FAB2(SCH_1):M_D_VREF   I111 @BASEBOARD_FAB2_LIB.BASEBOARD_FAB2(SCH_1):PAGE49
   152 M_D_DQS_DN<0> @BASEBOARD_FAB2_LIB.BASEBOARD_FAB2(SCH_1):M_D_DQS_DN(0)    I66 @BASEBOARD_FAB2_LIB.BASEBOARD_FAB2(SCH_1):PAGE49
   153 M_D_DQS_DP<0> @BASEBOARD_FAB2_LIB.BASEBOARD_FAB2(SCH_1):M_D_DQS_DP(0)    I66 @BASEBOARD_FAB2_LIB.BASEBOARD_FAB2(SCH_1):PAGE49
    19 M_D_DQS_DN<10> @BASEBOARD_FAB2_LIB.BASEBOARD_FAB2(SCH_1):M_D_DQS_DN(10)    I66 @BASEBOARD_FAB2_LIB.BASEBOARD_FAB2(SCH_1):PAGE49
    18 M_D_DQS_DP<10> @BASEBOARD_FAB2_LIB.BASEBOARD_FAB2(SCH_1):M_D_DQS_DP(10)    I66 @BASEBOARD_FAB2_LIB.BASEBOARD_FAB2(SCH_1):PAGE49
    30 M_D_DQS_DN<11> @BASEBOARD_FAB2_LIB.BASEBOARD_FAB2(SCH_1):M_D_DQS_DN(11)    I66 @BASEBOARD_FAB2_LIB.BASEBOARD_FAB2(SCH_1):PAGE49
    29 M_D_DQS_DP<11> @BASEBOARD_FAB2_LIB.BASEBOARD_FAB2(SCH_1):M_D_DQS_DP(11)    I66 @BASEBOARD_FAB2_LIB.BASEBOARD_FAB2(SCH_1):PAGE49
    41 M_D_DQS_DN<12> @BASEBOARD_FAB2_LIB.BASEBOARD_FAB2(SCH_1):M_D_DQS_DN(12)    I66 @BASEBOARD_FAB2_LIB.BASEBOARD_FAB2(SCH_1):PAGE49
    40 M_D_DQS_DP<12> @BASEBOARD_FAB2_LIB.BASEBOARD_FAB2(SCH_1):M_D_DQS_DP(12)    I66 @BASEBOARD_FAB2_LIB.BASEBOARD_FAB2(SCH_1):PAGE49
   100 M_D_DQS_DN<13> @BASEBOARD_FAB2_LIB.BASEBOARD_FAB2(SCH_1):M_D_DQS_DN(13)    I66 @BASEBOARD_FAB2_LIB.BASEBOARD_FAB2(SCH_1):PAGE49
    99 M_D_DQS_DP<13> @BASEBOARD_FAB2_LIB.BASEBOARD_FAB2(SCH_1):M_D_DQS_DP(13)    I66 @BASEBOARD_FAB2_LIB.BASEBOARD_FAB2(SCH_1):PAGE49
   111 M_D_DQS_DN<14> @BASEBOARD_FAB2_LIB.BASEBOARD_FAB2(SCH_1):M_D_DQS_DN(14)    I66 @BASEBOARD_FAB2_LIB.BASEBOARD_FAB2(SCH_1):PAGE49
   110 M_D_DQS_DP<14> @BASEBOARD_FAB2_LIB.BASEBOARD_FAB2(SCH_1):M_D_DQS_DP(14)    I66 @BASEBOARD_FAB2_LIB.BASEBOARD_FAB2(SCH_1):PAGE49
   122 M_D_DQS_DN<15> @BASEBOARD_FAB2_LIB.BASEBOARD_FAB2(SCH_1):M_D_DQS_DN(15)    I66 @BASEBOARD_FAB2_LIB.BASEBOARD_FAB2(SCH_1):PAGE49
   121 M_D_DQS_DP<15> @BASEBOARD_FAB2_LIB.BASEBOARD_FAB2(SCH_1):M_D_DQS_DP(15)    I66 @BASEBOARD_FAB2_LIB.BASEBOARD_FAB2(SCH_1):PAGE49
   133 M_D_DQS_DN<16> @BASEBOARD_FAB2_LIB.BASEBOARD_FAB2(SCH_1):M_D_DQS_DN(16)    I66 @BASEBOARD_FAB2_LIB.BASEBOARD_FAB2(SCH_1):PAGE49
   132 M_D_DQS_DP<16> @BASEBOARD_FAB2_LIB.BASEBOARD_FAB2(SCH_1):M_D_DQS_DP(16)    I66 @BASEBOARD_FAB2_LIB.BASEBOARD_FAB2(SCH_1):PAGE49
    52 M_D_DQS_DN<17> @BASEBOARD_FAB2_LIB.BASEBOARD_FAB2(SCH_1):M_D_DQS_DN(17)    I66 @BASEBOARD_FAB2_LIB.BASEBOARD_FAB2(SCH_1):PAGE49
    51 M_D_DQS_DP<17> @BASEBOARD_FAB2_LIB.BASEBOARD_FAB2(SCH_1):M_D_DQS_DP(17)    I66 @BASEBOARD_FAB2_LIB.BASEBOARD_FAB2(SCH_1):PAGE49
   163 M_D_DQS_DN<1> @BASEBOARD_FAB2_LIB.BASEBOARD_FAB2(SCH_1):M_D_DQS_DN(1)    I66 @BASEBOARD_FAB2_LIB.BASEBOARD_FAB2(SCH_1):PAGE49
   164 M_D_DQS_DP<1> @BASEBOARD_FAB2_LIB.BASEBOARD_FAB2(SCH_1):M_D_DQS_DP(1)    I66 @BASEBOARD_FAB2_LIB.BASEBOARD_FAB2(SCH_1):PAGE49
   174 M_D_DQS_DN<2> @BASEBOARD_FAB2_LIB.BASEBOARD_FAB2(SCH_1):M_D_DQS_DN(2)    I66 @BASEBOARD_FAB2_LIB.BASEBOARD_FAB2(SCH_1):PAGE49
   175 M_D_DQS_DP<2> @BASEBOARD_FAB2_LIB.BASEBOARD_FAB2(SCH_1):M_D_DQS_DP(2)    I66 @BASEBOARD_FAB2_LIB.BASEBOARD_FAB2(SCH_1):PAGE49
   185 M_D_DQS_DN<3> @BASEBOARD_FAB2_LIB.BASEBOARD_FAB2(SCH_1):M_D_DQS_DN(3)    I66 @BASEBOARD_FAB2_LIB.BASEBOARD_FAB2(SCH_1):PAGE49
   186 M_D_DQS_DP<3> @BASEBOARD_FAB2_LIB.BASEBOARD_FAB2(SCH_1):M_D_DQS_DP(3)    I66 @BASEBOARD_FAB2_LIB.BASEBOARD_FAB2(SCH_1):PAGE49
   244 M_D_DQS_DN<4> @BASEBOARD_FAB2_LIB.BASEBOARD_FAB2(SCH_1):M_D_DQS_DN(4)    I66 @BASEBOARD_FAB2_LIB.BASEBOARD_FAB2(SCH_1):PAGE49
   245 M_D_DQS_DP<4> @BASEBOARD_FAB2_LIB.BASEBOARD_FAB2(SCH_1):M_D_DQS_DP(4)    I66 @BASEBOARD_FAB2_LIB.BASEBOARD_FAB2(SCH_1):PAGE49
   255 M_D_DQS_DN<5> @BASEBOARD_FAB2_LIB.BASEBOARD_FAB2(SCH_1):M_D_DQS_DN(5)    I66 @BASEBOARD_FAB2_LIB.BASEBOARD_FAB2(SCH_1):PAGE49
   256 M_D_DQS_DP<5> @BASEBOARD_FAB2_LIB.BASEBOARD_FAB2(SCH_1):M_D_DQS_DP(5)    I66 @BASEBOARD_FAB2_LIB.BASEBOARD_FAB2(SCH_1):PAGE49
   266 M_D_DQS_DN<6> @BASEBOARD_FAB2_LIB.BASEBOARD_FAB2(SCH_1):M_D_DQS_DN(6)    I66 @BASEBOARD_FAB2_LIB.BASEBOARD_FAB2(SCH_1):PAGE49
   267 M_D_DQS_DP<6> @BASEBOARD_FAB2_LIB.BASEBOARD_FAB2(SCH_1):M_D_DQS_DP(6)    I66 @BASEBOARD_FAB2_LIB.BASEBOARD_FAB2(SCH_1):PAGE49
   277 M_D_DQS_DN<7> @BASEBOARD_FAB2_LIB.BASEBOARD_FAB2(SCH_1):M_D_DQS_DN(7)    I66 @BASEBOARD_FAB2_LIB.BASEBOARD_FAB2(SCH_1):PAGE49
   278 M_D_DQS_DP<7> @BASEBOARD_FAB2_LIB.BASEBOARD_FAB2(SCH_1):M_D_DQS_DP(7)    I66 @BASEBOARD_FAB2_LIB.BASEBOARD_FAB2(SCH_1):PAGE49
   196 M_D_DQS_DN<8> @BASEBOARD_FAB2_LIB.BASEBOARD_FAB2(SCH_1):M_D_DQS_DN(8)    I66 @BASEBOARD_FAB2_LIB.BASEBOARD_FAB2(SCH_1):PAGE49
   197 M_D_DQS_DP<8> @BASEBOARD_FAB2_LIB.BASEBOARD_FAB2(SCH_1):M_D_DQS_DP(8)    I66 @BASEBOARD_FAB2_LIB.BASEBOARD_FAB2(SCH_1):PAGE49
     8 M_D_DQS_DN<9> @BASEBOARD_FAB2_LIB.BASEBOARD_FAB2(SCH_1):M_D_DQS_DN(9)    I66 @BASEBOARD_FAB2_LIB.BASEBOARD_FAB2(SCH_1):PAGE49
     7 M_D_DQS_DP<9> @BASEBOARD_FAB2_LIB.BASEBOARD_FAB2(SCH_1):M_D_DQS_DP(9)    I66 @BASEBOARD_FAB2_LIB.BASEBOARD_FAB2(SCH_1):PAGE49
     2    GND @BASEBOARD_FAB2_LIB.BASEBOARD_FAB2(SCH_1):GND    I43 @BASEBOARD_FAB2_LIB.BASEBOARD_FAB2(SCH_1):PAGE49
     4    GND @BASEBOARD_FAB2_LIB.BASEBOARD_FAB2(SCH_1):GND    I43 @BASEBOARD_FAB2_LIB.BASEBOARD_FAB2(SCH_1):PAGE49
     6    GND @BASEBOARD_FAB2_LIB.BASEBOARD_FAB2(SCH_1):GND    I43 @BASEBOARD_FAB2_LIB.BASEBOARD_FAB2(SCH_1):PAGE49
     9    GND @BASEBOARD_FAB2_LIB.BASEBOARD_FAB2(SCH_1):GND    I43 @BASEBOARD_FAB2_LIB.BASEBOARD_FAB2(SCH_1):PAGE49
    11    GND @BASEBOARD_FAB2_LIB.BASEBOARD_FAB2(SCH_1):GND    I43 @BASEBOARD_FAB2_LIB.BASEBOARD_FAB2(SCH_1):PAGE49
    13    GND @BASEBOARD_FAB2_LIB.BASEBOARD_FAB2(SCH_1):GND    I43 @BASEBOARD_FAB2_LIB.BASEBOARD_FAB2(SCH_1):PAGE49
    15    GND @BASEBOARD_FAB2_LIB.BASEBOARD_FAB2(SCH_1):GND    I43 @BASEBOARD_FAB2_LIB.BASEBOARD_FAB2(SCH_1):PAGE49
    17    GND @BASEBOARD_FAB2_LIB.BASEBOARD_FAB2(SCH_1):GND    I43 @BASEBOARD_FAB2_LIB.BASEBOARD_FAB2(SCH_1):PAGE49
    20    GND @BASEBOARD_FAB2_LIB.BASEBOARD_FAB2(SCH_1):GND    I43 @BASEBOARD_FAB2_LIB.BASEBOARD_FAB2(SCH_1):PAGE49
    22    GND @BASEBOARD_FAB2_LIB.BASEBOARD_FAB2(SCH_1):GND    I43 @BASEBOARD_FAB2_LIB.BASEBOARD_FAB2(SCH_1):PAGE49
    24    GND @BASEBOARD_FAB2_LIB.BASEBOARD_FAB2(SCH_1):GND    I43 @BASEBOARD_FAB2_LIB.BASEBOARD_FAB2(SCH_1):PAGE49
    26    GND @BASEBOARD_FAB2_LIB.BASEBOARD_FAB2(SCH_1):GND    I43 @BASEBOARD_FAB2_LIB.BASEBOARD_FAB2(SCH_1):PAGE49
    28    GND @BASEBOARD_FAB2_LIB.BASEBOARD_FAB2(SCH_1):GND    I43 @BASEBOARD_FAB2_LIB.BASEBOARD_FAB2(SCH_1):PAGE49
    31    GND @BASEBOARD_FAB2_LIB.BASEBOARD_FAB2(SCH_1):GND    I43 @BASEBOARD_FAB2_LIB.BASEBOARD_FAB2(SCH_1):PAGE49
    33    GND @BASEBOARD_FAB2_LIB.BASEBOARD_FAB2(SCH_1):GND    I43 @BASEBOARD_FAB2_LIB.BASEBOARD_FAB2(SCH_1):PAGE49
    35    GND @BASEBOARD_FAB2_LIB.BASEBOARD_FAB2(SCH_1):GND    I43 @BASEBOARD_FAB2_LIB.BASEBOARD_FAB2(SCH_1):PAGE49
    37    GND @BASEBOARD_FAB2_LIB.BASEBOARD_FAB2(SCH_1):GND    I43 @BASEBOARD_FAB2_LIB.BASEBOARD_FAB2(SCH_1):PAGE49
    39    GND @BASEBOARD_FAB2_LIB.BASEBOARD_FAB2(SCH_1):GND    I43 @BASEBOARD_FAB2_LIB.BASEBOARD_FAB2(SCH_1):PAGE49
    42    GND @BASEBOARD_FAB2_LIB.BASEBOARD_FAB2(SCH_1):GND    I43 @BASEBOARD_FAB2_LIB.BASEBOARD_FAB2(SCH_1):PAGE49
    44    GND @BASEBOARD_FAB2_LIB.BASEBOARD_FAB2(SCH_1):GND    I43 @BASEBOARD_FAB2_LIB.BASEBOARD_FAB2(SCH_1):PAGE49
    46    GND @BASEBOARD_FAB2_LIB.BASEBOARD_FAB2(SCH_1):GND    I43 @BASEBOARD_FAB2_LIB.BASEBOARD_FAB2(SCH_1):PAGE49
    48    GND @BASEBOARD_FAB2_LIB.BASEBOARD_FAB2(SCH_1):GND    I43 @BASEBOARD_FAB2_LIB.BASEBOARD_FAB2(SCH_1):PAGE49
    50    GND @BASEBOARD_FAB2_LIB.BASEBOARD_FAB2(SCH_1):GND    I43 @BASEBOARD_FAB2_LIB.BASEBOARD_FAB2(SCH_1):PAGE49
    53    GND @BASEBOARD_FAB2_LIB.BASEBOARD_FAB2(SCH_1):GND    I43 @BASEBOARD_FAB2_LIB.BASEBOARD_FAB2(SCH_1):PAGE49
    55    GND @BASEBOARD_FAB2_LIB.BASEBOARD_FAB2(SCH_1):GND    I43 @BASEBOARD_FAB2_LIB.BASEBOARD_FAB2(SCH_1):PAGE49
    57    GND @BASEBOARD_FAB2_LIB.BASEBOARD_FAB2(SCH_1):GND    I43 @BASEBOARD_FAB2_LIB.BASEBOARD_FAB2(SCH_1):PAGE49
    94    GND @BASEBOARD_FAB2_LIB.BASEBOARD_FAB2(SCH_1):GND    I43 @BASEBOARD_FAB2_LIB.BASEBOARD_FAB2(SCH_1):PAGE49
    96    GND @BASEBOARD_FAB2_LIB.BASEBOARD_FAB2(SCH_1):GND    I43 @BASEBOARD_FAB2_LIB.BASEBOARD_FAB2(SCH_1):PAGE49
    98    GND @BASEBOARD_FAB2_LIB.BASEBOARD_FAB2(SCH_1):GND    I43 @BASEBOARD_FAB2_LIB.BASEBOARD_FAB2(SCH_1):PAGE49
   101    GND @BASEBOARD_FAB2_LIB.BASEBOARD_FAB2(SCH_1):GND    I43 @BASEBOARD_FAB2_LIB.BASEBOARD_FAB2(SCH_1):PAGE49
   103    GND @BASEBOARD_FAB2_LIB.BASEBOARD_FAB2(SCH_1):GND    I43 @BASEBOARD_FAB2_LIB.BASEBOARD_FAB2(SCH_1):PAGE49
   105    GND @BASEBOARD_FAB2_LIB.BASEBOARD_FAB2(SCH_1):GND    I43 @BASEBOARD_FAB2_LIB.BASEBOARD_FAB2(SCH_1):PAGE49
   107    GND @BASEBOARD_FAB2_LIB.BASEBOARD_FAB2(SCH_1):GND    I43 @BASEBOARD_FAB2_LIB.BASEBOARD_FAB2(SCH_1):PAGE49
   109    GND @BASEBOARD_FAB2_LIB.BASEBOARD_FAB2(SCH_1):GND    I43 @BASEBOARD_FAB2_LIB.BASEBOARD_FAB2(SCH_1):PAGE49
   112    GND @BASEBOARD_FAB2_LIB.BASEBOARD_FAB2(SCH_1):GND    I43 @BASEBOARD_FAB2_LIB.BASEBOARD_FAB2(SCH_1):PAGE49
   114    GND @BASEBOARD_FAB2_LIB.BASEBOARD_FAB2(SCH_1):GND    I43 @BASEBOARD_FAB2_LIB.BASEBOARD_FAB2(SCH_1):PAGE49
   116    GND @BASEBOARD_FAB2_LIB.BASEBOARD_FAB2(SCH_1):GND    I43 @BASEBOARD_FAB2_LIB.BASEBOARD_FAB2(SCH_1):PAGE49
   118    GND @BASEBOARD_FAB2_LIB.BASEBOARD_FAB2(SCH_1):GND    I43 @BASEBOARD_FAB2_LIB.BASEBOARD_FAB2(SCH_1):PAGE49
   120    GND @BASEBOARD_FAB2_LIB.BASEBOARD_FAB2(SCH_1):GND    I43 @BASEBOARD_FAB2_LIB.BASEBOARD_FAB2(SCH_1):PAGE49
   123    GND @BASEBOARD_FAB2_LIB.BASEBOARD_FAB2(SCH_1):GND    I43 @BASEBOARD_FAB2_LIB.BASEBOARD_FAB2(SCH_1):PAGE49
   125    GND @BASEBOARD_FAB2_LIB.BASEBOARD_FAB2(SCH_1):GND    I43 @BASEBOARD_FAB2_LIB.BASEBOARD_FAB2(SCH_1):PAGE49
   127    GND @BASEBOARD_FAB2_LIB.BASEBOARD_FAB2(SCH_1):GND    I43 @BASEBOARD_FAB2_LIB.BASEBOARD_FAB2(SCH_1):PAGE49
   129    GND @BASEBOARD_FAB2_LIB.BASEBOARD_FAB2(SCH_1):GND    I43 @BASEBOARD_FAB2_LIB.BASEBOARD_FAB2(SCH_1):PAGE49
   131    GND @BASEBOARD_FAB2_LIB.BASEBOARD_FAB2(SCH_1):GND    I43 @BASEBOARD_FAB2_LIB.BASEBOARD_FAB2(SCH_1):PAGE49
   134    GND @BASEBOARD_FAB2_LIB.BASEBOARD_FAB2(SCH_1):GND    I43 @BASEBOARD_FAB2_LIB.BASEBOARD_FAB2(SCH_1):PAGE49
   136    GND @BASEBOARD_FAB2_LIB.BASEBOARD_FAB2(SCH_1):GND    I43 @BASEBOARD_FAB2_LIB.BASEBOARD_FAB2(SCH_1):PAGE49
   138    GND @BASEBOARD_FAB2_LIB.BASEBOARD_FAB2(SCH_1):GND    I43 @BASEBOARD_FAB2_LIB.BASEBOARD_FAB2(SCH_1):PAGE49
   147    GND @BASEBOARD_FAB2_LIB.BASEBOARD_FAB2(SCH_1):GND    I43 @BASEBOARD_FAB2_LIB.BASEBOARD_FAB2(SCH_1):PAGE49
   149    GND @BASEBOARD_FAB2_LIB.BASEBOARD_FAB2(SCH_1):GND    I43 @BASEBOARD_FAB2_LIB.BASEBOARD_FAB2(SCH_1):PAGE49
   151    GND @BASEBOARD_FAB2_LIB.BASEBOARD_FAB2(SCH_1):GND    I43 @BASEBOARD_FAB2_LIB.BASEBOARD_FAB2(SCH_1):PAGE49
   154    GND @BASEBOARD_FAB2_LIB.BASEBOARD_FAB2(SCH_1):GND    I43 @BASEBOARD_FAB2_LIB.BASEBOARD_FAB2(SCH_1):PAGE49
   156    GND @BASEBOARD_FAB2_LIB.BASEBOARD_FAB2(SCH_1):GND    I43 @BASEBOARD_FAB2_LIB.BASEBOARD_FAB2(SCH_1):PAGE49
   158    GND @BASEBOARD_FAB2_LIB.BASEBOARD_FAB2(SCH_1):GND    I43 @BASEBOARD_FAB2_LIB.BASEBOARD_FAB2(SCH_1):PAGE49
   160    GND @BASEBOARD_FAB2_LIB.BASEBOARD_FAB2(SCH_1):GND    I43 @BASEBOARD_FAB2_LIB.BASEBOARD_FAB2(SCH_1):PAGE49
   162    GND @BASEBOARD_FAB2_LIB.BASEBOARD_FAB2(SCH_1):GND    I43 @BASEBOARD_FAB2_LIB.BASEBOARD_FAB2(SCH_1):PAGE49
   165    GND @BASEBOARD_FAB2_LIB.BASEBOARD_FAB2(SCH_1):GND    I43 @BASEBOARD_FAB2_LIB.BASEBOARD_FAB2(SCH_1):PAGE49
   167    GND @BASEBOARD_FAB2_LIB.BASEBOARD_FAB2(SCH_1):GND    I43 @BASEBOARD_FAB2_LIB.BASEBOARD_FAB2(SCH_1):PAGE49
   169    GND @BASEBOARD_FAB2_LIB.BASEBOARD_FAB2(SCH_1):GND    I43 @BASEBOARD_FAB2_LIB.BASEBOARD_FAB2(SCH_1):PAGE49
   171    GND @BASEBOARD_FAB2_LIB.BASEBOARD_FAB2(SCH_1):GND    I43 @BASEBOARD_FAB2_LIB.BASEBOARD_FAB2(SCH_1):PAGE49
   173    GND @BASEBOARD_FAB2_LIB.BASEBOARD_FAB2(SCH_1):GND    I43 @BASEBOARD_FAB2_LIB.BASEBOARD_FAB2(SCH_1):PAGE49
   176    GND @BASEBOARD_FAB2_LIB.BASEBOARD_FAB2(SCH_1):GND    I43 @BASEBOARD_FAB2_LIB.BASEBOARD_FAB2(SCH_1):PAGE49
   178    GND @BASEBOARD_FAB2_LIB.BASEBOARD_FAB2(SCH_1):GND    I43 @BASEBOARD_FAB2_LIB.BASEBOARD_FAB2(SCH_1):PAGE49
   180    GND @BASEBOARD_FAB2_LIB.BASEBOARD_FAB2(SCH_1):GND    I43 @BASEBOARD_FAB2_LIB.BASEBOARD_FAB2(SCH_1):PAGE49
   182    GND @BASEBOARD_FAB2_LIB.BASEBOARD_FAB2(SCH_1):GND    I43 @BASEBOARD_FAB2_LIB.BASEBOARD_FAB2(SCH_1):PAGE49
   184    GND @BASEBOARD_FAB2_LIB.BASEBOARD_FAB2(SCH_1):GND    I43 @BASEBOARD_FAB2_LIB.BASEBOARD_FAB2(SCH_1):PAGE49
   187    GND @BASEBOARD_FAB2_LIB.BASEBOARD_FAB2(SCH_1):GND    I43 @BASEBOARD_FAB2_LIB.BASEBOARD_FAB2(SCH_1):PAGE49
   189    GND @BASEBOARD_FAB2_LIB.BASEBOARD_FAB2(SCH_1):GND    I43 @BASEBOARD_FAB2_LIB.BASEBOARD_FAB2(SCH_1):PAGE49
   191    GND @BASEBOARD_FAB2_LIB.BASEBOARD_FAB2(SCH_1):GND    I43 @BASEBOARD_FAB2_LIB.BASEBOARD_FAB2(SCH_1):PAGE49
   193    GND @BASEBOARD_FAB2_LIB.BASEBOARD_FAB2(SCH_1):GND    I43 @BASEBOARD_FAB2_LIB.BASEBOARD_FAB2(SCH_1):PAGE49
   195    GND @BASEBOARD_FAB2_LIB.BASEBOARD_FAB2(SCH_1):GND    I43 @BASEBOARD_FAB2_LIB.BASEBOARD_FAB2(SCH_1):PAGE49
   198    GND @BASEBOARD_FAB2_LIB.BASEBOARD_FAB2(SCH_1):GND    I43 @BASEBOARD_FAB2_LIB.BASEBOARD_FAB2(SCH_1):PAGE49
   200    GND @BASEBOARD_FAB2_LIB.BASEBOARD_FAB2(SCH_1):GND    I43 @BASEBOARD_FAB2_LIB.BASEBOARD_FAB2(SCH_1):PAGE49
   202    GND @BASEBOARD_FAB2_LIB.BASEBOARD_FAB2(SCH_1):GND    I43 @BASEBOARD_FAB2_LIB.BASEBOARD_FAB2(SCH_1):PAGE49
   239    GND @BASEBOARD_FAB2_LIB.BASEBOARD_FAB2(SCH_1):GND    I43 @BASEBOARD_FAB2_LIB.BASEBOARD_FAB2(SCH_1):PAGE49
   241    GND @BASEBOARD_FAB2_LIB.BASEBOARD_FAB2(SCH_1):GND    I43 @BASEBOARD_FAB2_LIB.BASEBOARD_FAB2(SCH_1):PAGE49
   243    GND @BASEBOARD_FAB2_LIB.BASEBOARD_FAB2(SCH_1):GND    I43 @BASEBOARD_FAB2_LIB.BASEBOARD_FAB2(SCH_1):PAGE49
   246    GND @BASEBOARD_FAB2_LIB.BASEBOARD_FAB2(SCH_1):GND    I43 @BASEBOARD_FAB2_LIB.BASEBOARD_FAB2(SCH_1):PAGE49
   248    GND @BASEBOARD_FAB2_LIB.BASEBOARD_FAB2(SCH_1):GND    I43 @BASEBOARD_FAB2_LIB.BASEBOARD_FAB2(SCH_1):PAGE49
   250    GND @BASEBOARD_FAB2_LIB.BASEBOARD_FAB2(SCH_1):GND    I43 @BASEBOARD_FAB2_LIB.BASEBOARD_FAB2(SCH_1):PAGE49
   252    GND @BASEBOARD_FAB2_LIB.BASEBOARD_FAB2(SCH_1):GND    I43 @BASEBOARD_FAB2_LIB.BASEBOARD_FAB2(SCH_1):PAGE49
   254    GND @BASEBOARD_FAB2_LIB.BASEBOARD_FAB2(SCH_1):GND    I43 @BASEBOARD_FAB2_LIB.BASEBOARD_FAB2(SCH_1):PAGE49
   257    GND @BASEBOARD_FAB2_LIB.BASEBOARD_FAB2(SCH_1):GND    I43 @BASEBOARD_FAB2_LIB.BASEBOARD_FAB2(SCH_1):PAGE49
   259    GND @BASEBOARD_FAB2_LIB.BASEBOARD_FAB2(SCH_1):GND    I43 @BASEBOARD_FAB2_LIB.BASEBOARD_FAB2(SCH_1):PAGE49
   261    GND @BASEBOARD_FAB2_LIB.BASEBOARD_FAB2(SCH_1):GND    I43 @BASEBOARD_FAB2_LIB.BASEBOARD_FAB2(SCH_1):PAGE49
   263    GND @BASEBOARD_FAB2_LIB.BASEBOARD_FAB2(SCH_1):GND    I43 @BASEBOARD_FAB2_LIB.BASEBOARD_FAB2(SCH_1):PAGE49
   265    GND @BASEBOARD_FAB2_LIB.BASEBOARD_FAB2(SCH_1):GND    I43 @BASEBOARD_FAB2_LIB.BASEBOARD_FAB2(SCH_1):PAGE49
   268    GND @BASEBOARD_FAB2_LIB.BASEBOARD_FAB2(SCH_1):GND    I43 @BASEBOARD_FAB2_LIB.BASEBOARD_FAB2(SCH_1):PAGE49
   270    GND @BASEBOARD_FAB2_LIB.BASEBOARD_FAB2(SCH_1):GND    I43 @BASEBOARD_FAB2_LIB.BASEBOARD_FAB2(SCH_1):PAGE49
   272    GND @BASEBOARD_FAB2_LIB.BASEBOARD_FAB2(SCH_1):GND    I43 @BASEBOARD_FAB2_LIB.BASEBOARD_FAB2(SCH_1):PAGE49
   274    GND @BASEBOARD_FAB2_LIB.BASEBOARD_FAB2(SCH_1):GND    I43 @BASEBOARD_FAB2_LIB.BASEBOARD_FAB2(SCH_1):PAGE49
   276    GND @BASEBOARD_FAB2_LIB.BASEBOARD_FAB2(SCH_1):GND    I43 @BASEBOARD_FAB2_LIB.BASEBOARD_FAB2(SCH_1):PAGE49
   279    GND @BASEBOARD_FAB2_LIB.BASEBOARD_FAB2(SCH_1):GND    I43 @BASEBOARD_FAB2_LIB.BASEBOARD_FAB2(SCH_1):PAGE49
   281    GND @BASEBOARD_FAB2_LIB.BASEBOARD_FAB2(SCH_1):GND    I43 @BASEBOARD_FAB2_LIB.BASEBOARD_FAB2(SCH_1):PAGE49
   283    GND @BASEBOARD_FAB2_LIB.BASEBOARD_FAB2(SCH_1):GND    I43 @BASEBOARD_FAB2_LIB.BASEBOARD_FAB2(SCH_1):PAGE49
     1 P12V_NVDIMM_DEF @BASEBOARD_FAB2_LIB.BASEBOARD_FAB2(SCH_1):P12V_NVDIMM_DEF   I169 @BASEBOARD_FAB2_LIB.BASEBOARD_FAB2(SCH_1):PAGE49
   145 P12V_NVDIMM_DEF @BASEBOARD_FAB2_LIB.BASEBOARD_FAB2(SCH_1):P12V_NVDIMM_DEF   I169 @BASEBOARD_FAB2_LIB.BASEBOARD_FAB2(SCH_1):PAGE49
    59 PVDDQ_DEF @BASEBOARD_FAB2_LIB.BASEBOARD_FAB2(SCH_1):PVDDQ_DEF   I169 @BASEBOARD_FAB2_LIB.BASEBOARD_FAB2(SCH_1):PAGE49
    61 PVDDQ_DEF @BASEBOARD_FAB2_LIB.BASEBOARD_FAB2(SCH_1):PVDDQ_DEF   I169 @BASEBOARD_FAB2_LIB.BASEBOARD_FAB2(SCH_1):PAGE49
    64 PVDDQ_DEF @BASEBOARD_FAB2_LIB.BASEBOARD_FAB2(SCH_1):PVDDQ_DEF   I169 @BASEBOARD_FAB2_LIB.BASEBOARD_FAB2(SCH_1):PAGE49
    67 PVDDQ_DEF @BASEBOARD_FAB2_LIB.BASEBOARD_FAB2(SCH_1):PVDDQ_DEF   I169 @BASEBOARD_FAB2_LIB.BASEBOARD_FAB2(SCH_1):PAGE49
    70 PVDDQ_DEF @BASEBOARD_FAB2_LIB.BASEBOARD_FAB2(SCH_1):PVDDQ_DEF   I169 @BASEBOARD_FAB2_LIB.BASEBOARD_FAB2(SCH_1):PAGE49
    73 PVDDQ_DEF @BASEBOARD_FAB2_LIB.BASEBOARD_FAB2(SCH_1):PVDDQ_DEF   I169 @BASEBOARD_FAB2_LIB.BASEBOARD_FAB2(SCH_1):PAGE49
    76 PVDDQ_DEF @BASEBOARD_FAB2_LIB.BASEBOARD_FAB2(SCH_1):PVDDQ_DEF   I169 @BASEBOARD_FAB2_LIB.BASEBOARD_FAB2(SCH_1):PAGE49
    80 PVDDQ_DEF @BASEBOARD_FAB2_LIB.BASEBOARD_FAB2(SCH_1):PVDDQ_DEF   I169 @BASEBOARD_FAB2_LIB.BASEBOARD_FAB2(SCH_1):PAGE49
    83 PVDDQ_DEF @BASEBOARD_FAB2_LIB.BASEBOARD_FAB2(SCH_1):PVDDQ_DEF   I169 @BASEBOARD_FAB2_LIB.BASEBOARD_FAB2(SCH_1):PAGE49
    85 PVDDQ_DEF @BASEBOARD_FAB2_LIB.BASEBOARD_FAB2(SCH_1):PVDDQ_DEF   I169 @BASEBOARD_FAB2_LIB.BASEBOARD_FAB2(SCH_1):PAGE49
    88 PVDDQ_DEF @BASEBOARD_FAB2_LIB.BASEBOARD_FAB2(SCH_1):PVDDQ_DEF   I169 @BASEBOARD_FAB2_LIB.BASEBOARD_FAB2(SCH_1):PAGE49
    90 PVDDQ_DEF @BASEBOARD_FAB2_LIB.BASEBOARD_FAB2(SCH_1):PVDDQ_DEF   I169 @BASEBOARD_FAB2_LIB.BASEBOARD_FAB2(SCH_1):PAGE49
    92 PVDDQ_DEF @BASEBOARD_FAB2_LIB.BASEBOARD_FAB2(SCH_1):PVDDQ_DEF   I169 @BASEBOARD_FAB2_LIB.BASEBOARD_FAB2(SCH_1):PAGE49
   204 PVDDQ_DEF @BASEBOARD_FAB2_LIB.BASEBOARD_FAB2(SCH_1):PVDDQ_DEF   I169 @BASEBOARD_FAB2_LIB.BASEBOARD_FAB2(SCH_1):PAGE49
   206 PVDDQ_DEF @BASEBOARD_FAB2_LIB.BASEBOARD_FAB2(SCH_1):PVDDQ_DEF   I169 @BASEBOARD_FAB2_LIB.BASEBOARD_FAB2(SCH_1):PAGE49
   209 PVDDQ_DEF @BASEBOARD_FAB2_LIB.BASEBOARD_FAB2(SCH_1):PVDDQ_DEF   I169 @BASEBOARD_FAB2_LIB.BASEBOARD_FAB2(SCH_1):PAGE49
   212 PVDDQ_DEF @BASEBOARD_FAB2_LIB.BASEBOARD_FAB2(SCH_1):PVDDQ_DEF   I169 @BASEBOARD_FAB2_LIB.BASEBOARD_FAB2(SCH_1):PAGE49
   215 PVDDQ_DEF @BASEBOARD_FAB2_LIB.BASEBOARD_FAB2(SCH_1):PVDDQ_DEF   I169 @BASEBOARD_FAB2_LIB.BASEBOARD_FAB2(SCH_1):PAGE49
   217 PVDDQ_DEF @BASEBOARD_FAB2_LIB.BASEBOARD_FAB2(SCH_1):PVDDQ_DEF   I169 @BASEBOARD_FAB2_LIB.BASEBOARD_FAB2(SCH_1):PAGE49
   220 PVDDQ_DEF @BASEBOARD_FAB2_LIB.BASEBOARD_FAB2(SCH_1):PVDDQ_DEF   I169 @BASEBOARD_FAB2_LIB.BASEBOARD_FAB2(SCH_1):PAGE49
   223 PVDDQ_DEF @BASEBOARD_FAB2_LIB.BASEBOARD_FAB2(SCH_1):PVDDQ_DEF   I169 @BASEBOARD_FAB2_LIB.BASEBOARD_FAB2(SCH_1):PAGE49
   226 PVDDQ_DEF @BASEBOARD_FAB2_LIB.BASEBOARD_FAB2(SCH_1):PVDDQ_DEF   I169 @BASEBOARD_FAB2_LIB.BASEBOARD_FAB2(SCH_1):PAGE49
   229 PVDDQ_DEF @BASEBOARD_FAB2_LIB.BASEBOARD_FAB2(SCH_1):PVDDQ_DEF   I169 @BASEBOARD_FAB2_LIB.BASEBOARD_FAB2(SCH_1):PAGE49
   231 PVDDQ_DEF @BASEBOARD_FAB2_LIB.BASEBOARD_FAB2(SCH_1):PVDDQ_DEF   I169 @BASEBOARD_FAB2_LIB.BASEBOARD_FAB2(SCH_1):PAGE49
   233 PVDDQ_DEF @BASEBOARD_FAB2_LIB.BASEBOARD_FAB2(SCH_1):PVDDQ_DEF   I169 @BASEBOARD_FAB2_LIB.BASEBOARD_FAB2(SCH_1):PAGE49
   236 PVDDQ_DEF @BASEBOARD_FAB2_LIB.BASEBOARD_FAB2(SCH_1):PVDDQ_DEF   I169 @BASEBOARD_FAB2_LIB.BASEBOARD_FAB2(SCH_1):PAGE49
   142 PVPP_DEF @BASEBOARD_FAB2_LIB.BASEBOARD_FAB2(SCH_1):PVPP_DEF   I169 @BASEBOARD_FAB2_LIB.BASEBOARD_FAB2(SCH_1):PAGE49
   143 PVPP_DEF @BASEBOARD_FAB2_LIB.BASEBOARD_FAB2(SCH_1):PVPP_DEF   I169 @BASEBOARD_FAB2_LIB.BASEBOARD_FAB2(SCH_1):PAGE49
   288 PVPP_DEF @BASEBOARD_FAB2_LIB.BASEBOARD_FAB2(SCH_1):PVPP_DEF   I169 @BASEBOARD_FAB2_LIB.BASEBOARD_FAB2(SCH_1):PAGE49
   286 PVPP_DEF @BASEBOARD_FAB2_LIB.BASEBOARD_FAB2(SCH_1):PVPP_DEF   I169 @BASEBOARD_FAB2_LIB.BASEBOARD_FAB2(SCH_1):PAGE49
   287 PVPP_DEF @BASEBOARD_FAB2_LIB.BASEBOARD_FAB2(SCH_1):PVPP_DEF   I169 @BASEBOARD_FAB2_LIB.BASEBOARD_FAB2(SCH_1):PAGE49
    77 PVTT_DEF @BASEBOARD_FAB2_LIB.BASEBOARD_FAB2(SCH_1):PVTT_DEF   I169 @BASEBOARD_FAB2_LIB.BASEBOARD_FAB2(SCH_1):PAGE49
   221 PVTT_DEF @BASEBOARD_FAB2_LIB.BASEBOARD_FAB2(SCH_1):PVTT_DEF   I169 @BASEBOARD_FAB2_LIB.BASEBOARD_FAB2(SCH_1):PAGE49

J4B2 SCONN120_H61426002_SM-CONN,H61A
    A1 P12V_STBY @BASEBOARD_FAB2_LIB.BASEBOARD_FAB2(SCH_1):P12V_STBY    I46 @BASEBOARD_FAB2_LIB.BASEBOARD_FAB2(SCH_1):PAGE193
   A10    GND @BASEBOARD_FAB2_LIB.BASEBOARD_FAB2(SCH_1):GND    I46 @BASEBOARD_FAB2_LIB.BASEBOARD_FAB2(SCH_1):PAGE193
   A11 P3V3_STBY @BASEBOARD_FAB2_LIB.BASEBOARD_FAB2(SCH_1):P3V3_STBY    I46 @BASEBOARD_FAB2_LIB.BASEBOARD_FAB2(SCH_1):PAGE193
   A12    GND @BASEBOARD_FAB2_LIB.BASEBOARD_FAB2(SCH_1):GND    I46 @BASEBOARD_FAB2_LIB.BASEBOARD_FAB2(SCH_1):PAGE193
   A13 P5V_STBY @BASEBOARD_FAB2_LIB.BASEBOARD_FAB2(SCH_1):P5V_STBY    I46 @BASEBOARD_FAB2_LIB.BASEBOARD_FAB2(SCH_1):PAGE193
   A14    GND @BASEBOARD_FAB2_LIB.BASEBOARD_FAB2(SCH_1):GND    I46 @BASEBOARD_FAB2_LIB.BASEBOARD_FAB2(SCH_1):PAGE193
   A15 FM_P1V8MCP_CPU1_EN @BASEBOARD_FAB2_LIB.BASEBOARD_FAB2(SCH_1):FM_P1V8MCP_CPU1_EN    I46 @BASEBOARD_FAB2_LIB.BASEBOARD_FAB2(SCH_1):PAGE193
   A16 FM_PVCCIOMCP_CPU1_EN @BASEBOARD_FAB2_LIB.BASEBOARD_FAB2(SCH_1):FM_PVCCIOMCP_CPU1_EN    I46 @BASEBOARD_FAB2_LIB.BASEBOARD_FAB2(SCH_1):PAGE193
   A17    GND @BASEBOARD_FAB2_LIB.BASEBOARD_FAB2(SCH_1):GND    I46 @BASEBOARD_FAB2_LIB.BASEBOARD_FAB2(SCH_1):PAGE193
   A18 SMB_VR_STBY_LVC3_SCL @BASEBOARD_FAB2_LIB.BASEBOARD_FAB2(SCH_1):SMB_VR_STBY_LVC3_SCL    I46 @BASEBOARD_FAB2_LIB.BASEBOARD_FAB2(SCH_1):PAGE193
   A19 SVID_ALERT0_CPU1_R_N @BASEBOARD_FAB2_LIB.BASEBOARD_FAB2(SCH_1):SVID_ALERT0_CPU1_R_N    I46 @BASEBOARD_FAB2_LIB.BASEBOARD_FAB2(SCH_1):PAGE193
    A2 P12V_STBY @BASEBOARD_FAB2_LIB.BASEBOARD_FAB2(SCH_1):P12V_STBY    I46 @BASEBOARD_FAB2_LIB.BASEBOARD_FAB2(SCH_1):PAGE193
   A20 SVID_CLK0_CPU1_R @BASEBOARD_FAB2_LIB.BASEBOARD_FAB2(SCH_1):SVID_CLK0_CPU1_R    I46 @BASEBOARD_FAB2_LIB.BASEBOARD_FAB2(SCH_1):PAGE193
    A3 P12V_STBY @BASEBOARD_FAB2_LIB.BASEBOARD_FAB2(SCH_1):P12V_STBY    I46 @BASEBOARD_FAB2_LIB.BASEBOARD_FAB2(SCH_1):PAGE193
    A4 P12V_STBY @BASEBOARD_FAB2_LIB.BASEBOARD_FAB2(SCH_1):P12V_STBY    I46 @BASEBOARD_FAB2_LIB.BASEBOARD_FAB2(SCH_1):PAGE193
    A5 P12V_STBY @BASEBOARD_FAB2_LIB.BASEBOARD_FAB2(SCH_1):P12V_STBY    I46 @BASEBOARD_FAB2_LIB.BASEBOARD_FAB2(SCH_1):PAGE193
    A6 P12V_STBY @BASEBOARD_FAB2_LIB.BASEBOARD_FAB2(SCH_1):P12V_STBY    I46 @BASEBOARD_FAB2_LIB.BASEBOARD_FAB2(SCH_1):PAGE193
    A7 P12V_STBY @BASEBOARD_FAB2_LIB.BASEBOARD_FAB2(SCH_1):P12V_STBY    I46 @BASEBOARD_FAB2_LIB.BASEBOARD_FAB2(SCH_1):PAGE193
    A8 P12V_STBY @BASEBOARD_FAB2_LIB.BASEBOARD_FAB2(SCH_1):P12V_STBY    I46 @BASEBOARD_FAB2_LIB.BASEBOARD_FAB2(SCH_1):PAGE193
    A9    GND @BASEBOARD_FAB2_LIB.BASEBOARD_FAB2(SCH_1):GND    I46 @BASEBOARD_FAB2_LIB.BASEBOARD_FAB2(SCH_1):PAGE193
    B1 P12V_STBY @BASEBOARD_FAB2_LIB.BASEBOARD_FAB2(SCH_1):P12V_STBY    I46 @BASEBOARD_FAB2_LIB.BASEBOARD_FAB2(SCH_1):PAGE193
   B10    GND @BASEBOARD_FAB2_LIB.BASEBOARD_FAB2(SCH_1):GND    I46 @BASEBOARD_FAB2_LIB.BASEBOARD_FAB2(SCH_1):PAGE193
   B11 P3V3_STBY @BASEBOARD_FAB2_LIB.BASEBOARD_FAB2(SCH_1):P3V3_STBY    I46 @BASEBOARD_FAB2_LIB.BASEBOARD_FAB2(SCH_1):PAGE193
   B12    GND @BASEBOARD_FAB2_LIB.BASEBOARD_FAB2(SCH_1):GND    I46 @BASEBOARD_FAB2_LIB.BASEBOARD_FAB2(SCH_1):PAGE193
   B13 P5V_STBY @BASEBOARD_FAB2_LIB.BASEBOARD_FAB2(SCH_1):P5V_STBY    I46 @BASEBOARD_FAB2_LIB.BASEBOARD_FAB2(SCH_1):PAGE193
   B14    GND @BASEBOARD_FAB2_LIB.BASEBOARD_FAB2(SCH_1):GND    I46 @BASEBOARD_FAB2_LIB.BASEBOARD_FAB2(SCH_1):PAGE193
   B15 PWRGD_P1V8MCP_CPU1 @BASEBOARD_FAB2_LIB.BASEBOARD_FAB2(SCH_1):PWRGD_P1V8MCP_CPU1    I46 @BASEBOARD_FAB2_LIB.BASEBOARD_FAB2(SCH_1):PAGE193
   B16 PWRGD_PVCCIOMCP_CPU1 @BASEBOARD_FAB2_LIB.BASEBOARD_FAB2(SCH_1):PWRGD_PVCCIOMCP_CPU1    I46 @BASEBOARD_FAB2_LIB.BASEBOARD_FAB2(SCH_1):PAGE193
   B17    GND @BASEBOARD_FAB2_LIB.BASEBOARD_FAB2(SCH_1):GND    I46 @BASEBOARD_FAB2_LIB.BASEBOARD_FAB2(SCH_1):PAGE193
   B18 SMB_VR_STBY_LVC3_SDA @BASEBOARD_FAB2_LIB.BASEBOARD_FAB2(SCH_1):SMB_VR_STBY_LVC3_SDA    I46 @BASEBOARD_FAB2_LIB.BASEBOARD_FAB2(SCH_1):PAGE193
   B19 SVID_ALERT1_CPU1_R_N @BASEBOARD_FAB2_LIB.BASEBOARD_FAB2(SCH_1):SVID_ALERT1_CPU1_R_N    I46 @BASEBOARD_FAB2_LIB.BASEBOARD_FAB2(SCH_1):PAGE193
    B2 P12V_STBY @BASEBOARD_FAB2_LIB.BASEBOARD_FAB2(SCH_1):P12V_STBY    I46 @BASEBOARD_FAB2_LIB.BASEBOARD_FAB2(SCH_1):PAGE193
   B20 SVID_DIO0_CPU1_R @BASEBOARD_FAB2_LIB.BASEBOARD_FAB2(SCH_1):SVID_DIO0_CPU1_R    I46 @BASEBOARD_FAB2_LIB.BASEBOARD_FAB2(SCH_1):PAGE193
    B3 P12V_STBY @BASEBOARD_FAB2_LIB.BASEBOARD_FAB2(SCH_1):P12V_STBY    I46 @BASEBOARD_FAB2_LIB.BASEBOARD_FAB2(SCH_1):PAGE193
    B4 P12V_STBY @BASEBOARD_FAB2_LIB.BASEBOARD_FAB2(SCH_1):P12V_STBY    I46 @BASEBOARD_FAB2_LIB.BASEBOARD_FAB2(SCH_1):PAGE193
    B5 P12V_STBY @BASEBOARD_FAB2_LIB.BASEBOARD_FAB2(SCH_1):P12V_STBY    I46 @BASEBOARD_FAB2_LIB.BASEBOARD_FAB2(SCH_1):PAGE193
    B6 P12V_STBY @BASEBOARD_FAB2_LIB.BASEBOARD_FAB2(SCH_1):P12V_STBY    I46 @BASEBOARD_FAB2_LIB.BASEBOARD_FAB2(SCH_1):PAGE193
    B7 P12V_STBY @BASEBOARD_FAB2_LIB.BASEBOARD_FAB2(SCH_1):P12V_STBY    I46 @BASEBOARD_FAB2_LIB.BASEBOARD_FAB2(SCH_1):PAGE193
    B8 P12V_STBY @BASEBOARD_FAB2_LIB.BASEBOARD_FAB2(SCH_1):P12V_STBY    I46 @BASEBOARD_FAB2_LIB.BASEBOARD_FAB2(SCH_1):PAGE193
    B9    GND @BASEBOARD_FAB2_LIB.BASEBOARD_FAB2(SCH_1):GND    I46 @BASEBOARD_FAB2_LIB.BASEBOARD_FAB2(SCH_1):PAGE193
    C1    GND @BASEBOARD_FAB2_LIB.BASEBOARD_FAB2(SCH_1):GND    I46 @BASEBOARD_FAB2_LIB.BASEBOARD_FAB2(SCH_1):PAGE193
   C10    GND @BASEBOARD_FAB2_LIB.BASEBOARD_FAB2(SCH_1):GND    I46 @BASEBOARD_FAB2_LIB.BASEBOARD_FAB2(SCH_1):PAGE193
   C11 P3V3_STBY @BASEBOARD_FAB2_LIB.BASEBOARD_FAB2(SCH_1):P3V3_STBY    I46 @BASEBOARD_FAB2_LIB.BASEBOARD_FAB2(SCH_1):PAGE193
   C12    GND @BASEBOARD_FAB2_LIB.BASEBOARD_FAB2(SCH_1):GND    I46 @BASEBOARD_FAB2_LIB.BASEBOARD_FAB2(SCH_1):PAGE193
   C13 P5V_STBY @BASEBOARD_FAB2_LIB.BASEBOARD_FAB2(SCH_1):P5V_STBY    I46 @BASEBOARD_FAB2_LIB.BASEBOARD_FAB2(SCH_1):PAGE193
   C14    GND @BASEBOARD_FAB2_LIB.BASEBOARD_FAB2(SCH_1):GND    I46 @BASEBOARD_FAB2_LIB.BASEBOARD_FAB2(SCH_1):PAGE193
   C15    GND @BASEBOARD_FAB2_LIB.BASEBOARD_FAB2(SCH_1):GND    I46 @BASEBOARD_FAB2_LIB.BASEBOARD_FAB2(SCH_1):PAGE193
   C16    GND @BASEBOARD_FAB2_LIB.BASEBOARD_FAB2(SCH_1):GND    I46 @BASEBOARD_FAB2_LIB.BASEBOARD_FAB2(SCH_1):PAGE193
   C17 PVCCIOMCP_CPU1 @BASEBOARD_FAB2_LIB.BASEBOARD_FAB2(SCH_1):PVCCIOMCP_CPU1    I46 @BASEBOARD_FAB2_LIB.BASEBOARD_FAB2(SCH_1):PAGE193
   C18 PVCCIOMCP_CPU1 @BASEBOARD_FAB2_LIB.BASEBOARD_FAB2(SCH_1):PVCCIOMCP_CPU1    I46 @BASEBOARD_FAB2_LIB.BASEBOARD_FAB2(SCH_1):PAGE193
   C19 PVCCIOMCP_CPU1 @BASEBOARD_FAB2_LIB.BASEBOARD_FAB2(SCH_1):PVCCIOMCP_CPU1    I46 @BASEBOARD_FAB2_LIB.BASEBOARD_FAB2(SCH_1):PAGE193
    C2    GND @BASEBOARD_FAB2_LIB.BASEBOARD_FAB2(SCH_1):GND    I46 @BASEBOARD_FAB2_LIB.BASEBOARD_FAB2(SCH_1):PAGE193
   C20 FM_PVCCMCP_CPU1_EN @BASEBOARD_FAB2_LIB.BASEBOARD_FAB2(SCH_1):FM_PVCCMCP_CPU1_EN    I46 @BASEBOARD_FAB2_LIB.BASEBOARD_FAB2(SCH_1):PAGE193
    C3    GND @BASEBOARD_FAB2_LIB.BASEBOARD_FAB2(SCH_1):GND    I46 @BASEBOARD_FAB2_LIB.BASEBOARD_FAB2(SCH_1):PAGE193
    C4    GND @BASEBOARD_FAB2_LIB.BASEBOARD_FAB2(SCH_1):GND    I46 @BASEBOARD_FAB2_LIB.BASEBOARD_FAB2(SCH_1):PAGE193
    C5    GND @BASEBOARD_FAB2_LIB.BASEBOARD_FAB2(SCH_1):GND    I46 @BASEBOARD_FAB2_LIB.BASEBOARD_FAB2(SCH_1):PAGE193
    C6    GND @BASEBOARD_FAB2_LIB.BASEBOARD_FAB2(SCH_1):GND    I46 @BASEBOARD_FAB2_LIB.BASEBOARD_FAB2(SCH_1):PAGE193
    C7    GND @BASEBOARD_FAB2_LIB.BASEBOARD_FAB2(SCH_1):GND    I46 @BASEBOARD_FAB2_LIB.BASEBOARD_FAB2(SCH_1):PAGE193
    C8    GND @BASEBOARD_FAB2_LIB.BASEBOARD_FAB2(SCH_1):GND    I46 @BASEBOARD_FAB2_LIB.BASEBOARD_FAB2(SCH_1):PAGE193
    C9    GND @BASEBOARD_FAB2_LIB.BASEBOARD_FAB2(SCH_1):GND    I46 @BASEBOARD_FAB2_LIB.BASEBOARD_FAB2(SCH_1):PAGE193
    D1   P3V3 @BASEBOARD_FAB2_LIB.BASEBOARD_FAB2(SCH_1):P3V3    I46 @BASEBOARD_FAB2_LIB.BASEBOARD_FAB2(SCH_1):PAGE193
   D10    GND @BASEBOARD_FAB2_LIB.BASEBOARD_FAB2(SCH_1):GND    I46 @BASEBOARD_FAB2_LIB.BASEBOARD_FAB2(SCH_1):PAGE193
   D11    GND @BASEBOARD_FAB2_LIB.BASEBOARD_FAB2(SCH_1):GND    I46 @BASEBOARD_FAB2_LIB.BASEBOARD_FAB2(SCH_1):PAGE193
   D12    GND @BASEBOARD_FAB2_LIB.BASEBOARD_FAB2(SCH_1):GND    I46 @BASEBOARD_FAB2_LIB.BASEBOARD_FAB2(SCH_1):PAGE193
   D13    GND @BASEBOARD_FAB2_LIB.BASEBOARD_FAB2(SCH_1):GND    I46 @BASEBOARD_FAB2_LIB.BASEBOARD_FAB2(SCH_1):PAGE193
   D14    GND @BASEBOARD_FAB2_LIB.BASEBOARD_FAB2(SCH_1):GND    I46 @BASEBOARD_FAB2_LIB.BASEBOARD_FAB2(SCH_1):PAGE193
   D15 PVCCIOMCP_CPU1 @BASEBOARD_FAB2_LIB.BASEBOARD_FAB2(SCH_1):PVCCIOMCP_CPU1    I46 @BASEBOARD_FAB2_LIB.BASEBOARD_FAB2(SCH_1):PAGE193
   D16 PVCCIOMCP_CPU1 @BASEBOARD_FAB2_LIB.BASEBOARD_FAB2(SCH_1):PVCCIOMCP_CPU1    I46 @BASEBOARD_FAB2_LIB.BASEBOARD_FAB2(SCH_1):PAGE193
   D17 PVCCIOMCP_CPU1 @BASEBOARD_FAB2_LIB.BASEBOARD_FAB2(SCH_1):PVCCIOMCP_CPU1    I46 @BASEBOARD_FAB2_LIB.BASEBOARD_FAB2(SCH_1):PAGE193
   D18 PVCCIOMCP_CPU1 @BASEBOARD_FAB2_LIB.BASEBOARD_FAB2(SCH_1):PVCCIOMCP_CPU1    I46 @BASEBOARD_FAB2_LIB.BASEBOARD_FAB2(SCH_1):PAGE193
   D19 PVCCIOMCP_CPU1 @BASEBOARD_FAB2_LIB.BASEBOARD_FAB2(SCH_1):PVCCIOMCP_CPU1    I46 @BASEBOARD_FAB2_LIB.BASEBOARD_FAB2(SCH_1):PAGE193
    D2    GND @BASEBOARD_FAB2_LIB.BASEBOARD_FAB2(SCH_1):GND    I46 @BASEBOARD_FAB2_LIB.BASEBOARD_FAB2(SCH_1):PAGE193
   D20 PWRGD_PVCCMCP_CPU1 @BASEBOARD_FAB2_LIB.BASEBOARD_FAB2(SCH_1):PWRGD_PVCCMCP_CPU1    I46 @BASEBOARD_FAB2_LIB.BASEBOARD_FAB2(SCH_1):PAGE193
    D3    GND @BASEBOARD_FAB2_LIB.BASEBOARD_FAB2(SCH_1):GND    I46 @BASEBOARD_FAB2_LIB.BASEBOARD_FAB2(SCH_1):PAGE193
    D4    GND @BASEBOARD_FAB2_LIB.BASEBOARD_FAB2(SCH_1):GND    I46 @BASEBOARD_FAB2_LIB.BASEBOARD_FAB2(SCH_1):PAGE193
    D5    GND @BASEBOARD_FAB2_LIB.BASEBOARD_FAB2(SCH_1):GND    I46 @BASEBOARD_FAB2_LIB.BASEBOARD_FAB2(SCH_1):PAGE193
    D6    GND @BASEBOARD_FAB2_LIB.BASEBOARD_FAB2(SCH_1):GND    I46 @BASEBOARD_FAB2_LIB.BASEBOARD_FAB2(SCH_1):PAGE193
    D7    GND @BASEBOARD_FAB2_LIB.BASEBOARD_FAB2(SCH_1):GND    I46 @BASEBOARD_FAB2_LIB.BASEBOARD_FAB2(SCH_1):PAGE193
    D8    GND @BASEBOARD_FAB2_LIB.BASEBOARD_FAB2(SCH_1):GND    I46 @BASEBOARD_FAB2_LIB.BASEBOARD_FAB2(SCH_1):PAGE193
    D9    GND @BASEBOARD_FAB2_LIB.BASEBOARD_FAB2(SCH_1):GND    I46 @BASEBOARD_FAB2_LIB.BASEBOARD_FAB2(SCH_1):PAGE193
    E1 FM_CPU1_VRM_322M_156M_OSC_EN @BASEBOARD_FAB2_LIB.BASEBOARD_FAB2(SCH_1):FM_CPU1_VRM_322M_156M_OSC_EN    I46 @BASEBOARD_FAB2_LIB.BASEBOARD_FAB2(SCH_1):PAGE193
   E10 VR_PVCCIOMCP_CPU1_XADDR1 @BASEBOARD_FAB2_LIB.BASEBOARD_FAB2(SCH_1):VR_PVCCIOMCP_CPU1_XADDR1    I46 @BASEBOARD_FAB2_LIB.BASEBOARD_FAB2(SCH_1):PAGE193
   E11    GND @BASEBOARD_FAB2_LIB.BASEBOARD_FAB2(SCH_1):GND    I46 @BASEBOARD_FAB2_LIB.BASEBOARD_FAB2(SCH_1):PAGE193
   E12    GND @BASEBOARD_FAB2_LIB.BASEBOARD_FAB2(SCH_1):GND    I46 @BASEBOARD_FAB2_LIB.BASEBOARD_FAB2(SCH_1):PAGE193
   E13    GND @BASEBOARD_FAB2_LIB.BASEBOARD_FAB2(SCH_1):GND    I46 @BASEBOARD_FAB2_LIB.BASEBOARD_FAB2(SCH_1):PAGE193
   E14    GND @BASEBOARD_FAB2_LIB.BASEBOARD_FAB2(SCH_1):GND    I46 @BASEBOARD_FAB2_LIB.BASEBOARD_FAB2(SCH_1):PAGE193
   E15 PVCCIOMCP_CPU1 @BASEBOARD_FAB2_LIB.BASEBOARD_FAB2(SCH_1):PVCCIOMCP_CPU1    I46 @BASEBOARD_FAB2_LIB.BASEBOARD_FAB2(SCH_1):PAGE193
   E16 PVCCIOMCP_CPU1 @BASEBOARD_FAB2_LIB.BASEBOARD_FAB2(SCH_1):PVCCIOMCP_CPU1    I46 @BASEBOARD_FAB2_LIB.BASEBOARD_FAB2(SCH_1):PAGE193
   E17 PVCCIOMCP_CPU1 @BASEBOARD_FAB2_LIB.BASEBOARD_FAB2(SCH_1):PVCCIOMCP_CPU1    I46 @BASEBOARD_FAB2_LIB.BASEBOARD_FAB2(SCH_1):PAGE193
   E18 PVCCIOMCP_CPU1 @BASEBOARD_FAB2_LIB.BASEBOARD_FAB2(SCH_1):PVCCIOMCP_CPU1    I46 @BASEBOARD_FAB2_LIB.BASEBOARD_FAB2(SCH_1):PAGE193
   E19 PVCCIOMCP_CPU1 @BASEBOARD_FAB2_LIB.BASEBOARD_FAB2(SCH_1):PVCCIOMCP_CPU1    I46 @BASEBOARD_FAB2_LIB.BASEBOARD_FAB2(SCH_1):PAGE193
    E2    GND @BASEBOARD_FAB2_LIB.BASEBOARD_FAB2(SCH_1):GND    I46 @BASEBOARD_FAB2_LIB.BASEBOARD_FAB2(SCH_1):PAGE193
   E20 SVID_CLK1_CPU1_R @BASEBOARD_FAB2_LIB.BASEBOARD_FAB2(SCH_1):SVID_CLK1_CPU1_R    I46 @BASEBOARD_FAB2_LIB.BASEBOARD_FAB2(SCH_1):PAGE193
    E3    GND @BASEBOARD_FAB2_LIB.BASEBOARD_FAB2(SCH_1):GND    I46 @BASEBOARD_FAB2_LIB.BASEBOARD_FAB2(SCH_1):PAGE193
    E4    GND @BASEBOARD_FAB2_LIB.BASEBOARD_FAB2(SCH_1):GND    I46 @BASEBOARD_FAB2_LIB.BASEBOARD_FAB2(SCH_1):PAGE193
    E5    GND @BASEBOARD_FAB2_LIB.BASEBOARD_FAB2(SCH_1):GND    I46 @BASEBOARD_FAB2_LIB.BASEBOARD_FAB2(SCH_1):PAGE193
    E6    GND @BASEBOARD_FAB2_LIB.BASEBOARD_FAB2(SCH_1):GND    I46 @BASEBOARD_FAB2_LIB.BASEBOARD_FAB2(SCH_1):PAGE193
    E7    GND @BASEBOARD_FAB2_LIB.BASEBOARD_FAB2(SCH_1):GND    I46 @BASEBOARD_FAB2_LIB.BASEBOARD_FAB2(SCH_1):PAGE193
    E8 VSENSE_PVCCIOMCP_CPU1_SKT_VSEN @BASEBOARD_FAB2_LIB.BASEBOARD_FAB2(SCH_1):VSENSE_PVCCIOMCP_CPU1_SKT_VSEN    I46 @BASEBOARD_FAB2_LIB.BASEBOARD_FAB2(SCH_1):PAGE193
    E9    GND @BASEBOARD_FAB2_LIB.BASEBOARD_FAB2(SCH_1):GND    I46 @BASEBOARD_FAB2_LIB.BASEBOARD_FAB2(SCH_1):PAGE193
    F1 PVCCIO_CPU1 @BASEBOARD_FAB2_LIB.BASEBOARD_FAB2(SCH_1):PVCCIO_CPU1    I46 @BASEBOARD_FAB2_LIB.BASEBOARD_FAB2(SCH_1):PAGE193
   F10 VR_PVCCMCP_CPU1_XADDR2 @BASEBOARD_FAB2_LIB.BASEBOARD_FAB2(SCH_1):VR_PVCCMCP_CPU1_XADDR2    I46 @BASEBOARD_FAB2_LIB.BASEBOARD_FAB2(SCH_1):PAGE193
   F11    GND @BASEBOARD_FAB2_LIB.BASEBOARD_FAB2(SCH_1):GND    I46 @BASEBOARD_FAB2_LIB.BASEBOARD_FAB2(SCH_1):PAGE193
   F12    GND @BASEBOARD_FAB2_LIB.BASEBOARD_FAB2(SCH_1):GND    I46 @BASEBOARD_FAB2_LIB.BASEBOARD_FAB2(SCH_1):PAGE193
   F13    GND @BASEBOARD_FAB2_LIB.BASEBOARD_FAB2(SCH_1):GND    I46 @BASEBOARD_FAB2_LIB.BASEBOARD_FAB2(SCH_1):PAGE193
   F14    GND @BASEBOARD_FAB2_LIB.BASEBOARD_FAB2(SCH_1):GND    I46 @BASEBOARD_FAB2_LIB.BASEBOARD_FAB2(SCH_1):PAGE193
   F15 PVCCIOMCP_CPU1 @BASEBOARD_FAB2_LIB.BASEBOARD_FAB2(SCH_1):PVCCIOMCP_CPU1    I46 @BASEBOARD_FAB2_LIB.BASEBOARD_FAB2(SCH_1):PAGE193
   F16 PVCCIOMCP_CPU1 @BASEBOARD_FAB2_LIB.BASEBOARD_FAB2(SCH_1):PVCCIOMCP_CPU1    I46 @BASEBOARD_FAB2_LIB.BASEBOARD_FAB2(SCH_1):PAGE193
   F17 PVCCIOMCP_CPU1 @BASEBOARD_FAB2_LIB.BASEBOARD_FAB2(SCH_1):PVCCIOMCP_CPU1    I46 @BASEBOARD_FAB2_LIB.BASEBOARD_FAB2(SCH_1):PAGE193
   F18 PVCCIOMCP_CPU1 @BASEBOARD_FAB2_LIB.BASEBOARD_FAB2(SCH_1):PVCCIOMCP_CPU1    I46 @BASEBOARD_FAB2_LIB.BASEBOARD_FAB2(SCH_1):PAGE193
   F19 PVCCIOMCP_CPU1 @BASEBOARD_FAB2_LIB.BASEBOARD_FAB2(SCH_1):PVCCIOMCP_CPU1    I46 @BASEBOARD_FAB2_LIB.BASEBOARD_FAB2(SCH_1):PAGE193
    F2    GND @BASEBOARD_FAB2_LIB.BASEBOARD_FAB2(SCH_1):GND    I46 @BASEBOARD_FAB2_LIB.BASEBOARD_FAB2(SCH_1):PAGE193
   F20 SVID_DIO1_CPU1_R @BASEBOARD_FAB2_LIB.BASEBOARD_FAB2(SCH_1):SVID_DIO1_CPU1_R    I46 @BASEBOARD_FAB2_LIB.BASEBOARD_FAB2(SCH_1):PAGE193
    F3    GND @BASEBOARD_FAB2_LIB.BASEBOARD_FAB2(SCH_1):GND    I46 @BASEBOARD_FAB2_LIB.BASEBOARD_FAB2(SCH_1):PAGE193
    F4    GND @BASEBOARD_FAB2_LIB.BASEBOARD_FAB2(SCH_1):GND    I46 @BASEBOARD_FAB2_LIB.BASEBOARD_FAB2(SCH_1):PAGE193
    F5    GND @BASEBOARD_FAB2_LIB.BASEBOARD_FAB2(SCH_1):GND    I46 @BASEBOARD_FAB2_LIB.BASEBOARD_FAB2(SCH_1):PAGE193
    F6    GND @BASEBOARD_FAB2_LIB.BASEBOARD_FAB2(SCH_1):GND    I46 @BASEBOARD_FAB2_LIB.BASEBOARD_FAB2(SCH_1):PAGE193
    F7    GND @BASEBOARD_FAB2_LIB.BASEBOARD_FAB2(SCH_1):GND    I46 @BASEBOARD_FAB2_LIB.BASEBOARD_FAB2(SCH_1):PAGE193
    F8 VSENSE_PVCCIOMCP_CPU1_SKT_VRTN @BASEBOARD_FAB2_LIB.BASEBOARD_FAB2(SCH_1):VSENSE_PVCCIOMCP_CPU1_SKT_VRTN    I46 @BASEBOARD_FAB2_LIB.BASEBOARD_FAB2(SCH_1):PAGE193
    F9    GND @BASEBOARD_FAB2_LIB.BASEBOARD_FAB2(SCH_1):GND    I46 @BASEBOARD_FAB2_LIB.BASEBOARD_FAB2(SCH_1):PAGE193

J4E1 SCONN120_H61426002_SM-CONN,H61A
    A1 PVCCMCP_CPU1 @BASEBOARD_FAB2_LIB.BASEBOARD_FAB2(SCH_1):PVCCMCP_CPU1    I45 @BASEBOARD_FAB2_LIB.BASEBOARD_FAB2(SCH_1):PAGE193
   A10 PVCCMCP_CPU1 @BASEBOARD_FAB2_LIB.BASEBOARD_FAB2(SCH_1):PVCCMCP_CPU1    I45 @BASEBOARD_FAB2_LIB.BASEBOARD_FAB2(SCH_1):PAGE193
   A11 PVCCMCP_CPU1 @BASEBOARD_FAB2_LIB.BASEBOARD_FAB2(SCH_1):PVCCMCP_CPU1    I45 @BASEBOARD_FAB2_LIB.BASEBOARD_FAB2(SCH_1):PAGE193
   A12 PVCCMCP_CPU1 @BASEBOARD_FAB2_LIB.BASEBOARD_FAB2(SCH_1):PVCCMCP_CPU1    I45 @BASEBOARD_FAB2_LIB.BASEBOARD_FAB2(SCH_1):PAGE193
   A13 PVCCMCP_CPU1 @BASEBOARD_FAB2_LIB.BASEBOARD_FAB2(SCH_1):PVCCMCP_CPU1    I45 @BASEBOARD_FAB2_LIB.BASEBOARD_FAB2(SCH_1):PAGE193
   A14 PVCCMCP_CPU1 @BASEBOARD_FAB2_LIB.BASEBOARD_FAB2(SCH_1):PVCCMCP_CPU1    I45 @BASEBOARD_FAB2_LIB.BASEBOARD_FAB2(SCH_1):PAGE193
   A15 PVCCMCP_CPU1 @BASEBOARD_FAB2_LIB.BASEBOARD_FAB2(SCH_1):PVCCMCP_CPU1    I45 @BASEBOARD_FAB2_LIB.BASEBOARD_FAB2(SCH_1):PAGE193
   A16 PVCCMCP_CPU1 @BASEBOARD_FAB2_LIB.BASEBOARD_FAB2(SCH_1):PVCCMCP_CPU1    I45 @BASEBOARD_FAB2_LIB.BASEBOARD_FAB2(SCH_1):PAGE193
   A17 PVCCMCP_CPU1 @BASEBOARD_FAB2_LIB.BASEBOARD_FAB2(SCH_1):PVCCMCP_CPU1    I45 @BASEBOARD_FAB2_LIB.BASEBOARD_FAB2(SCH_1):PAGE193
   A18 PVCCMCP_CPU1 @BASEBOARD_FAB2_LIB.BASEBOARD_FAB2(SCH_1):PVCCMCP_CPU1    I45 @BASEBOARD_FAB2_LIB.BASEBOARD_FAB2(SCH_1):PAGE193
   A19    GND @BASEBOARD_FAB2_LIB.BASEBOARD_FAB2(SCH_1):GND    I45 @BASEBOARD_FAB2_LIB.BASEBOARD_FAB2(SCH_1):PAGE193
    A2 PVCCMCP_CPU1 @BASEBOARD_FAB2_LIB.BASEBOARD_FAB2(SCH_1):PVCCMCP_CPU1    I45 @BASEBOARD_FAB2_LIB.BASEBOARD_FAB2(SCH_1):PAGE193
   A20    GND @BASEBOARD_FAB2_LIB.BASEBOARD_FAB2(SCH_1):GND    I45 @BASEBOARD_FAB2_LIB.BASEBOARD_FAB2(SCH_1):PAGE193
    A3 PVCCMCP_CPU1 @BASEBOARD_FAB2_LIB.BASEBOARD_FAB2(SCH_1):PVCCMCP_CPU1    I45 @BASEBOARD_FAB2_LIB.BASEBOARD_FAB2(SCH_1):PAGE193
    A4 VSENSE_PVCCMCP_CPU1_SKT_VSEN @BASEBOARD_FAB2_LIB.BASEBOARD_FAB2(SCH_1):VSENSE_PVCCMCP_CPU1_SKT_VSEN    I45 @BASEBOARD_FAB2_LIB.BASEBOARD_FAB2(SCH_1):PAGE193
    A5 PVCCMCP_CPU1 @BASEBOARD_FAB2_LIB.BASEBOARD_FAB2(SCH_1):PVCCMCP_CPU1    I45 @BASEBOARD_FAB2_LIB.BASEBOARD_FAB2(SCH_1):PAGE193
    A6 PVCCMCP_CPU1 @BASEBOARD_FAB2_LIB.BASEBOARD_FAB2(SCH_1):PVCCMCP_CPU1    I45 @BASEBOARD_FAB2_LIB.BASEBOARD_FAB2(SCH_1):PAGE193
    A7 PVCCMCP_CPU1 @BASEBOARD_FAB2_LIB.BASEBOARD_FAB2(SCH_1):PVCCMCP_CPU1    I45 @BASEBOARD_FAB2_LIB.BASEBOARD_FAB2(SCH_1):PAGE193
    A8 PVCCMCP_CPU1 @BASEBOARD_FAB2_LIB.BASEBOARD_FAB2(SCH_1):PVCCMCP_CPU1    I45 @BASEBOARD_FAB2_LIB.BASEBOARD_FAB2(SCH_1):PAGE193
    A9 PVCCMCP_CPU1 @BASEBOARD_FAB2_LIB.BASEBOARD_FAB2(SCH_1):PVCCMCP_CPU1    I45 @BASEBOARD_FAB2_LIB.BASEBOARD_FAB2(SCH_1):PAGE193
    B1 PVCCMCP_CPU1 @BASEBOARD_FAB2_LIB.BASEBOARD_FAB2(SCH_1):PVCCMCP_CPU1    I45 @BASEBOARD_FAB2_LIB.BASEBOARD_FAB2(SCH_1):PAGE193
   B10 PVCCMCP_CPU1 @BASEBOARD_FAB2_LIB.BASEBOARD_FAB2(SCH_1):PVCCMCP_CPU1    I45 @BASEBOARD_FAB2_LIB.BASEBOARD_FAB2(SCH_1):PAGE193
   B11 PVCCMCP_CPU1 @BASEBOARD_FAB2_LIB.BASEBOARD_FAB2(SCH_1):PVCCMCP_CPU1    I45 @BASEBOARD_FAB2_LIB.BASEBOARD_FAB2(SCH_1):PAGE193
   B12 PVCCMCP_CPU1 @BASEBOARD_FAB2_LIB.BASEBOARD_FAB2(SCH_1):PVCCMCP_CPU1    I45 @BASEBOARD_FAB2_LIB.BASEBOARD_FAB2(SCH_1):PAGE193
   B13 PVCCMCP_CPU1 @BASEBOARD_FAB2_LIB.BASEBOARD_FAB2(SCH_1):PVCCMCP_CPU1    I45 @BASEBOARD_FAB2_LIB.BASEBOARD_FAB2(SCH_1):PAGE193
   B14 PVCCMCP_CPU1 @BASEBOARD_FAB2_LIB.BASEBOARD_FAB2(SCH_1):PVCCMCP_CPU1    I45 @BASEBOARD_FAB2_LIB.BASEBOARD_FAB2(SCH_1):PAGE193
   B15 PVCCMCP_CPU1 @BASEBOARD_FAB2_LIB.BASEBOARD_FAB2(SCH_1):PVCCMCP_CPU1    I45 @BASEBOARD_FAB2_LIB.BASEBOARD_FAB2(SCH_1):PAGE193
   B16 PVCCMCP_CPU1 @BASEBOARD_FAB2_LIB.BASEBOARD_FAB2(SCH_1):PVCCMCP_CPU1    I45 @BASEBOARD_FAB2_LIB.BASEBOARD_FAB2(SCH_1):PAGE193
   B17 PVCCMCP_CPU1 @BASEBOARD_FAB2_LIB.BASEBOARD_FAB2(SCH_1):PVCCMCP_CPU1    I45 @BASEBOARD_FAB2_LIB.BASEBOARD_FAB2(SCH_1):PAGE193
   B18 PVCCMCP_CPU1 @BASEBOARD_FAB2_LIB.BASEBOARD_FAB2(SCH_1):PVCCMCP_CPU1    I45 @BASEBOARD_FAB2_LIB.BASEBOARD_FAB2(SCH_1):PAGE193
   B19    GND @BASEBOARD_FAB2_LIB.BASEBOARD_FAB2(SCH_1):GND    I45 @BASEBOARD_FAB2_LIB.BASEBOARD_FAB2(SCH_1):PAGE193
    B2 PVCCMCP_CPU1 @BASEBOARD_FAB2_LIB.BASEBOARD_FAB2(SCH_1):PVCCMCP_CPU1    I45 @BASEBOARD_FAB2_LIB.BASEBOARD_FAB2(SCH_1):PAGE193
   B20    GND @BASEBOARD_FAB2_LIB.BASEBOARD_FAB2(SCH_1):GND    I45 @BASEBOARD_FAB2_LIB.BASEBOARD_FAB2(SCH_1):PAGE193
    B3 PVCCMCP_CPU1 @BASEBOARD_FAB2_LIB.BASEBOARD_FAB2(SCH_1):PVCCMCP_CPU1    I45 @BASEBOARD_FAB2_LIB.BASEBOARD_FAB2(SCH_1):PAGE193
    B4 VSENSE_PVCCMCP_CPU1_SKT_VRTN @BASEBOARD_FAB2_LIB.BASEBOARD_FAB2(SCH_1):VSENSE_PVCCMCP_CPU1_SKT_VRTN    I45 @BASEBOARD_FAB2_LIB.BASEBOARD_FAB2(SCH_1):PAGE193
    B5 PVCCMCP_CPU1 @BASEBOARD_FAB2_LIB.BASEBOARD_FAB2(SCH_1):PVCCMCP_CPU1    I45 @BASEBOARD_FAB2_LIB.BASEBOARD_FAB2(SCH_1):PAGE193
    B6 PVCCMCP_CPU1 @BASEBOARD_FAB2_LIB.BASEBOARD_FAB2(SCH_1):PVCCMCP_CPU1    I45 @BASEBOARD_FAB2_LIB.BASEBOARD_FAB2(SCH_1):PAGE193
    B7 PVCCMCP_CPU1 @BASEBOARD_FAB2_LIB.BASEBOARD_FAB2(SCH_1):PVCCMCP_CPU1    I45 @BASEBOARD_FAB2_LIB.BASEBOARD_FAB2(SCH_1):PAGE193
    B8 PVCCMCP_CPU1 @BASEBOARD_FAB2_LIB.BASEBOARD_FAB2(SCH_1):PVCCMCP_CPU1    I45 @BASEBOARD_FAB2_LIB.BASEBOARD_FAB2(SCH_1):PAGE193
    B9 PVCCMCP_CPU1 @BASEBOARD_FAB2_LIB.BASEBOARD_FAB2(SCH_1):PVCCMCP_CPU1    I45 @BASEBOARD_FAB2_LIB.BASEBOARD_FAB2(SCH_1):PAGE193
    C1 PVCCMCP_CPU1 @BASEBOARD_FAB2_LIB.BASEBOARD_FAB2(SCH_1):PVCCMCP_CPU1    I45 @BASEBOARD_FAB2_LIB.BASEBOARD_FAB2(SCH_1):PAGE193
   C10 PVCCMCP_CPU1 @BASEBOARD_FAB2_LIB.BASEBOARD_FAB2(SCH_1):PVCCMCP_CPU1    I45 @BASEBOARD_FAB2_LIB.BASEBOARD_FAB2(SCH_1):PAGE193
   C11 PVCCMCP_CPU1 @BASEBOARD_FAB2_LIB.BASEBOARD_FAB2(SCH_1):PVCCMCP_CPU1    I45 @BASEBOARD_FAB2_LIB.BASEBOARD_FAB2(SCH_1):PAGE193
   C12 PVCCMCP_CPU1 @BASEBOARD_FAB2_LIB.BASEBOARD_FAB2(SCH_1):PVCCMCP_CPU1    I45 @BASEBOARD_FAB2_LIB.BASEBOARD_FAB2(SCH_1):PAGE193
   C13 PVCCMCP_CPU1 @BASEBOARD_FAB2_LIB.BASEBOARD_FAB2(SCH_1):PVCCMCP_CPU1    I45 @BASEBOARD_FAB2_LIB.BASEBOARD_FAB2(SCH_1):PAGE193
   C14 PVCCMCP_CPU1 @BASEBOARD_FAB2_LIB.BASEBOARD_FAB2(SCH_1):PVCCMCP_CPU1    I45 @BASEBOARD_FAB2_LIB.BASEBOARD_FAB2(SCH_1):PAGE193
   C15 PVCCMCP_CPU1 @BASEBOARD_FAB2_LIB.BASEBOARD_FAB2(SCH_1):PVCCMCP_CPU1    I45 @BASEBOARD_FAB2_LIB.BASEBOARD_FAB2(SCH_1):PAGE193
   C16 PVCCMCP_CPU1 @BASEBOARD_FAB2_LIB.BASEBOARD_FAB2(SCH_1):PVCCMCP_CPU1    I45 @BASEBOARD_FAB2_LIB.BASEBOARD_FAB2(SCH_1):PAGE193
   C17 PVCCMCP_CPU1 @BASEBOARD_FAB2_LIB.BASEBOARD_FAB2(SCH_1):PVCCMCP_CPU1    I45 @BASEBOARD_FAB2_LIB.BASEBOARD_FAB2(SCH_1):PAGE193
   C18 PVCCMCP_CPU1 @BASEBOARD_FAB2_LIB.BASEBOARD_FAB2(SCH_1):PVCCMCP_CPU1    I45 @BASEBOARD_FAB2_LIB.BASEBOARD_FAB2(SCH_1):PAGE193
   C19    GND @BASEBOARD_FAB2_LIB.BASEBOARD_FAB2(SCH_1):GND    I45 @BASEBOARD_FAB2_LIB.BASEBOARD_FAB2(SCH_1):PAGE193
    C2 PVCCMCP_CPU1 @BASEBOARD_FAB2_LIB.BASEBOARD_FAB2(SCH_1):PVCCMCP_CPU1    I45 @BASEBOARD_FAB2_LIB.BASEBOARD_FAB2(SCH_1):PAGE193
   C20    GND @BASEBOARD_FAB2_LIB.BASEBOARD_FAB2(SCH_1):GND    I45 @BASEBOARD_FAB2_LIB.BASEBOARD_FAB2(SCH_1):PAGE193
    C3 PVCCMCP_CPU1 @BASEBOARD_FAB2_LIB.BASEBOARD_FAB2(SCH_1):PVCCMCP_CPU1    I45 @BASEBOARD_FAB2_LIB.BASEBOARD_FAB2(SCH_1):PAGE193
    C4 PVCCMCP_CPU1 @BASEBOARD_FAB2_LIB.BASEBOARD_FAB2(SCH_1):PVCCMCP_CPU1    I45 @BASEBOARD_FAB2_LIB.BASEBOARD_FAB2(SCH_1):PAGE193
    C5 PVCCMCP_CPU1 @BASEBOARD_FAB2_LIB.BASEBOARD_FAB2(SCH_1):PVCCMCP_CPU1    I45 @BASEBOARD_FAB2_LIB.BASEBOARD_FAB2(SCH_1):PAGE193
    C6 PVCCMCP_CPU1 @BASEBOARD_FAB2_LIB.BASEBOARD_FAB2(SCH_1):PVCCMCP_CPU1    I45 @BASEBOARD_FAB2_LIB.BASEBOARD_FAB2(SCH_1):PAGE193
    C7 PVCCMCP_CPU1 @BASEBOARD_FAB2_LIB.BASEBOARD_FAB2(SCH_1):PVCCMCP_CPU1    I45 @BASEBOARD_FAB2_LIB.BASEBOARD_FAB2(SCH_1):PAGE193
    C8 PVCCMCP_CPU1 @BASEBOARD_FAB2_LIB.BASEBOARD_FAB2(SCH_1):PVCCMCP_CPU1    I45 @BASEBOARD_FAB2_LIB.BASEBOARD_FAB2(SCH_1):PAGE193
    C9 PVCCMCP_CPU1 @BASEBOARD_FAB2_LIB.BASEBOARD_FAB2(SCH_1):PVCCMCP_CPU1    I45 @BASEBOARD_FAB2_LIB.BASEBOARD_FAB2(SCH_1):PAGE193
    D1 VSENSE_P1V8MCP_CPU1_SKT_VSEN @BASEBOARD_FAB2_LIB.BASEBOARD_FAB2(SCH_1):VSENSE_P1V8MCP_CPU1_SKT_VSEN    I45 @BASEBOARD_FAB2_LIB.BASEBOARD_FAB2(SCH_1):PAGE193
   D10    GND @BASEBOARD_FAB2_LIB.BASEBOARD_FAB2(SCH_1):GND    I45 @BASEBOARD_FAB2_LIB.BASEBOARD_FAB2(SCH_1):PAGE193
   D11    GND @BASEBOARD_FAB2_LIB.BASEBOARD_FAB2(SCH_1):GND    I45 @BASEBOARD_FAB2_LIB.BASEBOARD_FAB2(SCH_1):PAGE193
   D12    GND @BASEBOARD_FAB2_LIB.BASEBOARD_FAB2(SCH_1):GND    I45 @BASEBOARD_FAB2_LIB.BASEBOARD_FAB2(SCH_1):PAGE193
   D13    GND @BASEBOARD_FAB2_LIB.BASEBOARD_FAB2(SCH_1):GND    I45 @BASEBOARD_FAB2_LIB.BASEBOARD_FAB2(SCH_1):PAGE193
   D14    GND @BASEBOARD_FAB2_LIB.BASEBOARD_FAB2(SCH_1):GND    I45 @BASEBOARD_FAB2_LIB.BASEBOARD_FAB2(SCH_1):PAGE193
   D15    GND @BASEBOARD_FAB2_LIB.BASEBOARD_FAB2(SCH_1):GND    I45 @BASEBOARD_FAB2_LIB.BASEBOARD_FAB2(SCH_1):PAGE193
   D16    GND @BASEBOARD_FAB2_LIB.BASEBOARD_FAB2(SCH_1):GND    I45 @BASEBOARD_FAB2_LIB.BASEBOARD_FAB2(SCH_1):PAGE193
   D17    GND @BASEBOARD_FAB2_LIB.BASEBOARD_FAB2(SCH_1):GND    I45 @BASEBOARD_FAB2_LIB.BASEBOARD_FAB2(SCH_1):PAGE193
   D18    GND @BASEBOARD_FAB2_LIB.BASEBOARD_FAB2(SCH_1):GND    I45 @BASEBOARD_FAB2_LIB.BASEBOARD_FAB2(SCH_1):PAGE193
   D19    GND @BASEBOARD_FAB2_LIB.BASEBOARD_FAB2(SCH_1):GND    I45 @BASEBOARD_FAB2_LIB.BASEBOARD_FAB2(SCH_1):PAGE193
    D2 VSENSE_P1V8MCP_CPU1_SKT_VRTN @BASEBOARD_FAB2_LIB.BASEBOARD_FAB2(SCH_1):VSENSE_P1V8MCP_CPU1_SKT_VRTN    I45 @BASEBOARD_FAB2_LIB.BASEBOARD_FAB2(SCH_1):PAGE193
   D20    GND @BASEBOARD_FAB2_LIB.BASEBOARD_FAB2(SCH_1):GND    I45 @BASEBOARD_FAB2_LIB.BASEBOARD_FAB2(SCH_1):PAGE193
    D3    GND @BASEBOARD_FAB2_LIB.BASEBOARD_FAB2(SCH_1):GND    I45 @BASEBOARD_FAB2_LIB.BASEBOARD_FAB2(SCH_1):PAGE193
    D4    GND @BASEBOARD_FAB2_LIB.BASEBOARD_FAB2(SCH_1):GND    I45 @BASEBOARD_FAB2_LIB.BASEBOARD_FAB2(SCH_1):PAGE193
    D5    GND @BASEBOARD_FAB2_LIB.BASEBOARD_FAB2(SCH_1):GND    I45 @BASEBOARD_FAB2_LIB.BASEBOARD_FAB2(SCH_1):PAGE193
    D6    GND @BASEBOARD_FAB2_LIB.BASEBOARD_FAB2(SCH_1):GND    I45 @BASEBOARD_FAB2_LIB.BASEBOARD_FAB2(SCH_1):PAGE193
    D7    GND @BASEBOARD_FAB2_LIB.BASEBOARD_FAB2(SCH_1):GND    I45 @BASEBOARD_FAB2_LIB.BASEBOARD_FAB2(SCH_1):PAGE193
    D8    GND @BASEBOARD_FAB2_LIB.BASEBOARD_FAB2(SCH_1):GND    I45 @BASEBOARD_FAB2_LIB.BASEBOARD_FAB2(SCH_1):PAGE193
    D9    GND @BASEBOARD_FAB2_LIB.BASEBOARD_FAB2(SCH_1):GND    I45 @BASEBOARD_FAB2_LIB.BASEBOARD_FAB2(SCH_1):PAGE193
    E1 P1V8_MCP_CPU1 @BASEBOARD_FAB2_LIB.BASEBOARD_FAB2(SCH_1):P1V8_MCP_CPU1    I45 @BASEBOARD_FAB2_LIB.BASEBOARD_FAB2(SCH_1):PAGE193
   E10    GND @BASEBOARD_FAB2_LIB.BASEBOARD_FAB2(SCH_1):GND    I45 @BASEBOARD_FAB2_LIB.BASEBOARD_FAB2(SCH_1):PAGE193
   E11    GND @BASEBOARD_FAB2_LIB.BASEBOARD_FAB2(SCH_1):GND    I45 @BASEBOARD_FAB2_LIB.BASEBOARD_FAB2(SCH_1):PAGE193
   E12    GND @BASEBOARD_FAB2_LIB.BASEBOARD_FAB2(SCH_1):GND    I45 @BASEBOARD_FAB2_LIB.BASEBOARD_FAB2(SCH_1):PAGE193
   E13    GND @BASEBOARD_FAB2_LIB.BASEBOARD_FAB2(SCH_1):GND    I45 @BASEBOARD_FAB2_LIB.BASEBOARD_FAB2(SCH_1):PAGE193
   E14    GND @BASEBOARD_FAB2_LIB.BASEBOARD_FAB2(SCH_1):GND    I45 @BASEBOARD_FAB2_LIB.BASEBOARD_FAB2(SCH_1):PAGE193
   E15    GND @BASEBOARD_FAB2_LIB.BASEBOARD_FAB2(SCH_1):GND    I45 @BASEBOARD_FAB2_LIB.BASEBOARD_FAB2(SCH_1):PAGE193
   E16    GND @BASEBOARD_FAB2_LIB.BASEBOARD_FAB2(SCH_1):GND    I45 @BASEBOARD_FAB2_LIB.BASEBOARD_FAB2(SCH_1):PAGE193
   E17    GND @BASEBOARD_FAB2_LIB.BASEBOARD_FAB2(SCH_1):GND    I45 @BASEBOARD_FAB2_LIB.BASEBOARD_FAB2(SCH_1):PAGE193
   E18    GND @BASEBOARD_FAB2_LIB.BASEBOARD_FAB2(SCH_1):GND    I45 @BASEBOARD_FAB2_LIB.BASEBOARD_FAB2(SCH_1):PAGE193
   E19    GND @BASEBOARD_FAB2_LIB.BASEBOARD_FAB2(SCH_1):GND    I45 @BASEBOARD_FAB2_LIB.BASEBOARD_FAB2(SCH_1):PAGE193
    E2 P1V8_MCP_CPU1 @BASEBOARD_FAB2_LIB.BASEBOARD_FAB2(SCH_1):P1V8_MCP_CPU1    I45 @BASEBOARD_FAB2_LIB.BASEBOARD_FAB2(SCH_1):PAGE193
   E20    GND @BASEBOARD_FAB2_LIB.BASEBOARD_FAB2(SCH_1):GND    I45 @BASEBOARD_FAB2_LIB.BASEBOARD_FAB2(SCH_1):PAGE193
    E3    GND @BASEBOARD_FAB2_LIB.BASEBOARD_FAB2(SCH_1):GND    I45 @BASEBOARD_FAB2_LIB.BASEBOARD_FAB2(SCH_1):PAGE193
    E4    GND @BASEBOARD_FAB2_LIB.BASEBOARD_FAB2(SCH_1):GND    I45 @BASEBOARD_FAB2_LIB.BASEBOARD_FAB2(SCH_1):PAGE193
    E5 CLK_322M_156M_CPU1_OSC_VRM_DP @BASEBOARD_FAB2_LIB.BASEBOARD_FAB2(SCH_1):CLK_322M_156M_CPU1_OSC_VRM_DP    I45 @BASEBOARD_FAB2_LIB.BASEBOARD_FAB2(SCH_1):PAGE193
    E6    GND @BASEBOARD_FAB2_LIB.BASEBOARD_FAB2(SCH_1):GND    I45 @BASEBOARD_FAB2_LIB.BASEBOARD_FAB2(SCH_1):PAGE193
    E7    GND @BASEBOARD_FAB2_LIB.BASEBOARD_FAB2(SCH_1):GND    I45 @BASEBOARD_FAB2_LIB.BASEBOARD_FAB2(SCH_1):PAGE193
    E8    GND @BASEBOARD_FAB2_LIB.BASEBOARD_FAB2(SCH_1):GND    I45 @BASEBOARD_FAB2_LIB.BASEBOARD_FAB2(SCH_1):PAGE193
    E9    GND @BASEBOARD_FAB2_LIB.BASEBOARD_FAB2(SCH_1):GND    I45 @BASEBOARD_FAB2_LIB.BASEBOARD_FAB2(SCH_1):PAGE193
    F1 P1V8_MCP_CPU1 @BASEBOARD_FAB2_LIB.BASEBOARD_FAB2(SCH_1):P1V8_MCP_CPU1    I45 @BASEBOARD_FAB2_LIB.BASEBOARD_FAB2(SCH_1):PAGE193
   F10    GND @BASEBOARD_FAB2_LIB.BASEBOARD_FAB2(SCH_1):GND    I45 @BASEBOARD_FAB2_LIB.BASEBOARD_FAB2(SCH_1):PAGE193
   F11    GND @BASEBOARD_FAB2_LIB.BASEBOARD_FAB2(SCH_1):GND    I45 @BASEBOARD_FAB2_LIB.BASEBOARD_FAB2(SCH_1):PAGE193
   F12    GND @BASEBOARD_FAB2_LIB.BASEBOARD_FAB2(SCH_1):GND    I45 @BASEBOARD_FAB2_LIB.BASEBOARD_FAB2(SCH_1):PAGE193
   F13    GND @BASEBOARD_FAB2_LIB.BASEBOARD_FAB2(SCH_1):GND    I45 @BASEBOARD_FAB2_LIB.BASEBOARD_FAB2(SCH_1):PAGE193
   F14    GND @BASEBOARD_FAB2_LIB.BASEBOARD_FAB2(SCH_1):GND    I45 @BASEBOARD_FAB2_LIB.BASEBOARD_FAB2(SCH_1):PAGE193
   F15    GND @BASEBOARD_FAB2_LIB.BASEBOARD_FAB2(SCH_1):GND    I45 @BASEBOARD_FAB2_LIB.BASEBOARD_FAB2(SCH_1):PAGE193
   F16    GND @BASEBOARD_FAB2_LIB.BASEBOARD_FAB2(SCH_1):GND    I45 @BASEBOARD_FAB2_LIB.BASEBOARD_FAB2(SCH_1):PAGE193
   F17    GND @BASEBOARD_FAB2_LIB.BASEBOARD_FAB2(SCH_1):GND    I45 @BASEBOARD_FAB2_LIB.BASEBOARD_FAB2(SCH_1):PAGE193
   F18    GND @BASEBOARD_FAB2_LIB.BASEBOARD_FAB2(SCH_1):GND    I45 @BASEBOARD_FAB2_LIB.BASEBOARD_FAB2(SCH_1):PAGE193
   F19    GND @BASEBOARD_FAB2_LIB.BASEBOARD_FAB2(SCH_1):GND    I45 @BASEBOARD_FAB2_LIB.BASEBOARD_FAB2(SCH_1):PAGE193
    F2 P1V8_MCP_CPU1 @BASEBOARD_FAB2_LIB.BASEBOARD_FAB2(SCH_1):P1V8_MCP_CPU1    I45 @BASEBOARD_FAB2_LIB.BASEBOARD_FAB2(SCH_1):PAGE193
   F20    GND @BASEBOARD_FAB2_LIB.BASEBOARD_FAB2(SCH_1):GND    I45 @BASEBOARD_FAB2_LIB.BASEBOARD_FAB2(SCH_1):PAGE193
    F3    GND @BASEBOARD_FAB2_LIB.BASEBOARD_FAB2(SCH_1):GND    I45 @BASEBOARD_FAB2_LIB.BASEBOARD_FAB2(SCH_1):PAGE193
    F4    GND @BASEBOARD_FAB2_LIB.BASEBOARD_FAB2(SCH_1):GND    I45 @BASEBOARD_FAB2_LIB.BASEBOARD_FAB2(SCH_1):PAGE193
    F5 CLK_322M_156M_CPU1_OSC_VRM_DN @BASEBOARD_FAB2_LIB.BASEBOARD_FAB2(SCH_1):CLK_322M_156M_CPU1_OSC_VRM_DN    I45 @BASEBOARD_FAB2_LIB.BASEBOARD_FAB2(SCH_1):PAGE193
    F6    GND @BASEBOARD_FAB2_LIB.BASEBOARD_FAB2(SCH_1):GND    I45 @BASEBOARD_FAB2_LIB.BASEBOARD_FAB2(SCH_1):PAGE193
    F7    GND @BASEBOARD_FAB2_LIB.BASEBOARD_FAB2(SCH_1):GND    I45 @BASEBOARD_FAB2_LIB.BASEBOARD_FAB2(SCH_1):PAGE193
    F8    GND @BASEBOARD_FAB2_LIB.BASEBOARD_FAB2(SCH_1):GND    I45 @BASEBOARD_FAB2_LIB.BASEBOARD_FAB2(SCH_1):PAGE193
    F9    GND @BASEBOARD_FAB2_LIB.BASEBOARD_FAB2(SCH_1):GND    I45 @BASEBOARD_FAB2_LIB.BASEBOARD_FAB2(SCH_1):PAGE193

J4G1 SCONN288_H44441004_PIP-SCONN,HA
    79 M_A_MA<0> @BASEBOARD_FAB2_LIB.BASEBOARD_FAB2(SCH_1):M_A_MA(0)     I1 @BASEBOARD_FAB2_LIB.BASEBOARD_FAB2(SCH_1):PAGE43
    72 M_A_MA<1> @BASEBOARD_FAB2_LIB.BASEBOARD_FAB2(SCH_1):M_A_MA(1)     I1 @BASEBOARD_FAB2_LIB.BASEBOARD_FAB2(SCH_1):PAGE43
   225 M_A_MA<10> @BASEBOARD_FAB2_LIB.BASEBOARD_FAB2(SCH_1):M_A_MA(10)     I1 @BASEBOARD_FAB2_LIB.BASEBOARD_FAB2(SCH_1):PAGE43
   210 M_A_MA<11> @BASEBOARD_FAB2_LIB.BASEBOARD_FAB2(SCH_1):M_A_MA(11)     I1 @BASEBOARD_FAB2_LIB.BASEBOARD_FAB2(SCH_1):PAGE43
    65 M_A_MA<12> @BASEBOARD_FAB2_LIB.BASEBOARD_FAB2(SCH_1):M_A_MA(12)     I1 @BASEBOARD_FAB2_LIB.BASEBOARD_FAB2(SCH_1):PAGE43
   232 M_A_MA<13> @BASEBOARD_FAB2_LIB.BASEBOARD_FAB2(SCH_1):M_A_MA(13)     I1 @BASEBOARD_FAB2_LIB.BASEBOARD_FAB2(SCH_1):PAGE43
   228 M_A_MA<14> @BASEBOARD_FAB2_LIB.BASEBOARD_FAB2(SCH_1):M_A_MA(14)     I1 @BASEBOARD_FAB2_LIB.BASEBOARD_FAB2(SCH_1):PAGE43
    86 M_A_MA<15> @BASEBOARD_FAB2_LIB.BASEBOARD_FAB2(SCH_1):M_A_MA(15)     I1 @BASEBOARD_FAB2_LIB.BASEBOARD_FAB2(SCH_1):PAGE43
    82 M_A_MA<16> @BASEBOARD_FAB2_LIB.BASEBOARD_FAB2(SCH_1):M_A_MA(16)     I1 @BASEBOARD_FAB2_LIB.BASEBOARD_FAB2(SCH_1):PAGE43
   234 M_A_MA<17> @BASEBOARD_FAB2_LIB.BASEBOARD_FAB2(SCH_1):M_A_MA(17)     I1 @BASEBOARD_FAB2_LIB.BASEBOARD_FAB2(SCH_1):PAGE43
   216 M_A_MA<2> @BASEBOARD_FAB2_LIB.BASEBOARD_FAB2(SCH_1):M_A_MA(2)     I1 @BASEBOARD_FAB2_LIB.BASEBOARD_FAB2(SCH_1):PAGE43
    71 M_A_MA<3> @BASEBOARD_FAB2_LIB.BASEBOARD_FAB2(SCH_1):M_A_MA(3)     I1 @BASEBOARD_FAB2_LIB.BASEBOARD_FAB2(SCH_1):PAGE43
   214 M_A_MA<4> @BASEBOARD_FAB2_LIB.BASEBOARD_FAB2(SCH_1):M_A_MA(4)     I1 @BASEBOARD_FAB2_LIB.BASEBOARD_FAB2(SCH_1):PAGE43
   213 M_A_MA<5> @BASEBOARD_FAB2_LIB.BASEBOARD_FAB2(SCH_1):M_A_MA(5)     I1 @BASEBOARD_FAB2_LIB.BASEBOARD_FAB2(SCH_1):PAGE43
    69 M_A_MA<6> @BASEBOARD_FAB2_LIB.BASEBOARD_FAB2(SCH_1):M_A_MA(6)     I1 @BASEBOARD_FAB2_LIB.BASEBOARD_FAB2(SCH_1):PAGE43
   211 M_A_MA<7> @BASEBOARD_FAB2_LIB.BASEBOARD_FAB2(SCH_1):M_A_MA(7)     I1 @BASEBOARD_FAB2_LIB.BASEBOARD_FAB2(SCH_1):PAGE43
    68 M_A_MA<8> @BASEBOARD_FAB2_LIB.BASEBOARD_FAB2(SCH_1):M_A_MA(8)     I1 @BASEBOARD_FAB2_LIB.BASEBOARD_FAB2(SCH_1):PAGE43
    66 M_A_MA<9> @BASEBOARD_FAB2_LIB.BASEBOARD_FAB2(SCH_1):M_A_MA(9)     I1 @BASEBOARD_FAB2_LIB.BASEBOARD_FAB2(SCH_1):PAGE43
    62 M_A_ACT_N @BASEBOARD_FAB2_LIB.BASEBOARD_FAB2(SCH_1):M_A_ACT_N     I1 @BASEBOARD_FAB2_LIB.BASEBOARD_FAB2(SCH_1):PAGE43
   208 M_A_ALERT_N @BASEBOARD_FAB2_LIB.BASEBOARD_FAB2(SCH_1):M_A_ALERT_N     I1 @BASEBOARD_FAB2_LIB.BASEBOARD_FAB2(SCH_1):PAGE43
   224 M_A_BA<1> @BASEBOARD_FAB2_LIB.BASEBOARD_FAB2(SCH_1):M_A_BA(1)     I1 @BASEBOARD_FAB2_LIB.BASEBOARD_FAB2(SCH_1):PAGE43
    81 M_A_BA<0> @BASEBOARD_FAB2_LIB.BASEBOARD_FAB2(SCH_1):M_A_BA(0)     I1 @BASEBOARD_FAB2_LIB.BASEBOARD_FAB2(SCH_1):PAGE43
   207 M_A_BG<1> @BASEBOARD_FAB2_LIB.BASEBOARD_FAB2(SCH_1):M_A_BG(1)     I1 @BASEBOARD_FAB2_LIB.BASEBOARD_FAB2(SCH_1):PAGE43
    63 M_A_BG<0> @BASEBOARD_FAB2_LIB.BASEBOARD_FAB2(SCH_1):M_A_BG(0)     I1 @BASEBOARD_FAB2_LIB.BASEBOARD_FAB2(SCH_1):PAGE43
   235 M_A_C<2> @BASEBOARD_FAB2_LIB.BASEBOARD_FAB2(SCH_1):M_A_C(2)     I1 @BASEBOARD_FAB2_LIB.BASEBOARD_FAB2(SCH_1):PAGE43
   199 M_A_ECC<6> @BASEBOARD_FAB2_LIB.BASEBOARD_FAB2(SCH_1):M_A_ECC(6)     I1 @BASEBOARD_FAB2_LIB.BASEBOARD_FAB2(SCH_1):PAGE43
    54 M_A_ECC<7> @BASEBOARD_FAB2_LIB.BASEBOARD_FAB2(SCH_1):M_A_ECC(7)     I1 @BASEBOARD_FAB2_LIB.BASEBOARD_FAB2(SCH_1):PAGE43
   192 M_A_ECC<4> @BASEBOARD_FAB2_LIB.BASEBOARD_FAB2(SCH_1):M_A_ECC(4)     I1 @BASEBOARD_FAB2_LIB.BASEBOARD_FAB2(SCH_1):PAGE43
    47 M_A_ECC<5> @BASEBOARD_FAB2_LIB.BASEBOARD_FAB2(SCH_1):M_A_ECC(5)     I1 @BASEBOARD_FAB2_LIB.BASEBOARD_FAB2(SCH_1):PAGE43
   201 M_A_ECC<2> @BASEBOARD_FAB2_LIB.BASEBOARD_FAB2(SCH_1):M_A_ECC(2)     I1 @BASEBOARD_FAB2_LIB.BASEBOARD_FAB2(SCH_1):PAGE43
    56 M_A_ECC<3> @BASEBOARD_FAB2_LIB.BASEBOARD_FAB2(SCH_1):M_A_ECC(3)     I1 @BASEBOARD_FAB2_LIB.BASEBOARD_FAB2(SCH_1):PAGE43
   194 M_A_ECC<0> @BASEBOARD_FAB2_LIB.BASEBOARD_FAB2(SCH_1):M_A_ECC(0)     I1 @BASEBOARD_FAB2_LIB.BASEBOARD_FAB2(SCH_1):PAGE43
    49 M_A_ECC<1> @BASEBOARD_FAB2_LIB.BASEBOARD_FAB2(SCH_1):M_A_ECC(1)     I1 @BASEBOARD_FAB2_LIB.BASEBOARD_FAB2(SCH_1):PAGE43
    75 M_A_CLK_DN<0> @BASEBOARD_FAB2_LIB.BASEBOARD_FAB2(SCH_1):M_A_CLK_DN(0)     I1 @BASEBOARD_FAB2_LIB.BASEBOARD_FAB2(SCH_1):PAGE43
    74 M_A_CLK_DP<0> @BASEBOARD_FAB2_LIB.BASEBOARD_FAB2(SCH_1):M_A_CLK_DP(0)     I1 @BASEBOARD_FAB2_LIB.BASEBOARD_FAB2(SCH_1):PAGE43
   219 M_A_CLK_DN<1> @BASEBOARD_FAB2_LIB.BASEBOARD_FAB2(SCH_1):M_A_CLK_DN(1)     I1 @BASEBOARD_FAB2_LIB.BASEBOARD_FAB2(SCH_1):PAGE43
   218 M_A_CLK_DP<1> @BASEBOARD_FAB2_LIB.BASEBOARD_FAB2(SCH_1):M_A_CLK_DP(1)     I1 @BASEBOARD_FAB2_LIB.BASEBOARD_FAB2(SCH_1):PAGE43
   203 M_A_CKE<1> @BASEBOARD_FAB2_LIB.BASEBOARD_FAB2(SCH_1):M_A_CKE(1)     I1 @BASEBOARD_FAB2_LIB.BASEBOARD_FAB2(SCH_1):PAGE43
    60 M_A_CKE<0> @BASEBOARD_FAB2_LIB.BASEBOARD_FAB2(SCH_1):M_A_CKE(0)     I1 @BASEBOARD_FAB2_LIB.BASEBOARD_FAB2(SCH_1):PAGE43
   280 M_A_DQ<62> @BASEBOARD_FAB2_LIB.BASEBOARD_FAB2(SCH_1):M_A_DQ(62)     I1 @BASEBOARD_FAB2_LIB.BASEBOARD_FAB2(SCH_1):PAGE43
   135 M_A_DQ<63> @BASEBOARD_FAB2_LIB.BASEBOARD_FAB2(SCH_1):M_A_DQ(63)     I1 @BASEBOARD_FAB2_LIB.BASEBOARD_FAB2(SCH_1):PAGE43
   273 M_A_DQ<60> @BASEBOARD_FAB2_LIB.BASEBOARD_FAB2(SCH_1):M_A_DQ(60)     I1 @BASEBOARD_FAB2_LIB.BASEBOARD_FAB2(SCH_1):PAGE43
   128 M_A_DQ<61> @BASEBOARD_FAB2_LIB.BASEBOARD_FAB2(SCH_1):M_A_DQ(61)     I1 @BASEBOARD_FAB2_LIB.BASEBOARD_FAB2(SCH_1):PAGE43
   282 M_A_DQ<58> @BASEBOARD_FAB2_LIB.BASEBOARD_FAB2(SCH_1):M_A_DQ(58)     I1 @BASEBOARD_FAB2_LIB.BASEBOARD_FAB2(SCH_1):PAGE43
   137 M_A_DQ<59> @BASEBOARD_FAB2_LIB.BASEBOARD_FAB2(SCH_1):M_A_DQ(59)     I1 @BASEBOARD_FAB2_LIB.BASEBOARD_FAB2(SCH_1):PAGE43
   275 M_A_DQ<56> @BASEBOARD_FAB2_LIB.BASEBOARD_FAB2(SCH_1):M_A_DQ(56)     I1 @BASEBOARD_FAB2_LIB.BASEBOARD_FAB2(SCH_1):PAGE43
   130 M_A_DQ<57> @BASEBOARD_FAB2_LIB.BASEBOARD_FAB2(SCH_1):M_A_DQ(57)     I1 @BASEBOARD_FAB2_LIB.BASEBOARD_FAB2(SCH_1):PAGE43
   269 M_A_DQ<54> @BASEBOARD_FAB2_LIB.BASEBOARD_FAB2(SCH_1):M_A_DQ(54)     I1 @BASEBOARD_FAB2_LIB.BASEBOARD_FAB2(SCH_1):PAGE43
   124 M_A_DQ<55> @BASEBOARD_FAB2_LIB.BASEBOARD_FAB2(SCH_1):M_A_DQ(55)     I1 @BASEBOARD_FAB2_LIB.BASEBOARD_FAB2(SCH_1):PAGE43
   262 M_A_DQ<52> @BASEBOARD_FAB2_LIB.BASEBOARD_FAB2(SCH_1):M_A_DQ(52)     I1 @BASEBOARD_FAB2_LIB.BASEBOARD_FAB2(SCH_1):PAGE43
   117 M_A_DQ<53> @BASEBOARD_FAB2_LIB.BASEBOARD_FAB2(SCH_1):M_A_DQ(53)     I1 @BASEBOARD_FAB2_LIB.BASEBOARD_FAB2(SCH_1):PAGE43
   271 M_A_DQ<50> @BASEBOARD_FAB2_LIB.BASEBOARD_FAB2(SCH_1):M_A_DQ(50)     I1 @BASEBOARD_FAB2_LIB.BASEBOARD_FAB2(SCH_1):PAGE43
   126 M_A_DQ<51> @BASEBOARD_FAB2_LIB.BASEBOARD_FAB2(SCH_1):M_A_DQ(51)     I1 @BASEBOARD_FAB2_LIB.BASEBOARD_FAB2(SCH_1):PAGE43
   264 M_A_DQ<48> @BASEBOARD_FAB2_LIB.BASEBOARD_FAB2(SCH_1):M_A_DQ(48)     I1 @BASEBOARD_FAB2_LIB.BASEBOARD_FAB2(SCH_1):PAGE43
   119 M_A_DQ<49> @BASEBOARD_FAB2_LIB.BASEBOARD_FAB2(SCH_1):M_A_DQ(49)     I1 @BASEBOARD_FAB2_LIB.BASEBOARD_FAB2(SCH_1):PAGE43
   258 M_A_DQ<46> @BASEBOARD_FAB2_LIB.BASEBOARD_FAB2(SCH_1):M_A_DQ(46)     I1 @BASEBOARD_FAB2_LIB.BASEBOARD_FAB2(SCH_1):PAGE43
   113 M_A_DQ<47> @BASEBOARD_FAB2_LIB.BASEBOARD_FAB2(SCH_1):M_A_DQ(47)     I1 @BASEBOARD_FAB2_LIB.BASEBOARD_FAB2(SCH_1):PAGE43
   251 M_A_DQ<44> @BASEBOARD_FAB2_LIB.BASEBOARD_FAB2(SCH_1):M_A_DQ(44)     I1 @BASEBOARD_FAB2_LIB.BASEBOARD_FAB2(SCH_1):PAGE43
   106 M_A_DQ<45> @BASEBOARD_FAB2_LIB.BASEBOARD_FAB2(SCH_1):M_A_DQ(45)     I1 @BASEBOARD_FAB2_LIB.BASEBOARD_FAB2(SCH_1):PAGE43
   260 M_A_DQ<42> @BASEBOARD_FAB2_LIB.BASEBOARD_FAB2(SCH_1):M_A_DQ(42)     I1 @BASEBOARD_FAB2_LIB.BASEBOARD_FAB2(SCH_1):PAGE43
   115 M_A_DQ<43> @BASEBOARD_FAB2_LIB.BASEBOARD_FAB2(SCH_1):M_A_DQ(43)     I1 @BASEBOARD_FAB2_LIB.BASEBOARD_FAB2(SCH_1):PAGE43
   253 M_A_DQ<40> @BASEBOARD_FAB2_LIB.BASEBOARD_FAB2(SCH_1):M_A_DQ(40)     I1 @BASEBOARD_FAB2_LIB.BASEBOARD_FAB2(SCH_1):PAGE43
   108 M_A_DQ<41> @BASEBOARD_FAB2_LIB.BASEBOARD_FAB2(SCH_1):M_A_DQ(41)     I1 @BASEBOARD_FAB2_LIB.BASEBOARD_FAB2(SCH_1):PAGE43
   247 M_A_DQ<38> @BASEBOARD_FAB2_LIB.BASEBOARD_FAB2(SCH_1):M_A_DQ(38)     I1 @BASEBOARD_FAB2_LIB.BASEBOARD_FAB2(SCH_1):PAGE43
   102 M_A_DQ<39> @BASEBOARD_FAB2_LIB.BASEBOARD_FAB2(SCH_1):M_A_DQ(39)     I1 @BASEBOARD_FAB2_LIB.BASEBOARD_FAB2(SCH_1):PAGE43
   240 M_A_DQ<36> @BASEBOARD_FAB2_LIB.BASEBOARD_FAB2(SCH_1):M_A_DQ(36)     I1 @BASEBOARD_FAB2_LIB.BASEBOARD_FAB2(SCH_1):PAGE43
    95 M_A_DQ<37> @BASEBOARD_FAB2_LIB.BASEBOARD_FAB2(SCH_1):M_A_DQ(37)     I1 @BASEBOARD_FAB2_LIB.BASEBOARD_FAB2(SCH_1):PAGE43
   249 M_A_DQ<34> @BASEBOARD_FAB2_LIB.BASEBOARD_FAB2(SCH_1):M_A_DQ(34)     I1 @BASEBOARD_FAB2_LIB.BASEBOARD_FAB2(SCH_1):PAGE43
   104 M_A_DQ<35> @BASEBOARD_FAB2_LIB.BASEBOARD_FAB2(SCH_1):M_A_DQ(35)     I1 @BASEBOARD_FAB2_LIB.BASEBOARD_FAB2(SCH_1):PAGE43
   242 M_A_DQ<32> @BASEBOARD_FAB2_LIB.BASEBOARD_FAB2(SCH_1):M_A_DQ(32)     I1 @BASEBOARD_FAB2_LIB.BASEBOARD_FAB2(SCH_1):PAGE43
    97 M_A_DQ<33> @BASEBOARD_FAB2_LIB.BASEBOARD_FAB2(SCH_1):M_A_DQ(33)     I1 @BASEBOARD_FAB2_LIB.BASEBOARD_FAB2(SCH_1):PAGE43
   188 M_A_DQ<30> @BASEBOARD_FAB2_LIB.BASEBOARD_FAB2(SCH_1):M_A_DQ(30)     I1 @BASEBOARD_FAB2_LIB.BASEBOARD_FAB2(SCH_1):PAGE43
    43 M_A_DQ<31> @BASEBOARD_FAB2_LIB.BASEBOARD_FAB2(SCH_1):M_A_DQ(31)     I1 @BASEBOARD_FAB2_LIB.BASEBOARD_FAB2(SCH_1):PAGE43
   181 M_A_DQ<28> @BASEBOARD_FAB2_LIB.BASEBOARD_FAB2(SCH_1):M_A_DQ(28)     I1 @BASEBOARD_FAB2_LIB.BASEBOARD_FAB2(SCH_1):PAGE43
    36 M_A_DQ<29> @BASEBOARD_FAB2_LIB.BASEBOARD_FAB2(SCH_1):M_A_DQ(29)     I1 @BASEBOARD_FAB2_LIB.BASEBOARD_FAB2(SCH_1):PAGE43
   190 M_A_DQ<26> @BASEBOARD_FAB2_LIB.BASEBOARD_FAB2(SCH_1):M_A_DQ(26)     I1 @BASEBOARD_FAB2_LIB.BASEBOARD_FAB2(SCH_1):PAGE43
    45 M_A_DQ<27> @BASEBOARD_FAB2_LIB.BASEBOARD_FAB2(SCH_1):M_A_DQ(27)     I1 @BASEBOARD_FAB2_LIB.BASEBOARD_FAB2(SCH_1):PAGE43
   183 M_A_DQ<24> @BASEBOARD_FAB2_LIB.BASEBOARD_FAB2(SCH_1):M_A_DQ(24)     I1 @BASEBOARD_FAB2_LIB.BASEBOARD_FAB2(SCH_1):PAGE43
    38 M_A_DQ<25> @BASEBOARD_FAB2_LIB.BASEBOARD_FAB2(SCH_1):M_A_DQ(25)     I1 @BASEBOARD_FAB2_LIB.BASEBOARD_FAB2(SCH_1):PAGE43
   177 M_A_DQ<22> @BASEBOARD_FAB2_LIB.BASEBOARD_FAB2(SCH_1):M_A_DQ(22)     I1 @BASEBOARD_FAB2_LIB.BASEBOARD_FAB2(SCH_1):PAGE43
    32 M_A_DQ<23> @BASEBOARD_FAB2_LIB.BASEBOARD_FAB2(SCH_1):M_A_DQ(23)     I1 @BASEBOARD_FAB2_LIB.BASEBOARD_FAB2(SCH_1):PAGE43
   170 M_A_DQ<20> @BASEBOARD_FAB2_LIB.BASEBOARD_FAB2(SCH_1):M_A_DQ(20)     I1 @BASEBOARD_FAB2_LIB.BASEBOARD_FAB2(SCH_1):PAGE43
    25 M_A_DQ<21> @BASEBOARD_FAB2_LIB.BASEBOARD_FAB2(SCH_1):M_A_DQ(21)     I1 @BASEBOARD_FAB2_LIB.BASEBOARD_FAB2(SCH_1):PAGE43
   179 M_A_DQ<18> @BASEBOARD_FAB2_LIB.BASEBOARD_FAB2(SCH_1):M_A_DQ(18)     I1 @BASEBOARD_FAB2_LIB.BASEBOARD_FAB2(SCH_1):PAGE43
    34 M_A_DQ<19> @BASEBOARD_FAB2_LIB.BASEBOARD_FAB2(SCH_1):M_A_DQ(19)     I1 @BASEBOARD_FAB2_LIB.BASEBOARD_FAB2(SCH_1):PAGE43
   172 M_A_DQ<16> @BASEBOARD_FAB2_LIB.BASEBOARD_FAB2(SCH_1):M_A_DQ(16)     I1 @BASEBOARD_FAB2_LIB.BASEBOARD_FAB2(SCH_1):PAGE43
    27 M_A_DQ<17> @BASEBOARD_FAB2_LIB.BASEBOARD_FAB2(SCH_1):M_A_DQ(17)     I1 @BASEBOARD_FAB2_LIB.BASEBOARD_FAB2(SCH_1):PAGE43
   166 M_A_DQ<14> @BASEBOARD_FAB2_LIB.BASEBOARD_FAB2(SCH_1):M_A_DQ(14)     I1 @BASEBOARD_FAB2_LIB.BASEBOARD_FAB2(SCH_1):PAGE43
    21 M_A_DQ<15> @BASEBOARD_FAB2_LIB.BASEBOARD_FAB2(SCH_1):M_A_DQ(15)     I1 @BASEBOARD_FAB2_LIB.BASEBOARD_FAB2(SCH_1):PAGE43
   159 M_A_DQ<12> @BASEBOARD_FAB2_LIB.BASEBOARD_FAB2(SCH_1):M_A_DQ(12)     I1 @BASEBOARD_FAB2_LIB.BASEBOARD_FAB2(SCH_1):PAGE43
    14 M_A_DQ<13> @BASEBOARD_FAB2_LIB.BASEBOARD_FAB2(SCH_1):M_A_DQ(13)     I1 @BASEBOARD_FAB2_LIB.BASEBOARD_FAB2(SCH_1):PAGE43
   168 M_A_DQ<10> @BASEBOARD_FAB2_LIB.BASEBOARD_FAB2(SCH_1):M_A_DQ(10)     I1 @BASEBOARD_FAB2_LIB.BASEBOARD_FAB2(SCH_1):PAGE43
    23 M_A_DQ<11> @BASEBOARD_FAB2_LIB.BASEBOARD_FAB2(SCH_1):M_A_DQ(11)     I1 @BASEBOARD_FAB2_LIB.BASEBOARD_FAB2(SCH_1):PAGE43
   161 M_A_DQ<8> @BASEBOARD_FAB2_LIB.BASEBOARD_FAB2(SCH_1):M_A_DQ(8)     I1 @BASEBOARD_FAB2_LIB.BASEBOARD_FAB2(SCH_1):PAGE43
    16 M_A_DQ<9> @BASEBOARD_FAB2_LIB.BASEBOARD_FAB2(SCH_1):M_A_DQ(9)     I1 @BASEBOARD_FAB2_LIB.BASEBOARD_FAB2(SCH_1):PAGE43
   155 M_A_DQ<6> @BASEBOARD_FAB2_LIB.BASEBOARD_FAB2(SCH_1):M_A_DQ(6)     I1 @BASEBOARD_FAB2_LIB.BASEBOARD_FAB2(SCH_1):PAGE43
    10 M_A_DQ<7> @BASEBOARD_FAB2_LIB.BASEBOARD_FAB2(SCH_1):M_A_DQ(7)     I1 @BASEBOARD_FAB2_LIB.BASEBOARD_FAB2(SCH_1):PAGE43
   148 M_A_DQ<4> @BASEBOARD_FAB2_LIB.BASEBOARD_FAB2(SCH_1):M_A_DQ(4)     I1 @BASEBOARD_FAB2_LIB.BASEBOARD_FAB2(SCH_1):PAGE43
     3 M_A_DQ<5> @BASEBOARD_FAB2_LIB.BASEBOARD_FAB2(SCH_1):M_A_DQ(5)     I1 @BASEBOARD_FAB2_LIB.BASEBOARD_FAB2(SCH_1):PAGE43
   157 M_A_DQ<2> @BASEBOARD_FAB2_LIB.BASEBOARD_FAB2(SCH_1):M_A_DQ(2)     I1 @BASEBOARD_FAB2_LIB.BASEBOARD_FAB2(SCH_1):PAGE43
    12 M_A_DQ<3> @BASEBOARD_FAB2_LIB.BASEBOARD_FAB2(SCH_1):M_A_DQ(3)     I1 @BASEBOARD_FAB2_LIB.BASEBOARD_FAB2(SCH_1):PAGE43
   150 M_A_DQ<0> @BASEBOARD_FAB2_LIB.BASEBOARD_FAB2(SCH_1):M_A_DQ(0)     I1 @BASEBOARD_FAB2_LIB.BASEBOARD_FAB2(SCH_1):PAGE43
     5 M_A_DQ<1> @BASEBOARD_FAB2_LIB.BASEBOARD_FAB2(SCH_1):M_A_DQ(1)     I1 @BASEBOARD_FAB2_LIB.BASEBOARD_FAB2(SCH_1):PAGE43
    78 FM_DIMM_EVENT_COD_N @BASEBOARD_FAB2_LIB.BASEBOARD_FAB2(SCH_1):FM_DIMM_EVENT_COD_N     I1 @BASEBOARD_FAB2_LIB.BASEBOARD_FAB2(SCH_1):PAGE43
    91 M_A_ODT<1> @BASEBOARD_FAB2_LIB.BASEBOARD_FAB2(SCH_1):M_A_ODT(1)     I1 @BASEBOARD_FAB2_LIB.BASEBOARD_FAB2(SCH_1):PAGE43
    87 M_A_ODT<0> @BASEBOARD_FAB2_LIB.BASEBOARD_FAB2(SCH_1):M_A_ODT(0)     I1 @BASEBOARD_FAB2_LIB.BASEBOARD_FAB2(SCH_1):PAGE43
   222 M_A_PAR @BASEBOARD_FAB2_LIB.BASEBOARD_FAB2(SCH_1):M_A_PAR     I1 @BASEBOARD_FAB2_LIB.BASEBOARD_FAB2(SCH_1):PAGE43
    58 M_ABC_RST_N @BASEBOARD_FAB2_LIB.BASEBOARD_FAB2(SCH_1):M_ABC_RST_N     I1 @BASEBOARD_FAB2_LIB.BASEBOARD_FAB2(SCH_1):PAGE43
   144 TP_CH_A_DIMM_A0_RFU_2 @BASEBOARD_FAB2_LIB.BASEBOARD_FAB2(SCH_1):TP_CH_A_DIMM_A0_RFU_2     I1 @BASEBOARD_FAB2_LIB.BASEBOARD_FAB2(SCH_1):PAGE43
   227 TP_CH_A_DIMM_A0_RFU_1 @BASEBOARD_FAB2_LIB.BASEBOARD_FAB2(SCH_1):TP_CH_A_DIMM_A0_RFU_1     I1 @BASEBOARD_FAB2_LIB.BASEBOARD_FAB2(SCH_1):PAGE43
   205 TP_CH_A_DIMM_A0_RFU_0 @BASEBOARD_FAB2_LIB.BASEBOARD_FAB2(SCH_1):TP_CH_A_DIMM_A0_RFU_0     I1 @BASEBOARD_FAB2_LIB.BASEBOARD_FAB2(SCH_1):PAGE43
    84 M_A_CS_N<0> @BASEBOARD_FAB2_LIB.BASEBOARD_FAB2(SCH_1):M_A_CS_N(0)     I1 @BASEBOARD_FAB2_LIB.BASEBOARD_FAB2(SCH_1):PAGE43
    89 M_A_CS_N<1> @BASEBOARD_FAB2_LIB.BASEBOARD_FAB2(SCH_1):M_A_CS_N(1)     I1 @BASEBOARD_FAB2_LIB.BASEBOARD_FAB2(SCH_1):PAGE43
    93 M_A_CS_N<2> @BASEBOARD_FAB2_LIB.BASEBOARD_FAB2(SCH_1):M_A_CS_N(2)     I1 @BASEBOARD_FAB2_LIB.BASEBOARD_FAB2(SCH_1):PAGE43
   237 M_A_CS_N<3> @BASEBOARD_FAB2_LIB.BASEBOARD_FAB2(SCH_1):M_A_CS_N(3)     I1 @BASEBOARD_FAB2_LIB.BASEBOARD_FAB2(SCH_1):PAGE43
   238    GND @BASEBOARD_FAB2_LIB.BASEBOARD_FAB2(SCH_1):GND     I1 @BASEBOARD_FAB2_LIB.BASEBOARD_FAB2(SCH_1):PAGE43
   140    GND @BASEBOARD_FAB2_LIB.BASEBOARD_FAB2(SCH_1):GND     I1 @BASEBOARD_FAB2_LIB.BASEBOARD_FAB2(SCH_1):PAGE43
   139    GND @BASEBOARD_FAB2_LIB.BASEBOARD_FAB2(SCH_1):GND     I1 @BASEBOARD_FAB2_LIB.BASEBOARD_FAB2(SCH_1):PAGE43
   230 FM_ADR_COMPLETE_ABC_N @BASEBOARD_FAB2_LIB.BASEBOARD_FAB2(SCH_1):FM_ADR_COMPLETE_ABC_N     I1 @BASEBOARD_FAB2_LIB.BASEBOARD_FAB2(SCH_1):PAGE43
   141 SMB_DDR_ABC_VPP_SCL @BASEBOARD_FAB2_LIB.BASEBOARD_FAB2(SCH_1):SMB_DDR_ABC_VPP_SCL     I1 @BASEBOARD_FAB2_LIB.BASEBOARD_FAB2(SCH_1):PAGE43
   285 SMB_DDR_ABC_VPP_SDA @BASEBOARD_FAB2_LIB.BASEBOARD_FAB2(SCH_1):SMB_DDR_ABC_VPP_SDA     I1 @BASEBOARD_FAB2_LIB.BASEBOARD_FAB2(SCH_1):PAGE43
   284 PVPP_ABC @BASEBOARD_FAB2_LIB.BASEBOARD_FAB2(SCH_1):PVPP_ABC     I1 @BASEBOARD_FAB2_LIB.BASEBOARD_FAB2(SCH_1):PAGE43
   146 M_A_VREF @BASEBOARD_FAB2_LIB.BASEBOARD_FAB2(SCH_1):M_A_VREF     I1 @BASEBOARD_FAB2_LIB.BASEBOARD_FAB2(SCH_1):PAGE43
   152 M_A_DQS_DN<0> @BASEBOARD_FAB2_LIB.BASEBOARD_FAB2(SCH_1):M_A_DQS_DN(0)     I2 @BASEBOARD_FAB2_LIB.BASEBOARD_FAB2(SCH_1):PAGE43
   153 M_A_DQS_DP<0> @BASEBOARD_FAB2_LIB.BASEBOARD_FAB2(SCH_1):M_A_DQS_DP(0)     I2 @BASEBOARD_FAB2_LIB.BASEBOARD_FAB2(SCH_1):PAGE43
    19 M_A_DQS_DN<10> @BASEBOARD_FAB2_LIB.BASEBOARD_FAB2(SCH_1):M_A_DQS_DN(10)     I2 @BASEBOARD_FAB2_LIB.BASEBOARD_FAB2(SCH_1):PAGE43
    18 M_A_DQS_DP<10> @BASEBOARD_FAB2_LIB.BASEBOARD_FAB2(SCH_1):M_A_DQS_DP(10)     I2 @BASEBOARD_FAB2_LIB.BASEBOARD_FAB2(SCH_1):PAGE43
    30 M_A_DQS_DN<11> @BASEBOARD_FAB2_LIB.BASEBOARD_FAB2(SCH_1):M_A_DQS_DN(11)     I2 @BASEBOARD_FAB2_LIB.BASEBOARD_FAB2(SCH_1):PAGE43
    29 M_A_DQS_DP<11> @BASEBOARD_FAB2_LIB.BASEBOARD_FAB2(SCH_1):M_A_DQS_DP(11)     I2 @BASEBOARD_FAB2_LIB.BASEBOARD_FAB2(SCH_1):PAGE43
    41 M_A_DQS_DN<12> @BASEBOARD_FAB2_LIB.BASEBOARD_FAB2(SCH_1):M_A_DQS_DN(12)     I2 @BASEBOARD_FAB2_LIB.BASEBOARD_FAB2(SCH_1):PAGE43
    40 M_A_DQS_DP<12> @BASEBOARD_FAB2_LIB.BASEBOARD_FAB2(SCH_1):M_A_DQS_DP(12)     I2 @BASEBOARD_FAB2_LIB.BASEBOARD_FAB2(SCH_1):PAGE43
   100 M_A_DQS_DN<13> @BASEBOARD_FAB2_LIB.BASEBOARD_FAB2(SCH_1):M_A_DQS_DN(13)     I2 @BASEBOARD_FAB2_LIB.BASEBOARD_FAB2(SCH_1):PAGE43
    99 M_A_DQS_DP<13> @BASEBOARD_FAB2_LIB.BASEBOARD_FAB2(SCH_1):M_A_DQS_DP(13)     I2 @BASEBOARD_FAB2_LIB.BASEBOARD_FAB2(SCH_1):PAGE43
   111 M_A_DQS_DN<14> @BASEBOARD_FAB2_LIB.BASEBOARD_FAB2(SCH_1):M_A_DQS_DN(14)     I2 @BASEBOARD_FAB2_LIB.BASEBOARD_FAB2(SCH_1):PAGE43
   110 M_A_DQS_DP<14> @BASEBOARD_FAB2_LIB.BASEBOARD_FAB2(SCH_1):M_A_DQS_DP(14)     I2 @BASEBOARD_FAB2_LIB.BASEBOARD_FAB2(SCH_1):PAGE43
   122 M_A_DQS_DN<15> @BASEBOARD_FAB2_LIB.BASEBOARD_FAB2(SCH_1):M_A_DQS_DN(15)     I2 @BASEBOARD_FAB2_LIB.BASEBOARD_FAB2(SCH_1):PAGE43
   121 M_A_DQS_DP<15> @BASEBOARD_FAB2_LIB.BASEBOARD_FAB2(SCH_1):M_A_DQS_DP(15)     I2 @BASEBOARD_FAB2_LIB.BASEBOARD_FAB2(SCH_1):PAGE43
   133 M_A_DQS_DN<16> @BASEBOARD_FAB2_LIB.BASEBOARD_FAB2(SCH_1):M_A_DQS_DN(16)     I2 @BASEBOARD_FAB2_LIB.BASEBOARD_FAB2(SCH_1):PAGE43
   132 M_A_DQS_DP<16> @BASEBOARD_FAB2_LIB.BASEBOARD_FAB2(SCH_1):M_A_DQS_DP(16)     I2 @BASEBOARD_FAB2_LIB.BASEBOARD_FAB2(SCH_1):PAGE43
    52 M_A_DQS_DN<17> @BASEBOARD_FAB2_LIB.BASEBOARD_FAB2(SCH_1):M_A_DQS_DN(17)     I2 @BASEBOARD_FAB2_LIB.BASEBOARD_FAB2(SCH_1):PAGE43
    51 M_A_DQS_DP<17> @BASEBOARD_FAB2_LIB.BASEBOARD_FAB2(SCH_1):M_A_DQS_DP(17)     I2 @BASEBOARD_FAB2_LIB.BASEBOARD_FAB2(SCH_1):PAGE43
   163 M_A_DQS_DN<1> @BASEBOARD_FAB2_LIB.BASEBOARD_FAB2(SCH_1):M_A_DQS_DN(1)     I2 @BASEBOARD_FAB2_LIB.BASEBOARD_FAB2(SCH_1):PAGE43
   164 M_A_DQS_DP<1> @BASEBOARD_FAB2_LIB.BASEBOARD_FAB2(SCH_1):M_A_DQS_DP(1)     I2 @BASEBOARD_FAB2_LIB.BASEBOARD_FAB2(SCH_1):PAGE43
   174 M_A_DQS_DN<2> @BASEBOARD_FAB2_LIB.BASEBOARD_FAB2(SCH_1):M_A_DQS_DN(2)     I2 @BASEBOARD_FAB2_LIB.BASEBOARD_FAB2(SCH_1):PAGE43
   175 M_A_DQS_DP<2> @BASEBOARD_FAB2_LIB.BASEBOARD_FAB2(SCH_1):M_A_DQS_DP(2)     I2 @BASEBOARD_FAB2_LIB.BASEBOARD_FAB2(SCH_1):PAGE43
   185 M_A_DQS_DN<3> @BASEBOARD_FAB2_LIB.BASEBOARD_FAB2(SCH_1):M_A_DQS_DN(3)     I2 @BASEBOARD_FAB2_LIB.BASEBOARD_FAB2(SCH_1):PAGE43
   186 M_A_DQS_DP<3> @BASEBOARD_FAB2_LIB.BASEBOARD_FAB2(SCH_1):M_A_DQS_DP(3)     I2 @BASEBOARD_FAB2_LIB.BASEBOARD_FAB2(SCH_1):PAGE43
   244 M_A_DQS_DN<4> @BASEBOARD_FAB2_LIB.BASEBOARD_FAB2(SCH_1):M_A_DQS_DN(4)     I2 @BASEBOARD_FAB2_LIB.BASEBOARD_FAB2(SCH_1):PAGE43
   245 M_A_DQS_DP<4> @BASEBOARD_FAB2_LIB.BASEBOARD_FAB2(SCH_1):M_A_DQS_DP(4)     I2 @BASEBOARD_FAB2_LIB.BASEBOARD_FAB2(SCH_1):PAGE43
   255 M_A_DQS_DN<5> @BASEBOARD_FAB2_LIB.BASEBOARD_FAB2(SCH_1):M_A_DQS_DN(5)     I2 @BASEBOARD_FAB2_LIB.BASEBOARD_FAB2(SCH_1):PAGE43
   256 M_A_DQS_DP<5> @BASEBOARD_FAB2_LIB.BASEBOARD_FAB2(SCH_1):M_A_DQS_DP(5)     I2 @BASEBOARD_FAB2_LIB.BASEBOARD_FAB2(SCH_1):PAGE43
   266 M_A_DQS_DN<6> @BASEBOARD_FAB2_LIB.BASEBOARD_FAB2(SCH_1):M_A_DQS_DN(6)     I2 @BASEBOARD_FAB2_LIB.BASEBOARD_FAB2(SCH_1):PAGE43
   267 M_A_DQS_DP<6> @BASEBOARD_FAB2_LIB.BASEBOARD_FAB2(SCH_1):M_A_DQS_DP(6)     I2 @BASEBOARD_FAB2_LIB.BASEBOARD_FAB2(SCH_1):PAGE43
   277 M_A_DQS_DN<7> @BASEBOARD_FAB2_LIB.BASEBOARD_FAB2(SCH_1):M_A_DQS_DN(7)     I2 @BASEBOARD_FAB2_LIB.BASEBOARD_FAB2(SCH_1):PAGE43
   278 M_A_DQS_DP<7> @BASEBOARD_FAB2_LIB.BASEBOARD_FAB2(SCH_1):M_A_DQS_DP(7)     I2 @BASEBOARD_FAB2_LIB.BASEBOARD_FAB2(SCH_1):PAGE43
   196 M_A_DQS_DN<8> @BASEBOARD_FAB2_LIB.BASEBOARD_FAB2(SCH_1):M_A_DQS_DN(8)     I2 @BASEBOARD_FAB2_LIB.BASEBOARD_FAB2(SCH_1):PAGE43
   197 M_A_DQS_DP<8> @BASEBOARD_FAB2_LIB.BASEBOARD_FAB2(SCH_1):M_A_DQS_DP(8)     I2 @BASEBOARD_FAB2_LIB.BASEBOARD_FAB2(SCH_1):PAGE43
     8 M_A_DQS_DN<9> @BASEBOARD_FAB2_LIB.BASEBOARD_FAB2(SCH_1):M_A_DQS_DN(9)     I2 @BASEBOARD_FAB2_LIB.BASEBOARD_FAB2(SCH_1):PAGE43
     7 M_A_DQS_DP<9> @BASEBOARD_FAB2_LIB.BASEBOARD_FAB2(SCH_1):M_A_DQS_DP(9)     I2 @BASEBOARD_FAB2_LIB.BASEBOARD_FAB2(SCH_1):PAGE43
     2    GND @BASEBOARD_FAB2_LIB.BASEBOARD_FAB2(SCH_1):GND   I259 @BASEBOARD_FAB2_LIB.BASEBOARD_FAB2(SCH_1):PAGE43
     4    GND @BASEBOARD_FAB2_LIB.BASEBOARD_FAB2(SCH_1):GND   I259 @BASEBOARD_FAB2_LIB.BASEBOARD_FAB2(SCH_1):PAGE43
     6    GND @BASEBOARD_FAB2_LIB.BASEBOARD_FAB2(SCH_1):GND   I259 @BASEBOARD_FAB2_LIB.BASEBOARD_FAB2(SCH_1):PAGE43
     9    GND @BASEBOARD_FAB2_LIB.BASEBOARD_FAB2(SCH_1):GND   I259 @BASEBOARD_FAB2_LIB.BASEBOARD_FAB2(SCH_1):PAGE43
    11    GND @BASEBOARD_FAB2_LIB.BASEBOARD_FAB2(SCH_1):GND   I259 @BASEBOARD_FAB2_LIB.BASEBOARD_FAB2(SCH_1):PAGE43
    13    GND @BASEBOARD_FAB2_LIB.BASEBOARD_FAB2(SCH_1):GND   I259 @BASEBOARD_FAB2_LIB.BASEBOARD_FAB2(SCH_1):PAGE43
    15    GND @BASEBOARD_FAB2_LIB.BASEBOARD_FAB2(SCH_1):GND   I259 @BASEBOARD_FAB2_LIB.BASEBOARD_FAB2(SCH_1):PAGE43
    17    GND @BASEBOARD_FAB2_LIB.BASEBOARD_FAB2(SCH_1):GND   I259 @BASEBOARD_FAB2_LIB.BASEBOARD_FAB2(SCH_1):PAGE43
    20    GND @BASEBOARD_FAB2_LIB.BASEBOARD_FAB2(SCH_1):GND   I259 @BASEBOARD_FAB2_LIB.BASEBOARD_FAB2(SCH_1):PAGE43
    22    GND @BASEBOARD_FAB2_LIB.BASEBOARD_FAB2(SCH_1):GND   I259 @BASEBOARD_FAB2_LIB.BASEBOARD_FAB2(SCH_1):PAGE43
    24    GND @BASEBOARD_FAB2_LIB.BASEBOARD_FAB2(SCH_1):GND   I259 @BASEBOARD_FAB2_LIB.BASEBOARD_FAB2(SCH_1):PAGE43
    26    GND @BASEBOARD_FAB2_LIB.BASEBOARD_FAB2(SCH_1):GND   I259 @BASEBOARD_FAB2_LIB.BASEBOARD_FAB2(SCH_1):PAGE43
    28    GND @BASEBOARD_FAB2_LIB.BASEBOARD_FAB2(SCH_1):GND   I259 @BASEBOARD_FAB2_LIB.BASEBOARD_FAB2(SCH_1):PAGE43
    31    GND @BASEBOARD_FAB2_LIB.BASEBOARD_FAB2(SCH_1):GND   I259 @BASEBOARD_FAB2_LIB.BASEBOARD_FAB2(SCH_1):PAGE43
    33    GND @BASEBOARD_FAB2_LIB.BASEBOARD_FAB2(SCH_1):GND   I259 @BASEBOARD_FAB2_LIB.BASEBOARD_FAB2(SCH_1):PAGE43
    35    GND @BASEBOARD_FAB2_LIB.BASEBOARD_FAB2(SCH_1):GND   I259 @BASEBOARD_FAB2_LIB.BASEBOARD_FAB2(SCH_1):PAGE43
    37    GND @BASEBOARD_FAB2_LIB.BASEBOARD_FAB2(SCH_1):GND   I259 @BASEBOARD_FAB2_LIB.BASEBOARD_FAB2(SCH_1):PAGE43
    39    GND @BASEBOARD_FAB2_LIB.BASEBOARD_FAB2(SCH_1):GND   I259 @BASEBOARD_FAB2_LIB.BASEBOARD_FAB2(SCH_1):PAGE43
    42    GND @BASEBOARD_FAB2_LIB.BASEBOARD_FAB2(SCH_1):GND   I259 @BASEBOARD_FAB2_LIB.BASEBOARD_FAB2(SCH_1):PAGE43
    44    GND @BASEBOARD_FAB2_LIB.BASEBOARD_FAB2(SCH_1):GND   I259 @BASEBOARD_FAB2_LIB.BASEBOARD_FAB2(SCH_1):PAGE43
    46    GND @BASEBOARD_FAB2_LIB.BASEBOARD_FAB2(SCH_1):GND   I259 @BASEBOARD_FAB2_LIB.BASEBOARD_FAB2(SCH_1):PAGE43
    48    GND @BASEBOARD_FAB2_LIB.BASEBOARD_FAB2(SCH_1):GND   I259 @BASEBOARD_FAB2_LIB.BASEBOARD_FAB2(SCH_1):PAGE43
    50    GND @BASEBOARD_FAB2_LIB.BASEBOARD_FAB2(SCH_1):GND   I259 @BASEBOARD_FAB2_LIB.BASEBOARD_FAB2(SCH_1):PAGE43
    53    GND @BASEBOARD_FAB2_LIB.BASEBOARD_FAB2(SCH_1):GND   I259 @BASEBOARD_FAB2_LIB.BASEBOARD_FAB2(SCH_1):PAGE43
    55    GND @BASEBOARD_FAB2_LIB.BASEBOARD_FAB2(SCH_1):GND   I259 @BASEBOARD_FAB2_LIB.BASEBOARD_FAB2(SCH_1):PAGE43
    57    GND @BASEBOARD_FAB2_LIB.BASEBOARD_FAB2(SCH_1):GND   I259 @BASEBOARD_FAB2_LIB.BASEBOARD_FAB2(SCH_1):PAGE43
    94    GND @BASEBOARD_FAB2_LIB.BASEBOARD_FAB2(SCH_1):GND   I259 @BASEBOARD_FAB2_LIB.BASEBOARD_FAB2(SCH_1):PAGE43
    96    GND @BASEBOARD_FAB2_LIB.BASEBOARD_FAB2(SCH_1):GND   I259 @BASEBOARD_FAB2_LIB.BASEBOARD_FAB2(SCH_1):PAGE43
    98    GND @BASEBOARD_FAB2_LIB.BASEBOARD_FAB2(SCH_1):GND   I259 @BASEBOARD_FAB2_LIB.BASEBOARD_FAB2(SCH_1):PAGE43
   101    GND @BASEBOARD_FAB2_LIB.BASEBOARD_FAB2(SCH_1):GND   I259 @BASEBOARD_FAB2_LIB.BASEBOARD_FAB2(SCH_1):PAGE43
   103    GND @BASEBOARD_FAB2_LIB.BASEBOARD_FAB2(SCH_1):GND   I259 @BASEBOARD_FAB2_LIB.BASEBOARD_FAB2(SCH_1):PAGE43
   105    GND @BASEBOARD_FAB2_LIB.BASEBOARD_FAB2(SCH_1):GND   I259 @BASEBOARD_FAB2_LIB.BASEBOARD_FAB2(SCH_1):PAGE43
   107    GND @BASEBOARD_FAB2_LIB.BASEBOARD_FAB2(SCH_1):GND   I259 @BASEBOARD_FAB2_LIB.BASEBOARD_FAB2(SCH_1):PAGE43
   109    GND @BASEBOARD_FAB2_LIB.BASEBOARD_FAB2(SCH_1):GND   I259 @BASEBOARD_FAB2_LIB.BASEBOARD_FAB2(SCH_1):PAGE43
   112    GND @BASEBOARD_FAB2_LIB.BASEBOARD_FAB2(SCH_1):GND   I259 @BASEBOARD_FAB2_LIB.BASEBOARD_FAB2(SCH_1):PAGE43
   114    GND @BASEBOARD_FAB2_LIB.BASEBOARD_FAB2(SCH_1):GND   I259 @BASEBOARD_FAB2_LIB.BASEBOARD_FAB2(SCH_1):PAGE43
   116    GND @BASEBOARD_FAB2_LIB.BASEBOARD_FAB2(SCH_1):GND   I259 @BASEBOARD_FAB2_LIB.BASEBOARD_FAB2(SCH_1):PAGE43
   118    GND @BASEBOARD_FAB2_LIB.BASEBOARD_FAB2(SCH_1):GND   I259 @BASEBOARD_FAB2_LIB.BASEBOARD_FAB2(SCH_1):PAGE43
   120    GND @BASEBOARD_FAB2_LIB.BASEBOARD_FAB2(SCH_1):GND   I259 @BASEBOARD_FAB2_LIB.BASEBOARD_FAB2(SCH_1):PAGE43
   123    GND @BASEBOARD_FAB2_LIB.BASEBOARD_FAB2(SCH_1):GND   I259 @BASEBOARD_FAB2_LIB.BASEBOARD_FAB2(SCH_1):PAGE43
   125    GND @BASEBOARD_FAB2_LIB.BASEBOARD_FAB2(SCH_1):GND   I259 @BASEBOARD_FAB2_LIB.BASEBOARD_FAB2(SCH_1):PAGE43
   127    GND @BASEBOARD_FAB2_LIB.BASEBOARD_FAB2(SCH_1):GND   I259 @BASEBOARD_FAB2_LIB.BASEBOARD_FAB2(SCH_1):PAGE43
   129    GND @BASEBOARD_FAB2_LIB.BASEBOARD_FAB2(SCH_1):GND   I259 @BASEBOARD_FAB2_LIB.BASEBOARD_FAB2(SCH_1):PAGE43
   131    GND @BASEBOARD_FAB2_LIB.BASEBOARD_FAB2(SCH_1):GND   I259 @BASEBOARD_FAB2_LIB.BASEBOARD_FAB2(SCH_1):PAGE43
   134    GND @BASEBOARD_FAB2_LIB.BASEBOARD_FAB2(SCH_1):GND   I259 @BASEBOARD_FAB2_LIB.BASEBOARD_FAB2(SCH_1):PAGE43
   136    GND @BASEBOARD_FAB2_LIB.BASEBOARD_FAB2(SCH_1):GND   I259 @BASEBOARD_FAB2_LIB.BASEBOARD_FAB2(SCH_1):PAGE43
   138    GND @BASEBOARD_FAB2_LIB.BASEBOARD_FAB2(SCH_1):GND   I259 @BASEBOARD_FAB2_LIB.BASEBOARD_FAB2(SCH_1):PAGE43
   147    GND @BASEBOARD_FAB2_LIB.BASEBOARD_FAB2(SCH_1):GND   I259 @BASEBOARD_FAB2_LIB.BASEBOARD_FAB2(SCH_1):PAGE43
   149    GND @BASEBOARD_FAB2_LIB.BASEBOARD_FAB2(SCH_1):GND   I259 @BASEBOARD_FAB2_LIB.BASEBOARD_FAB2(SCH_1):PAGE43
   151    GND @BASEBOARD_FAB2_LIB.BASEBOARD_FAB2(SCH_1):GND   I259 @BASEBOARD_FAB2_LIB.BASEBOARD_FAB2(SCH_1):PAGE43
   154    GND @BASEBOARD_FAB2_LIB.BASEBOARD_FAB2(SCH_1):GND   I259 @BASEBOARD_FAB2_LIB.BASEBOARD_FAB2(SCH_1):PAGE43
   156    GND @BASEBOARD_FAB2_LIB.BASEBOARD_FAB2(SCH_1):GND   I259 @BASEBOARD_FAB2_LIB.BASEBOARD_FAB2(SCH_1):PAGE43
   158    GND @BASEBOARD_FAB2_LIB.BASEBOARD_FAB2(SCH_1):GND   I259 @BASEBOARD_FAB2_LIB.BASEBOARD_FAB2(SCH_1):PAGE43
   160    GND @BASEBOARD_FAB2_LIB.BASEBOARD_FAB2(SCH_1):GND   I259 @BASEBOARD_FAB2_LIB.BASEBOARD_FAB2(SCH_1):PAGE43
   162    GND @BASEBOARD_FAB2_LIB.BASEBOARD_FAB2(SCH_1):GND   I259 @BASEBOARD_FAB2_LIB.BASEBOARD_FAB2(SCH_1):PAGE43
   165    GND @BASEBOARD_FAB2_LIB.BASEBOARD_FAB2(SCH_1):GND   I259 @BASEBOARD_FAB2_LIB.BASEBOARD_FAB2(SCH_1):PAGE43
   167    GND @BASEBOARD_FAB2_LIB.BASEBOARD_FAB2(SCH_1):GND   I259 @BASEBOARD_FAB2_LIB.BASEBOARD_FAB2(SCH_1):PAGE43
   169    GND @BASEBOARD_FAB2_LIB.BASEBOARD_FAB2(SCH_1):GND   I259 @BASEBOARD_FAB2_LIB.BASEBOARD_FAB2(SCH_1):PAGE43
   171    GND @BASEBOARD_FAB2_LIB.BASEBOARD_FAB2(SCH_1):GND   I259 @BASEBOARD_FAB2_LIB.BASEBOARD_FAB2(SCH_1):PAGE43
   173    GND @BASEBOARD_FAB2_LIB.BASEBOARD_FAB2(SCH_1):GND   I259 @BASEBOARD_FAB2_LIB.BASEBOARD_FAB2(SCH_1):PAGE43
   176    GND @BASEBOARD_FAB2_LIB.BASEBOARD_FAB2(SCH_1):GND   I259 @BASEBOARD_FAB2_LIB.BASEBOARD_FAB2(SCH_1):PAGE43
   178    GND @BASEBOARD_FAB2_LIB.BASEBOARD_FAB2(SCH_1):GND   I259 @BASEBOARD_FAB2_LIB.BASEBOARD_FAB2(SCH_1):PAGE43
   180    GND @BASEBOARD_FAB2_LIB.BASEBOARD_FAB2(SCH_1):GND   I259 @BASEBOARD_FAB2_LIB.BASEBOARD_FAB2(SCH_1):PAGE43
   182    GND @BASEBOARD_FAB2_LIB.BASEBOARD_FAB2(SCH_1):GND   I259 @BASEBOARD_FAB2_LIB.BASEBOARD_FAB2(SCH_1):PAGE43
   184    GND @BASEBOARD_FAB2_LIB.BASEBOARD_FAB2(SCH_1):GND   I259 @BASEBOARD_FAB2_LIB.BASEBOARD_FAB2(SCH_1):PAGE43
   187    GND @BASEBOARD_FAB2_LIB.BASEBOARD_FAB2(SCH_1):GND   I259 @BASEBOARD_FAB2_LIB.BASEBOARD_FAB2(SCH_1):PAGE43
   189    GND @BASEBOARD_FAB2_LIB.BASEBOARD_FAB2(SCH_1):GND   I259 @BASEBOARD_FAB2_LIB.BASEBOARD_FAB2(SCH_1):PAGE43
   191    GND @BASEBOARD_FAB2_LIB.BASEBOARD_FAB2(SCH_1):GND   I259 @BASEBOARD_FAB2_LIB.BASEBOARD_FAB2(SCH_1):PAGE43
   193    GND @BASEBOARD_FAB2_LIB.BASEBOARD_FAB2(SCH_1):GND   I259 @BASEBOARD_FAB2_LIB.BASEBOARD_FAB2(SCH_1):PAGE43
   195    GND @BASEBOARD_FAB2_LIB.BASEBOARD_FAB2(SCH_1):GND   I259 @BASEBOARD_FAB2_LIB.BASEBOARD_FAB2(SCH_1):PAGE43
   198    GND @BASEBOARD_FAB2_LIB.BASEBOARD_FAB2(SCH_1):GND   I259 @BASEBOARD_FAB2_LIB.BASEBOARD_FAB2(SCH_1):PAGE43
   200    GND @BASEBOARD_FAB2_LIB.BASEBOARD_FAB2(SCH_1):GND   I259 @BASEBOARD_FAB2_LIB.BASEBOARD_FAB2(SCH_1):PAGE43
   202    GND @BASEBOARD_FAB2_LIB.BASEBOARD_FAB2(SCH_1):GND   I259 @BASEBOARD_FAB2_LIB.BASEBOARD_FAB2(SCH_1):PAGE43
   239    GND @BASEBOARD_FAB2_LIB.BASEBOARD_FAB2(SCH_1):GND   I259 @BASEBOARD_FAB2_LIB.BASEBOARD_FAB2(SCH_1):PAGE43
   241    GND @BASEBOARD_FAB2_LIB.BASEBOARD_FAB2(SCH_1):GND   I259 @BASEBOARD_FAB2_LIB.BASEBOARD_FAB2(SCH_1):PAGE43
   243    GND @BASEBOARD_FAB2_LIB.BASEBOARD_FAB2(SCH_1):GND   I259 @BASEBOARD_FAB2_LIB.BASEBOARD_FAB2(SCH_1):PAGE43
   246    GND @BASEBOARD_FAB2_LIB.BASEBOARD_FAB2(SCH_1):GND   I259 @BASEBOARD_FAB2_LIB.BASEBOARD_FAB2(SCH_1):PAGE43
   248    GND @BASEBOARD_FAB2_LIB.BASEBOARD_FAB2(SCH_1):GND   I259 @BASEBOARD_FAB2_LIB.BASEBOARD_FAB2(SCH_1):PAGE43
   250    GND @BASEBOARD_FAB2_LIB.BASEBOARD_FAB2(SCH_1):GND   I259 @BASEBOARD_FAB2_LIB.BASEBOARD_FAB2(SCH_1):PAGE43
   252    GND @BASEBOARD_FAB2_LIB.BASEBOARD_FAB2(SCH_1):GND   I259 @BASEBOARD_FAB2_LIB.BASEBOARD_FAB2(SCH_1):PAGE43
   254    GND @BASEBOARD_FAB2_LIB.BASEBOARD_FAB2(SCH_1):GND   I259 @BASEBOARD_FAB2_LIB.BASEBOARD_FAB2(SCH_1):PAGE43
   257    GND @BASEBOARD_FAB2_LIB.BASEBOARD_FAB2(SCH_1):GND   I259 @BASEBOARD_FAB2_LIB.BASEBOARD_FAB2(SCH_1):PAGE43
   259    GND @BASEBOARD_FAB2_LIB.BASEBOARD_FAB2(SCH_1):GND   I259 @BASEBOARD_FAB2_LIB.BASEBOARD_FAB2(SCH_1):PAGE43
   261    GND @BASEBOARD_FAB2_LIB.BASEBOARD_FAB2(SCH_1):GND   I259 @BASEBOARD_FAB2_LIB.BASEBOARD_FAB2(SCH_1):PAGE43
   263    GND @BASEBOARD_FAB2_LIB.BASEBOARD_FAB2(SCH_1):GND   I259 @BASEBOARD_FAB2_LIB.BASEBOARD_FAB2(SCH_1):PAGE43
   265    GND @BASEBOARD_FAB2_LIB.BASEBOARD_FAB2(SCH_1):GND   I259 @BASEBOARD_FAB2_LIB.BASEBOARD_FAB2(SCH_1):PAGE43
   268    GND @BASEBOARD_FAB2_LIB.BASEBOARD_FAB2(SCH_1):GND   I259 @BASEBOARD_FAB2_LIB.BASEBOARD_FAB2(SCH_1):PAGE43
   270    GND @BASEBOARD_FAB2_LIB.BASEBOARD_FAB2(SCH_1):GND   I259 @BASEBOARD_FAB2_LIB.BASEBOARD_FAB2(SCH_1):PAGE43
   272    GND @BASEBOARD_FAB2_LIB.BASEBOARD_FAB2(SCH_1):GND   I259 @BASEBOARD_FAB2_LIB.BASEBOARD_FAB2(SCH_1):PAGE43
   274    GND @BASEBOARD_FAB2_LIB.BASEBOARD_FAB2(SCH_1):GND   I259 @BASEBOARD_FAB2_LIB.BASEBOARD_FAB2(SCH_1):PAGE43
   276    GND @BASEBOARD_FAB2_LIB.BASEBOARD_FAB2(SCH_1):GND   I259 @BASEBOARD_FAB2_LIB.BASEBOARD_FAB2(SCH_1):PAGE43
   279    GND @BASEBOARD_FAB2_LIB.BASEBOARD_FAB2(SCH_1):GND   I259 @BASEBOARD_FAB2_LIB.BASEBOARD_FAB2(SCH_1):PAGE43
   281    GND @BASEBOARD_FAB2_LIB.BASEBOARD_FAB2(SCH_1):GND   I259 @BASEBOARD_FAB2_LIB.BASEBOARD_FAB2(SCH_1):PAGE43
   283    GND @BASEBOARD_FAB2_LIB.BASEBOARD_FAB2(SCH_1):GND   I259 @BASEBOARD_FAB2_LIB.BASEBOARD_FAB2(SCH_1):PAGE43
     1 P12V_NVDIMM_ABC @BASEBOARD_FAB2_LIB.BASEBOARD_FAB2(SCH_1):P12V_NVDIMM_ABC   I260 @BASEBOARD_FAB2_LIB.BASEBOARD_FAB2(SCH_1):PAGE43
   145 P12V_NVDIMM_ABC @BASEBOARD_FAB2_LIB.BASEBOARD_FAB2(SCH_1):P12V_NVDIMM_ABC   I260 @BASEBOARD_FAB2_LIB.BASEBOARD_FAB2(SCH_1):PAGE43
    59 PVDDQ_ABC @BASEBOARD_FAB2_LIB.BASEBOARD_FAB2(SCH_1):PVDDQ_ABC   I260 @BASEBOARD_FAB2_LIB.BASEBOARD_FAB2(SCH_1):PAGE43
    61 PVDDQ_ABC @BASEBOARD_FAB2_LIB.BASEBOARD_FAB2(SCH_1):PVDDQ_ABC   I260 @BASEBOARD_FAB2_LIB.BASEBOARD_FAB2(SCH_1):PAGE43
    64 PVDDQ_ABC @BASEBOARD_FAB2_LIB.BASEBOARD_FAB2(SCH_1):PVDDQ_ABC   I260 @BASEBOARD_FAB2_LIB.BASEBOARD_FAB2(SCH_1):PAGE43
    67 PVDDQ_ABC @BASEBOARD_FAB2_LIB.BASEBOARD_FAB2(SCH_1):PVDDQ_ABC   I260 @BASEBOARD_FAB2_LIB.BASEBOARD_FAB2(SCH_1):PAGE43
    70 PVDDQ_ABC @BASEBOARD_FAB2_LIB.BASEBOARD_FAB2(SCH_1):PVDDQ_ABC   I260 @BASEBOARD_FAB2_LIB.BASEBOARD_FAB2(SCH_1):PAGE43
    73 PVDDQ_ABC @BASEBOARD_FAB2_LIB.BASEBOARD_FAB2(SCH_1):PVDDQ_ABC   I260 @BASEBOARD_FAB2_LIB.BASEBOARD_FAB2(SCH_1):PAGE43
    76 PVDDQ_ABC @BASEBOARD_FAB2_LIB.BASEBOARD_FAB2(SCH_1):PVDDQ_ABC   I260 @BASEBOARD_FAB2_LIB.BASEBOARD_FAB2(SCH_1):PAGE43
    80 PVDDQ_ABC @BASEBOARD_FAB2_LIB.BASEBOARD_FAB2(SCH_1):PVDDQ_ABC   I260 @BASEBOARD_FAB2_LIB.BASEBOARD_FAB2(SCH_1):PAGE43
    83 PVDDQ_ABC @BASEBOARD_FAB2_LIB.BASEBOARD_FAB2(SCH_1):PVDDQ_ABC   I260 @BASEBOARD_FAB2_LIB.BASEBOARD_FAB2(SCH_1):PAGE43
    85 PVDDQ_ABC @BASEBOARD_FAB2_LIB.BASEBOARD_FAB2(SCH_1):PVDDQ_ABC   I260 @BASEBOARD_FAB2_LIB.BASEBOARD_FAB2(SCH_1):PAGE43
    88 PVDDQ_ABC @BASEBOARD_FAB2_LIB.BASEBOARD_FAB2(SCH_1):PVDDQ_ABC   I260 @BASEBOARD_FAB2_LIB.BASEBOARD_FAB2(SCH_1):PAGE43
    90 PVDDQ_ABC @BASEBOARD_FAB2_LIB.BASEBOARD_FAB2(SCH_1):PVDDQ_ABC   I260 @BASEBOARD_FAB2_LIB.BASEBOARD_FAB2(SCH_1):PAGE43
    92 PVDDQ_ABC @BASEBOARD_FAB2_LIB.BASEBOARD_FAB2(SCH_1):PVDDQ_ABC   I260 @BASEBOARD_FAB2_LIB.BASEBOARD_FAB2(SCH_1):PAGE43
   204 PVDDQ_ABC @BASEBOARD_FAB2_LIB.BASEBOARD_FAB2(SCH_1):PVDDQ_ABC   I260 @BASEBOARD_FAB2_LIB.BASEBOARD_FAB2(SCH_1):PAGE43
   206 PVDDQ_ABC @BASEBOARD_FAB2_LIB.BASEBOARD_FAB2(SCH_1):PVDDQ_ABC   I260 @BASEBOARD_FAB2_LIB.BASEBOARD_FAB2(SCH_1):PAGE43
   209 PVDDQ_ABC @BASEBOARD_FAB2_LIB.BASEBOARD_FAB2(SCH_1):PVDDQ_ABC   I260 @BASEBOARD_FAB2_LIB.BASEBOARD_FAB2(SCH_1):PAGE43
   212 PVDDQ_ABC @BASEBOARD_FAB2_LIB.BASEBOARD_FAB2(SCH_1):PVDDQ_ABC   I260 @BASEBOARD_FAB2_LIB.BASEBOARD_FAB2(SCH_1):PAGE43
   215 PVDDQ_ABC @BASEBOARD_FAB2_LIB.BASEBOARD_FAB2(SCH_1):PVDDQ_ABC   I260 @BASEBOARD_FAB2_LIB.BASEBOARD_FAB2(SCH_1):PAGE43
   217 PVDDQ_ABC @BASEBOARD_FAB2_LIB.BASEBOARD_FAB2(SCH_1):PVDDQ_ABC   I260 @BASEBOARD_FAB2_LIB.BASEBOARD_FAB2(SCH_1):PAGE43
   220 PVDDQ_ABC @BASEBOARD_FAB2_LIB.BASEBOARD_FAB2(SCH_1):PVDDQ_ABC   I260 @BASEBOARD_FAB2_LIB.BASEBOARD_FAB2(SCH_1):PAGE43
   223 PVDDQ_ABC @BASEBOARD_FAB2_LIB.BASEBOARD_FAB2(SCH_1):PVDDQ_ABC   I260 @BASEBOARD_FAB2_LIB.BASEBOARD_FAB2(SCH_1):PAGE43
   226 PVDDQ_ABC @BASEBOARD_FAB2_LIB.BASEBOARD_FAB2(SCH_1):PVDDQ_ABC   I260 @BASEBOARD_FAB2_LIB.BASEBOARD_FAB2(SCH_1):PAGE43
   229 PVDDQ_ABC @BASEBOARD_FAB2_LIB.BASEBOARD_FAB2(SCH_1):PVDDQ_ABC   I260 @BASEBOARD_FAB2_LIB.BASEBOARD_FAB2(SCH_1):PAGE43
   231 PVDDQ_ABC @BASEBOARD_FAB2_LIB.BASEBOARD_FAB2(SCH_1):PVDDQ_ABC   I260 @BASEBOARD_FAB2_LIB.BASEBOARD_FAB2(SCH_1):PAGE43
   233 PVDDQ_ABC @BASEBOARD_FAB2_LIB.BASEBOARD_FAB2(SCH_1):PVDDQ_ABC   I260 @BASEBOARD_FAB2_LIB.BASEBOARD_FAB2(SCH_1):PAGE43
   236 PVDDQ_ABC @BASEBOARD_FAB2_LIB.BASEBOARD_FAB2(SCH_1):PVDDQ_ABC   I260 @BASEBOARD_FAB2_LIB.BASEBOARD_FAB2(SCH_1):PAGE43
   142 PVPP_ABC @BASEBOARD_FAB2_LIB.BASEBOARD_FAB2(SCH_1):PVPP_ABC   I260 @BASEBOARD_FAB2_LIB.BASEBOARD_FAB2(SCH_1):PAGE43
   143 PVPP_ABC @BASEBOARD_FAB2_LIB.BASEBOARD_FAB2(SCH_1):PVPP_ABC   I260 @BASEBOARD_FAB2_LIB.BASEBOARD_FAB2(SCH_1):PAGE43
   288 PVPP_ABC @BASEBOARD_FAB2_LIB.BASEBOARD_FAB2(SCH_1):PVPP_ABC   I260 @BASEBOARD_FAB2_LIB.BASEBOARD_FAB2(SCH_1):PAGE43
   286 PVPP_ABC @BASEBOARD_FAB2_LIB.BASEBOARD_FAB2(SCH_1):PVPP_ABC   I260 @BASEBOARD_FAB2_LIB.BASEBOARD_FAB2(SCH_1):PAGE43
   287 PVPP_ABC @BASEBOARD_FAB2_LIB.BASEBOARD_FAB2(SCH_1):PVPP_ABC   I260 @BASEBOARD_FAB2_LIB.BASEBOARD_FAB2(SCH_1):PAGE43
    77 PVTT_ABC @BASEBOARD_FAB2_LIB.BASEBOARD_FAB2(SCH_1):PVTT_ABC   I260 @BASEBOARD_FAB2_LIB.BASEBOARD_FAB2(SCH_1):PAGE43
   221 PVTT_ABC @BASEBOARD_FAB2_LIB.BASEBOARD_FAB2(SCH_1):PVTT_ABC   I260 @BASEBOARD_FAB2_LIB.BASEBOARD_FAB2(SCH_1):PAGE43

J4G2 SCONN288_H44441004_PIP-SCONN,HA
    79 M_B_MA<0> @BASEBOARD_FAB2_LIB.BASEBOARD_FAB2(SCH_1):M_B_MA(0)   I111 @BASEBOARD_FAB2_LIB.BASEBOARD_FAB2(SCH_1):PAGE45
    72 M_B_MA<1> @BASEBOARD_FAB2_LIB.BASEBOARD_FAB2(SCH_1):M_B_MA(1)   I111 @BASEBOARD_FAB2_LIB.BASEBOARD_FAB2(SCH_1):PAGE45
   225 M_B_MA<10> @BASEBOARD_FAB2_LIB.BASEBOARD_FAB2(SCH_1):M_B_MA(10)   I111 @BASEBOARD_FAB2_LIB.BASEBOARD_FAB2(SCH_1):PAGE45
   210 M_B_MA<11> @BASEBOARD_FAB2_LIB.BASEBOARD_FAB2(SCH_1):M_B_MA(11)   I111 @BASEBOARD_FAB2_LIB.BASEBOARD_FAB2(SCH_1):PAGE45
    65 M_B_MA<12> @BASEBOARD_FAB2_LIB.BASEBOARD_FAB2(SCH_1):M_B_MA(12)   I111 @BASEBOARD_FAB2_LIB.BASEBOARD_FAB2(SCH_1):PAGE45
   232 M_B_MA<13> @BASEBOARD_FAB2_LIB.BASEBOARD_FAB2(SCH_1):M_B_MA(13)   I111 @BASEBOARD_FAB2_LIB.BASEBOARD_FAB2(SCH_1):PAGE45
   228 M_B_MA<14> @BASEBOARD_FAB2_LIB.BASEBOARD_FAB2(SCH_1):M_B_MA(14)   I111 @BASEBOARD_FAB2_LIB.BASEBOARD_FAB2(SCH_1):PAGE45
    86 M_B_MA<15> @BASEBOARD_FAB2_LIB.BASEBOARD_FAB2(SCH_1):M_B_MA(15)   I111 @BASEBOARD_FAB2_LIB.BASEBOARD_FAB2(SCH_1):PAGE45
    82 M_B_MA<16> @BASEBOARD_FAB2_LIB.BASEBOARD_FAB2(SCH_1):M_B_MA(16)   I111 @BASEBOARD_FAB2_LIB.BASEBOARD_FAB2(SCH_1):PAGE45
   234 M_B_MA<17> @BASEBOARD_FAB2_LIB.BASEBOARD_FAB2(SCH_1):M_B_MA(17)   I111 @BASEBOARD_FAB2_LIB.BASEBOARD_FAB2(SCH_1):PAGE45
   216 M_B_MA<2> @BASEBOARD_FAB2_LIB.BASEBOARD_FAB2(SCH_1):M_B_MA(2)   I111 @BASEBOARD_FAB2_LIB.BASEBOARD_FAB2(SCH_1):PAGE45
    71 M_B_MA<3> @BASEBOARD_FAB2_LIB.BASEBOARD_FAB2(SCH_1):M_B_MA(3)   I111 @BASEBOARD_FAB2_LIB.BASEBOARD_FAB2(SCH_1):PAGE45
   214 M_B_MA<4> @BASEBOARD_FAB2_LIB.BASEBOARD_FAB2(SCH_1):M_B_MA(4)   I111 @BASEBOARD_FAB2_LIB.BASEBOARD_FAB2(SCH_1):PAGE45
   213 M_B_MA<5> @BASEBOARD_FAB2_LIB.BASEBOARD_FAB2(SCH_1):M_B_MA(5)   I111 @BASEBOARD_FAB2_LIB.BASEBOARD_FAB2(SCH_1):PAGE45
    69 M_B_MA<6> @BASEBOARD_FAB2_LIB.BASEBOARD_FAB2(SCH_1):M_B_MA(6)   I111 @BASEBOARD_FAB2_LIB.BASEBOARD_FAB2(SCH_1):PAGE45
   211 M_B_MA<7> @BASEBOARD_FAB2_LIB.BASEBOARD_FAB2(SCH_1):M_B_MA(7)   I111 @BASEBOARD_FAB2_LIB.BASEBOARD_FAB2(SCH_1):PAGE45
    68 M_B_MA<8> @BASEBOARD_FAB2_LIB.BASEBOARD_FAB2(SCH_1):M_B_MA(8)   I111 @BASEBOARD_FAB2_LIB.BASEBOARD_FAB2(SCH_1):PAGE45
    66 M_B_MA<9> @BASEBOARD_FAB2_LIB.BASEBOARD_FAB2(SCH_1):M_B_MA(9)   I111 @BASEBOARD_FAB2_LIB.BASEBOARD_FAB2(SCH_1):PAGE45
    62 M_B_ACT_N @BASEBOARD_FAB2_LIB.BASEBOARD_FAB2(SCH_1):M_B_ACT_N   I111 @BASEBOARD_FAB2_LIB.BASEBOARD_FAB2(SCH_1):PAGE45
   208 M_B_ALERT_N @BASEBOARD_FAB2_LIB.BASEBOARD_FAB2(SCH_1):M_B_ALERT_N   I111 @BASEBOARD_FAB2_LIB.BASEBOARD_FAB2(SCH_1):PAGE45
   224 M_B_BA<1> @BASEBOARD_FAB2_LIB.BASEBOARD_FAB2(SCH_1):M_B_BA(1)   I111 @BASEBOARD_FAB2_LIB.BASEBOARD_FAB2(SCH_1):PAGE45
    81 M_B_BA<0> @BASEBOARD_FAB2_LIB.BASEBOARD_FAB2(SCH_1):M_B_BA(0)   I111 @BASEBOARD_FAB2_LIB.BASEBOARD_FAB2(SCH_1):PAGE45
   207 M_B_BG<1> @BASEBOARD_FAB2_LIB.BASEBOARD_FAB2(SCH_1):M_B_BG(1)   I111 @BASEBOARD_FAB2_LIB.BASEBOARD_FAB2(SCH_1):PAGE45
    63 M_B_BG<0> @BASEBOARD_FAB2_LIB.BASEBOARD_FAB2(SCH_1):M_B_BG(0)   I111 @BASEBOARD_FAB2_LIB.BASEBOARD_FAB2(SCH_1):PAGE45
   235 M_B_C<2> @BASEBOARD_FAB2_LIB.BASEBOARD_FAB2(SCH_1):M_B_C(2)   I111 @BASEBOARD_FAB2_LIB.BASEBOARD_FAB2(SCH_1):PAGE45
   199 M_B_ECC<6> @BASEBOARD_FAB2_LIB.BASEBOARD_FAB2(SCH_1):M_B_ECC(6)   I111 @BASEBOARD_FAB2_LIB.BASEBOARD_FAB2(SCH_1):PAGE45
    54 M_B_ECC<7> @BASEBOARD_FAB2_LIB.BASEBOARD_FAB2(SCH_1):M_B_ECC(7)   I111 @BASEBOARD_FAB2_LIB.BASEBOARD_FAB2(SCH_1):PAGE45
   192 M_B_ECC<4> @BASEBOARD_FAB2_LIB.BASEBOARD_FAB2(SCH_1):M_B_ECC(4)   I111 @BASEBOARD_FAB2_LIB.BASEBOARD_FAB2(SCH_1):PAGE45
    47 M_B_ECC<5> @BASEBOARD_FAB2_LIB.BASEBOARD_FAB2(SCH_1):M_B_ECC(5)   I111 @BASEBOARD_FAB2_LIB.BASEBOARD_FAB2(SCH_1):PAGE45
   201 M_B_ECC<2> @BASEBOARD_FAB2_LIB.BASEBOARD_FAB2(SCH_1):M_B_ECC(2)   I111 @BASEBOARD_FAB2_LIB.BASEBOARD_FAB2(SCH_1):PAGE45
    56 M_B_ECC<3> @BASEBOARD_FAB2_LIB.BASEBOARD_FAB2(SCH_1):M_B_ECC(3)   I111 @BASEBOARD_FAB2_LIB.BASEBOARD_FAB2(SCH_1):PAGE45
   194 M_B_ECC<0> @BASEBOARD_FAB2_LIB.BASEBOARD_FAB2(SCH_1):M_B_ECC(0)   I111 @BASEBOARD_FAB2_LIB.BASEBOARD_FAB2(SCH_1):PAGE45
    49 M_B_ECC<1> @BASEBOARD_FAB2_LIB.BASEBOARD_FAB2(SCH_1):M_B_ECC(1)   I111 @BASEBOARD_FAB2_LIB.BASEBOARD_FAB2(SCH_1):PAGE45
    75 M_B_CLK_DN<0> @BASEBOARD_FAB2_LIB.BASEBOARD_FAB2(SCH_1):M_B_CLK_DN(0)   I111 @BASEBOARD_FAB2_LIB.BASEBOARD_FAB2(SCH_1):PAGE45
    74 M_B_CLK_DP<0> @BASEBOARD_FAB2_LIB.BASEBOARD_FAB2(SCH_1):M_B_CLK_DP(0)   I111 @BASEBOARD_FAB2_LIB.BASEBOARD_FAB2(SCH_1):PAGE45
   219 M_B_CLK_DN<1> @BASEBOARD_FAB2_LIB.BASEBOARD_FAB2(SCH_1):M_B_CLK_DN(1)   I111 @BASEBOARD_FAB2_LIB.BASEBOARD_FAB2(SCH_1):PAGE45
   218 M_B_CLK_DP<1> @BASEBOARD_FAB2_LIB.BASEBOARD_FAB2(SCH_1):M_B_CLK_DP(1)   I111 @BASEBOARD_FAB2_LIB.BASEBOARD_FAB2(SCH_1):PAGE45
   203 M_B_CKE<1> @BASEBOARD_FAB2_LIB.BASEBOARD_FAB2(SCH_1):M_B_CKE(1)   I111 @BASEBOARD_FAB2_LIB.BASEBOARD_FAB2(SCH_1):PAGE45
    60 M_B_CKE<0> @BASEBOARD_FAB2_LIB.BASEBOARD_FAB2(SCH_1):M_B_CKE(0)   I111 @BASEBOARD_FAB2_LIB.BASEBOARD_FAB2(SCH_1):PAGE45
   280 M_B_DQ<62> @BASEBOARD_FAB2_LIB.BASEBOARD_FAB2(SCH_1):M_B_DQ(62)   I111 @BASEBOARD_FAB2_LIB.BASEBOARD_FAB2(SCH_1):PAGE45
   135 M_B_DQ<63> @BASEBOARD_FAB2_LIB.BASEBOARD_FAB2(SCH_1):M_B_DQ(63)   I111 @BASEBOARD_FAB2_LIB.BASEBOARD_FAB2(SCH_1):PAGE45
   273 M_B_DQ<60> @BASEBOARD_FAB2_LIB.BASEBOARD_FAB2(SCH_1):M_B_DQ(60)   I111 @BASEBOARD_FAB2_LIB.BASEBOARD_FAB2(SCH_1):PAGE45
   128 M_B_DQ<61> @BASEBOARD_FAB2_LIB.BASEBOARD_FAB2(SCH_1):M_B_DQ(61)   I111 @BASEBOARD_FAB2_LIB.BASEBOARD_FAB2(SCH_1):PAGE45
   282 M_B_DQ<58> @BASEBOARD_FAB2_LIB.BASEBOARD_FAB2(SCH_1):M_B_DQ(58)   I111 @BASEBOARD_FAB2_LIB.BASEBOARD_FAB2(SCH_1):PAGE45
   137 M_B_DQ<59> @BASEBOARD_FAB2_LIB.BASEBOARD_FAB2(SCH_1):M_B_DQ(59)   I111 @BASEBOARD_FAB2_LIB.BASEBOARD_FAB2(SCH_1):PAGE45
   275 M_B_DQ<56> @BASEBOARD_FAB2_LIB.BASEBOARD_FAB2(SCH_1):M_B_DQ(56)   I111 @BASEBOARD_FAB2_LIB.BASEBOARD_FAB2(SCH_1):PAGE45
   130 M_B_DQ<57> @BASEBOARD_FAB2_LIB.BASEBOARD_FAB2(SCH_1):M_B_DQ(57)   I111 @BASEBOARD_FAB2_LIB.BASEBOARD_FAB2(SCH_1):PAGE45
   269 M_B_DQ<54> @BASEBOARD_FAB2_LIB.BASEBOARD_FAB2(SCH_1):M_B_DQ(54)   I111 @BASEBOARD_FAB2_LIB.BASEBOARD_FAB2(SCH_1):PAGE45
   124 M_B_DQ<55> @BASEBOARD_FAB2_LIB.BASEBOARD_FAB2(SCH_1):M_B_DQ(55)   I111 @BASEBOARD_FAB2_LIB.BASEBOARD_FAB2(SCH_1):PAGE45
   262 M_B_DQ<52> @BASEBOARD_FAB2_LIB.BASEBOARD_FAB2(SCH_1):M_B_DQ(52)   I111 @BASEBOARD_FAB2_LIB.BASEBOARD_FAB2(SCH_1):PAGE45
   117 M_B_DQ<53> @BASEBOARD_FAB2_LIB.BASEBOARD_FAB2(SCH_1):M_B_DQ(53)   I111 @BASEBOARD_FAB2_LIB.BASEBOARD_FAB2(SCH_1):PAGE45
   271 M_B_DQ<50> @BASEBOARD_FAB2_LIB.BASEBOARD_FAB2(SCH_1):M_B_DQ(50)   I111 @BASEBOARD_FAB2_LIB.BASEBOARD_FAB2(SCH_1):PAGE45
   126 M_B_DQ<51> @BASEBOARD_FAB2_LIB.BASEBOARD_FAB2(SCH_1):M_B_DQ(51)   I111 @BASEBOARD_FAB2_LIB.BASEBOARD_FAB2(SCH_1):PAGE45
   264 M_B_DQ<48> @BASEBOARD_FAB2_LIB.BASEBOARD_FAB2(SCH_1):M_B_DQ(48)   I111 @BASEBOARD_FAB2_LIB.BASEBOARD_FAB2(SCH_1):PAGE45
   119 M_B_DQ<49> @BASEBOARD_FAB2_LIB.BASEBOARD_FAB2(SCH_1):M_B_DQ(49)   I111 @BASEBOARD_FAB2_LIB.BASEBOARD_FAB2(SCH_1):PAGE45
   258 M_B_DQ<46> @BASEBOARD_FAB2_LIB.BASEBOARD_FAB2(SCH_1):M_B_DQ(46)   I111 @BASEBOARD_FAB2_LIB.BASEBOARD_FAB2(SCH_1):PAGE45
   113 M_B_DQ<47> @BASEBOARD_FAB2_LIB.BASEBOARD_FAB2(SCH_1):M_B_DQ(47)   I111 @BASEBOARD_FAB2_LIB.BASEBOARD_FAB2(SCH_1):PAGE45
   251 M_B_DQ<44> @BASEBOARD_FAB2_LIB.BASEBOARD_FAB2(SCH_1):M_B_DQ(44)   I111 @BASEBOARD_FAB2_LIB.BASEBOARD_FAB2(SCH_1):PAGE45
   106 M_B_DQ<45> @BASEBOARD_FAB2_LIB.BASEBOARD_FAB2(SCH_1):M_B_DQ(45)   I111 @BASEBOARD_FAB2_LIB.BASEBOARD_FAB2(SCH_1):PAGE45
   260 M_B_DQ<42> @BASEBOARD_FAB2_LIB.BASEBOARD_FAB2(SCH_1):M_B_DQ(42)   I111 @BASEBOARD_FAB2_LIB.BASEBOARD_FAB2(SCH_1):PAGE45
   115 M_B_DQ<43> @BASEBOARD_FAB2_LIB.BASEBOARD_FAB2(SCH_1):M_B_DQ(43)   I111 @BASEBOARD_FAB2_LIB.BASEBOARD_FAB2(SCH_1):PAGE45
   253 M_B_DQ<40> @BASEBOARD_FAB2_LIB.BASEBOARD_FAB2(SCH_1):M_B_DQ(40)   I111 @BASEBOARD_FAB2_LIB.BASEBOARD_FAB2(SCH_1):PAGE45
   108 M_B_DQ<41> @BASEBOARD_FAB2_LIB.BASEBOARD_FAB2(SCH_1):M_B_DQ(41)   I111 @BASEBOARD_FAB2_LIB.BASEBOARD_FAB2(SCH_1):PAGE45
   247 M_B_DQ<38> @BASEBOARD_FAB2_LIB.BASEBOARD_FAB2(SCH_1):M_B_DQ(38)   I111 @BASEBOARD_FAB2_LIB.BASEBOARD_FAB2(SCH_1):PAGE45
   102 M_B_DQ<39> @BASEBOARD_FAB2_LIB.BASEBOARD_FAB2(SCH_1):M_B_DQ(39)   I111 @BASEBOARD_FAB2_LIB.BASEBOARD_FAB2(SCH_1):PAGE45
   240 M_B_DQ<36> @BASEBOARD_FAB2_LIB.BASEBOARD_FAB2(SCH_1):M_B_DQ(36)   I111 @BASEBOARD_FAB2_LIB.BASEBOARD_FAB2(SCH_1):PAGE45
    95 M_B_DQ<37> @BASEBOARD_FAB2_LIB.BASEBOARD_FAB2(SCH_1):M_B_DQ(37)   I111 @BASEBOARD_FAB2_LIB.BASEBOARD_FAB2(SCH_1):PAGE45
   249 M_B_DQ<34> @BASEBOARD_FAB2_LIB.BASEBOARD_FAB2(SCH_1):M_B_DQ(34)   I111 @BASEBOARD_FAB2_LIB.BASEBOARD_FAB2(SCH_1):PAGE45
   104 M_B_DQ<35> @BASEBOARD_FAB2_LIB.BASEBOARD_FAB2(SCH_1):M_B_DQ(35)   I111 @BASEBOARD_FAB2_LIB.BASEBOARD_FAB2(SCH_1):PAGE45
   242 M_B_DQ<32> @BASEBOARD_FAB2_LIB.BASEBOARD_FAB2(SCH_1):M_B_DQ(32)   I111 @BASEBOARD_FAB2_LIB.BASEBOARD_FAB2(SCH_1):PAGE45
    97 M_B_DQ<33> @BASEBOARD_FAB2_LIB.BASEBOARD_FAB2(SCH_1):M_B_DQ(33)   I111 @BASEBOARD_FAB2_LIB.BASEBOARD_FAB2(SCH_1):PAGE45
   188 M_B_DQ<30> @BASEBOARD_FAB2_LIB.BASEBOARD_FAB2(SCH_1):M_B_DQ(30)   I111 @BASEBOARD_FAB2_LIB.BASEBOARD_FAB2(SCH_1):PAGE45
    43 M_B_DQ<31> @BASEBOARD_FAB2_LIB.BASEBOARD_FAB2(SCH_1):M_B_DQ(31)   I111 @BASEBOARD_FAB2_LIB.BASEBOARD_FAB2(SCH_1):PAGE45
   181 M_B_DQ<28> @BASEBOARD_FAB2_LIB.BASEBOARD_FAB2(SCH_1):M_B_DQ(28)   I111 @BASEBOARD_FAB2_LIB.BASEBOARD_FAB2(SCH_1):PAGE45
    36 M_B_DQ<29> @BASEBOARD_FAB2_LIB.BASEBOARD_FAB2(SCH_1):M_B_DQ(29)   I111 @BASEBOARD_FAB2_LIB.BASEBOARD_FAB2(SCH_1):PAGE45
   190 M_B_DQ<26> @BASEBOARD_FAB2_LIB.BASEBOARD_FAB2(SCH_1):M_B_DQ(26)   I111 @BASEBOARD_FAB2_LIB.BASEBOARD_FAB2(SCH_1):PAGE45
    45 M_B_DQ<27> @BASEBOARD_FAB2_LIB.BASEBOARD_FAB2(SCH_1):M_B_DQ(27)   I111 @BASEBOARD_FAB2_LIB.BASEBOARD_FAB2(SCH_1):PAGE45
   183 M_B_DQ<24> @BASEBOARD_FAB2_LIB.BASEBOARD_FAB2(SCH_1):M_B_DQ(24)   I111 @BASEBOARD_FAB2_LIB.BASEBOARD_FAB2(SCH_1):PAGE45
    38 M_B_DQ<25> @BASEBOARD_FAB2_LIB.BASEBOARD_FAB2(SCH_1):M_B_DQ(25)   I111 @BASEBOARD_FAB2_LIB.BASEBOARD_FAB2(SCH_1):PAGE45
   177 M_B_DQ<22> @BASEBOARD_FAB2_LIB.BASEBOARD_FAB2(SCH_1):M_B_DQ(22)   I111 @BASEBOARD_FAB2_LIB.BASEBOARD_FAB2(SCH_1):PAGE45
    32 M_B_DQ<23> @BASEBOARD_FAB2_LIB.BASEBOARD_FAB2(SCH_1):M_B_DQ(23)   I111 @BASEBOARD_FAB2_LIB.BASEBOARD_FAB2(SCH_1):PAGE45
   170 M_B_DQ<20> @BASEBOARD_FAB2_LIB.BASEBOARD_FAB2(SCH_1):M_B_DQ(20)   I111 @BASEBOARD_FAB2_LIB.BASEBOARD_FAB2(SCH_1):PAGE45
    25 M_B_DQ<21> @BASEBOARD_FAB2_LIB.BASEBOARD_FAB2(SCH_1):M_B_DQ(21)   I111 @BASEBOARD_FAB2_LIB.BASEBOARD_FAB2(SCH_1):PAGE45
   179 M_B_DQ<18> @BASEBOARD_FAB2_LIB.BASEBOARD_FAB2(SCH_1):M_B_DQ(18)   I111 @BASEBOARD_FAB2_LIB.BASEBOARD_FAB2(SCH_1):PAGE45
    34 M_B_DQ<19> @BASEBOARD_FAB2_LIB.BASEBOARD_FAB2(SCH_1):M_B_DQ(19)   I111 @BASEBOARD_FAB2_LIB.BASEBOARD_FAB2(SCH_1):PAGE45
   172 M_B_DQ<16> @BASEBOARD_FAB2_LIB.BASEBOARD_FAB2(SCH_1):M_B_DQ(16)   I111 @BASEBOARD_FAB2_LIB.BASEBOARD_FAB2(SCH_1):PAGE45
    27 M_B_DQ<17> @BASEBOARD_FAB2_LIB.BASEBOARD_FAB2(SCH_1):M_B_DQ(17)   I111 @BASEBOARD_FAB2_LIB.BASEBOARD_FAB2(SCH_1):PAGE45
   166 M_B_DQ<14> @BASEBOARD_FAB2_LIB.BASEBOARD_FAB2(SCH_1):M_B_DQ(14)   I111 @BASEBOARD_FAB2_LIB.BASEBOARD_FAB2(SCH_1):PAGE45
    21 M_B_DQ<15> @BASEBOARD_FAB2_LIB.BASEBOARD_FAB2(SCH_1):M_B_DQ(15)   I111 @BASEBOARD_FAB2_LIB.BASEBOARD_FAB2(SCH_1):PAGE45
   159 M_B_DQ<12> @BASEBOARD_FAB2_LIB.BASEBOARD_FAB2(SCH_1):M_B_DQ(12)   I111 @BASEBOARD_FAB2_LIB.BASEBOARD_FAB2(SCH_1):PAGE45
    14 M_B_DQ<13> @BASEBOARD_FAB2_LIB.BASEBOARD_FAB2(SCH_1):M_B_DQ(13)   I111 @BASEBOARD_FAB2_LIB.BASEBOARD_FAB2(SCH_1):PAGE45
   168 M_B_DQ<10> @BASEBOARD_FAB2_LIB.BASEBOARD_FAB2(SCH_1):M_B_DQ(10)   I111 @BASEBOARD_FAB2_LIB.BASEBOARD_FAB2(SCH_1):PAGE45
    23 M_B_DQ<11> @BASEBOARD_FAB2_LIB.BASEBOARD_FAB2(SCH_1):M_B_DQ(11)   I111 @BASEBOARD_FAB2_LIB.BASEBOARD_FAB2(SCH_1):PAGE45
   161 M_B_DQ<8> @BASEBOARD_FAB2_LIB.BASEBOARD_FAB2(SCH_1):M_B_DQ(8)   I111 @BASEBOARD_FAB2_LIB.BASEBOARD_FAB2(SCH_1):PAGE45
    16 M_B_DQ<9> @BASEBOARD_FAB2_LIB.BASEBOARD_FAB2(SCH_1):M_B_DQ(9)   I111 @BASEBOARD_FAB2_LIB.BASEBOARD_FAB2(SCH_1):PAGE45
   155 M_B_DQ<6> @BASEBOARD_FAB2_LIB.BASEBOARD_FAB2(SCH_1):M_B_DQ(6)   I111 @BASEBOARD_FAB2_LIB.BASEBOARD_FAB2(SCH_1):PAGE45
    10 M_B_DQ<7> @BASEBOARD_FAB2_LIB.BASEBOARD_FAB2(SCH_1):M_B_DQ(7)   I111 @BASEBOARD_FAB2_LIB.BASEBOARD_FAB2(SCH_1):PAGE45
   148 M_B_DQ<4> @BASEBOARD_FAB2_LIB.BASEBOARD_FAB2(SCH_1):M_B_DQ(4)   I111 @BASEBOARD_FAB2_LIB.BASEBOARD_FAB2(SCH_1):PAGE45
     3 M_B_DQ<5> @BASEBOARD_FAB2_LIB.BASEBOARD_FAB2(SCH_1):M_B_DQ(5)   I111 @BASEBOARD_FAB2_LIB.BASEBOARD_FAB2(SCH_1):PAGE45
   157 M_B_DQ<2> @BASEBOARD_FAB2_LIB.BASEBOARD_FAB2(SCH_1):M_B_DQ(2)   I111 @BASEBOARD_FAB2_LIB.BASEBOARD_FAB2(SCH_1):PAGE45
    12 M_B_DQ<3> @BASEBOARD_FAB2_LIB.BASEBOARD_FAB2(SCH_1):M_B_DQ(3)   I111 @BASEBOARD_FAB2_LIB.BASEBOARD_FAB2(SCH_1):PAGE45
   150 M_B_DQ<0> @BASEBOARD_FAB2_LIB.BASEBOARD_FAB2(SCH_1):M_B_DQ(0)   I111 @BASEBOARD_FAB2_LIB.BASEBOARD_FAB2(SCH_1):PAGE45
     5 M_B_DQ<1> @BASEBOARD_FAB2_LIB.BASEBOARD_FAB2(SCH_1):M_B_DQ(1)   I111 @BASEBOARD_FAB2_LIB.BASEBOARD_FAB2(SCH_1):PAGE45
    78 FM_DIMM_EVENT_COD_N @BASEBOARD_FAB2_LIB.BASEBOARD_FAB2(SCH_1):FM_DIMM_EVENT_COD_N   I111 @BASEBOARD_FAB2_LIB.BASEBOARD_FAB2(SCH_1):PAGE45
    91 M_B_ODT<1> @BASEBOARD_FAB2_LIB.BASEBOARD_FAB2(SCH_1):M_B_ODT(1)   I111 @BASEBOARD_FAB2_LIB.BASEBOARD_FAB2(SCH_1):PAGE45
    87 M_B_ODT<0> @BASEBOARD_FAB2_LIB.BASEBOARD_FAB2(SCH_1):M_B_ODT(0)   I111 @BASEBOARD_FAB2_LIB.BASEBOARD_FAB2(SCH_1):PAGE45
   222 M_B_PAR @BASEBOARD_FAB2_LIB.BASEBOARD_FAB2(SCH_1):M_B_PAR   I111 @BASEBOARD_FAB2_LIB.BASEBOARD_FAB2(SCH_1):PAGE45
    58 M_ABC_RST_N @BASEBOARD_FAB2_LIB.BASEBOARD_FAB2(SCH_1):M_ABC_RST_N   I111 @BASEBOARD_FAB2_LIB.BASEBOARD_FAB2(SCH_1):PAGE45
   144 TP_CH_B_DIMM_B0_RFU_2 @BASEBOARD_FAB2_LIB.BASEBOARD_FAB2(SCH_1):TP_CH_B_DIMM_B0_RFU_2   I111 @BASEBOARD_FAB2_LIB.BASEBOARD_FAB2(SCH_1):PAGE45
   227 TP_CH_B_DIMM_B0_RFU_1 @BASEBOARD_FAB2_LIB.BASEBOARD_FAB2(SCH_1):TP_CH_B_DIMM_B0_RFU_1   I111 @BASEBOARD_FAB2_LIB.BASEBOARD_FAB2(SCH_1):PAGE45
   205 TP_CH_B_DIMM_B0_RFU_0 @BASEBOARD_FAB2_LIB.BASEBOARD_FAB2(SCH_1):TP_CH_B_DIMM_B0_RFU_0   I111 @BASEBOARD_FAB2_LIB.BASEBOARD_FAB2(SCH_1):PAGE45
    84 M_B_CS_N<0> @BASEBOARD_FAB2_LIB.BASEBOARD_FAB2(SCH_1):M_B_CS_N(0)   I111 @BASEBOARD_FAB2_LIB.BASEBOARD_FAB2(SCH_1):PAGE45
    89 M_B_CS_N<1> @BASEBOARD_FAB2_LIB.BASEBOARD_FAB2(SCH_1):M_B_CS_N(1)   I111 @BASEBOARD_FAB2_LIB.BASEBOARD_FAB2(SCH_1):PAGE45
    93 M_B_CS_N<2> @BASEBOARD_FAB2_LIB.BASEBOARD_FAB2(SCH_1):M_B_CS_N(2)   I111 @BASEBOARD_FAB2_LIB.BASEBOARD_FAB2(SCH_1):PAGE45
   237 M_B_CS_N<3> @BASEBOARD_FAB2_LIB.BASEBOARD_FAB2(SCH_1):M_B_CS_N(3)   I111 @BASEBOARD_FAB2_LIB.BASEBOARD_FAB2(SCH_1):PAGE45
   238    GND @BASEBOARD_FAB2_LIB.BASEBOARD_FAB2(SCH_1):GND   I111 @BASEBOARD_FAB2_LIB.BASEBOARD_FAB2(SCH_1):PAGE45
   140 PVPP_ABC @BASEBOARD_FAB2_LIB.BASEBOARD_FAB2(SCH_1):PVPP_ABC   I111 @BASEBOARD_FAB2_LIB.BASEBOARD_FAB2(SCH_1):PAGE45
   139    GND @BASEBOARD_FAB2_LIB.BASEBOARD_FAB2(SCH_1):GND   I111 @BASEBOARD_FAB2_LIB.BASEBOARD_FAB2(SCH_1):PAGE45
   230 FM_ADR_COMPLETE_ABC_N @BASEBOARD_FAB2_LIB.BASEBOARD_FAB2(SCH_1):FM_ADR_COMPLETE_ABC_N   I111 @BASEBOARD_FAB2_LIB.BASEBOARD_FAB2(SCH_1):PAGE45
   141 SMB_DDR_ABC_VPP_SCL @BASEBOARD_FAB2_LIB.BASEBOARD_FAB2(SCH_1):SMB_DDR_ABC_VPP_SCL   I111 @BASEBOARD_FAB2_LIB.BASEBOARD_FAB2(SCH_1):PAGE45
   285 SMB_DDR_ABC_VPP_SDA @BASEBOARD_FAB2_LIB.BASEBOARD_FAB2(SCH_1):SMB_DDR_ABC_VPP_SDA   I111 @BASEBOARD_FAB2_LIB.BASEBOARD_FAB2(SCH_1):PAGE45
   284 PVPP_ABC @BASEBOARD_FAB2_LIB.BASEBOARD_FAB2(SCH_1):PVPP_ABC   I111 @BASEBOARD_FAB2_LIB.BASEBOARD_FAB2(SCH_1):PAGE45
   146 M_B_VREF @BASEBOARD_FAB2_LIB.BASEBOARD_FAB2(SCH_1):M_B_VREF   I111 @BASEBOARD_FAB2_LIB.BASEBOARD_FAB2(SCH_1):PAGE45
   152 M_B_DQS_DN<0> @BASEBOARD_FAB2_LIB.BASEBOARD_FAB2(SCH_1):M_B_DQS_DN(0)    I61 @BASEBOARD_FAB2_LIB.BASEBOARD_FAB2(SCH_1):PAGE45
   153 M_B_DQS_DP<0> @BASEBOARD_FAB2_LIB.BASEBOARD_FAB2(SCH_1):M_B_DQS_DP(0)    I61 @BASEBOARD_FAB2_LIB.BASEBOARD_FAB2(SCH_1):PAGE45
    19 M_B_DQS_DN<10> @BASEBOARD_FAB2_LIB.BASEBOARD_FAB2(SCH_1):M_B_DQS_DN(10)    I61 @BASEBOARD_FAB2_LIB.BASEBOARD_FAB2(SCH_1):PAGE45
    18 M_B_DQS_DP<10> @BASEBOARD_FAB2_LIB.BASEBOARD_FAB2(SCH_1):M_B_DQS_DP(10)    I61 @BASEBOARD_FAB2_LIB.BASEBOARD_FAB2(SCH_1):PAGE45
    30 M_B_DQS_DN<11> @BASEBOARD_FAB2_LIB.BASEBOARD_FAB2(SCH_1):M_B_DQS_DN(11)    I61 @BASEBOARD_FAB2_LIB.BASEBOARD_FAB2(SCH_1):PAGE45
    29 M_B_DQS_DP<11> @BASEBOARD_FAB2_LIB.BASEBOARD_FAB2(SCH_1):M_B_DQS_DP(11)    I61 @BASEBOARD_FAB2_LIB.BASEBOARD_FAB2(SCH_1):PAGE45
    41 M_B_DQS_DN<12> @BASEBOARD_FAB2_LIB.BASEBOARD_FAB2(SCH_1):M_B_DQS_DN(12)    I61 @BASEBOARD_FAB2_LIB.BASEBOARD_FAB2(SCH_1):PAGE45
    40 M_B_DQS_DP<12> @BASEBOARD_FAB2_LIB.BASEBOARD_FAB2(SCH_1):M_B_DQS_DP(12)    I61 @BASEBOARD_FAB2_LIB.BASEBOARD_FAB2(SCH_1):PAGE45
   100 M_B_DQS_DN<13> @BASEBOARD_FAB2_LIB.BASEBOARD_FAB2(SCH_1):M_B_DQS_DN(13)    I61 @BASEBOARD_FAB2_LIB.BASEBOARD_FAB2(SCH_1):PAGE45
    99 M_B_DQS_DP<13> @BASEBOARD_FAB2_LIB.BASEBOARD_FAB2(SCH_1):M_B_DQS_DP(13)    I61 @BASEBOARD_FAB2_LIB.BASEBOARD_FAB2(SCH_1):PAGE45
   111 M_B_DQS_DN<14> @BASEBOARD_FAB2_LIB.BASEBOARD_FAB2(SCH_1):M_B_DQS_DN(14)    I61 @BASEBOARD_FAB2_LIB.BASEBOARD_FAB2(SCH_1):PAGE45
   110 M_B_DQS_DP<14> @BASEBOARD_FAB2_LIB.BASEBOARD_FAB2(SCH_1):M_B_DQS_DP(14)    I61 @BASEBOARD_FAB2_LIB.BASEBOARD_FAB2(SCH_1):PAGE45
   122 M_B_DQS_DN<15> @BASEBOARD_FAB2_LIB.BASEBOARD_FAB2(SCH_1):M_B_DQS_DN(15)    I61 @BASEBOARD_FAB2_LIB.BASEBOARD_FAB2(SCH_1):PAGE45
   121 M_B_DQS_DP<15> @BASEBOARD_FAB2_LIB.BASEBOARD_FAB2(SCH_1):M_B_DQS_DP(15)    I61 @BASEBOARD_FAB2_LIB.BASEBOARD_FAB2(SCH_1):PAGE45
   133 M_B_DQS_DN<16> @BASEBOARD_FAB2_LIB.BASEBOARD_FAB2(SCH_1):M_B_DQS_DN(16)    I61 @BASEBOARD_FAB2_LIB.BASEBOARD_FAB2(SCH_1):PAGE45
   132 M_B_DQS_DP<16> @BASEBOARD_FAB2_LIB.BASEBOARD_FAB2(SCH_1):M_B_DQS_DP(16)    I61 @BASEBOARD_FAB2_LIB.BASEBOARD_FAB2(SCH_1):PAGE45
    52 M_B_DQS_DN<17> @BASEBOARD_FAB2_LIB.BASEBOARD_FAB2(SCH_1):M_B_DQS_DN(17)    I61 @BASEBOARD_FAB2_LIB.BASEBOARD_FAB2(SCH_1):PAGE45
    51 M_B_DQS_DP<17> @BASEBOARD_FAB2_LIB.BASEBOARD_FAB2(SCH_1):M_B_DQS_DP(17)    I61 @BASEBOARD_FAB2_LIB.BASEBOARD_FAB2(SCH_1):PAGE45
   163 M_B_DQS_DN<1> @BASEBOARD_FAB2_LIB.BASEBOARD_FAB2(SCH_1):M_B_DQS_DN(1)    I61 @BASEBOARD_FAB2_LIB.BASEBOARD_FAB2(SCH_1):PAGE45
   164 M_B_DQS_DP<1> @BASEBOARD_FAB2_LIB.BASEBOARD_FAB2(SCH_1):M_B_DQS_DP(1)    I61 @BASEBOARD_FAB2_LIB.BASEBOARD_FAB2(SCH_1):PAGE45
   174 M_B_DQS_DN<2> @BASEBOARD_FAB2_LIB.BASEBOARD_FAB2(SCH_1):M_B_DQS_DN(2)    I61 @BASEBOARD_FAB2_LIB.BASEBOARD_FAB2(SCH_1):PAGE45
   175 M_B_DQS_DP<2> @BASEBOARD_FAB2_LIB.BASEBOARD_FAB2(SCH_1):M_B_DQS_DP(2)    I61 @BASEBOARD_FAB2_LIB.BASEBOARD_FAB2(SCH_1):PAGE45
   185 M_B_DQS_DN<3> @BASEBOARD_FAB2_LIB.BASEBOARD_FAB2(SCH_1):M_B_DQS_DN(3)    I61 @BASEBOARD_FAB2_LIB.BASEBOARD_FAB2(SCH_1):PAGE45
   186 M_B_DQS_DP<3> @BASEBOARD_FAB2_LIB.BASEBOARD_FAB2(SCH_1):M_B_DQS_DP(3)    I61 @BASEBOARD_FAB2_LIB.BASEBOARD_FAB2(SCH_1):PAGE45
   244 M_B_DQS_DN<4> @BASEBOARD_FAB2_LIB.BASEBOARD_FAB2(SCH_1):M_B_DQS_DN(4)    I61 @BASEBOARD_FAB2_LIB.BASEBOARD_FAB2(SCH_1):PAGE45
   245 M_B_DQS_DP<4> @BASEBOARD_FAB2_LIB.BASEBOARD_FAB2(SCH_1):M_B_DQS_DP(4)    I61 @BASEBOARD_FAB2_LIB.BASEBOARD_FAB2(SCH_1):PAGE45
   255 M_B_DQS_DN<5> @BASEBOARD_FAB2_LIB.BASEBOARD_FAB2(SCH_1):M_B_DQS_DN(5)    I61 @BASEBOARD_FAB2_LIB.BASEBOARD_FAB2(SCH_1):PAGE45
   256 M_B_DQS_DP<5> @BASEBOARD_FAB2_LIB.BASEBOARD_FAB2(SCH_1):M_B_DQS_DP(5)    I61 @BASEBOARD_FAB2_LIB.BASEBOARD_FAB2(SCH_1):PAGE45
   266 M_B_DQS_DN<6> @BASEBOARD_FAB2_LIB.BASEBOARD_FAB2(SCH_1):M_B_DQS_DN(6)    I61 @BASEBOARD_FAB2_LIB.BASEBOARD_FAB2(SCH_1):PAGE45
   267 M_B_DQS_DP<6> @BASEBOARD_FAB2_LIB.BASEBOARD_FAB2(SCH_1):M_B_DQS_DP(6)    I61 @BASEBOARD_FAB2_LIB.BASEBOARD_FAB2(SCH_1):PAGE45
   277 M_B_DQS_DN<7> @BASEBOARD_FAB2_LIB.BASEBOARD_FAB2(SCH_1):M_B_DQS_DN(7)    I61 @BASEBOARD_FAB2_LIB.BASEBOARD_FAB2(SCH_1):PAGE45
   278 M_B_DQS_DP<7> @BASEBOARD_FAB2_LIB.BASEBOARD_FAB2(SCH_1):M_B_DQS_DP(7)    I61 @BASEBOARD_FAB2_LIB.BASEBOARD_FAB2(SCH_1):PAGE45
   196 M_B_DQS_DN<8> @BASEBOARD_FAB2_LIB.BASEBOARD_FAB2(SCH_1):M_B_DQS_DN(8)    I61 @BASEBOARD_FAB2_LIB.BASEBOARD_FAB2(SCH_1):PAGE45
   197 M_B_DQS_DP<8> @BASEBOARD_FAB2_LIB.BASEBOARD_FAB2(SCH_1):M_B_DQS_DP(8)    I61 @BASEBOARD_FAB2_LIB.BASEBOARD_FAB2(SCH_1):PAGE45
     8 M_B_DQS_DN<9> @BASEBOARD_FAB2_LIB.BASEBOARD_FAB2(SCH_1):M_B_DQS_DN(9)    I61 @BASEBOARD_FAB2_LIB.BASEBOARD_FAB2(SCH_1):PAGE45
     7 M_B_DQS_DP<9> @BASEBOARD_FAB2_LIB.BASEBOARD_FAB2(SCH_1):M_B_DQS_DP(9)    I61 @BASEBOARD_FAB2_LIB.BASEBOARD_FAB2(SCH_1):PAGE45
     2    GND @BASEBOARD_FAB2_LIB.BASEBOARD_FAB2(SCH_1):GND    I43 @BASEBOARD_FAB2_LIB.BASEBOARD_FAB2(SCH_1):PAGE45
     4    GND @BASEBOARD_FAB2_LIB.BASEBOARD_FAB2(SCH_1):GND    I43 @BASEBOARD_FAB2_LIB.BASEBOARD_FAB2(SCH_1):PAGE45
     6    GND @BASEBOARD_FAB2_LIB.BASEBOARD_FAB2(SCH_1):GND    I43 @BASEBOARD_FAB2_LIB.BASEBOARD_FAB2(SCH_1):PAGE45
     9    GND @BASEBOARD_FAB2_LIB.BASEBOARD_FAB2(SCH_1):GND    I43 @BASEBOARD_FAB2_LIB.BASEBOARD_FAB2(SCH_1):PAGE45
    11    GND @BASEBOARD_FAB2_LIB.BASEBOARD_FAB2(SCH_1):GND    I43 @BASEBOARD_FAB2_LIB.BASEBOARD_FAB2(SCH_1):PAGE45
    13    GND @BASEBOARD_FAB2_LIB.BASEBOARD_FAB2(SCH_1):GND    I43 @BASEBOARD_FAB2_LIB.BASEBOARD_FAB2(SCH_1):PAGE45
    15    GND @BASEBOARD_FAB2_LIB.BASEBOARD_FAB2(SCH_1):GND    I43 @BASEBOARD_FAB2_LIB.BASEBOARD_FAB2(SCH_1):PAGE45
    17    GND @BASEBOARD_FAB2_LIB.BASEBOARD_FAB2(SCH_1):GND    I43 @BASEBOARD_FAB2_LIB.BASEBOARD_FAB2(SCH_1):PAGE45
    20    GND @BASEBOARD_FAB2_LIB.BASEBOARD_FAB2(SCH_1):GND    I43 @BASEBOARD_FAB2_LIB.BASEBOARD_FAB2(SCH_1):PAGE45
    22    GND @BASEBOARD_FAB2_LIB.BASEBOARD_FAB2(SCH_1):GND    I43 @BASEBOARD_FAB2_LIB.BASEBOARD_FAB2(SCH_1):PAGE45
    24    GND @BASEBOARD_FAB2_LIB.BASEBOARD_FAB2(SCH_1):GND    I43 @BASEBOARD_FAB2_LIB.BASEBOARD_FAB2(SCH_1):PAGE45
    26    GND @BASEBOARD_FAB2_LIB.BASEBOARD_FAB2(SCH_1):GND    I43 @BASEBOARD_FAB2_LIB.BASEBOARD_FAB2(SCH_1):PAGE45
    28    GND @BASEBOARD_FAB2_LIB.BASEBOARD_FAB2(SCH_1):GND    I43 @BASEBOARD_FAB2_LIB.BASEBOARD_FAB2(SCH_1):PAGE45
    31    GND @BASEBOARD_FAB2_LIB.BASEBOARD_FAB2(SCH_1):GND    I43 @BASEBOARD_FAB2_LIB.BASEBOARD_FAB2(SCH_1):PAGE45
    33    GND @BASEBOARD_FAB2_LIB.BASEBOARD_FAB2(SCH_1):GND    I43 @BASEBOARD_FAB2_LIB.BASEBOARD_FAB2(SCH_1):PAGE45
    35    GND @BASEBOARD_FAB2_LIB.BASEBOARD_FAB2(SCH_1):GND    I43 @BASEBOARD_FAB2_LIB.BASEBOARD_FAB2(SCH_1):PAGE45
    37    GND @BASEBOARD_FAB2_LIB.BASEBOARD_FAB2(SCH_1):GND    I43 @BASEBOARD_FAB2_LIB.BASEBOARD_FAB2(SCH_1):PAGE45
    39    GND @BASEBOARD_FAB2_LIB.BASEBOARD_FAB2(SCH_1):GND    I43 @BASEBOARD_FAB2_LIB.BASEBOARD_FAB2(SCH_1):PAGE45
    42    GND @BASEBOARD_FAB2_LIB.BASEBOARD_FAB2(SCH_1):GND    I43 @BASEBOARD_FAB2_LIB.BASEBOARD_FAB2(SCH_1):PAGE45
    44    GND @BASEBOARD_FAB2_LIB.BASEBOARD_FAB2(SCH_1):GND    I43 @BASEBOARD_FAB2_LIB.BASEBOARD_FAB2(SCH_1):PAGE45
    46    GND @BASEBOARD_FAB2_LIB.BASEBOARD_FAB2(SCH_1):GND    I43 @BASEBOARD_FAB2_LIB.BASEBOARD_FAB2(SCH_1):PAGE45
    48    GND @BASEBOARD_FAB2_LIB.BASEBOARD_FAB2(SCH_1):GND    I43 @BASEBOARD_FAB2_LIB.BASEBOARD_FAB2(SCH_1):PAGE45
    50    GND @BASEBOARD_FAB2_LIB.BASEBOARD_FAB2(SCH_1):GND    I43 @BASEBOARD_FAB2_LIB.BASEBOARD_FAB2(SCH_1):PAGE45
    53    GND @BASEBOARD_FAB2_LIB.BASEBOARD_FAB2(SCH_1):GND    I43 @BASEBOARD_FAB2_LIB.BASEBOARD_FAB2(SCH_1):PAGE45
    55    GND @BASEBOARD_FAB2_LIB.BASEBOARD_FAB2(SCH_1):GND    I43 @BASEBOARD_FAB2_LIB.BASEBOARD_FAB2(SCH_1):PAGE45
    57    GND @BASEBOARD_FAB2_LIB.BASEBOARD_FAB2(SCH_1):GND    I43 @BASEBOARD_FAB2_LIB.BASEBOARD_FAB2(SCH_1):PAGE45
    94    GND @BASEBOARD_FAB2_LIB.BASEBOARD_FAB2(SCH_1):GND    I43 @BASEBOARD_FAB2_LIB.BASEBOARD_FAB2(SCH_1):PAGE45
    96    GND @BASEBOARD_FAB2_LIB.BASEBOARD_FAB2(SCH_1):GND    I43 @BASEBOARD_FAB2_LIB.BASEBOARD_FAB2(SCH_1):PAGE45
    98    GND @BASEBOARD_FAB2_LIB.BASEBOARD_FAB2(SCH_1):GND    I43 @BASEBOARD_FAB2_LIB.BASEBOARD_FAB2(SCH_1):PAGE45
   101    GND @BASEBOARD_FAB2_LIB.BASEBOARD_FAB2(SCH_1):GND    I43 @BASEBOARD_FAB2_LIB.BASEBOARD_FAB2(SCH_1):PAGE45
   103    GND @BASEBOARD_FAB2_LIB.BASEBOARD_FAB2(SCH_1):GND    I43 @BASEBOARD_FAB2_LIB.BASEBOARD_FAB2(SCH_1):PAGE45
   105    GND @BASEBOARD_FAB2_LIB.BASEBOARD_FAB2(SCH_1):GND    I43 @BASEBOARD_FAB2_LIB.BASEBOARD_FAB2(SCH_1):PAGE45
   107    GND @BASEBOARD_FAB2_LIB.BASEBOARD_FAB2(SCH_1):GND    I43 @BASEBOARD_FAB2_LIB.BASEBOARD_FAB2(SCH_1):PAGE45
   109    GND @BASEBOARD_FAB2_LIB.BASEBOARD_FAB2(SCH_1):GND    I43 @BASEBOARD_FAB2_LIB.BASEBOARD_FAB2(SCH_1):PAGE45
   112    GND @BASEBOARD_FAB2_LIB.BASEBOARD_FAB2(SCH_1):GND    I43 @BASEBOARD_FAB2_LIB.BASEBOARD_FAB2(SCH_1):PAGE45
   114    GND @BASEBOARD_FAB2_LIB.BASEBOARD_FAB2(SCH_1):GND    I43 @BASEBOARD_FAB2_LIB.BASEBOARD_FAB2(SCH_1):PAGE45
   116    GND @BASEBOARD_FAB2_LIB.BASEBOARD_FAB2(SCH_1):GND    I43 @BASEBOARD_FAB2_LIB.BASEBOARD_FAB2(SCH_1):PAGE45
   118    GND @BASEBOARD_FAB2_LIB.BASEBOARD_FAB2(SCH_1):GND    I43 @BASEBOARD_FAB2_LIB.BASEBOARD_FAB2(SCH_1):PAGE45
   120    GND @BASEBOARD_FAB2_LIB.BASEBOARD_FAB2(SCH_1):GND    I43 @BASEBOARD_FAB2_LIB.BASEBOARD_FAB2(SCH_1):PAGE45
   123    GND @BASEBOARD_FAB2_LIB.BASEBOARD_FAB2(SCH_1):GND    I43 @BASEBOARD_FAB2_LIB.BASEBOARD_FAB2(SCH_1):PAGE45
   125    GND @BASEBOARD_FAB2_LIB.BASEBOARD_FAB2(SCH_1):GND    I43 @BASEBOARD_FAB2_LIB.BASEBOARD_FAB2(SCH_1):PAGE45
   127    GND @BASEBOARD_FAB2_LIB.BASEBOARD_FAB2(SCH_1):GND    I43 @BASEBOARD_FAB2_LIB.BASEBOARD_FAB2(SCH_1):PAGE45
   129    GND @BASEBOARD_FAB2_LIB.BASEBOARD_FAB2(SCH_1):GND    I43 @BASEBOARD_FAB2_LIB.BASEBOARD_FAB2(SCH_1):PAGE45
   131    GND @BASEBOARD_FAB2_LIB.BASEBOARD_FAB2(SCH_1):GND    I43 @BASEBOARD_FAB2_LIB.BASEBOARD_FAB2(SCH_1):PAGE45
   134    GND @BASEBOARD_FAB2_LIB.BASEBOARD_FAB2(SCH_1):GND    I43 @BASEBOARD_FAB2_LIB.BASEBOARD_FAB2(SCH_1):PAGE45
   136    GND @BASEBOARD_FAB2_LIB.BASEBOARD_FAB2(SCH_1):GND    I43 @BASEBOARD_FAB2_LIB.BASEBOARD_FAB2(SCH_1):PAGE45
   138    GND @BASEBOARD_FAB2_LIB.BASEBOARD_FAB2(SCH_1):GND    I43 @BASEBOARD_FAB2_LIB.BASEBOARD_FAB2(SCH_1):PAGE45
   147    GND @BASEBOARD_FAB2_LIB.BASEBOARD_FAB2(SCH_1):GND    I43 @BASEBOARD_FAB2_LIB.BASEBOARD_FAB2(SCH_1):PAGE45
   149    GND @BASEBOARD_FAB2_LIB.BASEBOARD_FAB2(SCH_1):GND    I43 @BASEBOARD_FAB2_LIB.BASEBOARD_FAB2(SCH_1):PAGE45
   151    GND @BASEBOARD_FAB2_LIB.BASEBOARD_FAB2(SCH_1):GND    I43 @BASEBOARD_FAB2_LIB.BASEBOARD_FAB2(SCH_1):PAGE45
   154    GND @BASEBOARD_FAB2_LIB.BASEBOARD_FAB2(SCH_1):GND    I43 @BASEBOARD_FAB2_LIB.BASEBOARD_FAB2(SCH_1):PAGE45
   156    GND @BASEBOARD_FAB2_LIB.BASEBOARD_FAB2(SCH_1):GND    I43 @BASEBOARD_FAB2_LIB.BASEBOARD_FAB2(SCH_1):PAGE45
   158    GND @BASEBOARD_FAB2_LIB.BASEBOARD_FAB2(SCH_1):GND    I43 @BASEBOARD_FAB2_LIB.BASEBOARD_FAB2(SCH_1):PAGE45
   160    GND @BASEBOARD_FAB2_LIB.BASEBOARD_FAB2(SCH_1):GND    I43 @BASEBOARD_FAB2_LIB.BASEBOARD_FAB2(SCH_1):PAGE45
   162    GND @BASEBOARD_FAB2_LIB.BASEBOARD_FAB2(SCH_1):GND    I43 @BASEBOARD_FAB2_LIB.BASEBOARD_FAB2(SCH_1):PAGE45
   165    GND @BASEBOARD_FAB2_LIB.BASEBOARD_FAB2(SCH_1):GND    I43 @BASEBOARD_FAB2_LIB.BASEBOARD_FAB2(SCH_1):PAGE45
   167    GND @BASEBOARD_FAB2_LIB.BASEBOARD_FAB2(SCH_1):GND    I43 @BASEBOARD_FAB2_LIB.BASEBOARD_FAB2(SCH_1):PAGE45
   169    GND @BASEBOARD_FAB2_LIB.BASEBOARD_FAB2(SCH_1):GND    I43 @BASEBOARD_FAB2_LIB.BASEBOARD_FAB2(SCH_1):PAGE45
   171    GND @BASEBOARD_FAB2_LIB.BASEBOARD_FAB2(SCH_1):GND    I43 @BASEBOARD_FAB2_LIB.BASEBOARD_FAB2(SCH_1):PAGE45
   173    GND @BASEBOARD_FAB2_LIB.BASEBOARD_FAB2(SCH_1):GND    I43 @BASEBOARD_FAB2_LIB.BASEBOARD_FAB2(SCH_1):PAGE45
   176    GND @BASEBOARD_FAB2_LIB.BASEBOARD_FAB2(SCH_1):GND    I43 @BASEBOARD_FAB2_LIB.BASEBOARD_FAB2(SCH_1):PAGE45
   178    GND @BASEBOARD_FAB2_LIB.BASEBOARD_FAB2(SCH_1):GND    I43 @BASEBOARD_FAB2_LIB.BASEBOARD_FAB2(SCH_1):PAGE45
   180    GND @BASEBOARD_FAB2_LIB.BASEBOARD_FAB2(SCH_1):GND    I43 @BASEBOARD_FAB2_LIB.BASEBOARD_FAB2(SCH_1):PAGE45
   182    GND @BASEBOARD_FAB2_LIB.BASEBOARD_FAB2(SCH_1):GND    I43 @BASEBOARD_FAB2_LIB.BASEBOARD_FAB2(SCH_1):PAGE45
   184    GND @BASEBOARD_FAB2_LIB.BASEBOARD_FAB2(SCH_1):GND    I43 @BASEBOARD_FAB2_LIB.BASEBOARD_FAB2(SCH_1):PAGE45
   187    GND @BASEBOARD_FAB2_LIB.BASEBOARD_FAB2(SCH_1):GND    I43 @BASEBOARD_FAB2_LIB.BASEBOARD_FAB2(SCH_1):PAGE45
   189    GND @BASEBOARD_FAB2_LIB.BASEBOARD_FAB2(SCH_1):GND    I43 @BASEBOARD_FAB2_LIB.BASEBOARD_FAB2(SCH_1):PAGE45
   191    GND @BASEBOARD_FAB2_LIB.BASEBOARD_FAB2(SCH_1):GND    I43 @BASEBOARD_FAB2_LIB.BASEBOARD_FAB2(SCH_1):PAGE45
   193    GND @BASEBOARD_FAB2_LIB.BASEBOARD_FAB2(SCH_1):GND    I43 @BASEBOARD_FAB2_LIB.BASEBOARD_FAB2(SCH_1):PAGE45
   195    GND @BASEBOARD_FAB2_LIB.BASEBOARD_FAB2(SCH_1):GND    I43 @BASEBOARD_FAB2_LIB.BASEBOARD_FAB2(SCH_1):PAGE45
   198    GND @BASEBOARD_FAB2_LIB.BASEBOARD_FAB2(SCH_1):GND    I43 @BASEBOARD_FAB2_LIB.BASEBOARD_FAB2(SCH_1):PAGE45
   200    GND @BASEBOARD_FAB2_LIB.BASEBOARD_FAB2(SCH_1):GND    I43 @BASEBOARD_FAB2_LIB.BASEBOARD_FAB2(SCH_1):PAGE45
   202    GND @BASEBOARD_FAB2_LIB.BASEBOARD_FAB2(SCH_1):GND    I43 @BASEBOARD_FAB2_LIB.BASEBOARD_FAB2(SCH_1):PAGE45
   239    GND @BASEBOARD_FAB2_LIB.BASEBOARD_FAB2(SCH_1):GND    I43 @BASEBOARD_FAB2_LIB.BASEBOARD_FAB2(SCH_1):PAGE45
   241    GND @BASEBOARD_FAB2_LIB.BASEBOARD_FAB2(SCH_1):GND    I43 @BASEBOARD_FAB2_LIB.BASEBOARD_FAB2(SCH_1):PAGE45
   243    GND @BASEBOARD_FAB2_LIB.BASEBOARD_FAB2(SCH_1):GND    I43 @BASEBOARD_FAB2_LIB.BASEBOARD_FAB2(SCH_1):PAGE45
   246    GND @BASEBOARD_FAB2_LIB.BASEBOARD_FAB2(SCH_1):GND    I43 @BASEBOARD_FAB2_LIB.BASEBOARD_FAB2(SCH_1):PAGE45
   248    GND @BASEBOARD_FAB2_LIB.BASEBOARD_FAB2(SCH_1):GND    I43 @BASEBOARD_FAB2_LIB.BASEBOARD_FAB2(SCH_1):PAGE45
   250    GND @BASEBOARD_FAB2_LIB.BASEBOARD_FAB2(SCH_1):GND    I43 @BASEBOARD_FAB2_LIB.BASEBOARD_FAB2(SCH_1):PAGE45
   252    GND @BASEBOARD_FAB2_LIB.BASEBOARD_FAB2(SCH_1):GND    I43 @BASEBOARD_FAB2_LIB.BASEBOARD_FAB2(SCH_1):PAGE45
   254    GND @BASEBOARD_FAB2_LIB.BASEBOARD_FAB2(SCH_1):GND    I43 @BASEBOARD_FAB2_LIB.BASEBOARD_FAB2(SCH_1):PAGE45
   257    GND @BASEBOARD_FAB2_LIB.BASEBOARD_FAB2(SCH_1):GND    I43 @BASEBOARD_FAB2_LIB.BASEBOARD_FAB2(SCH_1):PAGE45
   259    GND @BASEBOARD_FAB2_LIB.BASEBOARD_FAB2(SCH_1):GND    I43 @BASEBOARD_FAB2_LIB.BASEBOARD_FAB2(SCH_1):PAGE45
   261    GND @BASEBOARD_FAB2_LIB.BASEBOARD_FAB2(SCH_1):GND    I43 @BASEBOARD_FAB2_LIB.BASEBOARD_FAB2(SCH_1):PAGE45
   263    GND @BASEBOARD_FAB2_LIB.BASEBOARD_FAB2(SCH_1):GND    I43 @BASEBOARD_FAB2_LIB.BASEBOARD_FAB2(SCH_1):PAGE45
   265    GND @BASEBOARD_FAB2_LIB.BASEBOARD_FAB2(SCH_1):GND    I43 @BASEBOARD_FAB2_LIB.BASEBOARD_FAB2(SCH_1):PAGE45
   268    GND @BASEBOARD_FAB2_LIB.BASEBOARD_FAB2(SCH_1):GND    I43 @BASEBOARD_FAB2_LIB.BASEBOARD_FAB2(SCH_1):PAGE45
   270    GND @BASEBOARD_FAB2_LIB.BASEBOARD_FAB2(SCH_1):GND    I43 @BASEBOARD_FAB2_LIB.BASEBOARD_FAB2(SCH_1):PAGE45
   272    GND @BASEBOARD_FAB2_LIB.BASEBOARD_FAB2(SCH_1):GND    I43 @BASEBOARD_FAB2_LIB.BASEBOARD_FAB2(SCH_1):PAGE45
   274    GND @BASEBOARD_FAB2_LIB.BASEBOARD_FAB2(SCH_1):GND    I43 @BASEBOARD_FAB2_LIB.BASEBOARD_FAB2(SCH_1):PAGE45
   276    GND @BASEBOARD_FAB2_LIB.BASEBOARD_FAB2(SCH_1):GND    I43 @BASEBOARD_FAB2_LIB.BASEBOARD_FAB2(SCH_1):PAGE45
   279    GND @BASEBOARD_FAB2_LIB.BASEBOARD_FAB2(SCH_1):GND    I43 @BASEBOARD_FAB2_LIB.BASEBOARD_FAB2(SCH_1):PAGE45
   281    GND @BASEBOARD_FAB2_LIB.BASEBOARD_FAB2(SCH_1):GND    I43 @BASEBOARD_FAB2_LIB.BASEBOARD_FAB2(SCH_1):PAGE45
   283    GND @BASEBOARD_FAB2_LIB.BASEBOARD_FAB2(SCH_1):GND    I43 @BASEBOARD_FAB2_LIB.BASEBOARD_FAB2(SCH_1):PAGE45
     1 P12V_NVDIMM_ABC @BASEBOARD_FAB2_LIB.BASEBOARD_FAB2(SCH_1):P12V_NVDIMM_ABC   I169 @BASEBOARD_FAB2_LIB.BASEBOARD_FAB2(SCH_1):PAGE45
   145 P12V_NVDIMM_ABC @BASEBOARD_FAB2_LIB.BASEBOARD_FAB2(SCH_1):P12V_NVDIMM_ABC   I169 @BASEBOARD_FAB2_LIB.BASEBOARD_FAB2(SCH_1):PAGE45
    59 PVDDQ_ABC @BASEBOARD_FAB2_LIB.BASEBOARD_FAB2(SCH_1):PVDDQ_ABC   I169 @BASEBOARD_FAB2_LIB.BASEBOARD_FAB2(SCH_1):PAGE45
    61 PVDDQ_ABC @BASEBOARD_FAB2_LIB.BASEBOARD_FAB2(SCH_1):PVDDQ_ABC   I169 @BASEBOARD_FAB2_LIB.BASEBOARD_FAB2(SCH_1):PAGE45
    64 PVDDQ_ABC @BASEBOARD_FAB2_LIB.BASEBOARD_FAB2(SCH_1):PVDDQ_ABC   I169 @BASEBOARD_FAB2_LIB.BASEBOARD_FAB2(SCH_1):PAGE45
    67 PVDDQ_ABC @BASEBOARD_FAB2_LIB.BASEBOARD_FAB2(SCH_1):PVDDQ_ABC   I169 @BASEBOARD_FAB2_LIB.BASEBOARD_FAB2(SCH_1):PAGE45
    70 PVDDQ_ABC @BASEBOARD_FAB2_LIB.BASEBOARD_FAB2(SCH_1):PVDDQ_ABC   I169 @BASEBOARD_FAB2_LIB.BASEBOARD_FAB2(SCH_1):PAGE45
    73 PVDDQ_ABC @BASEBOARD_FAB2_LIB.BASEBOARD_FAB2(SCH_1):PVDDQ_ABC   I169 @BASEBOARD_FAB2_LIB.BASEBOARD_FAB2(SCH_1):PAGE45
    76 PVDDQ_ABC @BASEBOARD_FAB2_LIB.BASEBOARD_FAB2(SCH_1):PVDDQ_ABC   I169 @BASEBOARD_FAB2_LIB.BASEBOARD_FAB2(SCH_1):PAGE45
    80 PVDDQ_ABC @BASEBOARD_FAB2_LIB.BASEBOARD_FAB2(SCH_1):PVDDQ_ABC   I169 @BASEBOARD_FAB2_LIB.BASEBOARD_FAB2(SCH_1):PAGE45
    83 PVDDQ_ABC @BASEBOARD_FAB2_LIB.BASEBOARD_FAB2(SCH_1):PVDDQ_ABC   I169 @BASEBOARD_FAB2_LIB.BASEBOARD_FAB2(SCH_1):PAGE45
    85 PVDDQ_ABC @BASEBOARD_FAB2_LIB.BASEBOARD_FAB2(SCH_1):PVDDQ_ABC   I169 @BASEBOARD_FAB2_LIB.BASEBOARD_FAB2(SCH_1):PAGE45
    88 PVDDQ_ABC @BASEBOARD_FAB2_LIB.BASEBOARD_FAB2(SCH_1):PVDDQ_ABC   I169 @BASEBOARD_FAB2_LIB.BASEBOARD_FAB2(SCH_1):PAGE45
    90 PVDDQ_ABC @BASEBOARD_FAB2_LIB.BASEBOARD_FAB2(SCH_1):PVDDQ_ABC   I169 @BASEBOARD_FAB2_LIB.BASEBOARD_FAB2(SCH_1):PAGE45
    92 PVDDQ_ABC @BASEBOARD_FAB2_LIB.BASEBOARD_FAB2(SCH_1):PVDDQ_ABC   I169 @BASEBOARD_FAB2_LIB.BASEBOARD_FAB2(SCH_1):PAGE45
   204 PVDDQ_ABC @BASEBOARD_FAB2_LIB.BASEBOARD_FAB2(SCH_1):PVDDQ_ABC   I169 @BASEBOARD_FAB2_LIB.BASEBOARD_FAB2(SCH_1):PAGE45
   206 PVDDQ_ABC @BASEBOARD_FAB2_LIB.BASEBOARD_FAB2(SCH_1):PVDDQ_ABC   I169 @BASEBOARD_FAB2_LIB.BASEBOARD_FAB2(SCH_1):PAGE45
   209 PVDDQ_ABC @BASEBOARD_FAB2_LIB.BASEBOARD_FAB2(SCH_1):PVDDQ_ABC   I169 @BASEBOARD_FAB2_LIB.BASEBOARD_FAB2(SCH_1):PAGE45
   212 PVDDQ_ABC @BASEBOARD_FAB2_LIB.BASEBOARD_FAB2(SCH_1):PVDDQ_ABC   I169 @BASEBOARD_FAB2_LIB.BASEBOARD_FAB2(SCH_1):PAGE45
   215 PVDDQ_ABC @BASEBOARD_FAB2_LIB.BASEBOARD_FAB2(SCH_1):PVDDQ_ABC   I169 @BASEBOARD_FAB2_LIB.BASEBOARD_FAB2(SCH_1):PAGE45
   217 PVDDQ_ABC @BASEBOARD_FAB2_LIB.BASEBOARD_FAB2(SCH_1):PVDDQ_ABC   I169 @BASEBOARD_FAB2_LIB.BASEBOARD_FAB2(SCH_1):PAGE45
   220 PVDDQ_ABC @BASEBOARD_FAB2_LIB.BASEBOARD_FAB2(SCH_1):PVDDQ_ABC   I169 @BASEBOARD_FAB2_LIB.BASEBOARD_FAB2(SCH_1):PAGE45
   223 PVDDQ_ABC @BASEBOARD_FAB2_LIB.BASEBOARD_FAB2(SCH_1):PVDDQ_ABC   I169 @BASEBOARD_FAB2_LIB.BASEBOARD_FAB2(SCH_1):PAGE45
   226 PVDDQ_ABC @BASEBOARD_FAB2_LIB.BASEBOARD_FAB2(SCH_1):PVDDQ_ABC   I169 @BASEBOARD_FAB2_LIB.BASEBOARD_FAB2(SCH_1):PAGE45
   229 PVDDQ_ABC @BASEBOARD_FAB2_LIB.BASEBOARD_FAB2(SCH_1):PVDDQ_ABC   I169 @BASEBOARD_FAB2_LIB.BASEBOARD_FAB2(SCH_1):PAGE45
   231 PVDDQ_ABC @BASEBOARD_FAB2_LIB.BASEBOARD_FAB2(SCH_1):PVDDQ_ABC   I169 @BASEBOARD_FAB2_LIB.BASEBOARD_FAB2(SCH_1):PAGE45
   233 PVDDQ_ABC @BASEBOARD_FAB2_LIB.BASEBOARD_FAB2(SCH_1):PVDDQ_ABC   I169 @BASEBOARD_FAB2_LIB.BASEBOARD_FAB2(SCH_1):PAGE45
   236 PVDDQ_ABC @BASEBOARD_FAB2_LIB.BASEBOARD_FAB2(SCH_1):PVDDQ_ABC   I169 @BASEBOARD_FAB2_LIB.BASEBOARD_FAB2(SCH_1):PAGE45
   142 PVPP_ABC @BASEBOARD_FAB2_LIB.BASEBOARD_FAB2(SCH_1):PVPP_ABC   I169 @BASEBOARD_FAB2_LIB.BASEBOARD_FAB2(SCH_1):PAGE45
   143 PVPP_ABC @BASEBOARD_FAB2_LIB.BASEBOARD_FAB2(SCH_1):PVPP_ABC   I169 @BASEBOARD_FAB2_LIB.BASEBOARD_FAB2(SCH_1):PAGE45
   288 PVPP_ABC @BASEBOARD_FAB2_LIB.BASEBOARD_FAB2(SCH_1):PVPP_ABC   I169 @BASEBOARD_FAB2_LIB.BASEBOARD_FAB2(SCH_1):PAGE45
   286 PVPP_ABC @BASEBOARD_FAB2_LIB.BASEBOARD_FAB2(SCH_1):PVPP_ABC   I169 @BASEBOARD_FAB2_LIB.BASEBOARD_FAB2(SCH_1):PAGE45
   287 PVPP_ABC @BASEBOARD_FAB2_LIB.BASEBOARD_FAB2(SCH_1):PVPP_ABC   I169 @BASEBOARD_FAB2_LIB.BASEBOARD_FAB2(SCH_1):PAGE45
    77 PVTT_ABC @BASEBOARD_FAB2_LIB.BASEBOARD_FAB2(SCH_1):PVTT_ABC   I169 @BASEBOARD_FAB2_LIB.BASEBOARD_FAB2(SCH_1):PAGE45
   221 PVTT_ABC @BASEBOARD_FAB2_LIB.BASEBOARD_FAB2(SCH_1):PVTT_ABC   I169 @BASEBOARD_FAB2_LIB.BASEBOARD_FAB2(SCH_1):PAGE45

J4G3 SCONN288_H44441004_PIP-SCONN,HA
    79 M_C_MA<0> @BASEBOARD_FAB2_LIB.BASEBOARD_FAB2(SCH_1):M_C_MA(0)   I111 @BASEBOARD_FAB2_LIB.BASEBOARD_FAB2(SCH_1):PAGE47
    72 M_C_MA<1> @BASEBOARD_FAB2_LIB.BASEBOARD_FAB2(SCH_1):M_C_MA(1)   I111 @BASEBOARD_FAB2_LIB.BASEBOARD_FAB2(SCH_1):PAGE47
   225 M_C_MA<10> @BASEBOARD_FAB2_LIB.BASEBOARD_FAB2(SCH_1):M_C_MA(10)   I111 @BASEBOARD_FAB2_LIB.BASEBOARD_FAB2(SCH_1):PAGE47
   210 M_C_MA<11> @BASEBOARD_FAB2_LIB.BASEBOARD_FAB2(SCH_1):M_C_MA(11)   I111 @BASEBOARD_FAB2_LIB.BASEBOARD_FAB2(SCH_1):PAGE47
    65 M_C_MA<12> @BASEBOARD_FAB2_LIB.BASEBOARD_FAB2(SCH_1):M_C_MA(12)   I111 @BASEBOARD_FAB2_LIB.BASEBOARD_FAB2(SCH_1):PAGE47
   232 M_C_MA<13> @BASEBOARD_FAB2_LIB.BASEBOARD_FAB2(SCH_1):M_C_MA(13)   I111 @BASEBOARD_FAB2_LIB.BASEBOARD_FAB2(SCH_1):PAGE47
   228 M_C_MA<14> @BASEBOARD_FAB2_LIB.BASEBOARD_FAB2(SCH_1):M_C_MA(14)   I111 @BASEBOARD_FAB2_LIB.BASEBOARD_FAB2(SCH_1):PAGE47
    86 M_C_MA<15> @BASEBOARD_FAB2_LIB.BASEBOARD_FAB2(SCH_1):M_C_MA(15)   I111 @BASEBOARD_FAB2_LIB.BASEBOARD_FAB2(SCH_1):PAGE47
    82 M_C_MA<16> @BASEBOARD_FAB2_LIB.BASEBOARD_FAB2(SCH_1):M_C_MA(16)   I111 @BASEBOARD_FAB2_LIB.BASEBOARD_FAB2(SCH_1):PAGE47
   234 M_C_MA<17> @BASEBOARD_FAB2_LIB.BASEBOARD_FAB2(SCH_1):M_C_MA(17)   I111 @BASEBOARD_FAB2_LIB.BASEBOARD_FAB2(SCH_1):PAGE47
   216 M_C_MA<2> @BASEBOARD_FAB2_LIB.BASEBOARD_FAB2(SCH_1):M_C_MA(2)   I111 @BASEBOARD_FAB2_LIB.BASEBOARD_FAB2(SCH_1):PAGE47
    71 M_C_MA<3> @BASEBOARD_FAB2_LIB.BASEBOARD_FAB2(SCH_1):M_C_MA(3)   I111 @BASEBOARD_FAB2_LIB.BASEBOARD_FAB2(SCH_1):PAGE47
   214 M_C_MA<4> @BASEBOARD_FAB2_LIB.BASEBOARD_FAB2(SCH_1):M_C_MA(4)   I111 @BASEBOARD_FAB2_LIB.BASEBOARD_FAB2(SCH_1):PAGE47
   213 M_C_MA<5> @BASEBOARD_FAB2_LIB.BASEBOARD_FAB2(SCH_1):M_C_MA(5)   I111 @BASEBOARD_FAB2_LIB.BASEBOARD_FAB2(SCH_1):PAGE47
    69 M_C_MA<6> @BASEBOARD_FAB2_LIB.BASEBOARD_FAB2(SCH_1):M_C_MA(6)   I111 @BASEBOARD_FAB2_LIB.BASEBOARD_FAB2(SCH_1):PAGE47
   211 M_C_MA<7> @BASEBOARD_FAB2_LIB.BASEBOARD_FAB2(SCH_1):M_C_MA(7)   I111 @BASEBOARD_FAB2_LIB.BASEBOARD_FAB2(SCH_1):PAGE47
    68 M_C_MA<8> @BASEBOARD_FAB2_LIB.BASEBOARD_FAB2(SCH_1):M_C_MA(8)   I111 @BASEBOARD_FAB2_LIB.BASEBOARD_FAB2(SCH_1):PAGE47
    66 M_C_MA<9> @BASEBOARD_FAB2_LIB.BASEBOARD_FAB2(SCH_1):M_C_MA(9)   I111 @BASEBOARD_FAB2_LIB.BASEBOARD_FAB2(SCH_1):PAGE47
    62 M_C_ACT_N @BASEBOARD_FAB2_LIB.BASEBOARD_FAB2(SCH_1):M_C_ACT_N   I111 @BASEBOARD_FAB2_LIB.BASEBOARD_FAB2(SCH_1):PAGE47
   208 M_C_ALERT_N @BASEBOARD_FAB2_LIB.BASEBOARD_FAB2(SCH_1):M_C_ALERT_N   I111 @BASEBOARD_FAB2_LIB.BASEBOARD_FAB2(SCH_1):PAGE47
   224 M_C_BA<1> @BASEBOARD_FAB2_LIB.BASEBOARD_FAB2(SCH_1):M_C_BA(1)   I111 @BASEBOARD_FAB2_LIB.BASEBOARD_FAB2(SCH_1):PAGE47
    81 M_C_BA<0> @BASEBOARD_FAB2_LIB.BASEBOARD_FAB2(SCH_1):M_C_BA(0)   I111 @BASEBOARD_FAB2_LIB.BASEBOARD_FAB2(SCH_1):PAGE47
   207 M_C_BG<1> @BASEBOARD_FAB2_LIB.BASEBOARD_FAB2(SCH_1):M_C_BG(1)   I111 @BASEBOARD_FAB2_LIB.BASEBOARD_FAB2(SCH_1):PAGE47
    63 M_C_BG<0> @BASEBOARD_FAB2_LIB.BASEBOARD_FAB2(SCH_1):M_C_BG(0)   I111 @BASEBOARD_FAB2_LIB.BASEBOARD_FAB2(SCH_1):PAGE47
   235 M_C_C<2> @BASEBOARD_FAB2_LIB.BASEBOARD_FAB2(SCH_1):M_C_C(2)   I111 @BASEBOARD_FAB2_LIB.BASEBOARD_FAB2(SCH_1):PAGE47
   199 M_C_ECC<6> @BASEBOARD_FAB2_LIB.BASEBOARD_FAB2(SCH_1):M_C_ECC(6)   I111 @BASEBOARD_FAB2_LIB.BASEBOARD_FAB2(SCH_1):PAGE47
    54 M_C_ECC<7> @BASEBOARD_FAB2_LIB.BASEBOARD_FAB2(SCH_1):M_C_ECC(7)   I111 @BASEBOARD_FAB2_LIB.BASEBOARD_FAB2(SCH_1):PAGE47
   192 M_C_ECC<4> @BASEBOARD_FAB2_LIB.BASEBOARD_FAB2(SCH_1):M_C_ECC(4)   I111 @BASEBOARD_FAB2_LIB.BASEBOARD_FAB2(SCH_1):PAGE47
    47 M_C_ECC<5> @BASEBOARD_FAB2_LIB.BASEBOARD_FAB2(SCH_1):M_C_ECC(5)   I111 @BASEBOARD_FAB2_LIB.BASEBOARD_FAB2(SCH_1):PAGE47
   201 M_C_ECC<2> @BASEBOARD_FAB2_LIB.BASEBOARD_FAB2(SCH_1):M_C_ECC(2)   I111 @BASEBOARD_FAB2_LIB.BASEBOARD_FAB2(SCH_1):PAGE47
    56 M_C_ECC<3> @BASEBOARD_FAB2_LIB.BASEBOARD_FAB2(SCH_1):M_C_ECC(3)   I111 @BASEBOARD_FAB2_LIB.BASEBOARD_FAB2(SCH_1):PAGE47
   194 M_C_ECC<0> @BASEBOARD_FAB2_LIB.BASEBOARD_FAB2(SCH_1):M_C_ECC(0)   I111 @BASEBOARD_FAB2_LIB.BASEBOARD_FAB2(SCH_1):PAGE47
    49 M_C_ECC<1> @BASEBOARD_FAB2_LIB.BASEBOARD_FAB2(SCH_1):M_C_ECC(1)   I111 @BASEBOARD_FAB2_LIB.BASEBOARD_FAB2(SCH_1):PAGE47
    75 M_C_CLK_DN<0> @BASEBOARD_FAB2_LIB.BASEBOARD_FAB2(SCH_1):M_C_CLK_DN(0)   I111 @BASEBOARD_FAB2_LIB.BASEBOARD_FAB2(SCH_1):PAGE47
    74 M_C_CLK_DP<0> @BASEBOARD_FAB2_LIB.BASEBOARD_FAB2(SCH_1):M_C_CLK_DP(0)   I111 @BASEBOARD_FAB2_LIB.BASEBOARD_FAB2(SCH_1):PAGE47
   219 M_C_CLK_DN<1> @BASEBOARD_FAB2_LIB.BASEBOARD_FAB2(SCH_1):M_C_CLK_DN(1)   I111 @BASEBOARD_FAB2_LIB.BASEBOARD_FAB2(SCH_1):PAGE47
   218 M_C_CLK_DP<1> @BASEBOARD_FAB2_LIB.BASEBOARD_FAB2(SCH_1):M_C_CLK_DP(1)   I111 @BASEBOARD_FAB2_LIB.BASEBOARD_FAB2(SCH_1):PAGE47
   203 M_C_CKE<1> @BASEBOARD_FAB2_LIB.BASEBOARD_FAB2(SCH_1):M_C_CKE(1)   I111 @BASEBOARD_FAB2_LIB.BASEBOARD_FAB2(SCH_1):PAGE47
    60 M_C_CKE<0> @BASEBOARD_FAB2_LIB.BASEBOARD_FAB2(SCH_1):M_C_CKE(0)   I111 @BASEBOARD_FAB2_LIB.BASEBOARD_FAB2(SCH_1):PAGE47
   280 M_C_DQ<62> @BASEBOARD_FAB2_LIB.BASEBOARD_FAB2(SCH_1):M_C_DQ(62)   I111 @BASEBOARD_FAB2_LIB.BASEBOARD_FAB2(SCH_1):PAGE47
   135 M_C_DQ<63> @BASEBOARD_FAB2_LIB.BASEBOARD_FAB2(SCH_1):M_C_DQ(63)   I111 @BASEBOARD_FAB2_LIB.BASEBOARD_FAB2(SCH_1):PAGE47
   273 M_C_DQ<60> @BASEBOARD_FAB2_LIB.BASEBOARD_FAB2(SCH_1):M_C_DQ(60)   I111 @BASEBOARD_FAB2_LIB.BASEBOARD_FAB2(SCH_1):PAGE47
   128 M_C_DQ<61> @BASEBOARD_FAB2_LIB.BASEBOARD_FAB2(SCH_1):M_C_DQ(61)   I111 @BASEBOARD_FAB2_LIB.BASEBOARD_FAB2(SCH_1):PAGE47
   282 M_C_DQ<58> @BASEBOARD_FAB2_LIB.BASEBOARD_FAB2(SCH_1):M_C_DQ(58)   I111 @BASEBOARD_FAB2_LIB.BASEBOARD_FAB2(SCH_1):PAGE47
   137 M_C_DQ<59> @BASEBOARD_FAB2_LIB.BASEBOARD_FAB2(SCH_1):M_C_DQ(59)   I111 @BASEBOARD_FAB2_LIB.BASEBOARD_FAB2(SCH_1):PAGE47
   275 M_C_DQ<56> @BASEBOARD_FAB2_LIB.BASEBOARD_FAB2(SCH_1):M_C_DQ(56)   I111 @BASEBOARD_FAB2_LIB.BASEBOARD_FAB2(SCH_1):PAGE47
   130 M_C_DQ<57> @BASEBOARD_FAB2_LIB.BASEBOARD_FAB2(SCH_1):M_C_DQ(57)   I111 @BASEBOARD_FAB2_LIB.BASEBOARD_FAB2(SCH_1):PAGE47
   269 M_C_DQ<54> @BASEBOARD_FAB2_LIB.BASEBOARD_FAB2(SCH_1):M_C_DQ(54)   I111 @BASEBOARD_FAB2_LIB.BASEBOARD_FAB2(SCH_1):PAGE47
   124 M_C_DQ<55> @BASEBOARD_FAB2_LIB.BASEBOARD_FAB2(SCH_1):M_C_DQ(55)   I111 @BASEBOARD_FAB2_LIB.BASEBOARD_FAB2(SCH_1):PAGE47
   262 M_C_DQ<52> @BASEBOARD_FAB2_LIB.BASEBOARD_FAB2(SCH_1):M_C_DQ(52)   I111 @BASEBOARD_FAB2_LIB.BASEBOARD_FAB2(SCH_1):PAGE47
   117 M_C_DQ<53> @BASEBOARD_FAB2_LIB.BASEBOARD_FAB2(SCH_1):M_C_DQ(53)   I111 @BASEBOARD_FAB2_LIB.BASEBOARD_FAB2(SCH_1):PAGE47
   271 M_C_DQ<50> @BASEBOARD_FAB2_LIB.BASEBOARD_FAB2(SCH_1):M_C_DQ(50)   I111 @BASEBOARD_FAB2_LIB.BASEBOARD_FAB2(SCH_1):PAGE47
   126 M_C_DQ<51> @BASEBOARD_FAB2_LIB.BASEBOARD_FAB2(SCH_1):M_C_DQ(51)   I111 @BASEBOARD_FAB2_LIB.BASEBOARD_FAB2(SCH_1):PAGE47
   264 M_C_DQ<48> @BASEBOARD_FAB2_LIB.BASEBOARD_FAB2(SCH_1):M_C_DQ(48)   I111 @BASEBOARD_FAB2_LIB.BASEBOARD_FAB2(SCH_1):PAGE47
   119 M_C_DQ<49> @BASEBOARD_FAB2_LIB.BASEBOARD_FAB2(SCH_1):M_C_DQ(49)   I111 @BASEBOARD_FAB2_LIB.BASEBOARD_FAB2(SCH_1):PAGE47
   258 M_C_DQ<46> @BASEBOARD_FAB2_LIB.BASEBOARD_FAB2(SCH_1):M_C_DQ(46)   I111 @BASEBOARD_FAB2_LIB.BASEBOARD_FAB2(SCH_1):PAGE47
   113 M_C_DQ<47> @BASEBOARD_FAB2_LIB.BASEBOARD_FAB2(SCH_1):M_C_DQ(47)   I111 @BASEBOARD_FAB2_LIB.BASEBOARD_FAB2(SCH_1):PAGE47
   251 M_C_DQ<44> @BASEBOARD_FAB2_LIB.BASEBOARD_FAB2(SCH_1):M_C_DQ(44)   I111 @BASEBOARD_FAB2_LIB.BASEBOARD_FAB2(SCH_1):PAGE47
   106 M_C_DQ<45> @BASEBOARD_FAB2_LIB.BASEBOARD_FAB2(SCH_1):M_C_DQ(45)   I111 @BASEBOARD_FAB2_LIB.BASEBOARD_FAB2(SCH_1):PAGE47
   260 M_C_DQ<42> @BASEBOARD_FAB2_LIB.BASEBOARD_FAB2(SCH_1):M_C_DQ(42)   I111 @BASEBOARD_FAB2_LIB.BASEBOARD_FAB2(SCH_1):PAGE47
   115 M_C_DQ<43> @BASEBOARD_FAB2_LIB.BASEBOARD_FAB2(SCH_1):M_C_DQ(43)   I111 @BASEBOARD_FAB2_LIB.BASEBOARD_FAB2(SCH_1):PAGE47
   253 M_C_DQ<40> @BASEBOARD_FAB2_LIB.BASEBOARD_FAB2(SCH_1):M_C_DQ(40)   I111 @BASEBOARD_FAB2_LIB.BASEBOARD_FAB2(SCH_1):PAGE47
   108 M_C_DQ<41> @BASEBOARD_FAB2_LIB.BASEBOARD_FAB2(SCH_1):M_C_DQ(41)   I111 @BASEBOARD_FAB2_LIB.BASEBOARD_FAB2(SCH_1):PAGE47
   247 M_C_DQ<38> @BASEBOARD_FAB2_LIB.BASEBOARD_FAB2(SCH_1):M_C_DQ(38)   I111 @BASEBOARD_FAB2_LIB.BASEBOARD_FAB2(SCH_1):PAGE47
   102 M_C_DQ<39> @BASEBOARD_FAB2_LIB.BASEBOARD_FAB2(SCH_1):M_C_DQ(39)   I111 @BASEBOARD_FAB2_LIB.BASEBOARD_FAB2(SCH_1):PAGE47
   240 M_C_DQ<36> @BASEBOARD_FAB2_LIB.BASEBOARD_FAB2(SCH_1):M_C_DQ(36)   I111 @BASEBOARD_FAB2_LIB.BASEBOARD_FAB2(SCH_1):PAGE47
    95 M_C_DQ<37> @BASEBOARD_FAB2_LIB.BASEBOARD_FAB2(SCH_1):M_C_DQ(37)   I111 @BASEBOARD_FAB2_LIB.BASEBOARD_FAB2(SCH_1):PAGE47
   249 M_C_DQ<34> @BASEBOARD_FAB2_LIB.BASEBOARD_FAB2(SCH_1):M_C_DQ(34)   I111 @BASEBOARD_FAB2_LIB.BASEBOARD_FAB2(SCH_1):PAGE47
   104 M_C_DQ<35> @BASEBOARD_FAB2_LIB.BASEBOARD_FAB2(SCH_1):M_C_DQ(35)   I111 @BASEBOARD_FAB2_LIB.BASEBOARD_FAB2(SCH_1):PAGE47
   242 M_C_DQ<32> @BASEBOARD_FAB2_LIB.BASEBOARD_FAB2(SCH_1):M_C_DQ(32)   I111 @BASEBOARD_FAB2_LIB.BASEBOARD_FAB2(SCH_1):PAGE47
    97 M_C_DQ<33> @BASEBOARD_FAB2_LIB.BASEBOARD_FAB2(SCH_1):M_C_DQ(33)   I111 @BASEBOARD_FAB2_LIB.BASEBOARD_FAB2(SCH_1):PAGE47
   188 M_C_DQ<30> @BASEBOARD_FAB2_LIB.BASEBOARD_FAB2(SCH_1):M_C_DQ(30)   I111 @BASEBOARD_FAB2_LIB.BASEBOARD_FAB2(SCH_1):PAGE47
    43 M_C_DQ<31> @BASEBOARD_FAB2_LIB.BASEBOARD_FAB2(SCH_1):M_C_DQ(31)   I111 @BASEBOARD_FAB2_LIB.BASEBOARD_FAB2(SCH_1):PAGE47
   181 M_C_DQ<28> @BASEBOARD_FAB2_LIB.BASEBOARD_FAB2(SCH_1):M_C_DQ(28)   I111 @BASEBOARD_FAB2_LIB.BASEBOARD_FAB2(SCH_1):PAGE47
    36 M_C_DQ<29> @BASEBOARD_FAB2_LIB.BASEBOARD_FAB2(SCH_1):M_C_DQ(29)   I111 @BASEBOARD_FAB2_LIB.BASEBOARD_FAB2(SCH_1):PAGE47
   190 M_C_DQ<26> @BASEBOARD_FAB2_LIB.BASEBOARD_FAB2(SCH_1):M_C_DQ(26)   I111 @BASEBOARD_FAB2_LIB.BASEBOARD_FAB2(SCH_1):PAGE47
    45 M_C_DQ<27> @BASEBOARD_FAB2_LIB.BASEBOARD_FAB2(SCH_1):M_C_DQ(27)   I111 @BASEBOARD_FAB2_LIB.BASEBOARD_FAB2(SCH_1):PAGE47
   183 M_C_DQ<24> @BASEBOARD_FAB2_LIB.BASEBOARD_FAB2(SCH_1):M_C_DQ(24)   I111 @BASEBOARD_FAB2_LIB.BASEBOARD_FAB2(SCH_1):PAGE47
    38 M_C_DQ<25> @BASEBOARD_FAB2_LIB.BASEBOARD_FAB2(SCH_1):M_C_DQ(25)   I111 @BASEBOARD_FAB2_LIB.BASEBOARD_FAB2(SCH_1):PAGE47
   177 M_C_DQ<22> @BASEBOARD_FAB2_LIB.BASEBOARD_FAB2(SCH_1):M_C_DQ(22)   I111 @BASEBOARD_FAB2_LIB.BASEBOARD_FAB2(SCH_1):PAGE47
    32 M_C_DQ<23> @BASEBOARD_FAB2_LIB.BASEBOARD_FAB2(SCH_1):M_C_DQ(23)   I111 @BASEBOARD_FAB2_LIB.BASEBOARD_FAB2(SCH_1):PAGE47
   170 M_C_DQ<20> @BASEBOARD_FAB2_LIB.BASEBOARD_FAB2(SCH_1):M_C_DQ(20)   I111 @BASEBOARD_FAB2_LIB.BASEBOARD_FAB2(SCH_1):PAGE47
    25 M_C_DQ<21> @BASEBOARD_FAB2_LIB.BASEBOARD_FAB2(SCH_1):M_C_DQ(21)   I111 @BASEBOARD_FAB2_LIB.BASEBOARD_FAB2(SCH_1):PAGE47
   179 M_C_DQ<18> @BASEBOARD_FAB2_LIB.BASEBOARD_FAB2(SCH_1):M_C_DQ(18)   I111 @BASEBOARD_FAB2_LIB.BASEBOARD_FAB2(SCH_1):PAGE47
    34 M_C_DQ<19> @BASEBOARD_FAB2_LIB.BASEBOARD_FAB2(SCH_1):M_C_DQ(19)   I111 @BASEBOARD_FAB2_LIB.BASEBOARD_FAB2(SCH_1):PAGE47
   172 M_C_DQ<16> @BASEBOARD_FAB2_LIB.BASEBOARD_FAB2(SCH_1):M_C_DQ(16)   I111 @BASEBOARD_FAB2_LIB.BASEBOARD_FAB2(SCH_1):PAGE47
    27 M_C_DQ<17> @BASEBOARD_FAB2_LIB.BASEBOARD_FAB2(SCH_1):M_C_DQ(17)   I111 @BASEBOARD_FAB2_LIB.BASEBOARD_FAB2(SCH_1):PAGE47
   166 M_C_DQ<14> @BASEBOARD_FAB2_LIB.BASEBOARD_FAB2(SCH_1):M_C_DQ(14)   I111 @BASEBOARD_FAB2_LIB.BASEBOARD_FAB2(SCH_1):PAGE47
    21 M_C_DQ<15> @BASEBOARD_FAB2_LIB.BASEBOARD_FAB2(SCH_1):M_C_DQ(15)   I111 @BASEBOARD_FAB2_LIB.BASEBOARD_FAB2(SCH_1):PAGE47
   159 M_C_DQ<12> @BASEBOARD_FAB2_LIB.BASEBOARD_FAB2(SCH_1):M_C_DQ(12)   I111 @BASEBOARD_FAB2_LIB.BASEBOARD_FAB2(SCH_1):PAGE47
    14 M_C_DQ<13> @BASEBOARD_FAB2_LIB.BASEBOARD_FAB2(SCH_1):M_C_DQ(13)   I111 @BASEBOARD_FAB2_LIB.BASEBOARD_FAB2(SCH_1):PAGE47
   168 M_C_DQ<10> @BASEBOARD_FAB2_LIB.BASEBOARD_FAB2(SCH_1):M_C_DQ(10)   I111 @BASEBOARD_FAB2_LIB.BASEBOARD_FAB2(SCH_1):PAGE47
    23 M_C_DQ<11> @BASEBOARD_FAB2_LIB.BASEBOARD_FAB2(SCH_1):M_C_DQ(11)   I111 @BASEBOARD_FAB2_LIB.BASEBOARD_FAB2(SCH_1):PAGE47
   161 M_C_DQ<8> @BASEBOARD_FAB2_LIB.BASEBOARD_FAB2(SCH_1):M_C_DQ(8)   I111 @BASEBOARD_FAB2_LIB.BASEBOARD_FAB2(SCH_1):PAGE47
    16 M_C_DQ<9> @BASEBOARD_FAB2_LIB.BASEBOARD_FAB2(SCH_1):M_C_DQ(9)   I111 @BASEBOARD_FAB2_LIB.BASEBOARD_FAB2(SCH_1):PAGE47
   155 M_C_DQ<6> @BASEBOARD_FAB2_LIB.BASEBOARD_FAB2(SCH_1):M_C_DQ(6)   I111 @BASEBOARD_FAB2_LIB.BASEBOARD_FAB2(SCH_1):PAGE47
    10 M_C_DQ<7> @BASEBOARD_FAB2_LIB.BASEBOARD_FAB2(SCH_1):M_C_DQ(7)   I111 @BASEBOARD_FAB2_LIB.BASEBOARD_FAB2(SCH_1):PAGE47
   148 M_C_DQ<4> @BASEBOARD_FAB2_LIB.BASEBOARD_FAB2(SCH_1):M_C_DQ(4)   I111 @BASEBOARD_FAB2_LIB.BASEBOARD_FAB2(SCH_1):PAGE47
     3 M_C_DQ<5> @BASEBOARD_FAB2_LIB.BASEBOARD_FAB2(SCH_1):M_C_DQ(5)   I111 @BASEBOARD_FAB2_LIB.BASEBOARD_FAB2(SCH_1):PAGE47
   157 M_C_DQ<2> @BASEBOARD_FAB2_LIB.BASEBOARD_FAB2(SCH_1):M_C_DQ(2)   I111 @BASEBOARD_FAB2_LIB.BASEBOARD_FAB2(SCH_1):PAGE47
    12 M_C_DQ<3> @BASEBOARD_FAB2_LIB.BASEBOARD_FAB2(SCH_1):M_C_DQ(3)   I111 @BASEBOARD_FAB2_LIB.BASEBOARD_FAB2(SCH_1):PAGE47
   150 M_C_DQ<0> @BASEBOARD_FAB2_LIB.BASEBOARD_FAB2(SCH_1):M_C_DQ(0)   I111 @BASEBOARD_FAB2_LIB.BASEBOARD_FAB2(SCH_1):PAGE47
     5 M_C_DQ<1> @BASEBOARD_FAB2_LIB.BASEBOARD_FAB2(SCH_1):M_C_DQ(1)   I111 @BASEBOARD_FAB2_LIB.BASEBOARD_FAB2(SCH_1):PAGE47
    78 FM_DIMM_EVENT_COD_N @BASEBOARD_FAB2_LIB.BASEBOARD_FAB2(SCH_1):FM_DIMM_EVENT_COD_N   I111 @BASEBOARD_FAB2_LIB.BASEBOARD_FAB2(SCH_1):PAGE47
    91 M_C_ODT<1> @BASEBOARD_FAB2_LIB.BASEBOARD_FAB2(SCH_1):M_C_ODT(1)   I111 @BASEBOARD_FAB2_LIB.BASEBOARD_FAB2(SCH_1):PAGE47
    87 M_C_ODT<0> @BASEBOARD_FAB2_LIB.BASEBOARD_FAB2(SCH_1):M_C_ODT(0)   I111 @BASEBOARD_FAB2_LIB.BASEBOARD_FAB2(SCH_1):PAGE47
   222 M_C_PAR @BASEBOARD_FAB2_LIB.BASEBOARD_FAB2(SCH_1):M_C_PAR   I111 @BASEBOARD_FAB2_LIB.BASEBOARD_FAB2(SCH_1):PAGE47
    58 M_ABC_RST_N @BASEBOARD_FAB2_LIB.BASEBOARD_FAB2(SCH_1):M_ABC_RST_N   I111 @BASEBOARD_FAB2_LIB.BASEBOARD_FAB2(SCH_1):PAGE47
   144 TP_CH_C_DIMM_C0_RFU_2 @BASEBOARD_FAB2_LIB.BASEBOARD_FAB2(SCH_1):TP_CH_C_DIMM_C0_RFU_2   I111 @BASEBOARD_FAB2_LIB.BASEBOARD_FAB2(SCH_1):PAGE47
   227 TP_CH_C_DIMM_C0_RFU_1 @BASEBOARD_FAB2_LIB.BASEBOARD_FAB2(SCH_1):TP_CH_C_DIMM_C0_RFU_1   I111 @BASEBOARD_FAB2_LIB.BASEBOARD_FAB2(SCH_1):PAGE47
   205 TP_CH_C_DIMM_C0_RFU_0 @BASEBOARD_FAB2_LIB.BASEBOARD_FAB2(SCH_1):TP_CH_C_DIMM_C0_RFU_0   I111 @BASEBOARD_FAB2_LIB.BASEBOARD_FAB2(SCH_1):PAGE47
    84 M_C_CS_N<0> @BASEBOARD_FAB2_LIB.BASEBOARD_FAB2(SCH_1):M_C_CS_N(0)   I111 @BASEBOARD_FAB2_LIB.BASEBOARD_FAB2(SCH_1):PAGE47
    89 M_C_CS_N<1> @BASEBOARD_FAB2_LIB.BASEBOARD_FAB2(SCH_1):M_C_CS_N(1)   I111 @BASEBOARD_FAB2_LIB.BASEBOARD_FAB2(SCH_1):PAGE47
    93 M_C_CS_N<2> @BASEBOARD_FAB2_LIB.BASEBOARD_FAB2(SCH_1):M_C_CS_N(2)   I111 @BASEBOARD_FAB2_LIB.BASEBOARD_FAB2(SCH_1):PAGE47
   237 M_C_CS_N<3> @BASEBOARD_FAB2_LIB.BASEBOARD_FAB2(SCH_1):M_C_CS_N(3)   I111 @BASEBOARD_FAB2_LIB.BASEBOARD_FAB2(SCH_1):PAGE47
   238 PVPP_ABC @BASEBOARD_FAB2_LIB.BASEBOARD_FAB2(SCH_1):PVPP_ABC   I111 @BASEBOARD_FAB2_LIB.BASEBOARD_FAB2(SCH_1):PAGE47
   140    GND @BASEBOARD_FAB2_LIB.BASEBOARD_FAB2(SCH_1):GND   I111 @BASEBOARD_FAB2_LIB.BASEBOARD_FAB2(SCH_1):PAGE47
   139    GND @BASEBOARD_FAB2_LIB.BASEBOARD_FAB2(SCH_1):GND   I111 @BASEBOARD_FAB2_LIB.BASEBOARD_FAB2(SCH_1):PAGE47
   230 FM_ADR_COMPLETE_ABC_N @BASEBOARD_FAB2_LIB.BASEBOARD_FAB2(SCH_1):FM_ADR_COMPLETE_ABC_N   I111 @BASEBOARD_FAB2_LIB.BASEBOARD_FAB2(SCH_1):PAGE47
   141 SMB_DDR_ABC_VPP_SCL @BASEBOARD_FAB2_LIB.BASEBOARD_FAB2(SCH_1):SMB_DDR_ABC_VPP_SCL   I111 @BASEBOARD_FAB2_LIB.BASEBOARD_FAB2(SCH_1):PAGE47
   285 SMB_DDR_ABC_VPP_SDA @BASEBOARD_FAB2_LIB.BASEBOARD_FAB2(SCH_1):SMB_DDR_ABC_VPP_SDA   I111 @BASEBOARD_FAB2_LIB.BASEBOARD_FAB2(SCH_1):PAGE47
   284 PVPP_ABC @BASEBOARD_FAB2_LIB.BASEBOARD_FAB2(SCH_1):PVPP_ABC   I111 @BASEBOARD_FAB2_LIB.BASEBOARD_FAB2(SCH_1):PAGE47
   146 M_C_VREF @BASEBOARD_FAB2_LIB.BASEBOARD_FAB2(SCH_1):M_C_VREF   I111 @BASEBOARD_FAB2_LIB.BASEBOARD_FAB2(SCH_1):PAGE47
   152 M_C_DQS_DN<0> @BASEBOARD_FAB2_LIB.BASEBOARD_FAB2(SCH_1):M_C_DQS_DN(0)    I61 @BASEBOARD_FAB2_LIB.BASEBOARD_FAB2(SCH_1):PAGE47
   153 M_C_DQS_DP<0> @BASEBOARD_FAB2_LIB.BASEBOARD_FAB2(SCH_1):M_C_DQS_DP(0)    I61 @BASEBOARD_FAB2_LIB.BASEBOARD_FAB2(SCH_1):PAGE47
    19 M_C_DQS_DN<10> @BASEBOARD_FAB2_LIB.BASEBOARD_FAB2(SCH_1):M_C_DQS_DN(10)    I61 @BASEBOARD_FAB2_LIB.BASEBOARD_FAB2(SCH_1):PAGE47
    18 M_C_DQS_DP<10> @BASEBOARD_FAB2_LIB.BASEBOARD_FAB2(SCH_1):M_C_DQS_DP(10)    I61 @BASEBOARD_FAB2_LIB.BASEBOARD_FAB2(SCH_1):PAGE47
    30 M_C_DQS_DN<11> @BASEBOARD_FAB2_LIB.BASEBOARD_FAB2(SCH_1):M_C_DQS_DN(11)    I61 @BASEBOARD_FAB2_LIB.BASEBOARD_FAB2(SCH_1):PAGE47
    29 M_C_DQS_DP<11> @BASEBOARD_FAB2_LIB.BASEBOARD_FAB2(SCH_1):M_C_DQS_DP(11)    I61 @BASEBOARD_FAB2_LIB.BASEBOARD_FAB2(SCH_1):PAGE47
    41 M_C_DQS_DN<12> @BASEBOARD_FAB2_LIB.BASEBOARD_FAB2(SCH_1):M_C_DQS_DN(12)    I61 @BASEBOARD_FAB2_LIB.BASEBOARD_FAB2(SCH_1):PAGE47
    40 M_C_DQS_DP<12> @BASEBOARD_FAB2_LIB.BASEBOARD_FAB2(SCH_1):M_C_DQS_DP(12)    I61 @BASEBOARD_FAB2_LIB.BASEBOARD_FAB2(SCH_1):PAGE47
   100 M_C_DQS_DN<13> @BASEBOARD_FAB2_LIB.BASEBOARD_FAB2(SCH_1):M_C_DQS_DN(13)    I61 @BASEBOARD_FAB2_LIB.BASEBOARD_FAB2(SCH_1):PAGE47
    99 M_C_DQS_DP<13> @BASEBOARD_FAB2_LIB.BASEBOARD_FAB2(SCH_1):M_C_DQS_DP(13)    I61 @BASEBOARD_FAB2_LIB.BASEBOARD_FAB2(SCH_1):PAGE47
   111 M_C_DQS_DN<14> @BASEBOARD_FAB2_LIB.BASEBOARD_FAB2(SCH_1):M_C_DQS_DN(14)    I61 @BASEBOARD_FAB2_LIB.BASEBOARD_FAB2(SCH_1):PAGE47
   110 M_C_DQS_DP<14> @BASEBOARD_FAB2_LIB.BASEBOARD_FAB2(SCH_1):M_C_DQS_DP(14)    I61 @BASEBOARD_FAB2_LIB.BASEBOARD_FAB2(SCH_1):PAGE47
   122 M_C_DQS_DN<15> @BASEBOARD_FAB2_LIB.BASEBOARD_FAB2(SCH_1):M_C_DQS_DN(15)    I61 @BASEBOARD_FAB2_LIB.BASEBOARD_FAB2(SCH_1):PAGE47
   121 M_C_DQS_DP<15> @BASEBOARD_FAB2_LIB.BASEBOARD_FAB2(SCH_1):M_C_DQS_DP(15)    I61 @BASEBOARD_FAB2_LIB.BASEBOARD_FAB2(SCH_1):PAGE47
   133 M_C_DQS_DN<16> @BASEBOARD_FAB2_LIB.BASEBOARD_FAB2(SCH_1):M_C_DQS_DN(16)    I61 @BASEBOARD_FAB2_LIB.BASEBOARD_FAB2(SCH_1):PAGE47
   132 M_C_DQS_DP<16> @BASEBOARD_FAB2_LIB.BASEBOARD_FAB2(SCH_1):M_C_DQS_DP(16)    I61 @BASEBOARD_FAB2_LIB.BASEBOARD_FAB2(SCH_1):PAGE47
    52 M_C_DQS_DN<17> @BASEBOARD_FAB2_LIB.BASEBOARD_FAB2(SCH_1):M_C_DQS_DN(17)    I61 @BASEBOARD_FAB2_LIB.BASEBOARD_FAB2(SCH_1):PAGE47
    51 M_C_DQS_DP<17> @BASEBOARD_FAB2_LIB.BASEBOARD_FAB2(SCH_1):M_C_DQS_DP(17)    I61 @BASEBOARD_FAB2_LIB.BASEBOARD_FAB2(SCH_1):PAGE47
   163 M_C_DQS_DN<1> @BASEBOARD_FAB2_LIB.BASEBOARD_FAB2(SCH_1):M_C_DQS_DN(1)    I61 @BASEBOARD_FAB2_LIB.BASEBOARD_FAB2(SCH_1):PAGE47
   164 M_C_DQS_DP<1> @BASEBOARD_FAB2_LIB.BASEBOARD_FAB2(SCH_1):M_C_DQS_DP(1)    I61 @BASEBOARD_FAB2_LIB.BASEBOARD_FAB2(SCH_1):PAGE47
   174 M_C_DQS_DN<2> @BASEBOARD_FAB2_LIB.BASEBOARD_FAB2(SCH_1):M_C_DQS_DN(2)    I61 @BASEBOARD_FAB2_LIB.BASEBOARD_FAB2(SCH_1):PAGE47
   175 M_C_DQS_DP<2> @BASEBOARD_FAB2_LIB.BASEBOARD_FAB2(SCH_1):M_C_DQS_DP(2)    I61 @BASEBOARD_FAB2_LIB.BASEBOARD_FAB2(SCH_1):PAGE47
   185 M_C_DQS_DN<3> @BASEBOARD_FAB2_LIB.BASEBOARD_FAB2(SCH_1):M_C_DQS_DN(3)    I61 @BASEBOARD_FAB2_LIB.BASEBOARD_FAB2(SCH_1):PAGE47
   186 M_C_DQS_DP<3> @BASEBOARD_FAB2_LIB.BASEBOARD_FAB2(SCH_1):M_C_DQS_DP(3)    I61 @BASEBOARD_FAB2_LIB.BASEBOARD_FAB2(SCH_1):PAGE47
   244 M_C_DQS_DN<4> @BASEBOARD_FAB2_LIB.BASEBOARD_FAB2(SCH_1):M_C_DQS_DN(4)    I61 @BASEBOARD_FAB2_LIB.BASEBOARD_FAB2(SCH_1):PAGE47
   245 M_C_DQS_DP<4> @BASEBOARD_FAB2_LIB.BASEBOARD_FAB2(SCH_1):M_C_DQS_DP(4)    I61 @BASEBOARD_FAB2_LIB.BASEBOARD_FAB2(SCH_1):PAGE47
   255 M_C_DQS_DN<5> @BASEBOARD_FAB2_LIB.BASEBOARD_FAB2(SCH_1):M_C_DQS_DN(5)    I61 @BASEBOARD_FAB2_LIB.BASEBOARD_FAB2(SCH_1):PAGE47
   256 M_C_DQS_DP<5> @BASEBOARD_FAB2_LIB.BASEBOARD_FAB2(SCH_1):M_C_DQS_DP(5)    I61 @BASEBOARD_FAB2_LIB.BASEBOARD_FAB2(SCH_1):PAGE47
   266 M_C_DQS_DN<6> @BASEBOARD_FAB2_LIB.BASEBOARD_FAB2(SCH_1):M_C_DQS_DN(6)    I61 @BASEBOARD_FAB2_LIB.BASEBOARD_FAB2(SCH_1):PAGE47
   267 M_C_DQS_DP<6> @BASEBOARD_FAB2_LIB.BASEBOARD_FAB2(SCH_1):M_C_DQS_DP(6)    I61 @BASEBOARD_FAB2_LIB.BASEBOARD_FAB2(SCH_1):PAGE47
   277 M_C_DQS_DN<7> @BASEBOARD_FAB2_LIB.BASEBOARD_FAB2(SCH_1):M_C_DQS_DN(7)    I61 @BASEBOARD_FAB2_LIB.BASEBOARD_FAB2(SCH_1):PAGE47
   278 M_C_DQS_DP<7> @BASEBOARD_FAB2_LIB.BASEBOARD_FAB2(SCH_1):M_C_DQS_DP(7)    I61 @BASEBOARD_FAB2_LIB.BASEBOARD_FAB2(SCH_1):PAGE47
   196 M_C_DQS_DN<8> @BASEBOARD_FAB2_LIB.BASEBOARD_FAB2(SCH_1):M_C_DQS_DN(8)    I61 @BASEBOARD_FAB2_LIB.BASEBOARD_FAB2(SCH_1):PAGE47
   197 M_C_DQS_DP<8> @BASEBOARD_FAB2_LIB.BASEBOARD_FAB2(SCH_1):M_C_DQS_DP(8)    I61 @BASEBOARD_FAB2_LIB.BASEBOARD_FAB2(SCH_1):PAGE47
     8 M_C_DQS_DN<9> @BASEBOARD_FAB2_LIB.BASEBOARD_FAB2(SCH_1):M_C_DQS_DN(9)    I61 @BASEBOARD_FAB2_LIB.BASEBOARD_FAB2(SCH_1):PAGE47
     7 M_C_DQS_DP<9> @BASEBOARD_FAB2_LIB.BASEBOARD_FAB2(SCH_1):M_C_DQS_DP(9)    I61 @BASEBOARD_FAB2_LIB.BASEBOARD_FAB2(SCH_1):PAGE47
     2    GND @BASEBOARD_FAB2_LIB.BASEBOARD_FAB2(SCH_1):GND    I43 @BASEBOARD_FAB2_LIB.BASEBOARD_FAB2(SCH_1):PAGE47
     4    GND @BASEBOARD_FAB2_LIB.BASEBOARD_FAB2(SCH_1):GND    I43 @BASEBOARD_FAB2_LIB.BASEBOARD_FAB2(SCH_1):PAGE47
     6    GND @BASEBOARD_FAB2_LIB.BASEBOARD_FAB2(SCH_1):GND    I43 @BASEBOARD_FAB2_LIB.BASEBOARD_FAB2(SCH_1):PAGE47
     9    GND @BASEBOARD_FAB2_LIB.BASEBOARD_FAB2(SCH_1):GND    I43 @BASEBOARD_FAB2_LIB.BASEBOARD_FAB2(SCH_1):PAGE47
    11    GND @BASEBOARD_FAB2_LIB.BASEBOARD_FAB2(SCH_1):GND    I43 @BASEBOARD_FAB2_LIB.BASEBOARD_FAB2(SCH_1):PAGE47
    13    GND @BASEBOARD_FAB2_LIB.BASEBOARD_FAB2(SCH_1):GND    I43 @BASEBOARD_FAB2_LIB.BASEBOARD_FAB2(SCH_1):PAGE47
    15    GND @BASEBOARD_FAB2_LIB.BASEBOARD_FAB2(SCH_1):GND    I43 @BASEBOARD_FAB2_LIB.BASEBOARD_FAB2(SCH_1):PAGE47
    17    GND @BASEBOARD_FAB2_LIB.BASEBOARD_FAB2(SCH_1):GND    I43 @BASEBOARD_FAB2_LIB.BASEBOARD_FAB2(SCH_1):PAGE47
    20    GND @BASEBOARD_FAB2_LIB.BASEBOARD_FAB2(SCH_1):GND    I43 @BASEBOARD_FAB2_LIB.BASEBOARD_FAB2(SCH_1):PAGE47
    22    GND @BASEBOARD_FAB2_LIB.BASEBOARD_FAB2(SCH_1):GND    I43 @BASEBOARD_FAB2_LIB.BASEBOARD_FAB2(SCH_1):PAGE47
    24    GND @BASEBOARD_FAB2_LIB.BASEBOARD_FAB2(SCH_1):GND    I43 @BASEBOARD_FAB2_LIB.BASEBOARD_FAB2(SCH_1):PAGE47
    26    GND @BASEBOARD_FAB2_LIB.BASEBOARD_FAB2(SCH_1):GND    I43 @BASEBOARD_FAB2_LIB.BASEBOARD_FAB2(SCH_1):PAGE47
    28    GND @BASEBOARD_FAB2_LIB.BASEBOARD_FAB2(SCH_1):GND    I43 @BASEBOARD_FAB2_LIB.BASEBOARD_FAB2(SCH_1):PAGE47
    31    GND @BASEBOARD_FAB2_LIB.BASEBOARD_FAB2(SCH_1):GND    I43 @BASEBOARD_FAB2_LIB.BASEBOARD_FAB2(SCH_1):PAGE47
    33    GND @BASEBOARD_FAB2_LIB.BASEBOARD_FAB2(SCH_1):GND    I43 @BASEBOARD_FAB2_LIB.BASEBOARD_FAB2(SCH_1):PAGE47
    35    GND @BASEBOARD_FAB2_LIB.BASEBOARD_FAB2(SCH_1):GND    I43 @BASEBOARD_FAB2_LIB.BASEBOARD_FAB2(SCH_1):PAGE47
    37    GND @BASEBOARD_FAB2_LIB.BASEBOARD_FAB2(SCH_1):GND    I43 @BASEBOARD_FAB2_LIB.BASEBOARD_FAB2(SCH_1):PAGE47
    39    GND @BASEBOARD_FAB2_LIB.BASEBOARD_FAB2(SCH_1):GND    I43 @BASEBOARD_FAB2_LIB.BASEBOARD_FAB2(SCH_1):PAGE47
    42    GND @BASEBOARD_FAB2_LIB.BASEBOARD_FAB2(SCH_1):GND    I43 @BASEBOARD_FAB2_LIB.BASEBOARD_FAB2(SCH_1):PAGE47
    44    GND @BASEBOARD_FAB2_LIB.BASEBOARD_FAB2(SCH_1):GND    I43 @BASEBOARD_FAB2_LIB.BASEBOARD_FAB2(SCH_1):PAGE47
    46    GND @BASEBOARD_FAB2_LIB.BASEBOARD_FAB2(SCH_1):GND    I43 @BASEBOARD_FAB2_LIB.BASEBOARD_FAB2(SCH_1):PAGE47
    48    GND @BASEBOARD_FAB2_LIB.BASEBOARD_FAB2(SCH_1):GND    I43 @BASEBOARD_FAB2_LIB.BASEBOARD_FAB2(SCH_1):PAGE47
    50    GND @BASEBOARD_FAB2_LIB.BASEBOARD_FAB2(SCH_1):GND    I43 @BASEBOARD_FAB2_LIB.BASEBOARD_FAB2(SCH_1):PAGE47
    53    GND @BASEBOARD_FAB2_LIB.BASEBOARD_FAB2(SCH_1):GND    I43 @BASEBOARD_FAB2_LIB.BASEBOARD_FAB2(SCH_1):PAGE47
    55    GND @BASEBOARD_FAB2_LIB.BASEBOARD_FAB2(SCH_1):GND    I43 @BASEBOARD_FAB2_LIB.BASEBOARD_FAB2(SCH_1):PAGE47
    57    GND @BASEBOARD_FAB2_LIB.BASEBOARD_FAB2(SCH_1):GND    I43 @BASEBOARD_FAB2_LIB.BASEBOARD_FAB2(SCH_1):PAGE47
    94    GND @BASEBOARD_FAB2_LIB.BASEBOARD_FAB2(SCH_1):GND    I43 @BASEBOARD_FAB2_LIB.BASEBOARD_FAB2(SCH_1):PAGE47
    96    GND @BASEBOARD_FAB2_LIB.BASEBOARD_FAB2(SCH_1):GND    I43 @BASEBOARD_FAB2_LIB.BASEBOARD_FAB2(SCH_1):PAGE47
    98    GND @BASEBOARD_FAB2_LIB.BASEBOARD_FAB2(SCH_1):GND    I43 @BASEBOARD_FAB2_LIB.BASEBOARD_FAB2(SCH_1):PAGE47
   101    GND @BASEBOARD_FAB2_LIB.BASEBOARD_FAB2(SCH_1):GND    I43 @BASEBOARD_FAB2_LIB.BASEBOARD_FAB2(SCH_1):PAGE47
   103    GND @BASEBOARD_FAB2_LIB.BASEBOARD_FAB2(SCH_1):GND    I43 @BASEBOARD_FAB2_LIB.BASEBOARD_FAB2(SCH_1):PAGE47
   105    GND @BASEBOARD_FAB2_LIB.BASEBOARD_FAB2(SCH_1):GND    I43 @BASEBOARD_FAB2_LIB.BASEBOARD_FAB2(SCH_1):PAGE47
   107    GND @BASEBOARD_FAB2_LIB.BASEBOARD_FAB2(SCH_1):GND    I43 @BASEBOARD_FAB2_LIB.BASEBOARD_FAB2(SCH_1):PAGE47
   109    GND @BASEBOARD_FAB2_LIB.BASEBOARD_FAB2(SCH_1):GND    I43 @BASEBOARD_FAB2_LIB.BASEBOARD_FAB2(SCH_1):PAGE47
   112    GND @BASEBOARD_FAB2_LIB.BASEBOARD_FAB2(SCH_1):GND    I43 @BASEBOARD_FAB2_LIB.BASEBOARD_FAB2(SCH_1):PAGE47
   114    GND @BASEBOARD_FAB2_LIB.BASEBOARD_FAB2(SCH_1):GND    I43 @BASEBOARD_FAB2_LIB.BASEBOARD_FAB2(SCH_1):PAGE47
   116    GND @BASEBOARD_FAB2_LIB.BASEBOARD_FAB2(SCH_1):GND    I43 @BASEBOARD_FAB2_LIB.BASEBOARD_FAB2(SCH_1):PAGE47
   118    GND @BASEBOARD_FAB2_LIB.BASEBOARD_FAB2(SCH_1):GND    I43 @BASEBOARD_FAB2_LIB.BASEBOARD_FAB2(SCH_1):PAGE47
   120    GND @BASEBOARD_FAB2_LIB.BASEBOARD_FAB2(SCH_1):GND    I43 @BASEBOARD_FAB2_LIB.BASEBOARD_FAB2(SCH_1):PAGE47
   123    GND @BASEBOARD_FAB2_LIB.BASEBOARD_FAB2(SCH_1):GND    I43 @BASEBOARD_FAB2_LIB.BASEBOARD_FAB2(SCH_1):PAGE47
   125    GND @BASEBOARD_FAB2_LIB.BASEBOARD_FAB2(SCH_1):GND    I43 @BASEBOARD_FAB2_LIB.BASEBOARD_FAB2(SCH_1):PAGE47
   127    GND @BASEBOARD_FAB2_LIB.BASEBOARD_FAB2(SCH_1):GND    I43 @BASEBOARD_FAB2_LIB.BASEBOARD_FAB2(SCH_1):PAGE47
   129    GND @BASEBOARD_FAB2_LIB.BASEBOARD_FAB2(SCH_1):GND    I43 @BASEBOARD_FAB2_LIB.BASEBOARD_FAB2(SCH_1):PAGE47
   131    GND @BASEBOARD_FAB2_LIB.BASEBOARD_FAB2(SCH_1):GND    I43 @BASEBOARD_FAB2_LIB.BASEBOARD_FAB2(SCH_1):PAGE47
   134    GND @BASEBOARD_FAB2_LIB.BASEBOARD_FAB2(SCH_1):GND    I43 @BASEBOARD_FAB2_LIB.BASEBOARD_FAB2(SCH_1):PAGE47
   136    GND @BASEBOARD_FAB2_LIB.BASEBOARD_FAB2(SCH_1):GND    I43 @BASEBOARD_FAB2_LIB.BASEBOARD_FAB2(SCH_1):PAGE47
   138    GND @BASEBOARD_FAB2_LIB.BASEBOARD_FAB2(SCH_1):GND    I43 @BASEBOARD_FAB2_LIB.BASEBOARD_FAB2(SCH_1):PAGE47
   147    GND @BASEBOARD_FAB2_LIB.BASEBOARD_FAB2(SCH_1):GND    I43 @BASEBOARD_FAB2_LIB.BASEBOARD_FAB2(SCH_1):PAGE47
   149    GND @BASEBOARD_FAB2_LIB.BASEBOARD_FAB2(SCH_1):GND    I43 @BASEBOARD_FAB2_LIB.BASEBOARD_FAB2(SCH_1):PAGE47
   151    GND @BASEBOARD_FAB2_LIB.BASEBOARD_FAB2(SCH_1):GND    I43 @BASEBOARD_FAB2_LIB.BASEBOARD_FAB2(SCH_1):PAGE47
   154    GND @BASEBOARD_FAB2_LIB.BASEBOARD_FAB2(SCH_1):GND    I43 @BASEBOARD_FAB2_LIB.BASEBOARD_FAB2(SCH_1):PAGE47
   156    GND @BASEBOARD_FAB2_LIB.BASEBOARD_FAB2(SCH_1):GND    I43 @BASEBOARD_FAB2_LIB.BASEBOARD_FAB2(SCH_1):PAGE47
   158    GND @BASEBOARD_FAB2_LIB.BASEBOARD_FAB2(SCH_1):GND    I43 @BASEBOARD_FAB2_LIB.BASEBOARD_FAB2(SCH_1):PAGE47
   160    GND @BASEBOARD_FAB2_LIB.BASEBOARD_FAB2(SCH_1):GND    I43 @BASEBOARD_FAB2_LIB.BASEBOARD_FAB2(SCH_1):PAGE47
   162    GND @BASEBOARD_FAB2_LIB.BASEBOARD_FAB2(SCH_1):GND    I43 @BASEBOARD_FAB2_LIB.BASEBOARD_FAB2(SCH_1):PAGE47
   165    GND @BASEBOARD_FAB2_LIB.BASEBOARD_FAB2(SCH_1):GND    I43 @BASEBOARD_FAB2_LIB.BASEBOARD_FAB2(SCH_1):PAGE47
   167    GND @BASEBOARD_FAB2_LIB.BASEBOARD_FAB2(SCH_1):GND    I43 @BASEBOARD_FAB2_LIB.BASEBOARD_FAB2(SCH_1):PAGE47
   169    GND @BASEBOARD_FAB2_LIB.BASEBOARD_FAB2(SCH_1):GND    I43 @BASEBOARD_FAB2_LIB.BASEBOARD_FAB2(SCH_1):PAGE47
   171    GND @BASEBOARD_FAB2_LIB.BASEBOARD_FAB2(SCH_1):GND    I43 @BASEBOARD_FAB2_LIB.BASEBOARD_FAB2(SCH_1):PAGE47
   173    GND @BASEBOARD_FAB2_LIB.BASEBOARD_FAB2(SCH_1):GND    I43 @BASEBOARD_FAB2_LIB.BASEBOARD_FAB2(SCH_1):PAGE47
   176    GND @BASEBOARD_FAB2_LIB.BASEBOARD_FAB2(SCH_1):GND    I43 @BASEBOARD_FAB2_LIB.BASEBOARD_FAB2(SCH_1):PAGE47
   178    GND @BASEBOARD_FAB2_LIB.BASEBOARD_FAB2(SCH_1):GND    I43 @BASEBOARD_FAB2_LIB.BASEBOARD_FAB2(SCH_1):PAGE47
   180    GND @BASEBOARD_FAB2_LIB.BASEBOARD_FAB2(SCH_1):GND    I43 @BASEBOARD_FAB2_LIB.BASEBOARD_FAB2(SCH_1):PAGE47
   182    GND @BASEBOARD_FAB2_LIB.BASEBOARD_FAB2(SCH_1):GND    I43 @BASEBOARD_FAB2_LIB.BASEBOARD_FAB2(SCH_1):PAGE47
   184    GND @BASEBOARD_FAB2_LIB.BASEBOARD_FAB2(SCH_1):GND    I43 @BASEBOARD_FAB2_LIB.BASEBOARD_FAB2(SCH_1):PAGE47
   187    GND @BASEBOARD_FAB2_LIB.BASEBOARD_FAB2(SCH_1):GND    I43 @BASEBOARD_FAB2_LIB.BASEBOARD_FAB2(SCH_1):PAGE47
   189    GND @BASEBOARD_FAB2_LIB.BASEBOARD_FAB2(SCH_1):GND    I43 @BASEBOARD_FAB2_LIB.BASEBOARD_FAB2(SCH_1):PAGE47
   191    GND @BASEBOARD_FAB2_LIB.BASEBOARD_FAB2(SCH_1):GND    I43 @BASEBOARD_FAB2_LIB.BASEBOARD_FAB2(SCH_1):PAGE47
   193    GND @BASEBOARD_FAB2_LIB.BASEBOARD_FAB2(SCH_1):GND    I43 @BASEBOARD_FAB2_LIB.BASEBOARD_FAB2(SCH_1):PAGE47
   195    GND @BASEBOARD_FAB2_LIB.BASEBOARD_FAB2(SCH_1):GND    I43 @BASEBOARD_FAB2_LIB.BASEBOARD_FAB2(SCH_1):PAGE47
   198    GND @BASEBOARD_FAB2_LIB.BASEBOARD_FAB2(SCH_1):GND    I43 @BASEBOARD_FAB2_LIB.BASEBOARD_FAB2(SCH_1):PAGE47
   200    GND @BASEBOARD_FAB2_LIB.BASEBOARD_FAB2(SCH_1):GND    I43 @BASEBOARD_FAB2_LIB.BASEBOARD_FAB2(SCH_1):PAGE47
   202    GND @BASEBOARD_FAB2_LIB.BASEBOARD_FAB2(SCH_1):GND    I43 @BASEBOARD_FAB2_LIB.BASEBOARD_FAB2(SCH_1):PAGE47
   239    GND @BASEBOARD_FAB2_LIB.BASEBOARD_FAB2(SCH_1):GND    I43 @BASEBOARD_FAB2_LIB.BASEBOARD_FAB2(SCH_1):PAGE47
   241    GND @BASEBOARD_FAB2_LIB.BASEBOARD_FAB2(SCH_1):GND    I43 @BASEBOARD_FAB2_LIB.BASEBOARD_FAB2(SCH_1):PAGE47
   243    GND @BASEBOARD_FAB2_LIB.BASEBOARD_FAB2(SCH_1):GND    I43 @BASEBOARD_FAB2_LIB.BASEBOARD_FAB2(SCH_1):PAGE47
   246    GND @BASEBOARD_FAB2_LIB.BASEBOARD_FAB2(SCH_1):GND    I43 @BASEBOARD_FAB2_LIB.BASEBOARD_FAB2(SCH_1):PAGE47
   248    GND @BASEBOARD_FAB2_LIB.BASEBOARD_FAB2(SCH_1):GND    I43 @BASEBOARD_FAB2_LIB.BASEBOARD_FAB2(SCH_1):PAGE47
   250    GND @BASEBOARD_FAB2_LIB.BASEBOARD_FAB2(SCH_1):GND    I43 @BASEBOARD_FAB2_LIB.BASEBOARD_FAB2(SCH_1):PAGE47
   252    GND @BASEBOARD_FAB2_LIB.BASEBOARD_FAB2(SCH_1):GND    I43 @BASEBOARD_FAB2_LIB.BASEBOARD_FAB2(SCH_1):PAGE47
   254    GND @BASEBOARD_FAB2_LIB.BASEBOARD_FAB2(SCH_1):GND    I43 @BASEBOARD_FAB2_LIB.BASEBOARD_FAB2(SCH_1):PAGE47
   257    GND @BASEBOARD_FAB2_LIB.BASEBOARD_FAB2(SCH_1):GND    I43 @BASEBOARD_FAB2_LIB.BASEBOARD_FAB2(SCH_1):PAGE47
   259    GND @BASEBOARD_FAB2_LIB.BASEBOARD_FAB2(SCH_1):GND    I43 @BASEBOARD_FAB2_LIB.BASEBOARD_FAB2(SCH_1):PAGE47
   261    GND @BASEBOARD_FAB2_LIB.BASEBOARD_FAB2(SCH_1):GND    I43 @BASEBOARD_FAB2_LIB.BASEBOARD_FAB2(SCH_1):PAGE47
   263    GND @BASEBOARD_FAB2_LIB.BASEBOARD_FAB2(SCH_1):GND    I43 @BASEBOARD_FAB2_LIB.BASEBOARD_FAB2(SCH_1):PAGE47
   265    GND @BASEBOARD_FAB2_LIB.BASEBOARD_FAB2(SCH_1):GND    I43 @BASEBOARD_FAB2_LIB.BASEBOARD_FAB2(SCH_1):PAGE47
   268    GND @BASEBOARD_FAB2_LIB.BASEBOARD_FAB2(SCH_1):GND    I43 @BASEBOARD_FAB2_LIB.BASEBOARD_FAB2(SCH_1):PAGE47
   270    GND @BASEBOARD_FAB2_LIB.BASEBOARD_FAB2(SCH_1):GND    I43 @BASEBOARD_FAB2_LIB.BASEBOARD_FAB2(SCH_1):PAGE47
   272    GND @BASEBOARD_FAB2_LIB.BASEBOARD_FAB2(SCH_1):GND    I43 @BASEBOARD_FAB2_LIB.BASEBOARD_FAB2(SCH_1):PAGE47
   274    GND @BASEBOARD_FAB2_LIB.BASEBOARD_FAB2(SCH_1):GND    I43 @BASEBOARD_FAB2_LIB.BASEBOARD_FAB2(SCH_1):PAGE47
   276    GND @BASEBOARD_FAB2_LIB.BASEBOARD_FAB2(SCH_1):GND    I43 @BASEBOARD_FAB2_LIB.BASEBOARD_FAB2(SCH_1):PAGE47
   279    GND @BASEBOARD_FAB2_LIB.BASEBOARD_FAB2(SCH_1):GND    I43 @BASEBOARD_FAB2_LIB.BASEBOARD_FAB2(SCH_1):PAGE47
   281    GND @BASEBOARD_FAB2_LIB.BASEBOARD_FAB2(SCH_1):GND    I43 @BASEBOARD_FAB2_LIB.BASEBOARD_FAB2(SCH_1):PAGE47
   283    GND @BASEBOARD_FAB2_LIB.BASEBOARD_FAB2(SCH_1):GND    I43 @BASEBOARD_FAB2_LIB.BASEBOARD_FAB2(SCH_1):PAGE47
     1 P12V_NVDIMM_ABC @BASEBOARD_FAB2_LIB.BASEBOARD_FAB2(SCH_1):P12V_NVDIMM_ABC   I179 @BASEBOARD_FAB2_LIB.BASEBOARD_FAB2(SCH_1):PAGE47
   145 P12V_NVDIMM_ABC @BASEBOARD_FAB2_LIB.BASEBOARD_FAB2(SCH_1):P12V_NVDIMM_ABC   I179 @BASEBOARD_FAB2_LIB.BASEBOARD_FAB2(SCH_1):PAGE47
    59 PVDDQ_ABC @BASEBOARD_FAB2_LIB.BASEBOARD_FAB2(SCH_1):PVDDQ_ABC   I179 @BASEBOARD_FAB2_LIB.BASEBOARD_FAB2(SCH_1):PAGE47
    61 PVDDQ_ABC @BASEBOARD_FAB2_LIB.BASEBOARD_FAB2(SCH_1):PVDDQ_ABC   I179 @BASEBOARD_FAB2_LIB.BASEBOARD_FAB2(SCH_1):PAGE47
    64 PVDDQ_ABC @BASEBOARD_FAB2_LIB.BASEBOARD_FAB2(SCH_1):PVDDQ_ABC   I179 @BASEBOARD_FAB2_LIB.BASEBOARD_FAB2(SCH_1):PAGE47
    67 PVDDQ_ABC @BASEBOARD_FAB2_LIB.BASEBOARD_FAB2(SCH_1):PVDDQ_ABC   I179 @BASEBOARD_FAB2_LIB.BASEBOARD_FAB2(SCH_1):PAGE47
    70 PVDDQ_ABC @BASEBOARD_FAB2_LIB.BASEBOARD_FAB2(SCH_1):PVDDQ_ABC   I179 @BASEBOARD_FAB2_LIB.BASEBOARD_FAB2(SCH_1):PAGE47
    73 PVDDQ_ABC @BASEBOARD_FAB2_LIB.BASEBOARD_FAB2(SCH_1):PVDDQ_ABC   I179 @BASEBOARD_FAB2_LIB.BASEBOARD_FAB2(SCH_1):PAGE47
    76 PVDDQ_ABC @BASEBOARD_FAB2_LIB.BASEBOARD_FAB2(SCH_1):PVDDQ_ABC   I179 @BASEBOARD_FAB2_LIB.BASEBOARD_FAB2(SCH_1):PAGE47
    80 PVDDQ_ABC @BASEBOARD_FAB2_LIB.BASEBOARD_FAB2(SCH_1):PVDDQ_ABC   I179 @BASEBOARD_FAB2_LIB.BASEBOARD_FAB2(SCH_1):PAGE47
    83 PVDDQ_ABC @BASEBOARD_FAB2_LIB.BASEBOARD_FAB2(SCH_1):PVDDQ_ABC   I179 @BASEBOARD_FAB2_LIB.BASEBOARD_FAB2(SCH_1):PAGE47
    85 PVDDQ_ABC @BASEBOARD_FAB2_LIB.BASEBOARD_FAB2(SCH_1):PVDDQ_ABC   I179 @BASEBOARD_FAB2_LIB.BASEBOARD_FAB2(SCH_1):PAGE47
    88 PVDDQ_ABC @BASEBOARD_FAB2_LIB.BASEBOARD_FAB2(SCH_1):PVDDQ_ABC   I179 @BASEBOARD_FAB2_LIB.BASEBOARD_FAB2(SCH_1):PAGE47
    90 PVDDQ_ABC @BASEBOARD_FAB2_LIB.BASEBOARD_FAB2(SCH_1):PVDDQ_ABC   I179 @BASEBOARD_FAB2_LIB.BASEBOARD_FAB2(SCH_1):PAGE47
    92 PVDDQ_ABC @BASEBOARD_FAB2_LIB.BASEBOARD_FAB2(SCH_1):PVDDQ_ABC   I179 @BASEBOARD_FAB2_LIB.BASEBOARD_FAB2(SCH_1):PAGE47
   204 PVDDQ_ABC @BASEBOARD_FAB2_LIB.BASEBOARD_FAB2(SCH_1):PVDDQ_ABC   I179 @BASEBOARD_FAB2_LIB.BASEBOARD_FAB2(SCH_1):PAGE47
   206 PVDDQ_ABC @BASEBOARD_FAB2_LIB.BASEBOARD_FAB2(SCH_1):PVDDQ_ABC   I179 @BASEBOARD_FAB2_LIB.BASEBOARD_FAB2(SCH_1):PAGE47
   209 PVDDQ_ABC @BASEBOARD_FAB2_LIB.BASEBOARD_FAB2(SCH_1):PVDDQ_ABC   I179 @BASEBOARD_FAB2_LIB.BASEBOARD_FAB2(SCH_1):PAGE47
   212 PVDDQ_ABC @BASEBOARD_FAB2_LIB.BASEBOARD_FAB2(SCH_1):PVDDQ_ABC   I179 @BASEBOARD_FAB2_LIB.BASEBOARD_FAB2(SCH_1):PAGE47
   215 PVDDQ_ABC @BASEBOARD_FAB2_LIB.BASEBOARD_FAB2(SCH_1):PVDDQ_ABC   I179 @BASEBOARD_FAB2_LIB.BASEBOARD_FAB2(SCH_1):PAGE47
   217 PVDDQ_ABC @BASEBOARD_FAB2_LIB.BASEBOARD_FAB2(SCH_1):PVDDQ_ABC   I179 @BASEBOARD_FAB2_LIB.BASEBOARD_FAB2(SCH_1):PAGE47
   220 PVDDQ_ABC @BASEBOARD_FAB2_LIB.BASEBOARD_FAB2(SCH_1):PVDDQ_ABC   I179 @BASEBOARD_FAB2_LIB.BASEBOARD_FAB2(SCH_1):PAGE47
   223 PVDDQ_ABC @BASEBOARD_FAB2_LIB.BASEBOARD_FAB2(SCH_1):PVDDQ_ABC   I179 @BASEBOARD_FAB2_LIB.BASEBOARD_FAB2(SCH_1):PAGE47
   226 PVDDQ_ABC @BASEBOARD_FAB2_LIB.BASEBOARD_FAB2(SCH_1):PVDDQ_ABC   I179 @BASEBOARD_FAB2_LIB.BASEBOARD_FAB2(SCH_1):PAGE47
   229 PVDDQ_ABC @BASEBOARD_FAB2_LIB.BASEBOARD_FAB2(SCH_1):PVDDQ_ABC   I179 @BASEBOARD_FAB2_LIB.BASEBOARD_FAB2(SCH_1):PAGE47
   231 PVDDQ_ABC @BASEBOARD_FAB2_LIB.BASEBOARD_FAB2(SCH_1):PVDDQ_ABC   I179 @BASEBOARD_FAB2_LIB.BASEBOARD_FAB2(SCH_1):PAGE47
   233 PVDDQ_ABC @BASEBOARD_FAB2_LIB.BASEBOARD_FAB2(SCH_1):PVDDQ_ABC   I179 @BASEBOARD_FAB2_LIB.BASEBOARD_FAB2(SCH_1):PAGE47
   236 PVDDQ_ABC @BASEBOARD_FAB2_LIB.BASEBOARD_FAB2(SCH_1):PVDDQ_ABC   I179 @BASEBOARD_FAB2_LIB.BASEBOARD_FAB2(SCH_1):PAGE47
   142 PVPP_ABC @BASEBOARD_FAB2_LIB.BASEBOARD_FAB2(SCH_1):PVPP_ABC   I179 @BASEBOARD_FAB2_LIB.BASEBOARD_FAB2(SCH_1):PAGE47
   143 PVPP_ABC @BASEBOARD_FAB2_LIB.BASEBOARD_FAB2(SCH_1):PVPP_ABC   I179 @BASEBOARD_FAB2_LIB.BASEBOARD_FAB2(SCH_1):PAGE47
   288 PVPP_ABC @BASEBOARD_FAB2_LIB.BASEBOARD_FAB2(SCH_1):PVPP_ABC   I179 @BASEBOARD_FAB2_LIB.BASEBOARD_FAB2(SCH_1):PAGE47
   286 PVPP_ABC @BASEBOARD_FAB2_LIB.BASEBOARD_FAB2(SCH_1):PVPP_ABC   I179 @BASEBOARD_FAB2_LIB.BASEBOARD_FAB2(SCH_1):PAGE47
   287 PVPP_ABC @BASEBOARD_FAB2_LIB.BASEBOARD_FAB2(SCH_1):PVPP_ABC   I179 @BASEBOARD_FAB2_LIB.BASEBOARD_FAB2(SCH_1):PAGE47
    77 PVTT_ABC @BASEBOARD_FAB2_LIB.BASEBOARD_FAB2(SCH_1):PVTT_ABC   I179 @BASEBOARD_FAB2_LIB.BASEBOARD_FAB2(SCH_1):PAGE47
   221 PVTT_ABC @BASEBOARD_FAB2_LIB.BASEBOARD_FAB2(SCH_1):PVTT_ABC   I179 @BASEBOARD_FAB2_LIB.BASEBOARD_FAB2(SCH_1):PAGE47

J6B1 SCONN120_H61426002_SM-CONN,H61A
    A1 P12V_STBY @BASEBOARD_FAB2_LIB.BASEBOARD_FAB2(SCH_1):P12V_STBY    I56 @BASEBOARD_FAB2_LIB.BASEBOARD_FAB2(SCH_1):PAGE194
   A10    GND @BASEBOARD_FAB2_LIB.BASEBOARD_FAB2(SCH_1):GND    I56 @BASEBOARD_FAB2_LIB.BASEBOARD_FAB2(SCH_1):PAGE194
   A11 P3V3_STBY @BASEBOARD_FAB2_LIB.BASEBOARD_FAB2(SCH_1):P3V3_STBY    I56 @BASEBOARD_FAB2_LIB.BASEBOARD_FAB2(SCH_1):PAGE194
   A12    GND @BASEBOARD_FAB2_LIB.BASEBOARD_FAB2(SCH_1):GND    I56 @BASEBOARD_FAB2_LIB.BASEBOARD_FAB2(SCH_1):PAGE194
   A13 P5V_STBY @BASEBOARD_FAB2_LIB.BASEBOARD_FAB2(SCH_1):P5V_STBY    I56 @BASEBOARD_FAB2_LIB.BASEBOARD_FAB2(SCH_1):PAGE194
   A14    GND @BASEBOARD_FAB2_LIB.BASEBOARD_FAB2(SCH_1):GND    I56 @BASEBOARD_FAB2_LIB.BASEBOARD_FAB2(SCH_1):PAGE194
   A15 FM_P1V8MCP_CPU0_EN @BASEBOARD_FAB2_LIB.BASEBOARD_FAB2(SCH_1):FM_P1V8MCP_CPU0_EN    I56 @BASEBOARD_FAB2_LIB.BASEBOARD_FAB2(SCH_1):PAGE194
   A16 FM_PVCCIOMCP_CPU0_EN @BASEBOARD_FAB2_LIB.BASEBOARD_FAB2(SCH_1):FM_PVCCIOMCP_CPU0_EN    I56 @BASEBOARD_FAB2_LIB.BASEBOARD_FAB2(SCH_1):PAGE194
   A17    GND @BASEBOARD_FAB2_LIB.BASEBOARD_FAB2(SCH_1):GND    I56 @BASEBOARD_FAB2_LIB.BASEBOARD_FAB2(SCH_1):PAGE194
   A18 SMB_VR_STBY_LVC3_SCL @BASEBOARD_FAB2_LIB.BASEBOARD_FAB2(SCH_1):SMB_VR_STBY_LVC3_SCL    I56 @BASEBOARD_FAB2_LIB.BASEBOARD_FAB2(SCH_1):PAGE194
   A19 SVID_ALERT0_CPU0_R_N @BASEBOARD_FAB2_LIB.BASEBOARD_FAB2(SCH_1):SVID_ALERT0_CPU0_R_N    I56 @BASEBOARD_FAB2_LIB.BASEBOARD_FAB2(SCH_1):PAGE194
    A2 P12V_STBY @BASEBOARD_FAB2_LIB.BASEBOARD_FAB2(SCH_1):P12V_STBY    I56 @BASEBOARD_FAB2_LIB.BASEBOARD_FAB2(SCH_1):PAGE194
   A20 SVID_CLK0_CPU0_R @BASEBOARD_FAB2_LIB.BASEBOARD_FAB2(SCH_1):SVID_CLK0_CPU0_R    I56 @BASEBOARD_FAB2_LIB.BASEBOARD_FAB2(SCH_1):PAGE194
    A3 P12V_STBY @BASEBOARD_FAB2_LIB.BASEBOARD_FAB2(SCH_1):P12V_STBY    I56 @BASEBOARD_FAB2_LIB.BASEBOARD_FAB2(SCH_1):PAGE194
    A4 P12V_STBY @BASEBOARD_FAB2_LIB.BASEBOARD_FAB2(SCH_1):P12V_STBY    I56 @BASEBOARD_FAB2_LIB.BASEBOARD_FAB2(SCH_1):PAGE194
    A5 P12V_STBY @BASEBOARD_FAB2_LIB.BASEBOARD_FAB2(SCH_1):P12V_STBY    I56 @BASEBOARD_FAB2_LIB.BASEBOARD_FAB2(SCH_1):PAGE194
    A6 P12V_STBY @BASEBOARD_FAB2_LIB.BASEBOARD_FAB2(SCH_1):P12V_STBY    I56 @BASEBOARD_FAB2_LIB.BASEBOARD_FAB2(SCH_1):PAGE194
    A7 P12V_STBY @BASEBOARD_FAB2_LIB.BASEBOARD_FAB2(SCH_1):P12V_STBY    I56 @BASEBOARD_FAB2_LIB.BASEBOARD_FAB2(SCH_1):PAGE194
    A8 P12V_STBY @BASEBOARD_FAB2_LIB.BASEBOARD_FAB2(SCH_1):P12V_STBY    I56 @BASEBOARD_FAB2_LIB.BASEBOARD_FAB2(SCH_1):PAGE194
    A9    GND @BASEBOARD_FAB2_LIB.BASEBOARD_FAB2(SCH_1):GND    I56 @BASEBOARD_FAB2_LIB.BASEBOARD_FAB2(SCH_1):PAGE194
    B1 P12V_STBY @BASEBOARD_FAB2_LIB.BASEBOARD_FAB2(SCH_1):P12V_STBY    I56 @BASEBOARD_FAB2_LIB.BASEBOARD_FAB2(SCH_1):PAGE194
   B10    GND @BASEBOARD_FAB2_LIB.BASEBOARD_FAB2(SCH_1):GND    I56 @BASEBOARD_FAB2_LIB.BASEBOARD_FAB2(SCH_1):PAGE194
   B11 P3V3_STBY @BASEBOARD_FAB2_LIB.BASEBOARD_FAB2(SCH_1):P3V3_STBY    I56 @BASEBOARD_FAB2_LIB.BASEBOARD_FAB2(SCH_1):PAGE194
   B12    GND @BASEBOARD_FAB2_LIB.BASEBOARD_FAB2(SCH_1):GND    I56 @BASEBOARD_FAB2_LIB.BASEBOARD_FAB2(SCH_1):PAGE194
   B13 P5V_STBY @BASEBOARD_FAB2_LIB.BASEBOARD_FAB2(SCH_1):P5V_STBY    I56 @BASEBOARD_FAB2_LIB.BASEBOARD_FAB2(SCH_1):PAGE194
   B14    GND @BASEBOARD_FAB2_LIB.BASEBOARD_FAB2(SCH_1):GND    I56 @BASEBOARD_FAB2_LIB.BASEBOARD_FAB2(SCH_1):PAGE194
   B15 PWRGD_P1V8MCP_CPU0 @BASEBOARD_FAB2_LIB.BASEBOARD_FAB2(SCH_1):PWRGD_P1V8MCP_CPU0    I56 @BASEBOARD_FAB2_LIB.BASEBOARD_FAB2(SCH_1):PAGE194
   B16 PWRGD_PVCCIOMCP_CPU0 @BASEBOARD_FAB2_LIB.BASEBOARD_FAB2(SCH_1):PWRGD_PVCCIOMCP_CPU0    I56 @BASEBOARD_FAB2_LIB.BASEBOARD_FAB2(SCH_1):PAGE194
   B17    GND @BASEBOARD_FAB2_LIB.BASEBOARD_FAB2(SCH_1):GND    I56 @BASEBOARD_FAB2_LIB.BASEBOARD_FAB2(SCH_1):PAGE194
   B18 SMB_VR_STBY_LVC3_SDA @BASEBOARD_FAB2_LIB.BASEBOARD_FAB2(SCH_1):SMB_VR_STBY_LVC3_SDA    I56 @BASEBOARD_FAB2_LIB.BASEBOARD_FAB2(SCH_1):PAGE194
   B19 SVID_ALERT1_CPU0_R_N @BASEBOARD_FAB2_LIB.BASEBOARD_FAB2(SCH_1):SVID_ALERT1_CPU0_R_N    I56 @BASEBOARD_FAB2_LIB.BASEBOARD_FAB2(SCH_1):PAGE194
    B2 P12V_STBY @BASEBOARD_FAB2_LIB.BASEBOARD_FAB2(SCH_1):P12V_STBY    I56 @BASEBOARD_FAB2_LIB.BASEBOARD_FAB2(SCH_1):PAGE194
   B20 SVID_DIO0_CPU0_R @BASEBOARD_FAB2_LIB.BASEBOARD_FAB2(SCH_1):SVID_DIO0_CPU0_R    I56 @BASEBOARD_FAB2_LIB.BASEBOARD_FAB2(SCH_1):PAGE194
    B3 P12V_STBY @BASEBOARD_FAB2_LIB.BASEBOARD_FAB2(SCH_1):P12V_STBY    I56 @BASEBOARD_FAB2_LIB.BASEBOARD_FAB2(SCH_1):PAGE194
    B4 P12V_STBY @BASEBOARD_FAB2_LIB.BASEBOARD_FAB2(SCH_1):P12V_STBY    I56 @BASEBOARD_FAB2_LIB.BASEBOARD_FAB2(SCH_1):PAGE194
    B5 P12V_STBY @BASEBOARD_FAB2_LIB.BASEBOARD_FAB2(SCH_1):P12V_STBY    I56 @BASEBOARD_FAB2_LIB.BASEBOARD_FAB2(SCH_1):PAGE194
    B6 P12V_STBY @BASEBOARD_FAB2_LIB.BASEBOARD_FAB2(SCH_1):P12V_STBY    I56 @BASEBOARD_FAB2_LIB.BASEBOARD_FAB2(SCH_1):PAGE194
    B7 P12V_STBY @BASEBOARD_FAB2_LIB.BASEBOARD_FAB2(SCH_1):P12V_STBY    I56 @BASEBOARD_FAB2_LIB.BASEBOARD_FAB2(SCH_1):PAGE194
    B8 P12V_STBY @BASEBOARD_FAB2_LIB.BASEBOARD_FAB2(SCH_1):P12V_STBY    I56 @BASEBOARD_FAB2_LIB.BASEBOARD_FAB2(SCH_1):PAGE194
    B9    GND @BASEBOARD_FAB2_LIB.BASEBOARD_FAB2(SCH_1):GND    I56 @BASEBOARD_FAB2_LIB.BASEBOARD_FAB2(SCH_1):PAGE194
    C1    GND @BASEBOARD_FAB2_LIB.BASEBOARD_FAB2(SCH_1):GND    I56 @BASEBOARD_FAB2_LIB.BASEBOARD_FAB2(SCH_1):PAGE194
   C10    GND @BASEBOARD_FAB2_LIB.BASEBOARD_FAB2(SCH_1):GND    I56 @BASEBOARD_FAB2_LIB.BASEBOARD_FAB2(SCH_1):PAGE194
   C11 P3V3_STBY @BASEBOARD_FAB2_LIB.BASEBOARD_FAB2(SCH_1):P3V3_STBY    I56 @BASEBOARD_FAB2_LIB.BASEBOARD_FAB2(SCH_1):PAGE194
   C12    GND @BASEBOARD_FAB2_LIB.BASEBOARD_FAB2(SCH_1):GND    I56 @BASEBOARD_FAB2_LIB.BASEBOARD_FAB2(SCH_1):PAGE194
   C13 P5V_STBY @BASEBOARD_FAB2_LIB.BASEBOARD_FAB2(SCH_1):P5V_STBY    I56 @BASEBOARD_FAB2_LIB.BASEBOARD_FAB2(SCH_1):PAGE194
   C14    GND @BASEBOARD_FAB2_LIB.BASEBOARD_FAB2(SCH_1):GND    I56 @BASEBOARD_FAB2_LIB.BASEBOARD_FAB2(SCH_1):PAGE194
   C15    GND @BASEBOARD_FAB2_LIB.BASEBOARD_FAB2(SCH_1):GND    I56 @BASEBOARD_FAB2_LIB.BASEBOARD_FAB2(SCH_1):PAGE194
   C16    GND @BASEBOARD_FAB2_LIB.BASEBOARD_FAB2(SCH_1):GND    I56 @BASEBOARD_FAB2_LIB.BASEBOARD_FAB2(SCH_1):PAGE194
   C17 PVCCIOMCP_CPU0 @BASEBOARD_FAB2_LIB.BASEBOARD_FAB2(SCH_1):PVCCIOMCP_CPU0    I56 @BASEBOARD_FAB2_LIB.BASEBOARD_FAB2(SCH_1):PAGE194
   C18 PVCCIOMCP_CPU0 @BASEBOARD_FAB2_LIB.BASEBOARD_FAB2(SCH_1):PVCCIOMCP_CPU0    I56 @BASEBOARD_FAB2_LIB.BASEBOARD_FAB2(SCH_1):PAGE194
   C19 PVCCIOMCP_CPU0 @BASEBOARD_FAB2_LIB.BASEBOARD_FAB2(SCH_1):PVCCIOMCP_CPU0    I56 @BASEBOARD_FAB2_LIB.BASEBOARD_FAB2(SCH_1):PAGE194
    C2    GND @BASEBOARD_FAB2_LIB.BASEBOARD_FAB2(SCH_1):GND    I56 @BASEBOARD_FAB2_LIB.BASEBOARD_FAB2(SCH_1):PAGE194
   C20 FM_PVCCMCP_CPU0_EN @BASEBOARD_FAB2_LIB.BASEBOARD_FAB2(SCH_1):FM_PVCCMCP_CPU0_EN    I56 @BASEBOARD_FAB2_LIB.BASEBOARD_FAB2(SCH_1):PAGE194
    C3    GND @BASEBOARD_FAB2_LIB.BASEBOARD_FAB2(SCH_1):GND    I56 @BASEBOARD_FAB2_LIB.BASEBOARD_FAB2(SCH_1):PAGE194
    C4    GND @BASEBOARD_FAB2_LIB.BASEBOARD_FAB2(SCH_1):GND    I56 @BASEBOARD_FAB2_LIB.BASEBOARD_FAB2(SCH_1):PAGE194
    C5    GND @BASEBOARD_FAB2_LIB.BASEBOARD_FAB2(SCH_1):GND    I56 @BASEBOARD_FAB2_LIB.BASEBOARD_FAB2(SCH_1):PAGE194
    C6    GND @BASEBOARD_FAB2_LIB.BASEBOARD_FAB2(SCH_1):GND    I56 @BASEBOARD_FAB2_LIB.BASEBOARD_FAB2(SCH_1):PAGE194
    C7    GND @BASEBOARD_FAB2_LIB.BASEBOARD_FAB2(SCH_1):GND    I56 @BASEBOARD_FAB2_LIB.BASEBOARD_FAB2(SCH_1):PAGE194
    C8    GND @BASEBOARD_FAB2_LIB.BASEBOARD_FAB2(SCH_1):GND    I56 @BASEBOARD_FAB2_LIB.BASEBOARD_FAB2(SCH_1):PAGE194
    C9    GND @BASEBOARD_FAB2_LIB.BASEBOARD_FAB2(SCH_1):GND    I56 @BASEBOARD_FAB2_LIB.BASEBOARD_FAB2(SCH_1):PAGE194
    D1   P3V3 @BASEBOARD_FAB2_LIB.BASEBOARD_FAB2(SCH_1):P3V3    I56 @BASEBOARD_FAB2_LIB.BASEBOARD_FAB2(SCH_1):PAGE194
   D10    GND @BASEBOARD_FAB2_LIB.BASEBOARD_FAB2(SCH_1):GND    I56 @BASEBOARD_FAB2_LIB.BASEBOARD_FAB2(SCH_1):PAGE194
   D11    GND @BASEBOARD_FAB2_LIB.BASEBOARD_FAB2(SCH_1):GND    I56 @BASEBOARD_FAB2_LIB.BASEBOARD_FAB2(SCH_1):PAGE194
   D12    GND @BASEBOARD_FAB2_LIB.BASEBOARD_FAB2(SCH_1):GND    I56 @BASEBOARD_FAB2_LIB.BASEBOARD_FAB2(SCH_1):PAGE194
   D13    GND @BASEBOARD_FAB2_LIB.BASEBOARD_FAB2(SCH_1):GND    I56 @BASEBOARD_FAB2_LIB.BASEBOARD_FAB2(SCH_1):PAGE194
   D14    GND @BASEBOARD_FAB2_LIB.BASEBOARD_FAB2(SCH_1):GND    I56 @BASEBOARD_FAB2_LIB.BASEBOARD_FAB2(SCH_1):PAGE194
   D15 PVCCIOMCP_CPU0 @BASEBOARD_FAB2_LIB.BASEBOARD_FAB2(SCH_1):PVCCIOMCP_CPU0    I56 @BASEBOARD_FAB2_LIB.BASEBOARD_FAB2(SCH_1):PAGE194
   D16 PVCCIOMCP_CPU0 @BASEBOARD_FAB2_LIB.BASEBOARD_FAB2(SCH_1):PVCCIOMCP_CPU0    I56 @BASEBOARD_FAB2_LIB.BASEBOARD_FAB2(SCH_1):PAGE194
   D17 PVCCIOMCP_CPU0 @BASEBOARD_FAB2_LIB.BASEBOARD_FAB2(SCH_1):PVCCIOMCP_CPU0    I56 @BASEBOARD_FAB2_LIB.BASEBOARD_FAB2(SCH_1):PAGE194
   D18 PVCCIOMCP_CPU0 @BASEBOARD_FAB2_LIB.BASEBOARD_FAB2(SCH_1):PVCCIOMCP_CPU0    I56 @BASEBOARD_FAB2_LIB.BASEBOARD_FAB2(SCH_1):PAGE194
   D19 PVCCIOMCP_CPU0 @BASEBOARD_FAB2_LIB.BASEBOARD_FAB2(SCH_1):PVCCIOMCP_CPU0    I56 @BASEBOARD_FAB2_LIB.BASEBOARD_FAB2(SCH_1):PAGE194
    D2    GND @BASEBOARD_FAB2_LIB.BASEBOARD_FAB2(SCH_1):GND    I56 @BASEBOARD_FAB2_LIB.BASEBOARD_FAB2(SCH_1):PAGE194
   D20 PWRGD_PVCCMCP_CPU0 @BASEBOARD_FAB2_LIB.BASEBOARD_FAB2(SCH_1):PWRGD_PVCCMCP_CPU0    I56 @BASEBOARD_FAB2_LIB.BASEBOARD_FAB2(SCH_1):PAGE194
    D3    GND @BASEBOARD_FAB2_LIB.BASEBOARD_FAB2(SCH_1):GND    I56 @BASEBOARD_FAB2_LIB.BASEBOARD_FAB2(SCH_1):PAGE194
    D4    GND @BASEBOARD_FAB2_LIB.BASEBOARD_FAB2(SCH_1):GND    I56 @BASEBOARD_FAB2_LIB.BASEBOARD_FAB2(SCH_1):PAGE194
    D5    GND @BASEBOARD_FAB2_LIB.BASEBOARD_FAB2(SCH_1):GND    I56 @BASEBOARD_FAB2_LIB.BASEBOARD_FAB2(SCH_1):PAGE194
    D6    GND @BASEBOARD_FAB2_LIB.BASEBOARD_FAB2(SCH_1):GND    I56 @BASEBOARD_FAB2_LIB.BASEBOARD_FAB2(SCH_1):PAGE194
    D7    GND @BASEBOARD_FAB2_LIB.BASEBOARD_FAB2(SCH_1):GND    I56 @BASEBOARD_FAB2_LIB.BASEBOARD_FAB2(SCH_1):PAGE194
    D8    GND @BASEBOARD_FAB2_LIB.BASEBOARD_FAB2(SCH_1):GND    I56 @BASEBOARD_FAB2_LIB.BASEBOARD_FAB2(SCH_1):PAGE194
    D9    GND @BASEBOARD_FAB2_LIB.BASEBOARD_FAB2(SCH_1):GND    I56 @BASEBOARD_FAB2_LIB.BASEBOARD_FAB2(SCH_1):PAGE194
    E1 FM_CPU0_VRM_322M_156M_OSC_EN @BASEBOARD_FAB2_LIB.BASEBOARD_FAB2(SCH_1):FM_CPU0_VRM_322M_156M_OSC_EN    I56 @BASEBOARD_FAB2_LIB.BASEBOARD_FAB2(SCH_1):PAGE194
   E10 VR_PVCCIOMCP_CPU0_XADDR1 @BASEBOARD_FAB2_LIB.BASEBOARD_FAB2(SCH_1):VR_PVCCIOMCP_CPU0_XADDR1    I56 @BASEBOARD_FAB2_LIB.BASEBOARD_FAB2(SCH_1):PAGE194
   E11    GND @BASEBOARD_FAB2_LIB.BASEBOARD_FAB2(SCH_1):GND    I56 @BASEBOARD_FAB2_LIB.BASEBOARD_FAB2(SCH_1):PAGE194
   E12    GND @BASEBOARD_FAB2_LIB.BASEBOARD_FAB2(SCH_1):GND    I56 @BASEBOARD_FAB2_LIB.BASEBOARD_FAB2(SCH_1):PAGE194
   E13    GND @BASEBOARD_FAB2_LIB.BASEBOARD_FAB2(SCH_1):GND    I56 @BASEBOARD_FAB2_LIB.BASEBOARD_FAB2(SCH_1):PAGE194
   E14    GND @BASEBOARD_FAB2_LIB.BASEBOARD_FAB2(SCH_1):GND    I56 @BASEBOARD_FAB2_LIB.BASEBOARD_FAB2(SCH_1):PAGE194
   E15 PVCCIOMCP_CPU0 @BASEBOARD_FAB2_LIB.BASEBOARD_FAB2(SCH_1):PVCCIOMCP_CPU0    I56 @BASEBOARD_FAB2_LIB.BASEBOARD_FAB2(SCH_1):PAGE194
   E16 PVCCIOMCP_CPU0 @BASEBOARD_FAB2_LIB.BASEBOARD_FAB2(SCH_1):PVCCIOMCP_CPU0    I56 @BASEBOARD_FAB2_LIB.BASEBOARD_FAB2(SCH_1):PAGE194
   E17 PVCCIOMCP_CPU0 @BASEBOARD_FAB2_LIB.BASEBOARD_FAB2(SCH_1):PVCCIOMCP_CPU0    I56 @BASEBOARD_FAB2_LIB.BASEBOARD_FAB2(SCH_1):PAGE194
   E18 PVCCIOMCP_CPU0 @BASEBOARD_FAB2_LIB.BASEBOARD_FAB2(SCH_1):PVCCIOMCP_CPU0    I56 @BASEBOARD_FAB2_LIB.BASEBOARD_FAB2(SCH_1):PAGE194
   E19 PVCCIOMCP_CPU0 @BASEBOARD_FAB2_LIB.BASEBOARD_FAB2(SCH_1):PVCCIOMCP_CPU0    I56 @BASEBOARD_FAB2_LIB.BASEBOARD_FAB2(SCH_1):PAGE194
    E2    GND @BASEBOARD_FAB2_LIB.BASEBOARD_FAB2(SCH_1):GND    I56 @BASEBOARD_FAB2_LIB.BASEBOARD_FAB2(SCH_1):PAGE194
   E20 SVID_CLK1_CPU0_R @BASEBOARD_FAB2_LIB.BASEBOARD_FAB2(SCH_1):SVID_CLK1_CPU0_R    I56 @BASEBOARD_FAB2_LIB.BASEBOARD_FAB2(SCH_1):PAGE194
    E3    GND @BASEBOARD_FAB2_LIB.BASEBOARD_FAB2(SCH_1):GND    I56 @BASEBOARD_FAB2_LIB.BASEBOARD_FAB2(SCH_1):PAGE194
    E4    GND @BASEBOARD_FAB2_LIB.BASEBOARD_FAB2(SCH_1):GND    I56 @BASEBOARD_FAB2_LIB.BASEBOARD_FAB2(SCH_1):PAGE194
    E5    GND @BASEBOARD_FAB2_LIB.BASEBOARD_FAB2(SCH_1):GND    I56 @BASEBOARD_FAB2_LIB.BASEBOARD_FAB2(SCH_1):PAGE194
    E6    GND @BASEBOARD_FAB2_LIB.BASEBOARD_FAB2(SCH_1):GND    I56 @BASEBOARD_FAB2_LIB.BASEBOARD_FAB2(SCH_1):PAGE194
    E7    GND @BASEBOARD_FAB2_LIB.BASEBOARD_FAB2(SCH_1):GND    I56 @BASEBOARD_FAB2_LIB.BASEBOARD_FAB2(SCH_1):PAGE194
    E8 VSENSE_PVCCIOMCP_CPU0_SKT_VSEN @BASEBOARD_FAB2_LIB.BASEBOARD_FAB2(SCH_1):VSENSE_PVCCIOMCP_CPU0_SKT_VSEN    I56 @BASEBOARD_FAB2_LIB.BASEBOARD_FAB2(SCH_1):PAGE194
    E9    GND @BASEBOARD_FAB2_LIB.BASEBOARD_FAB2(SCH_1):GND    I56 @BASEBOARD_FAB2_LIB.BASEBOARD_FAB2(SCH_1):PAGE194
    F1 PVCCIO_CPU0 @BASEBOARD_FAB2_LIB.BASEBOARD_FAB2(SCH_1):PVCCIO_CPU0    I56 @BASEBOARD_FAB2_LIB.BASEBOARD_FAB2(SCH_1):PAGE194
   F10 VR_PVCCMCP_CPU0_XADDR2 @BASEBOARD_FAB2_LIB.BASEBOARD_FAB2(SCH_1):VR_PVCCMCP_CPU0_XADDR2    I56 @BASEBOARD_FAB2_LIB.BASEBOARD_FAB2(SCH_1):PAGE194
   F11    GND @BASEBOARD_FAB2_LIB.BASEBOARD_FAB2(SCH_1):GND    I56 @BASEBOARD_FAB2_LIB.BASEBOARD_FAB2(SCH_1):PAGE194
   F12    GND @BASEBOARD_FAB2_LIB.BASEBOARD_FAB2(SCH_1):GND    I56 @BASEBOARD_FAB2_LIB.BASEBOARD_FAB2(SCH_1):PAGE194
   F13    GND @BASEBOARD_FAB2_LIB.BASEBOARD_FAB2(SCH_1):GND    I56 @BASEBOARD_FAB2_LIB.BASEBOARD_FAB2(SCH_1):PAGE194
   F14    GND @BASEBOARD_FAB2_LIB.BASEBOARD_FAB2(SCH_1):GND    I56 @BASEBOARD_FAB2_LIB.BASEBOARD_FAB2(SCH_1):PAGE194
   F15 PVCCIOMCP_CPU0 @BASEBOARD_FAB2_LIB.BASEBOARD_FAB2(SCH_1):PVCCIOMCP_CPU0    I56 @BASEBOARD_FAB2_LIB.BASEBOARD_FAB2(SCH_1):PAGE194
   F16 PVCCIOMCP_CPU0 @BASEBOARD_FAB2_LIB.BASEBOARD_FAB2(SCH_1):PVCCIOMCP_CPU0    I56 @BASEBOARD_FAB2_LIB.BASEBOARD_FAB2(SCH_1):PAGE194
   F17 PVCCIOMCP_CPU0 @BASEBOARD_FAB2_LIB.BASEBOARD_FAB2(SCH_1):PVCCIOMCP_CPU0    I56 @BASEBOARD_FAB2_LIB.BASEBOARD_FAB2(SCH_1):PAGE194
   F18 PVCCIOMCP_CPU0 @BASEBOARD_FAB2_LIB.BASEBOARD_FAB2(SCH_1):PVCCIOMCP_CPU0    I56 @BASEBOARD_FAB2_LIB.BASEBOARD_FAB2(SCH_1):PAGE194
   F19 PVCCIOMCP_CPU0 @BASEBOARD_FAB2_LIB.BASEBOARD_FAB2(SCH_1):PVCCIOMCP_CPU0    I56 @BASEBOARD_FAB2_LIB.BASEBOARD_FAB2(SCH_1):PAGE194
    F2    GND @BASEBOARD_FAB2_LIB.BASEBOARD_FAB2(SCH_1):GND    I56 @BASEBOARD_FAB2_LIB.BASEBOARD_FAB2(SCH_1):PAGE194
   F20 SVID_DIO1_CPU0_R @BASEBOARD_FAB2_LIB.BASEBOARD_FAB2(SCH_1):SVID_DIO1_CPU0_R    I56 @BASEBOARD_FAB2_LIB.BASEBOARD_FAB2(SCH_1):PAGE194
    F3    GND @BASEBOARD_FAB2_LIB.BASEBOARD_FAB2(SCH_1):GND    I56 @BASEBOARD_FAB2_LIB.BASEBOARD_FAB2(SCH_1):PAGE194
    F4    GND @BASEBOARD_FAB2_LIB.BASEBOARD_FAB2(SCH_1):GND    I56 @BASEBOARD_FAB2_LIB.BASEBOARD_FAB2(SCH_1):PAGE194
    F5    GND @BASEBOARD_FAB2_LIB.BASEBOARD_FAB2(SCH_1):GND    I56 @BASEBOARD_FAB2_LIB.BASEBOARD_FAB2(SCH_1):PAGE194
    F6    GND @BASEBOARD_FAB2_LIB.BASEBOARD_FAB2(SCH_1):GND    I56 @BASEBOARD_FAB2_LIB.BASEBOARD_FAB2(SCH_1):PAGE194
    F7    GND @BASEBOARD_FAB2_LIB.BASEBOARD_FAB2(SCH_1):GND    I56 @BASEBOARD_FAB2_LIB.BASEBOARD_FAB2(SCH_1):PAGE194
    F8 VSENSE_PVCCIOMCP_CPU0_SKT_VRTN @BASEBOARD_FAB2_LIB.BASEBOARD_FAB2(SCH_1):VSENSE_PVCCIOMCP_CPU0_SKT_VRTN    I56 @BASEBOARD_FAB2_LIB.BASEBOARD_FAB2(SCH_1):PAGE194
    F9    GND @BASEBOARD_FAB2_LIB.BASEBOARD_FAB2(SCH_1):GND    I56 @BASEBOARD_FAB2_LIB.BASEBOARD_FAB2(SCH_1):PAGE194

J6E1 SCONN120_H61426002_SM-CONN,H61A
    A1 PVCCMCP_CPU0 @BASEBOARD_FAB2_LIB.BASEBOARD_FAB2(SCH_1):PVCCMCP_CPU0    I55 @BASEBOARD_FAB2_LIB.BASEBOARD_FAB2(SCH_1):PAGE194
   A10 PVCCMCP_CPU0 @BASEBOARD_FAB2_LIB.BASEBOARD_FAB2(SCH_1):PVCCMCP_CPU0    I55 @BASEBOARD_FAB2_LIB.BASEBOARD_FAB2(SCH_1):PAGE194
   A11 PVCCMCP_CPU0 @BASEBOARD_FAB2_LIB.BASEBOARD_FAB2(SCH_1):PVCCMCP_CPU0    I55 @BASEBOARD_FAB2_LIB.BASEBOARD_FAB2(SCH_1):PAGE194
   A12 PVCCMCP_CPU0 @BASEBOARD_FAB2_LIB.BASEBOARD_FAB2(SCH_1):PVCCMCP_CPU0    I55 @BASEBOARD_FAB2_LIB.BASEBOARD_FAB2(SCH_1):PAGE194
   A13 PVCCMCP_CPU0 @BASEBOARD_FAB2_LIB.BASEBOARD_FAB2(SCH_1):PVCCMCP_CPU0    I55 @BASEBOARD_FAB2_LIB.BASEBOARD_FAB2(SCH_1):PAGE194
   A14 PVCCMCP_CPU0 @BASEBOARD_FAB2_LIB.BASEBOARD_FAB2(SCH_1):PVCCMCP_CPU0    I55 @BASEBOARD_FAB2_LIB.BASEBOARD_FAB2(SCH_1):PAGE194
   A15 PVCCMCP_CPU0 @BASEBOARD_FAB2_LIB.BASEBOARD_FAB2(SCH_1):PVCCMCP_CPU0    I55 @BASEBOARD_FAB2_LIB.BASEBOARD_FAB2(SCH_1):PAGE194
   A16 PVCCMCP_CPU0 @BASEBOARD_FAB2_LIB.BASEBOARD_FAB2(SCH_1):PVCCMCP_CPU0    I55 @BASEBOARD_FAB2_LIB.BASEBOARD_FAB2(SCH_1):PAGE194
   A17 PVCCMCP_CPU0 @BASEBOARD_FAB2_LIB.BASEBOARD_FAB2(SCH_1):PVCCMCP_CPU0    I55 @BASEBOARD_FAB2_LIB.BASEBOARD_FAB2(SCH_1):PAGE194
   A18 PVCCMCP_CPU0 @BASEBOARD_FAB2_LIB.BASEBOARD_FAB2(SCH_1):PVCCMCP_CPU0    I55 @BASEBOARD_FAB2_LIB.BASEBOARD_FAB2(SCH_1):PAGE194
   A19    GND @BASEBOARD_FAB2_LIB.BASEBOARD_FAB2(SCH_1):GND    I55 @BASEBOARD_FAB2_LIB.BASEBOARD_FAB2(SCH_1):PAGE194
    A2 PVCCMCP_CPU0 @BASEBOARD_FAB2_LIB.BASEBOARD_FAB2(SCH_1):PVCCMCP_CPU0    I55 @BASEBOARD_FAB2_LIB.BASEBOARD_FAB2(SCH_1):PAGE194
   A20    GND @BASEBOARD_FAB2_LIB.BASEBOARD_FAB2(SCH_1):GND    I55 @BASEBOARD_FAB2_LIB.BASEBOARD_FAB2(SCH_1):PAGE194
    A3 PVCCMCP_CPU0 @BASEBOARD_FAB2_LIB.BASEBOARD_FAB2(SCH_1):PVCCMCP_CPU0    I55 @BASEBOARD_FAB2_LIB.BASEBOARD_FAB2(SCH_1):PAGE194
    A4 VSENSE_PVCCMCP_CPU0_SKT_VSEN @BASEBOARD_FAB2_LIB.BASEBOARD_FAB2(SCH_1):VSENSE_PVCCMCP_CPU0_SKT_VSEN    I55 @BASEBOARD_FAB2_LIB.BASEBOARD_FAB2(SCH_1):PAGE194
    A5 PVCCMCP_CPU0 @BASEBOARD_FAB2_LIB.BASEBOARD_FAB2(SCH_1):PVCCMCP_CPU0    I55 @BASEBOARD_FAB2_LIB.BASEBOARD_FAB2(SCH_1):PAGE194
    A6 PVCCMCP_CPU0 @BASEBOARD_FAB2_LIB.BASEBOARD_FAB2(SCH_1):PVCCMCP_CPU0    I55 @BASEBOARD_FAB2_LIB.BASEBOARD_FAB2(SCH_1):PAGE194
    A7 PVCCMCP_CPU0 @BASEBOARD_FAB2_LIB.BASEBOARD_FAB2(SCH_1):PVCCMCP_CPU0    I55 @BASEBOARD_FAB2_LIB.BASEBOARD_FAB2(SCH_1):PAGE194
    A8 PVCCMCP_CPU0 @BASEBOARD_FAB2_LIB.BASEBOARD_FAB2(SCH_1):PVCCMCP_CPU0    I55 @BASEBOARD_FAB2_LIB.BASEBOARD_FAB2(SCH_1):PAGE194
    A9 PVCCMCP_CPU0 @BASEBOARD_FAB2_LIB.BASEBOARD_FAB2(SCH_1):PVCCMCP_CPU0    I55 @BASEBOARD_FAB2_LIB.BASEBOARD_FAB2(SCH_1):PAGE194
    B1 PVCCMCP_CPU0 @BASEBOARD_FAB2_LIB.BASEBOARD_FAB2(SCH_1):PVCCMCP_CPU0    I55 @BASEBOARD_FAB2_LIB.BASEBOARD_FAB2(SCH_1):PAGE194
   B10 PVCCMCP_CPU0 @BASEBOARD_FAB2_LIB.BASEBOARD_FAB2(SCH_1):PVCCMCP_CPU0    I55 @BASEBOARD_FAB2_LIB.BASEBOARD_FAB2(SCH_1):PAGE194
   B11 PVCCMCP_CPU0 @BASEBOARD_FAB2_LIB.BASEBOARD_FAB2(SCH_1):PVCCMCP_CPU0    I55 @BASEBOARD_FAB2_LIB.BASEBOARD_FAB2(SCH_1):PAGE194
   B12 PVCCMCP_CPU0 @BASEBOARD_FAB2_LIB.BASEBOARD_FAB2(SCH_1):PVCCMCP_CPU0    I55 @BASEBOARD_FAB2_LIB.BASEBOARD_FAB2(SCH_1):PAGE194
   B13 PVCCMCP_CPU0 @BASEBOARD_FAB2_LIB.BASEBOARD_FAB2(SCH_1):PVCCMCP_CPU0    I55 @BASEBOARD_FAB2_LIB.BASEBOARD_FAB2(SCH_1):PAGE194
   B14 PVCCMCP_CPU0 @BASEBOARD_FAB2_LIB.BASEBOARD_FAB2(SCH_1):PVCCMCP_CPU0    I55 @BASEBOARD_FAB2_LIB.BASEBOARD_FAB2(SCH_1):PAGE194
   B15 PVCCMCP_CPU0 @BASEBOARD_FAB2_LIB.BASEBOARD_FAB2(SCH_1):PVCCMCP_CPU0    I55 @BASEBOARD_FAB2_LIB.BASEBOARD_FAB2(SCH_1):PAGE194
   B16 PVCCMCP_CPU0 @BASEBOARD_FAB2_LIB.BASEBOARD_FAB2(SCH_1):PVCCMCP_CPU0    I55 @BASEBOARD_FAB2_LIB.BASEBOARD_FAB2(SCH_1):PAGE194
   B17 PVCCMCP_CPU0 @BASEBOARD_FAB2_LIB.BASEBOARD_FAB2(SCH_1):PVCCMCP_CPU0    I55 @BASEBOARD_FAB2_LIB.BASEBOARD_FAB2(SCH_1):PAGE194
   B18 PVCCMCP_CPU0 @BASEBOARD_FAB2_LIB.BASEBOARD_FAB2(SCH_1):PVCCMCP_CPU0    I55 @BASEBOARD_FAB2_LIB.BASEBOARD_FAB2(SCH_1):PAGE194
   B19    GND @BASEBOARD_FAB2_LIB.BASEBOARD_FAB2(SCH_1):GND    I55 @BASEBOARD_FAB2_LIB.BASEBOARD_FAB2(SCH_1):PAGE194
    B2 PVCCMCP_CPU0 @BASEBOARD_FAB2_LIB.BASEBOARD_FAB2(SCH_1):PVCCMCP_CPU0    I55 @BASEBOARD_FAB2_LIB.BASEBOARD_FAB2(SCH_1):PAGE194
   B20    GND @BASEBOARD_FAB2_LIB.BASEBOARD_FAB2(SCH_1):GND    I55 @BASEBOARD_FAB2_LIB.BASEBOARD_FAB2(SCH_1):PAGE194
    B3 PVCCMCP_CPU0 @BASEBOARD_FAB2_LIB.BASEBOARD_FAB2(SCH_1):PVCCMCP_CPU0    I55 @BASEBOARD_FAB2_LIB.BASEBOARD_FAB2(SCH_1):PAGE194
    B4 VSENSE_PVCCMCP_CPU0_SKT_VRTN @BASEBOARD_FAB2_LIB.BASEBOARD_FAB2(SCH_1):VSENSE_PVCCMCP_CPU0_SKT_VRTN    I55 @BASEBOARD_FAB2_LIB.BASEBOARD_FAB2(SCH_1):PAGE194
    B5 PVCCMCP_CPU0 @BASEBOARD_FAB2_LIB.BASEBOARD_FAB2(SCH_1):PVCCMCP_CPU0    I55 @BASEBOARD_FAB2_LIB.BASEBOARD_FAB2(SCH_1):PAGE194
    B6 PVCCMCP_CPU0 @BASEBOARD_FAB2_LIB.BASEBOARD_FAB2(SCH_1):PVCCMCP_CPU0    I55 @BASEBOARD_FAB2_LIB.BASEBOARD_FAB2(SCH_1):PAGE194
    B7 PVCCMCP_CPU0 @BASEBOARD_FAB2_LIB.BASEBOARD_FAB2(SCH_1):PVCCMCP_CPU0    I55 @BASEBOARD_FAB2_LIB.BASEBOARD_FAB2(SCH_1):PAGE194
    B8 PVCCMCP_CPU0 @BASEBOARD_FAB2_LIB.BASEBOARD_FAB2(SCH_1):PVCCMCP_CPU0    I55 @BASEBOARD_FAB2_LIB.BASEBOARD_FAB2(SCH_1):PAGE194
    B9 PVCCMCP_CPU0 @BASEBOARD_FAB2_LIB.BASEBOARD_FAB2(SCH_1):PVCCMCP_CPU0    I55 @BASEBOARD_FAB2_LIB.BASEBOARD_FAB2(SCH_1):PAGE194
    C1 PVCCMCP_CPU0 @BASEBOARD_FAB2_LIB.BASEBOARD_FAB2(SCH_1):PVCCMCP_CPU0    I55 @BASEBOARD_FAB2_LIB.BASEBOARD_FAB2(SCH_1):PAGE194
   C10 PVCCMCP_CPU0 @BASEBOARD_FAB2_LIB.BASEBOARD_FAB2(SCH_1):PVCCMCP_CPU0    I55 @BASEBOARD_FAB2_LIB.BASEBOARD_FAB2(SCH_1):PAGE194
   C11 PVCCMCP_CPU0 @BASEBOARD_FAB2_LIB.BASEBOARD_FAB2(SCH_1):PVCCMCP_CPU0    I55 @BASEBOARD_FAB2_LIB.BASEBOARD_FAB2(SCH_1):PAGE194
   C12 PVCCMCP_CPU0 @BASEBOARD_FAB2_LIB.BASEBOARD_FAB2(SCH_1):PVCCMCP_CPU0    I55 @BASEBOARD_FAB2_LIB.BASEBOARD_FAB2(SCH_1):PAGE194
   C13 PVCCMCP_CPU0 @BASEBOARD_FAB2_LIB.BASEBOARD_FAB2(SCH_1):PVCCMCP_CPU0    I55 @BASEBOARD_FAB2_LIB.BASEBOARD_FAB2(SCH_1):PAGE194
   C14 PVCCMCP_CPU0 @BASEBOARD_FAB2_LIB.BASEBOARD_FAB2(SCH_1):PVCCMCP_CPU0    I55 @BASEBOARD_FAB2_LIB.BASEBOARD_FAB2(SCH_1):PAGE194
   C15 PVCCMCP_CPU0 @BASEBOARD_FAB2_LIB.BASEBOARD_FAB2(SCH_1):PVCCMCP_CPU0    I55 @BASEBOARD_FAB2_LIB.BASEBOARD_FAB2(SCH_1):PAGE194
   C16 PVCCMCP_CPU0 @BASEBOARD_FAB2_LIB.BASEBOARD_FAB2(SCH_1):PVCCMCP_CPU0    I55 @BASEBOARD_FAB2_LIB.BASEBOARD_FAB2(SCH_1):PAGE194
   C17 PVCCMCP_CPU0 @BASEBOARD_FAB2_LIB.BASEBOARD_FAB2(SCH_1):PVCCMCP_CPU0    I55 @BASEBOARD_FAB2_LIB.BASEBOARD_FAB2(SCH_1):PAGE194
   C18 PVCCMCP_CPU0 @BASEBOARD_FAB2_LIB.BASEBOARD_FAB2(SCH_1):PVCCMCP_CPU0    I55 @BASEBOARD_FAB2_LIB.BASEBOARD_FAB2(SCH_1):PAGE194
   C19    GND @BASEBOARD_FAB2_LIB.BASEBOARD_FAB2(SCH_1):GND    I55 @BASEBOARD_FAB2_LIB.BASEBOARD_FAB2(SCH_1):PAGE194
    C2 PVCCMCP_CPU0 @BASEBOARD_FAB2_LIB.BASEBOARD_FAB2(SCH_1):PVCCMCP_CPU0    I55 @BASEBOARD_FAB2_LIB.BASEBOARD_FAB2(SCH_1):PAGE194
   C20    GND @BASEBOARD_FAB2_LIB.BASEBOARD_FAB2(SCH_1):GND    I55 @BASEBOARD_FAB2_LIB.BASEBOARD_FAB2(SCH_1):PAGE194
    C3 PVCCMCP_CPU0 @BASEBOARD_FAB2_LIB.BASEBOARD_FAB2(SCH_1):PVCCMCP_CPU0    I55 @BASEBOARD_FAB2_LIB.BASEBOARD_FAB2(SCH_1):PAGE194
    C4 PVCCMCP_CPU0 @BASEBOARD_FAB2_LIB.BASEBOARD_FAB2(SCH_1):PVCCMCP_CPU0    I55 @BASEBOARD_FAB2_LIB.BASEBOARD_FAB2(SCH_1):PAGE194
    C5 PVCCMCP_CPU0 @BASEBOARD_FAB2_LIB.BASEBOARD_FAB2(SCH_1):PVCCMCP_CPU0    I55 @BASEBOARD_FAB2_LIB.BASEBOARD_FAB2(SCH_1):PAGE194
    C6 PVCCMCP_CPU0 @BASEBOARD_FAB2_LIB.BASEBOARD_FAB2(SCH_1):PVCCMCP_CPU0    I55 @BASEBOARD_FAB2_LIB.BASEBOARD_FAB2(SCH_1):PAGE194
    C7 PVCCMCP_CPU0 @BASEBOARD_FAB2_LIB.BASEBOARD_FAB2(SCH_1):PVCCMCP_CPU0    I55 @BASEBOARD_FAB2_LIB.BASEBOARD_FAB2(SCH_1):PAGE194
    C8 PVCCMCP_CPU0 @BASEBOARD_FAB2_LIB.BASEBOARD_FAB2(SCH_1):PVCCMCP_CPU0    I55 @BASEBOARD_FAB2_LIB.BASEBOARD_FAB2(SCH_1):PAGE194
    C9 PVCCMCP_CPU0 @BASEBOARD_FAB2_LIB.BASEBOARD_FAB2(SCH_1):PVCCMCP_CPU0    I55 @BASEBOARD_FAB2_LIB.BASEBOARD_FAB2(SCH_1):PAGE194
    D1 VSENSE_P1V8MCP_CPU0_SKT_VSEN @BASEBOARD_FAB2_LIB.BASEBOARD_FAB2(SCH_1):VSENSE_P1V8MCP_CPU0_SKT_VSEN    I55 @BASEBOARD_FAB2_LIB.BASEBOARD_FAB2(SCH_1):PAGE194
   D10    GND @BASEBOARD_FAB2_LIB.BASEBOARD_FAB2(SCH_1):GND    I55 @BASEBOARD_FAB2_LIB.BASEBOARD_FAB2(SCH_1):PAGE194
   D11    GND @BASEBOARD_FAB2_LIB.BASEBOARD_FAB2(SCH_1):GND    I55 @BASEBOARD_FAB2_LIB.BASEBOARD_FAB2(SCH_1):PAGE194
   D12    GND @BASEBOARD_FAB2_LIB.BASEBOARD_FAB2(SCH_1):GND    I55 @BASEBOARD_FAB2_LIB.BASEBOARD_FAB2(SCH_1):PAGE194
   D13    GND @BASEBOARD_FAB2_LIB.BASEBOARD_FAB2(SCH_1):GND    I55 @BASEBOARD_FAB2_LIB.BASEBOARD_FAB2(SCH_1):PAGE194
   D14    GND @BASEBOARD_FAB2_LIB.BASEBOARD_FAB2(SCH_1):GND    I55 @BASEBOARD_FAB2_LIB.BASEBOARD_FAB2(SCH_1):PAGE194
   D15    GND @BASEBOARD_FAB2_LIB.BASEBOARD_FAB2(SCH_1):GND    I55 @BASEBOARD_FAB2_LIB.BASEBOARD_FAB2(SCH_1):PAGE194
   D16    GND @BASEBOARD_FAB2_LIB.BASEBOARD_FAB2(SCH_1):GND    I55 @BASEBOARD_FAB2_LIB.BASEBOARD_FAB2(SCH_1):PAGE194
   D17    GND @BASEBOARD_FAB2_LIB.BASEBOARD_FAB2(SCH_1):GND    I55 @BASEBOARD_FAB2_LIB.BASEBOARD_FAB2(SCH_1):PAGE194
   D18    GND @BASEBOARD_FAB2_LIB.BASEBOARD_FAB2(SCH_1):GND    I55 @BASEBOARD_FAB2_LIB.BASEBOARD_FAB2(SCH_1):PAGE194
   D19    GND @BASEBOARD_FAB2_LIB.BASEBOARD_FAB2(SCH_1):GND    I55 @BASEBOARD_FAB2_LIB.BASEBOARD_FAB2(SCH_1):PAGE194
    D2 VSENSE_P1V8MCP_CPU0_SKT_VRTN @BASEBOARD_FAB2_LIB.BASEBOARD_FAB2(SCH_1):VSENSE_P1V8MCP_CPU0_SKT_VRTN    I55 @BASEBOARD_FAB2_LIB.BASEBOARD_FAB2(SCH_1):PAGE194
   D20    GND @BASEBOARD_FAB2_LIB.BASEBOARD_FAB2(SCH_1):GND    I55 @BASEBOARD_FAB2_LIB.BASEBOARD_FAB2(SCH_1):PAGE194
    D3    GND @BASEBOARD_FAB2_LIB.BASEBOARD_FAB2(SCH_1):GND    I55 @BASEBOARD_FAB2_LIB.BASEBOARD_FAB2(SCH_1):PAGE194
    D4    GND @BASEBOARD_FAB2_LIB.BASEBOARD_FAB2(SCH_1):GND    I55 @BASEBOARD_FAB2_LIB.BASEBOARD_FAB2(SCH_1):PAGE194
    D5    GND @BASEBOARD_FAB2_LIB.BASEBOARD_FAB2(SCH_1):GND    I55 @BASEBOARD_FAB2_LIB.BASEBOARD_FAB2(SCH_1):PAGE194
    D6    GND @BASEBOARD_FAB2_LIB.BASEBOARD_FAB2(SCH_1):GND    I55 @BASEBOARD_FAB2_LIB.BASEBOARD_FAB2(SCH_1):PAGE194
    D7    GND @BASEBOARD_FAB2_LIB.BASEBOARD_FAB2(SCH_1):GND    I55 @BASEBOARD_FAB2_LIB.BASEBOARD_FAB2(SCH_1):PAGE194
    D8    GND @BASEBOARD_FAB2_LIB.BASEBOARD_FAB2(SCH_1):GND    I55 @BASEBOARD_FAB2_LIB.BASEBOARD_FAB2(SCH_1):PAGE194
    D9    GND @BASEBOARD_FAB2_LIB.BASEBOARD_FAB2(SCH_1):GND    I55 @BASEBOARD_FAB2_LIB.BASEBOARD_FAB2(SCH_1):PAGE194
    E1 P1V8_MCP_CPU0 @BASEBOARD_FAB2_LIB.BASEBOARD_FAB2(SCH_1):P1V8_MCP_CPU0    I55 @BASEBOARD_FAB2_LIB.BASEBOARD_FAB2(SCH_1):PAGE194
   E10    GND @BASEBOARD_FAB2_LIB.BASEBOARD_FAB2(SCH_1):GND    I55 @BASEBOARD_FAB2_LIB.BASEBOARD_FAB2(SCH_1):PAGE194
   E11    GND @BASEBOARD_FAB2_LIB.BASEBOARD_FAB2(SCH_1):GND    I55 @BASEBOARD_FAB2_LIB.BASEBOARD_FAB2(SCH_1):PAGE194
   E12    GND @BASEBOARD_FAB2_LIB.BASEBOARD_FAB2(SCH_1):GND    I55 @BASEBOARD_FAB2_LIB.BASEBOARD_FAB2(SCH_1):PAGE194
   E13    GND @BASEBOARD_FAB2_LIB.BASEBOARD_FAB2(SCH_1):GND    I55 @BASEBOARD_FAB2_LIB.BASEBOARD_FAB2(SCH_1):PAGE194
   E14    GND @BASEBOARD_FAB2_LIB.BASEBOARD_FAB2(SCH_1):GND    I55 @BASEBOARD_FAB2_LIB.BASEBOARD_FAB2(SCH_1):PAGE194
   E15    GND @BASEBOARD_FAB2_LIB.BASEBOARD_FAB2(SCH_1):GND    I55 @BASEBOARD_FAB2_LIB.BASEBOARD_FAB2(SCH_1):PAGE194
   E16    GND @BASEBOARD_FAB2_LIB.BASEBOARD_FAB2(SCH_1):GND    I55 @BASEBOARD_FAB2_LIB.BASEBOARD_FAB2(SCH_1):PAGE194
   E17    GND @BASEBOARD_FAB2_LIB.BASEBOARD_FAB2(SCH_1):GND    I55 @BASEBOARD_FAB2_LIB.BASEBOARD_FAB2(SCH_1):PAGE194
   E18    GND @BASEBOARD_FAB2_LIB.BASEBOARD_FAB2(SCH_1):GND    I55 @BASEBOARD_FAB2_LIB.BASEBOARD_FAB2(SCH_1):PAGE194
   E19    GND @BASEBOARD_FAB2_LIB.BASEBOARD_FAB2(SCH_1):GND    I55 @BASEBOARD_FAB2_LIB.BASEBOARD_FAB2(SCH_1):PAGE194
    E2 P1V8_MCP_CPU0 @BASEBOARD_FAB2_LIB.BASEBOARD_FAB2(SCH_1):P1V8_MCP_CPU0    I55 @BASEBOARD_FAB2_LIB.BASEBOARD_FAB2(SCH_1):PAGE194
   E20    GND @BASEBOARD_FAB2_LIB.BASEBOARD_FAB2(SCH_1):GND    I55 @BASEBOARD_FAB2_LIB.BASEBOARD_FAB2(SCH_1):PAGE194
    E3    GND @BASEBOARD_FAB2_LIB.BASEBOARD_FAB2(SCH_1):GND    I55 @BASEBOARD_FAB2_LIB.BASEBOARD_FAB2(SCH_1):PAGE194
    E4    GND @BASEBOARD_FAB2_LIB.BASEBOARD_FAB2(SCH_1):GND    I55 @BASEBOARD_FAB2_LIB.BASEBOARD_FAB2(SCH_1):PAGE194
    E5 CLK_322M_156M_CPU0_OSC_VRM_DP @BASEBOARD_FAB2_LIB.BASEBOARD_FAB2(SCH_1):CLK_322M_156M_CPU0_OSC_VRM_DP    I55 @BASEBOARD_FAB2_LIB.BASEBOARD_FAB2(SCH_1):PAGE194
    E6    GND @BASEBOARD_FAB2_LIB.BASEBOARD_FAB2(SCH_1):GND    I55 @BASEBOARD_FAB2_LIB.BASEBOARD_FAB2(SCH_1):PAGE194
    E7    GND @BASEBOARD_FAB2_LIB.BASEBOARD_FAB2(SCH_1):GND    I55 @BASEBOARD_FAB2_LIB.BASEBOARD_FAB2(SCH_1):PAGE194
    E8    GND @BASEBOARD_FAB2_LIB.BASEBOARD_FAB2(SCH_1):GND    I55 @BASEBOARD_FAB2_LIB.BASEBOARD_FAB2(SCH_1):PAGE194
    E9    GND @BASEBOARD_FAB2_LIB.BASEBOARD_FAB2(SCH_1):GND    I55 @BASEBOARD_FAB2_LIB.BASEBOARD_FAB2(SCH_1):PAGE194
    F1 P1V8_MCP_CPU0 @BASEBOARD_FAB2_LIB.BASEBOARD_FAB2(SCH_1):P1V8_MCP_CPU0    I55 @BASEBOARD_FAB2_LIB.BASEBOARD_FAB2(SCH_1):PAGE194
   F10    GND @BASEBOARD_FAB2_LIB.BASEBOARD_FAB2(SCH_1):GND    I55 @BASEBOARD_FAB2_LIB.BASEBOARD_FAB2(SCH_1):PAGE194
   F11    GND @BASEBOARD_FAB2_LIB.BASEBOARD_FAB2(SCH_1):GND    I55 @BASEBOARD_FAB2_LIB.BASEBOARD_FAB2(SCH_1):PAGE194
   F12    GND @BASEBOARD_FAB2_LIB.BASEBOARD_FAB2(SCH_1):GND    I55 @BASEBOARD_FAB2_LIB.BASEBOARD_FAB2(SCH_1):PAGE194
   F13    GND @BASEBOARD_FAB2_LIB.BASEBOARD_FAB2(SCH_1):GND    I55 @BASEBOARD_FAB2_LIB.BASEBOARD_FAB2(SCH_1):PAGE194
   F14    GND @BASEBOARD_FAB2_LIB.BASEBOARD_FAB2(SCH_1):GND    I55 @BASEBOARD_FAB2_LIB.BASEBOARD_FAB2(SCH_1):PAGE194
   F15    GND @BASEBOARD_FAB2_LIB.BASEBOARD_FAB2(SCH_1):GND    I55 @BASEBOARD_FAB2_LIB.BASEBOARD_FAB2(SCH_1):PAGE194
   F16    GND @BASEBOARD_FAB2_LIB.BASEBOARD_FAB2(SCH_1):GND    I55 @BASEBOARD_FAB2_LIB.BASEBOARD_FAB2(SCH_1):PAGE194
   F17    GND @BASEBOARD_FAB2_LIB.BASEBOARD_FAB2(SCH_1):GND    I55 @BASEBOARD_FAB2_LIB.BASEBOARD_FAB2(SCH_1):PAGE194
   F18    GND @BASEBOARD_FAB2_LIB.BASEBOARD_FAB2(SCH_1):GND    I55 @BASEBOARD_FAB2_LIB.BASEBOARD_FAB2(SCH_1):PAGE194
   F19    GND @BASEBOARD_FAB2_LIB.BASEBOARD_FAB2(SCH_1):GND    I55 @BASEBOARD_FAB2_LIB.BASEBOARD_FAB2(SCH_1):PAGE194
    F2 P1V8_MCP_CPU0 @BASEBOARD_FAB2_LIB.BASEBOARD_FAB2(SCH_1):P1V8_MCP_CPU0    I55 @BASEBOARD_FAB2_LIB.BASEBOARD_FAB2(SCH_1):PAGE194
   F20    GND @BASEBOARD_FAB2_LIB.BASEBOARD_FAB2(SCH_1):GND    I55 @BASEBOARD_FAB2_LIB.BASEBOARD_FAB2(SCH_1):PAGE194
    F3    GND @BASEBOARD_FAB2_LIB.BASEBOARD_FAB2(SCH_1):GND    I55 @BASEBOARD_FAB2_LIB.BASEBOARD_FAB2(SCH_1):PAGE194
    F4    GND @BASEBOARD_FAB2_LIB.BASEBOARD_FAB2(SCH_1):GND    I55 @BASEBOARD_FAB2_LIB.BASEBOARD_FAB2(SCH_1):PAGE194
    F5 CLK_322M_156M_CPU0_OSC_VRM_DN @BASEBOARD_FAB2_LIB.BASEBOARD_FAB2(SCH_1):CLK_322M_156M_CPU0_OSC_VRM_DN    I55 @BASEBOARD_FAB2_LIB.BASEBOARD_FAB2(SCH_1):PAGE194
    F6    GND @BASEBOARD_FAB2_LIB.BASEBOARD_FAB2(SCH_1):GND    I55 @BASEBOARD_FAB2_LIB.BASEBOARD_FAB2(SCH_1):PAGE194
    F7    GND @BASEBOARD_FAB2_LIB.BASEBOARD_FAB2(SCH_1):GND    I55 @BASEBOARD_FAB2_LIB.BASEBOARD_FAB2(SCH_1):PAGE194
    F8    GND @BASEBOARD_FAB2_LIB.BASEBOARD_FAB2(SCH_1):GND    I55 @BASEBOARD_FAB2_LIB.BASEBOARD_FAB2(SCH_1):PAGE194
    F9    GND @BASEBOARD_FAB2_LIB.BASEBOARD_FAB2(SCH_1):GND    I55 @BASEBOARD_FAB2_LIB.BASEBOARD_FAB2(SCH_1):PAGE194

J6L1 SCONN288_H44441003_PIP-SCONN,HA
    79 M_F_MA<0> @BASEBOARD_FAB2_LIB.BASEBOARD_FAB2(SCH_1):M_F_MA(0)   I111 @BASEBOARD_FAB2_LIB.BASEBOARD_FAB2(SCH_1):PAGE54
    72 M_F_MA<1> @BASEBOARD_FAB2_LIB.BASEBOARD_FAB2(SCH_1):M_F_MA(1)   I111 @BASEBOARD_FAB2_LIB.BASEBOARD_FAB2(SCH_1):PAGE54
   225 M_F_MA<10> @BASEBOARD_FAB2_LIB.BASEBOARD_FAB2(SCH_1):M_F_MA(10)   I111 @BASEBOARD_FAB2_LIB.BASEBOARD_FAB2(SCH_1):PAGE54
   210 M_F_MA<11> @BASEBOARD_FAB2_LIB.BASEBOARD_FAB2(SCH_1):M_F_MA(11)   I111 @BASEBOARD_FAB2_LIB.BASEBOARD_FAB2(SCH_1):PAGE54
    65 M_F_MA<12> @BASEBOARD_FAB2_LIB.BASEBOARD_FAB2(SCH_1):M_F_MA(12)   I111 @BASEBOARD_FAB2_LIB.BASEBOARD_FAB2(SCH_1):PAGE54
   232 M_F_MA<13> @BASEBOARD_FAB2_LIB.BASEBOARD_FAB2(SCH_1):M_F_MA(13)   I111 @BASEBOARD_FAB2_LIB.BASEBOARD_FAB2(SCH_1):PAGE54
   228 M_F_MA<14> @BASEBOARD_FAB2_LIB.BASEBOARD_FAB2(SCH_1):M_F_MA(14)   I111 @BASEBOARD_FAB2_LIB.BASEBOARD_FAB2(SCH_1):PAGE54
    86 M_F_MA<15> @BASEBOARD_FAB2_LIB.BASEBOARD_FAB2(SCH_1):M_F_MA(15)   I111 @BASEBOARD_FAB2_LIB.BASEBOARD_FAB2(SCH_1):PAGE54
    82 M_F_MA<16> @BASEBOARD_FAB2_LIB.BASEBOARD_FAB2(SCH_1):M_F_MA(16)   I111 @BASEBOARD_FAB2_LIB.BASEBOARD_FAB2(SCH_1):PAGE54
   234 M_F_MA<17> @BASEBOARD_FAB2_LIB.BASEBOARD_FAB2(SCH_1):M_F_MA(17)   I111 @BASEBOARD_FAB2_LIB.BASEBOARD_FAB2(SCH_1):PAGE54
   216 M_F_MA<2> @BASEBOARD_FAB2_LIB.BASEBOARD_FAB2(SCH_1):M_F_MA(2)   I111 @BASEBOARD_FAB2_LIB.BASEBOARD_FAB2(SCH_1):PAGE54
    71 M_F_MA<3> @BASEBOARD_FAB2_LIB.BASEBOARD_FAB2(SCH_1):M_F_MA(3)   I111 @BASEBOARD_FAB2_LIB.BASEBOARD_FAB2(SCH_1):PAGE54
   214 M_F_MA<4> @BASEBOARD_FAB2_LIB.BASEBOARD_FAB2(SCH_1):M_F_MA(4)   I111 @BASEBOARD_FAB2_LIB.BASEBOARD_FAB2(SCH_1):PAGE54
   213 M_F_MA<5> @BASEBOARD_FAB2_LIB.BASEBOARD_FAB2(SCH_1):M_F_MA(5)   I111 @BASEBOARD_FAB2_LIB.BASEBOARD_FAB2(SCH_1):PAGE54
    69 M_F_MA<6> @BASEBOARD_FAB2_LIB.BASEBOARD_FAB2(SCH_1):M_F_MA(6)   I111 @BASEBOARD_FAB2_LIB.BASEBOARD_FAB2(SCH_1):PAGE54
   211 M_F_MA<7> @BASEBOARD_FAB2_LIB.BASEBOARD_FAB2(SCH_1):M_F_MA(7)   I111 @BASEBOARD_FAB2_LIB.BASEBOARD_FAB2(SCH_1):PAGE54
    68 M_F_MA<8> @BASEBOARD_FAB2_LIB.BASEBOARD_FAB2(SCH_1):M_F_MA(8)   I111 @BASEBOARD_FAB2_LIB.BASEBOARD_FAB2(SCH_1):PAGE54
    66 M_F_MA<9> @BASEBOARD_FAB2_LIB.BASEBOARD_FAB2(SCH_1):M_F_MA(9)   I111 @BASEBOARD_FAB2_LIB.BASEBOARD_FAB2(SCH_1):PAGE54
    62 M_F_ACT_N @BASEBOARD_FAB2_LIB.BASEBOARD_FAB2(SCH_1):M_F_ACT_N   I111 @BASEBOARD_FAB2_LIB.BASEBOARD_FAB2(SCH_1):PAGE54
   208 M_F_ALERT_N @BASEBOARD_FAB2_LIB.BASEBOARD_FAB2(SCH_1):M_F_ALERT_N   I111 @BASEBOARD_FAB2_LIB.BASEBOARD_FAB2(SCH_1):PAGE54
   224 M_F_BA<1> @BASEBOARD_FAB2_LIB.BASEBOARD_FAB2(SCH_1):M_F_BA(1)   I111 @BASEBOARD_FAB2_LIB.BASEBOARD_FAB2(SCH_1):PAGE54
    81 M_F_BA<0> @BASEBOARD_FAB2_LIB.BASEBOARD_FAB2(SCH_1):M_F_BA(0)   I111 @BASEBOARD_FAB2_LIB.BASEBOARD_FAB2(SCH_1):PAGE54
   207 M_F_BG<1> @BASEBOARD_FAB2_LIB.BASEBOARD_FAB2(SCH_1):M_F_BG(1)   I111 @BASEBOARD_FAB2_LIB.BASEBOARD_FAB2(SCH_1):PAGE54
    63 M_F_BG<0> @BASEBOARD_FAB2_LIB.BASEBOARD_FAB2(SCH_1):M_F_BG(0)   I111 @BASEBOARD_FAB2_LIB.BASEBOARD_FAB2(SCH_1):PAGE54
   235 M_F_C<2> @BASEBOARD_FAB2_LIB.BASEBOARD_FAB2(SCH_1):M_F_C(2)   I111 @BASEBOARD_FAB2_LIB.BASEBOARD_FAB2(SCH_1):PAGE54
   199 M_F_ECC<7> @BASEBOARD_FAB2_LIB.BASEBOARD_FAB2(SCH_1):M_F_ECC(7)   I111 @BASEBOARD_FAB2_LIB.BASEBOARD_FAB2(SCH_1):PAGE54
    54 M_F_ECC<6> @BASEBOARD_FAB2_LIB.BASEBOARD_FAB2(SCH_1):M_F_ECC(6)   I111 @BASEBOARD_FAB2_LIB.BASEBOARD_FAB2(SCH_1):PAGE54
   192 M_F_ECC<5> @BASEBOARD_FAB2_LIB.BASEBOARD_FAB2(SCH_1):M_F_ECC(5)   I111 @BASEBOARD_FAB2_LIB.BASEBOARD_FAB2(SCH_1):PAGE54
    47 M_F_ECC<4> @BASEBOARD_FAB2_LIB.BASEBOARD_FAB2(SCH_1):M_F_ECC(4)   I111 @BASEBOARD_FAB2_LIB.BASEBOARD_FAB2(SCH_1):PAGE54
   201 M_F_ECC<3> @BASEBOARD_FAB2_LIB.BASEBOARD_FAB2(SCH_1):M_F_ECC(3)   I111 @BASEBOARD_FAB2_LIB.BASEBOARD_FAB2(SCH_1):PAGE54
    56 M_F_ECC<2> @BASEBOARD_FAB2_LIB.BASEBOARD_FAB2(SCH_1):M_F_ECC(2)   I111 @BASEBOARD_FAB2_LIB.BASEBOARD_FAB2(SCH_1):PAGE54
   194 M_F_ECC<1> @BASEBOARD_FAB2_LIB.BASEBOARD_FAB2(SCH_1):M_F_ECC(1)   I111 @BASEBOARD_FAB2_LIB.BASEBOARD_FAB2(SCH_1):PAGE54
    49 M_F_ECC<0> @BASEBOARD_FAB2_LIB.BASEBOARD_FAB2(SCH_1):M_F_ECC(0)   I111 @BASEBOARD_FAB2_LIB.BASEBOARD_FAB2(SCH_1):PAGE54
    75 M_F_CLK_DN<2> @BASEBOARD_FAB2_LIB.BASEBOARD_FAB2(SCH_1):M_F_CLK_DN(2)   I111 @BASEBOARD_FAB2_LIB.BASEBOARD_FAB2(SCH_1):PAGE54
    74 M_F_CLK_DP<2> @BASEBOARD_FAB2_LIB.BASEBOARD_FAB2(SCH_1):M_F_CLK_DP(2)   I111 @BASEBOARD_FAB2_LIB.BASEBOARD_FAB2(SCH_1):PAGE54
   219 M_F_CLK_DN<3> @BASEBOARD_FAB2_LIB.BASEBOARD_FAB2(SCH_1):M_F_CLK_DN(3)   I111 @BASEBOARD_FAB2_LIB.BASEBOARD_FAB2(SCH_1):PAGE54
   218 M_F_CLK_DP<3> @BASEBOARD_FAB2_LIB.BASEBOARD_FAB2(SCH_1):M_F_CLK_DP(3)   I111 @BASEBOARD_FAB2_LIB.BASEBOARD_FAB2(SCH_1):PAGE54
   203 M_F_CKE<3> @BASEBOARD_FAB2_LIB.BASEBOARD_FAB2(SCH_1):M_F_CKE(3)   I111 @BASEBOARD_FAB2_LIB.BASEBOARD_FAB2(SCH_1):PAGE54
    60 M_F_CKE<2> @BASEBOARD_FAB2_LIB.BASEBOARD_FAB2(SCH_1):M_F_CKE(2)   I111 @BASEBOARD_FAB2_LIB.BASEBOARD_FAB2(SCH_1):PAGE54
   280 M_F_DQ<63> @BASEBOARD_FAB2_LIB.BASEBOARD_FAB2(SCH_1):M_F_DQ(63)   I111 @BASEBOARD_FAB2_LIB.BASEBOARD_FAB2(SCH_1):PAGE54
   135 M_F_DQ<62> @BASEBOARD_FAB2_LIB.BASEBOARD_FAB2(SCH_1):M_F_DQ(62)   I111 @BASEBOARD_FAB2_LIB.BASEBOARD_FAB2(SCH_1):PAGE54
   273 M_F_DQ<61> @BASEBOARD_FAB2_LIB.BASEBOARD_FAB2(SCH_1):M_F_DQ(61)   I111 @BASEBOARD_FAB2_LIB.BASEBOARD_FAB2(SCH_1):PAGE54
   128 M_F_DQ<60> @BASEBOARD_FAB2_LIB.BASEBOARD_FAB2(SCH_1):M_F_DQ(60)   I111 @BASEBOARD_FAB2_LIB.BASEBOARD_FAB2(SCH_1):PAGE54
   282 M_F_DQ<59> @BASEBOARD_FAB2_LIB.BASEBOARD_FAB2(SCH_1):M_F_DQ(59)   I111 @BASEBOARD_FAB2_LIB.BASEBOARD_FAB2(SCH_1):PAGE54
   137 M_F_DQ<58> @BASEBOARD_FAB2_LIB.BASEBOARD_FAB2(SCH_1):M_F_DQ(58)   I111 @BASEBOARD_FAB2_LIB.BASEBOARD_FAB2(SCH_1):PAGE54
   275 M_F_DQ<57> @BASEBOARD_FAB2_LIB.BASEBOARD_FAB2(SCH_1):M_F_DQ(57)   I111 @BASEBOARD_FAB2_LIB.BASEBOARD_FAB2(SCH_1):PAGE54
   130 M_F_DQ<56> @BASEBOARD_FAB2_LIB.BASEBOARD_FAB2(SCH_1):M_F_DQ(56)   I111 @BASEBOARD_FAB2_LIB.BASEBOARD_FAB2(SCH_1):PAGE54
   269 M_F_DQ<55> @BASEBOARD_FAB2_LIB.BASEBOARD_FAB2(SCH_1):M_F_DQ(55)   I111 @BASEBOARD_FAB2_LIB.BASEBOARD_FAB2(SCH_1):PAGE54
   124 M_F_DQ<54> @BASEBOARD_FAB2_LIB.BASEBOARD_FAB2(SCH_1):M_F_DQ(54)   I111 @BASEBOARD_FAB2_LIB.BASEBOARD_FAB2(SCH_1):PAGE54
   262 M_F_DQ<53> @BASEBOARD_FAB2_LIB.BASEBOARD_FAB2(SCH_1):M_F_DQ(53)   I111 @BASEBOARD_FAB2_LIB.BASEBOARD_FAB2(SCH_1):PAGE54
   117 M_F_DQ<52> @BASEBOARD_FAB2_LIB.BASEBOARD_FAB2(SCH_1):M_F_DQ(52)   I111 @BASEBOARD_FAB2_LIB.BASEBOARD_FAB2(SCH_1):PAGE54
   271 M_F_DQ<51> @BASEBOARD_FAB2_LIB.BASEBOARD_FAB2(SCH_1):M_F_DQ(51)   I111 @BASEBOARD_FAB2_LIB.BASEBOARD_FAB2(SCH_1):PAGE54
   126 M_F_DQ<50> @BASEBOARD_FAB2_LIB.BASEBOARD_FAB2(SCH_1):M_F_DQ(50)   I111 @BASEBOARD_FAB2_LIB.BASEBOARD_FAB2(SCH_1):PAGE54
   264 M_F_DQ<49> @BASEBOARD_FAB2_LIB.BASEBOARD_FAB2(SCH_1):M_F_DQ(49)   I111 @BASEBOARD_FAB2_LIB.BASEBOARD_FAB2(SCH_1):PAGE54
   119 M_F_DQ<48> @BASEBOARD_FAB2_LIB.BASEBOARD_FAB2(SCH_1):M_F_DQ(48)   I111 @BASEBOARD_FAB2_LIB.BASEBOARD_FAB2(SCH_1):PAGE54
   258 M_F_DQ<47> @BASEBOARD_FAB2_LIB.BASEBOARD_FAB2(SCH_1):M_F_DQ(47)   I111 @BASEBOARD_FAB2_LIB.BASEBOARD_FAB2(SCH_1):PAGE54
   113 M_F_DQ<46> @BASEBOARD_FAB2_LIB.BASEBOARD_FAB2(SCH_1):M_F_DQ(46)   I111 @BASEBOARD_FAB2_LIB.BASEBOARD_FAB2(SCH_1):PAGE54
   251 M_F_DQ<45> @BASEBOARD_FAB2_LIB.BASEBOARD_FAB2(SCH_1):M_F_DQ(45)   I111 @BASEBOARD_FAB2_LIB.BASEBOARD_FAB2(SCH_1):PAGE54
   106 M_F_DQ<44> @BASEBOARD_FAB2_LIB.BASEBOARD_FAB2(SCH_1):M_F_DQ(44)   I111 @BASEBOARD_FAB2_LIB.BASEBOARD_FAB2(SCH_1):PAGE54
   260 M_F_DQ<43> @BASEBOARD_FAB2_LIB.BASEBOARD_FAB2(SCH_1):M_F_DQ(43)   I111 @BASEBOARD_FAB2_LIB.BASEBOARD_FAB2(SCH_1):PAGE54
   115 M_F_DQ<42> @BASEBOARD_FAB2_LIB.BASEBOARD_FAB2(SCH_1):M_F_DQ(42)   I111 @BASEBOARD_FAB2_LIB.BASEBOARD_FAB2(SCH_1):PAGE54
   253 M_F_DQ<41> @BASEBOARD_FAB2_LIB.BASEBOARD_FAB2(SCH_1):M_F_DQ(41)   I111 @BASEBOARD_FAB2_LIB.BASEBOARD_FAB2(SCH_1):PAGE54
   108 M_F_DQ<40> @BASEBOARD_FAB2_LIB.BASEBOARD_FAB2(SCH_1):M_F_DQ(40)   I111 @BASEBOARD_FAB2_LIB.BASEBOARD_FAB2(SCH_1):PAGE54
   247 M_F_DQ<39> @BASEBOARD_FAB2_LIB.BASEBOARD_FAB2(SCH_1):M_F_DQ(39)   I111 @BASEBOARD_FAB2_LIB.BASEBOARD_FAB2(SCH_1):PAGE54
   102 M_F_DQ<38> @BASEBOARD_FAB2_LIB.BASEBOARD_FAB2(SCH_1):M_F_DQ(38)   I111 @BASEBOARD_FAB2_LIB.BASEBOARD_FAB2(SCH_1):PAGE54
   240 M_F_DQ<37> @BASEBOARD_FAB2_LIB.BASEBOARD_FAB2(SCH_1):M_F_DQ(37)   I111 @BASEBOARD_FAB2_LIB.BASEBOARD_FAB2(SCH_1):PAGE54
    95 M_F_DQ<36> @BASEBOARD_FAB2_LIB.BASEBOARD_FAB2(SCH_1):M_F_DQ(36)   I111 @BASEBOARD_FAB2_LIB.BASEBOARD_FAB2(SCH_1):PAGE54
   249 M_F_DQ<35> @BASEBOARD_FAB2_LIB.BASEBOARD_FAB2(SCH_1):M_F_DQ(35)   I111 @BASEBOARD_FAB2_LIB.BASEBOARD_FAB2(SCH_1):PAGE54
   104 M_F_DQ<34> @BASEBOARD_FAB2_LIB.BASEBOARD_FAB2(SCH_1):M_F_DQ(34)   I111 @BASEBOARD_FAB2_LIB.BASEBOARD_FAB2(SCH_1):PAGE54
   242 M_F_DQ<33> @BASEBOARD_FAB2_LIB.BASEBOARD_FAB2(SCH_1):M_F_DQ(33)   I111 @BASEBOARD_FAB2_LIB.BASEBOARD_FAB2(SCH_1):PAGE54
    97 M_F_DQ<32> @BASEBOARD_FAB2_LIB.BASEBOARD_FAB2(SCH_1):M_F_DQ(32)   I111 @BASEBOARD_FAB2_LIB.BASEBOARD_FAB2(SCH_1):PAGE54
   188 M_F_DQ<31> @BASEBOARD_FAB2_LIB.BASEBOARD_FAB2(SCH_1):M_F_DQ(31)   I111 @BASEBOARD_FAB2_LIB.BASEBOARD_FAB2(SCH_1):PAGE54
    43 M_F_DQ<30> @BASEBOARD_FAB2_LIB.BASEBOARD_FAB2(SCH_1):M_F_DQ(30)   I111 @BASEBOARD_FAB2_LIB.BASEBOARD_FAB2(SCH_1):PAGE54
   181 M_F_DQ<29> @BASEBOARD_FAB2_LIB.BASEBOARD_FAB2(SCH_1):M_F_DQ(29)   I111 @BASEBOARD_FAB2_LIB.BASEBOARD_FAB2(SCH_1):PAGE54
    36 M_F_DQ<28> @BASEBOARD_FAB2_LIB.BASEBOARD_FAB2(SCH_1):M_F_DQ(28)   I111 @BASEBOARD_FAB2_LIB.BASEBOARD_FAB2(SCH_1):PAGE54
   190 M_F_DQ<27> @BASEBOARD_FAB2_LIB.BASEBOARD_FAB2(SCH_1):M_F_DQ(27)   I111 @BASEBOARD_FAB2_LIB.BASEBOARD_FAB2(SCH_1):PAGE54
    45 M_F_DQ<26> @BASEBOARD_FAB2_LIB.BASEBOARD_FAB2(SCH_1):M_F_DQ(26)   I111 @BASEBOARD_FAB2_LIB.BASEBOARD_FAB2(SCH_1):PAGE54
   183 M_F_DQ<25> @BASEBOARD_FAB2_LIB.BASEBOARD_FAB2(SCH_1):M_F_DQ(25)   I111 @BASEBOARD_FAB2_LIB.BASEBOARD_FAB2(SCH_1):PAGE54
    38 M_F_DQ<24> @BASEBOARD_FAB2_LIB.BASEBOARD_FAB2(SCH_1):M_F_DQ(24)   I111 @BASEBOARD_FAB2_LIB.BASEBOARD_FAB2(SCH_1):PAGE54
   177 M_F_DQ<23> @BASEBOARD_FAB2_LIB.BASEBOARD_FAB2(SCH_1):M_F_DQ(23)   I111 @BASEBOARD_FAB2_LIB.BASEBOARD_FAB2(SCH_1):PAGE54
    32 M_F_DQ<22> @BASEBOARD_FAB2_LIB.BASEBOARD_FAB2(SCH_1):M_F_DQ(22)   I111 @BASEBOARD_FAB2_LIB.BASEBOARD_FAB2(SCH_1):PAGE54
   170 M_F_DQ<21> @BASEBOARD_FAB2_LIB.BASEBOARD_FAB2(SCH_1):M_F_DQ(21)   I111 @BASEBOARD_FAB2_LIB.BASEBOARD_FAB2(SCH_1):PAGE54
    25 M_F_DQ<20> @BASEBOARD_FAB2_LIB.BASEBOARD_FAB2(SCH_1):M_F_DQ(20)   I111 @BASEBOARD_FAB2_LIB.BASEBOARD_FAB2(SCH_1):PAGE54
   179 M_F_DQ<19> @BASEBOARD_FAB2_LIB.BASEBOARD_FAB2(SCH_1):M_F_DQ(19)   I111 @BASEBOARD_FAB2_LIB.BASEBOARD_FAB2(SCH_1):PAGE54
    34 M_F_DQ<18> @BASEBOARD_FAB2_LIB.BASEBOARD_FAB2(SCH_1):M_F_DQ(18)   I111 @BASEBOARD_FAB2_LIB.BASEBOARD_FAB2(SCH_1):PAGE54
   172 M_F_DQ<17> @BASEBOARD_FAB2_LIB.BASEBOARD_FAB2(SCH_1):M_F_DQ(17)   I111 @BASEBOARD_FAB2_LIB.BASEBOARD_FAB2(SCH_1):PAGE54
    27 M_F_DQ<16> @BASEBOARD_FAB2_LIB.BASEBOARD_FAB2(SCH_1):M_F_DQ(16)   I111 @BASEBOARD_FAB2_LIB.BASEBOARD_FAB2(SCH_1):PAGE54
   166 M_F_DQ<15> @BASEBOARD_FAB2_LIB.BASEBOARD_FAB2(SCH_1):M_F_DQ(15)   I111 @BASEBOARD_FAB2_LIB.BASEBOARD_FAB2(SCH_1):PAGE54
    21 M_F_DQ<14> @BASEBOARD_FAB2_LIB.BASEBOARD_FAB2(SCH_1):M_F_DQ(14)   I111 @BASEBOARD_FAB2_LIB.BASEBOARD_FAB2(SCH_1):PAGE54
   159 M_F_DQ<13> @BASEBOARD_FAB2_LIB.BASEBOARD_FAB2(SCH_1):M_F_DQ(13)   I111 @BASEBOARD_FAB2_LIB.BASEBOARD_FAB2(SCH_1):PAGE54
    14 M_F_DQ<12> @BASEBOARD_FAB2_LIB.BASEBOARD_FAB2(SCH_1):M_F_DQ(12)   I111 @BASEBOARD_FAB2_LIB.BASEBOARD_FAB2(SCH_1):PAGE54
   168 M_F_DQ<11> @BASEBOARD_FAB2_LIB.BASEBOARD_FAB2(SCH_1):M_F_DQ(11)   I111 @BASEBOARD_FAB2_LIB.BASEBOARD_FAB2(SCH_1):PAGE54
    23 M_F_DQ<10> @BASEBOARD_FAB2_LIB.BASEBOARD_FAB2(SCH_1):M_F_DQ(10)   I111 @BASEBOARD_FAB2_LIB.BASEBOARD_FAB2(SCH_1):PAGE54
   161 M_F_DQ<9> @BASEBOARD_FAB2_LIB.BASEBOARD_FAB2(SCH_1):M_F_DQ(9)   I111 @BASEBOARD_FAB2_LIB.BASEBOARD_FAB2(SCH_1):PAGE54
    16 M_F_DQ<8> @BASEBOARD_FAB2_LIB.BASEBOARD_FAB2(SCH_1):M_F_DQ(8)   I111 @BASEBOARD_FAB2_LIB.BASEBOARD_FAB2(SCH_1):PAGE54
   155 M_F_DQ<7> @BASEBOARD_FAB2_LIB.BASEBOARD_FAB2(SCH_1):M_F_DQ(7)   I111 @BASEBOARD_FAB2_LIB.BASEBOARD_FAB2(SCH_1):PAGE54
    10 M_F_DQ<6> @BASEBOARD_FAB2_LIB.BASEBOARD_FAB2(SCH_1):M_F_DQ(6)   I111 @BASEBOARD_FAB2_LIB.BASEBOARD_FAB2(SCH_1):PAGE54
   148 M_F_DQ<5> @BASEBOARD_FAB2_LIB.BASEBOARD_FAB2(SCH_1):M_F_DQ(5)   I111 @BASEBOARD_FAB2_LIB.BASEBOARD_FAB2(SCH_1):PAGE54
     3 M_F_DQ<4> @BASEBOARD_FAB2_LIB.BASEBOARD_FAB2(SCH_1):M_F_DQ(4)   I111 @BASEBOARD_FAB2_LIB.BASEBOARD_FAB2(SCH_1):PAGE54
   157 M_F_DQ<3> @BASEBOARD_FAB2_LIB.BASEBOARD_FAB2(SCH_1):M_F_DQ(3)   I111 @BASEBOARD_FAB2_LIB.BASEBOARD_FAB2(SCH_1):PAGE54
    12 M_F_DQ<2> @BASEBOARD_FAB2_LIB.BASEBOARD_FAB2(SCH_1):M_F_DQ(2)   I111 @BASEBOARD_FAB2_LIB.BASEBOARD_FAB2(SCH_1):PAGE54
   150 M_F_DQ<1> @BASEBOARD_FAB2_LIB.BASEBOARD_FAB2(SCH_1):M_F_DQ(1)   I111 @BASEBOARD_FAB2_LIB.BASEBOARD_FAB2(SCH_1):PAGE54
     5 M_F_DQ<0> @BASEBOARD_FAB2_LIB.BASEBOARD_FAB2(SCH_1):M_F_DQ(0)   I111 @BASEBOARD_FAB2_LIB.BASEBOARD_FAB2(SCH_1):PAGE54
    78 FM_DIMM_EVENT_COD_N @BASEBOARD_FAB2_LIB.BASEBOARD_FAB2(SCH_1):FM_DIMM_EVENT_COD_N   I111 @BASEBOARD_FAB2_LIB.BASEBOARD_FAB2(SCH_1):PAGE54
    91 M_F_ODT<3> @BASEBOARD_FAB2_LIB.BASEBOARD_FAB2(SCH_1):M_F_ODT(3)   I111 @BASEBOARD_FAB2_LIB.BASEBOARD_FAB2(SCH_1):PAGE54
    87 M_F_ODT<2> @BASEBOARD_FAB2_LIB.BASEBOARD_FAB2(SCH_1):M_F_ODT(2)   I111 @BASEBOARD_FAB2_LIB.BASEBOARD_FAB2(SCH_1):PAGE54
   222 M_F_PAR @BASEBOARD_FAB2_LIB.BASEBOARD_FAB2(SCH_1):M_F_PAR   I111 @BASEBOARD_FAB2_LIB.BASEBOARD_FAB2(SCH_1):PAGE54
    58 M_DEF_RST_N @BASEBOARD_FAB2_LIB.BASEBOARD_FAB2(SCH_1):M_DEF_RST_N   I111 @BASEBOARD_FAB2_LIB.BASEBOARD_FAB2(SCH_1):PAGE54
   144 TP_CH_F_DIMM_F1_RFU_2 @BASEBOARD_FAB2_LIB.BASEBOARD_FAB2(SCH_1):TP_CH_F_DIMM_F1_RFU_2   I111 @BASEBOARD_FAB2_LIB.BASEBOARD_FAB2(SCH_1):PAGE54
   227 TP_CH_F_DIMM_F1_RFU_1 @BASEBOARD_FAB2_LIB.BASEBOARD_FAB2(SCH_1):TP_CH_F_DIMM_F1_RFU_1   I111 @BASEBOARD_FAB2_LIB.BASEBOARD_FAB2(SCH_1):PAGE54
   205 TP_CH_F_DIMM_F1_RFU_0 @BASEBOARD_FAB2_LIB.BASEBOARD_FAB2(SCH_1):TP_CH_F_DIMM_F1_RFU_0   I111 @BASEBOARD_FAB2_LIB.BASEBOARD_FAB2(SCH_1):PAGE54
    84 M_F_CS_N<4> @BASEBOARD_FAB2_LIB.BASEBOARD_FAB2(SCH_1):M_F_CS_N(4)   I111 @BASEBOARD_FAB2_LIB.BASEBOARD_FAB2(SCH_1):PAGE54
    89 M_F_CS_N<5> @BASEBOARD_FAB2_LIB.BASEBOARD_FAB2(SCH_1):M_F_CS_N(5)   I111 @BASEBOARD_FAB2_LIB.BASEBOARD_FAB2(SCH_1):PAGE54
    93 M_F_CS_N<6> @BASEBOARD_FAB2_LIB.BASEBOARD_FAB2(SCH_1):M_F_CS_N(6)   I111 @BASEBOARD_FAB2_LIB.BASEBOARD_FAB2(SCH_1):PAGE54
   237 M_F_CS_N<7> @BASEBOARD_FAB2_LIB.BASEBOARD_FAB2(SCH_1):M_F_CS_N(7)   I111 @BASEBOARD_FAB2_LIB.BASEBOARD_FAB2(SCH_1):PAGE54
   238 PVPP_DEF @BASEBOARD_FAB2_LIB.BASEBOARD_FAB2(SCH_1):PVPP_DEF   I111 @BASEBOARD_FAB2_LIB.BASEBOARD_FAB2(SCH_1):PAGE54
   140    GND @BASEBOARD_FAB2_LIB.BASEBOARD_FAB2(SCH_1):GND   I111 @BASEBOARD_FAB2_LIB.BASEBOARD_FAB2(SCH_1):PAGE54
   139 PVPP_DEF @BASEBOARD_FAB2_LIB.BASEBOARD_FAB2(SCH_1):PVPP_DEF   I111 @BASEBOARD_FAB2_LIB.BASEBOARD_FAB2(SCH_1):PAGE54
   230 FM_ADR_COMPLETE_DEF_N @BASEBOARD_FAB2_LIB.BASEBOARD_FAB2(SCH_1):FM_ADR_COMPLETE_DEF_N   I111 @BASEBOARD_FAB2_LIB.BASEBOARD_FAB2(SCH_1):PAGE54
   141 SMB_DDR_DEF_VPP_SCL @BASEBOARD_FAB2_LIB.BASEBOARD_FAB2(SCH_1):SMB_DDR_DEF_VPP_SCL   I111 @BASEBOARD_FAB2_LIB.BASEBOARD_FAB2(SCH_1):PAGE54
   285 SMB_DDR_DEF_VPP_SDA @BASEBOARD_FAB2_LIB.BASEBOARD_FAB2(SCH_1):SMB_DDR_DEF_VPP_SDA   I111 @BASEBOARD_FAB2_LIB.BASEBOARD_FAB2(SCH_1):PAGE54
   284 PVPP_DEF @BASEBOARD_FAB2_LIB.BASEBOARD_FAB2(SCH_1):PVPP_DEF   I111 @BASEBOARD_FAB2_LIB.BASEBOARD_FAB2(SCH_1):PAGE54
   146 M_F_VREF @BASEBOARD_FAB2_LIB.BASEBOARD_FAB2(SCH_1):M_F_VREF   I111 @BASEBOARD_FAB2_LIB.BASEBOARD_FAB2(SCH_1):PAGE54
   152 M_F_DQS_DN<0> @BASEBOARD_FAB2_LIB.BASEBOARD_FAB2(SCH_1):M_F_DQS_DN(0)    I66 @BASEBOARD_FAB2_LIB.BASEBOARD_FAB2(SCH_1):PAGE54
   153 M_F_DQS_DP<0> @BASEBOARD_FAB2_LIB.BASEBOARD_FAB2(SCH_1):M_F_DQS_DP(0)    I66 @BASEBOARD_FAB2_LIB.BASEBOARD_FAB2(SCH_1):PAGE54
    19 M_F_DQS_DN<10> @BASEBOARD_FAB2_LIB.BASEBOARD_FAB2(SCH_1):M_F_DQS_DN(10)    I66 @BASEBOARD_FAB2_LIB.BASEBOARD_FAB2(SCH_1):PAGE54
    18 M_F_DQS_DP<10> @BASEBOARD_FAB2_LIB.BASEBOARD_FAB2(SCH_1):M_F_DQS_DP(10)    I66 @BASEBOARD_FAB2_LIB.BASEBOARD_FAB2(SCH_1):PAGE54
    30 M_F_DQS_DN<11> @BASEBOARD_FAB2_LIB.BASEBOARD_FAB2(SCH_1):M_F_DQS_DN(11)    I66 @BASEBOARD_FAB2_LIB.BASEBOARD_FAB2(SCH_1):PAGE54
    29 M_F_DQS_DP<11> @BASEBOARD_FAB2_LIB.BASEBOARD_FAB2(SCH_1):M_F_DQS_DP(11)    I66 @BASEBOARD_FAB2_LIB.BASEBOARD_FAB2(SCH_1):PAGE54
    41 M_F_DQS_DN<12> @BASEBOARD_FAB2_LIB.BASEBOARD_FAB2(SCH_1):M_F_DQS_DN(12)    I66 @BASEBOARD_FAB2_LIB.BASEBOARD_FAB2(SCH_1):PAGE54
    40 M_F_DQS_DP<12> @BASEBOARD_FAB2_LIB.BASEBOARD_FAB2(SCH_1):M_F_DQS_DP(12)    I66 @BASEBOARD_FAB2_LIB.BASEBOARD_FAB2(SCH_1):PAGE54
   100 M_F_DQS_DN<13> @BASEBOARD_FAB2_LIB.BASEBOARD_FAB2(SCH_1):M_F_DQS_DN(13)    I66 @BASEBOARD_FAB2_LIB.BASEBOARD_FAB2(SCH_1):PAGE54
    99 M_F_DQS_DP<13> @BASEBOARD_FAB2_LIB.BASEBOARD_FAB2(SCH_1):M_F_DQS_DP(13)    I66 @BASEBOARD_FAB2_LIB.BASEBOARD_FAB2(SCH_1):PAGE54
   111 M_F_DQS_DN<14> @BASEBOARD_FAB2_LIB.BASEBOARD_FAB2(SCH_1):M_F_DQS_DN(14)    I66 @BASEBOARD_FAB2_LIB.BASEBOARD_FAB2(SCH_1):PAGE54
   110 M_F_DQS_DP<14> @BASEBOARD_FAB2_LIB.BASEBOARD_FAB2(SCH_1):M_F_DQS_DP(14)    I66 @BASEBOARD_FAB2_LIB.BASEBOARD_FAB2(SCH_1):PAGE54
   122 M_F_DQS_DN<15> @BASEBOARD_FAB2_LIB.BASEBOARD_FAB2(SCH_1):M_F_DQS_DN(15)    I66 @BASEBOARD_FAB2_LIB.BASEBOARD_FAB2(SCH_1):PAGE54
   121 M_F_DQS_DP<15> @BASEBOARD_FAB2_LIB.BASEBOARD_FAB2(SCH_1):M_F_DQS_DP(15)    I66 @BASEBOARD_FAB2_LIB.BASEBOARD_FAB2(SCH_1):PAGE54
   133 M_F_DQS_DN<16> @BASEBOARD_FAB2_LIB.BASEBOARD_FAB2(SCH_1):M_F_DQS_DN(16)    I66 @BASEBOARD_FAB2_LIB.BASEBOARD_FAB2(SCH_1):PAGE54
   132 M_F_DQS_DP<16> @BASEBOARD_FAB2_LIB.BASEBOARD_FAB2(SCH_1):M_F_DQS_DP(16)    I66 @BASEBOARD_FAB2_LIB.BASEBOARD_FAB2(SCH_1):PAGE54
    52 M_F_DQS_DN<17> @BASEBOARD_FAB2_LIB.BASEBOARD_FAB2(SCH_1):M_F_DQS_DN(17)    I66 @BASEBOARD_FAB2_LIB.BASEBOARD_FAB2(SCH_1):PAGE54
    51 M_F_DQS_DP<17> @BASEBOARD_FAB2_LIB.BASEBOARD_FAB2(SCH_1):M_F_DQS_DP(17)    I66 @BASEBOARD_FAB2_LIB.BASEBOARD_FAB2(SCH_1):PAGE54
   163 M_F_DQS_DN<1> @BASEBOARD_FAB2_LIB.BASEBOARD_FAB2(SCH_1):M_F_DQS_DN(1)    I66 @BASEBOARD_FAB2_LIB.BASEBOARD_FAB2(SCH_1):PAGE54
   164 M_F_DQS_DP<1> @BASEBOARD_FAB2_LIB.BASEBOARD_FAB2(SCH_1):M_F_DQS_DP(1)    I66 @BASEBOARD_FAB2_LIB.BASEBOARD_FAB2(SCH_1):PAGE54
   174 M_F_DQS_DN<2> @BASEBOARD_FAB2_LIB.BASEBOARD_FAB2(SCH_1):M_F_DQS_DN(2)    I66 @BASEBOARD_FAB2_LIB.BASEBOARD_FAB2(SCH_1):PAGE54
   175 M_F_DQS_DP<2> @BASEBOARD_FAB2_LIB.BASEBOARD_FAB2(SCH_1):M_F_DQS_DP(2)    I66 @BASEBOARD_FAB2_LIB.BASEBOARD_FAB2(SCH_1):PAGE54
   185 M_F_DQS_DN<3> @BASEBOARD_FAB2_LIB.BASEBOARD_FAB2(SCH_1):M_F_DQS_DN(3)    I66 @BASEBOARD_FAB2_LIB.BASEBOARD_FAB2(SCH_1):PAGE54
   186 M_F_DQS_DP<3> @BASEBOARD_FAB2_LIB.BASEBOARD_FAB2(SCH_1):M_F_DQS_DP(3)    I66 @BASEBOARD_FAB2_LIB.BASEBOARD_FAB2(SCH_1):PAGE54
   244 M_F_DQS_DN<4> @BASEBOARD_FAB2_LIB.BASEBOARD_FAB2(SCH_1):M_F_DQS_DN(4)    I66 @BASEBOARD_FAB2_LIB.BASEBOARD_FAB2(SCH_1):PAGE54
   245 M_F_DQS_DP<4> @BASEBOARD_FAB2_LIB.BASEBOARD_FAB2(SCH_1):M_F_DQS_DP(4)    I66 @BASEBOARD_FAB2_LIB.BASEBOARD_FAB2(SCH_1):PAGE54
   255 M_F_DQS_DN<5> @BASEBOARD_FAB2_LIB.BASEBOARD_FAB2(SCH_1):M_F_DQS_DN(5)    I66 @BASEBOARD_FAB2_LIB.BASEBOARD_FAB2(SCH_1):PAGE54
   256 M_F_DQS_DP<5> @BASEBOARD_FAB2_LIB.BASEBOARD_FAB2(SCH_1):M_F_DQS_DP(5)    I66 @BASEBOARD_FAB2_LIB.BASEBOARD_FAB2(SCH_1):PAGE54
   266 M_F_DQS_DN<6> @BASEBOARD_FAB2_LIB.BASEBOARD_FAB2(SCH_1):M_F_DQS_DN(6)    I66 @BASEBOARD_FAB2_LIB.BASEBOARD_FAB2(SCH_1):PAGE54
   267 M_F_DQS_DP<6> @BASEBOARD_FAB2_LIB.BASEBOARD_FAB2(SCH_1):M_F_DQS_DP(6)    I66 @BASEBOARD_FAB2_LIB.BASEBOARD_FAB2(SCH_1):PAGE54
   277 M_F_DQS_DN<7> @BASEBOARD_FAB2_LIB.BASEBOARD_FAB2(SCH_1):M_F_DQS_DN(7)    I66 @BASEBOARD_FAB2_LIB.BASEBOARD_FAB2(SCH_1):PAGE54
   278 M_F_DQS_DP<7> @BASEBOARD_FAB2_LIB.BASEBOARD_FAB2(SCH_1):M_F_DQS_DP(7)    I66 @BASEBOARD_FAB2_LIB.BASEBOARD_FAB2(SCH_1):PAGE54
   196 M_F_DQS_DN<8> @BASEBOARD_FAB2_LIB.BASEBOARD_FAB2(SCH_1):M_F_DQS_DN(8)    I66 @BASEBOARD_FAB2_LIB.BASEBOARD_FAB2(SCH_1):PAGE54
   197 M_F_DQS_DP<8> @BASEBOARD_FAB2_LIB.BASEBOARD_FAB2(SCH_1):M_F_DQS_DP(8)    I66 @BASEBOARD_FAB2_LIB.BASEBOARD_FAB2(SCH_1):PAGE54
     8 M_F_DQS_DN<9> @BASEBOARD_FAB2_LIB.BASEBOARD_FAB2(SCH_1):M_F_DQS_DN(9)    I66 @BASEBOARD_FAB2_LIB.BASEBOARD_FAB2(SCH_1):PAGE54
     7 M_F_DQS_DP<9> @BASEBOARD_FAB2_LIB.BASEBOARD_FAB2(SCH_1):M_F_DQS_DP(9)    I66 @BASEBOARD_FAB2_LIB.BASEBOARD_FAB2(SCH_1):PAGE54
     2    GND @BASEBOARD_FAB2_LIB.BASEBOARD_FAB2(SCH_1):GND    I43 @BASEBOARD_FAB2_LIB.BASEBOARD_FAB2(SCH_1):PAGE54
     4    GND @BASEBOARD_FAB2_LIB.BASEBOARD_FAB2(SCH_1):GND    I43 @BASEBOARD_FAB2_LIB.BASEBOARD_FAB2(SCH_1):PAGE54
     6    GND @BASEBOARD_FAB2_LIB.BASEBOARD_FAB2(SCH_1):GND    I43 @BASEBOARD_FAB2_LIB.BASEBOARD_FAB2(SCH_1):PAGE54
     9    GND @BASEBOARD_FAB2_LIB.BASEBOARD_FAB2(SCH_1):GND    I43 @BASEBOARD_FAB2_LIB.BASEBOARD_FAB2(SCH_1):PAGE54
    11    GND @BASEBOARD_FAB2_LIB.BASEBOARD_FAB2(SCH_1):GND    I43 @BASEBOARD_FAB2_LIB.BASEBOARD_FAB2(SCH_1):PAGE54
    13    GND @BASEBOARD_FAB2_LIB.BASEBOARD_FAB2(SCH_1):GND    I43 @BASEBOARD_FAB2_LIB.BASEBOARD_FAB2(SCH_1):PAGE54
    15    GND @BASEBOARD_FAB2_LIB.BASEBOARD_FAB2(SCH_1):GND    I43 @BASEBOARD_FAB2_LIB.BASEBOARD_FAB2(SCH_1):PAGE54
    17    GND @BASEBOARD_FAB2_LIB.BASEBOARD_FAB2(SCH_1):GND    I43 @BASEBOARD_FAB2_LIB.BASEBOARD_FAB2(SCH_1):PAGE54
    20    GND @BASEBOARD_FAB2_LIB.BASEBOARD_FAB2(SCH_1):GND    I43 @BASEBOARD_FAB2_LIB.BASEBOARD_FAB2(SCH_1):PAGE54
    22    GND @BASEBOARD_FAB2_LIB.BASEBOARD_FAB2(SCH_1):GND    I43 @BASEBOARD_FAB2_LIB.BASEBOARD_FAB2(SCH_1):PAGE54
    24    GND @BASEBOARD_FAB2_LIB.BASEBOARD_FAB2(SCH_1):GND    I43 @BASEBOARD_FAB2_LIB.BASEBOARD_FAB2(SCH_1):PAGE54
    26    GND @BASEBOARD_FAB2_LIB.BASEBOARD_FAB2(SCH_1):GND    I43 @BASEBOARD_FAB2_LIB.BASEBOARD_FAB2(SCH_1):PAGE54
    28    GND @BASEBOARD_FAB2_LIB.BASEBOARD_FAB2(SCH_1):GND    I43 @BASEBOARD_FAB2_LIB.BASEBOARD_FAB2(SCH_1):PAGE54
    31    GND @BASEBOARD_FAB2_LIB.BASEBOARD_FAB2(SCH_1):GND    I43 @BASEBOARD_FAB2_LIB.BASEBOARD_FAB2(SCH_1):PAGE54
    33    GND @BASEBOARD_FAB2_LIB.BASEBOARD_FAB2(SCH_1):GND    I43 @BASEBOARD_FAB2_LIB.BASEBOARD_FAB2(SCH_1):PAGE54
    35    GND @BASEBOARD_FAB2_LIB.BASEBOARD_FAB2(SCH_1):GND    I43 @BASEBOARD_FAB2_LIB.BASEBOARD_FAB2(SCH_1):PAGE54
    37    GND @BASEBOARD_FAB2_LIB.BASEBOARD_FAB2(SCH_1):GND    I43 @BASEBOARD_FAB2_LIB.BASEBOARD_FAB2(SCH_1):PAGE54
    39    GND @BASEBOARD_FAB2_LIB.BASEBOARD_FAB2(SCH_1):GND    I43 @BASEBOARD_FAB2_LIB.BASEBOARD_FAB2(SCH_1):PAGE54
    42    GND @BASEBOARD_FAB2_LIB.BASEBOARD_FAB2(SCH_1):GND    I43 @BASEBOARD_FAB2_LIB.BASEBOARD_FAB2(SCH_1):PAGE54
    44    GND @BASEBOARD_FAB2_LIB.BASEBOARD_FAB2(SCH_1):GND    I43 @BASEBOARD_FAB2_LIB.BASEBOARD_FAB2(SCH_1):PAGE54
    46    GND @BASEBOARD_FAB2_LIB.BASEBOARD_FAB2(SCH_1):GND    I43 @BASEBOARD_FAB2_LIB.BASEBOARD_FAB2(SCH_1):PAGE54
    48    GND @BASEBOARD_FAB2_LIB.BASEBOARD_FAB2(SCH_1):GND    I43 @BASEBOARD_FAB2_LIB.BASEBOARD_FAB2(SCH_1):PAGE54
    50    GND @BASEBOARD_FAB2_LIB.BASEBOARD_FAB2(SCH_1):GND    I43 @BASEBOARD_FAB2_LIB.BASEBOARD_FAB2(SCH_1):PAGE54
    53    GND @BASEBOARD_FAB2_LIB.BASEBOARD_FAB2(SCH_1):GND    I43 @BASEBOARD_FAB2_LIB.BASEBOARD_FAB2(SCH_1):PAGE54
    55    GND @BASEBOARD_FAB2_LIB.BASEBOARD_FAB2(SCH_1):GND    I43 @BASEBOARD_FAB2_LIB.BASEBOARD_FAB2(SCH_1):PAGE54
    57    GND @BASEBOARD_FAB2_LIB.BASEBOARD_FAB2(SCH_1):GND    I43 @BASEBOARD_FAB2_LIB.BASEBOARD_FAB2(SCH_1):PAGE54
    94    GND @BASEBOARD_FAB2_LIB.BASEBOARD_FAB2(SCH_1):GND    I43 @BASEBOARD_FAB2_LIB.BASEBOARD_FAB2(SCH_1):PAGE54
    96    GND @BASEBOARD_FAB2_LIB.BASEBOARD_FAB2(SCH_1):GND    I43 @BASEBOARD_FAB2_LIB.BASEBOARD_FAB2(SCH_1):PAGE54
    98    GND @BASEBOARD_FAB2_LIB.BASEBOARD_FAB2(SCH_1):GND    I43 @BASEBOARD_FAB2_LIB.BASEBOARD_FAB2(SCH_1):PAGE54
   101    GND @BASEBOARD_FAB2_LIB.BASEBOARD_FAB2(SCH_1):GND    I43 @BASEBOARD_FAB2_LIB.BASEBOARD_FAB2(SCH_1):PAGE54
   103    GND @BASEBOARD_FAB2_LIB.BASEBOARD_FAB2(SCH_1):GND    I43 @BASEBOARD_FAB2_LIB.BASEBOARD_FAB2(SCH_1):PAGE54
   105    GND @BASEBOARD_FAB2_LIB.BASEBOARD_FAB2(SCH_1):GND    I43 @BASEBOARD_FAB2_LIB.BASEBOARD_FAB2(SCH_1):PAGE54
   107    GND @BASEBOARD_FAB2_LIB.BASEBOARD_FAB2(SCH_1):GND    I43 @BASEBOARD_FAB2_LIB.BASEBOARD_FAB2(SCH_1):PAGE54
   109    GND @BASEBOARD_FAB2_LIB.BASEBOARD_FAB2(SCH_1):GND    I43 @BASEBOARD_FAB2_LIB.BASEBOARD_FAB2(SCH_1):PAGE54
   112    GND @BASEBOARD_FAB2_LIB.BASEBOARD_FAB2(SCH_1):GND    I43 @BASEBOARD_FAB2_LIB.BASEBOARD_FAB2(SCH_1):PAGE54
   114    GND @BASEBOARD_FAB2_LIB.BASEBOARD_FAB2(SCH_1):GND    I43 @BASEBOARD_FAB2_LIB.BASEBOARD_FAB2(SCH_1):PAGE54
   116    GND @BASEBOARD_FAB2_LIB.BASEBOARD_FAB2(SCH_1):GND    I43 @BASEBOARD_FAB2_LIB.BASEBOARD_FAB2(SCH_1):PAGE54
   118    GND @BASEBOARD_FAB2_LIB.BASEBOARD_FAB2(SCH_1):GND    I43 @BASEBOARD_FAB2_LIB.BASEBOARD_FAB2(SCH_1):PAGE54
   120    GND @BASEBOARD_FAB2_LIB.BASEBOARD_FAB2(SCH_1):GND    I43 @BASEBOARD_FAB2_LIB.BASEBOARD_FAB2(SCH_1):PAGE54
   123    GND @BASEBOARD_FAB2_LIB.BASEBOARD_FAB2(SCH_1):GND    I43 @BASEBOARD_FAB2_LIB.BASEBOARD_FAB2(SCH_1):PAGE54
   125    GND @BASEBOARD_FAB2_LIB.BASEBOARD_FAB2(SCH_1):GND    I43 @BASEBOARD_FAB2_LIB.BASEBOARD_FAB2(SCH_1):PAGE54
   127    GND @BASEBOARD_FAB2_LIB.BASEBOARD_FAB2(SCH_1):GND    I43 @BASEBOARD_FAB2_LIB.BASEBOARD_FAB2(SCH_1):PAGE54
   129    GND @BASEBOARD_FAB2_LIB.BASEBOARD_FAB2(SCH_1):GND    I43 @BASEBOARD_FAB2_LIB.BASEBOARD_FAB2(SCH_1):PAGE54
   131    GND @BASEBOARD_FAB2_LIB.BASEBOARD_FAB2(SCH_1):GND    I43 @BASEBOARD_FAB2_LIB.BASEBOARD_FAB2(SCH_1):PAGE54
   134    GND @BASEBOARD_FAB2_LIB.BASEBOARD_FAB2(SCH_1):GND    I43 @BASEBOARD_FAB2_LIB.BASEBOARD_FAB2(SCH_1):PAGE54
   136    GND @BASEBOARD_FAB2_LIB.BASEBOARD_FAB2(SCH_1):GND    I43 @BASEBOARD_FAB2_LIB.BASEBOARD_FAB2(SCH_1):PAGE54
   138    GND @BASEBOARD_FAB2_LIB.BASEBOARD_FAB2(SCH_1):GND    I43 @BASEBOARD_FAB2_LIB.BASEBOARD_FAB2(SCH_1):PAGE54
   147    GND @BASEBOARD_FAB2_LIB.BASEBOARD_FAB2(SCH_1):GND    I43 @BASEBOARD_FAB2_LIB.BASEBOARD_FAB2(SCH_1):PAGE54
   149    GND @BASEBOARD_FAB2_LIB.BASEBOARD_FAB2(SCH_1):GND    I43 @BASEBOARD_FAB2_LIB.BASEBOARD_FAB2(SCH_1):PAGE54
   151    GND @BASEBOARD_FAB2_LIB.BASEBOARD_FAB2(SCH_1):GND    I43 @BASEBOARD_FAB2_LIB.BASEBOARD_FAB2(SCH_1):PAGE54
   154    GND @BASEBOARD_FAB2_LIB.BASEBOARD_FAB2(SCH_1):GND    I43 @BASEBOARD_FAB2_LIB.BASEBOARD_FAB2(SCH_1):PAGE54
   156    GND @BASEBOARD_FAB2_LIB.BASEBOARD_FAB2(SCH_1):GND    I43 @BASEBOARD_FAB2_LIB.BASEBOARD_FAB2(SCH_1):PAGE54
   158    GND @BASEBOARD_FAB2_LIB.BASEBOARD_FAB2(SCH_1):GND    I43 @BASEBOARD_FAB2_LIB.BASEBOARD_FAB2(SCH_1):PAGE54
   160    GND @BASEBOARD_FAB2_LIB.BASEBOARD_FAB2(SCH_1):GND    I43 @BASEBOARD_FAB2_LIB.BASEBOARD_FAB2(SCH_1):PAGE54
   162    GND @BASEBOARD_FAB2_LIB.BASEBOARD_FAB2(SCH_1):GND    I43 @BASEBOARD_FAB2_LIB.BASEBOARD_FAB2(SCH_1):PAGE54
   165    GND @BASEBOARD_FAB2_LIB.BASEBOARD_FAB2(SCH_1):GND    I43 @BASEBOARD_FAB2_LIB.BASEBOARD_FAB2(SCH_1):PAGE54
   167    GND @BASEBOARD_FAB2_LIB.BASEBOARD_FAB2(SCH_1):GND    I43 @BASEBOARD_FAB2_LIB.BASEBOARD_FAB2(SCH_1):PAGE54
   169    GND @BASEBOARD_FAB2_LIB.BASEBOARD_FAB2(SCH_1):GND    I43 @BASEBOARD_FAB2_LIB.BASEBOARD_FAB2(SCH_1):PAGE54
   171    GND @BASEBOARD_FAB2_LIB.BASEBOARD_FAB2(SCH_1):GND    I43 @BASEBOARD_FAB2_LIB.BASEBOARD_FAB2(SCH_1):PAGE54
   173    GND @BASEBOARD_FAB2_LIB.BASEBOARD_FAB2(SCH_1):GND    I43 @BASEBOARD_FAB2_LIB.BASEBOARD_FAB2(SCH_1):PAGE54
   176    GND @BASEBOARD_FAB2_LIB.BASEBOARD_FAB2(SCH_1):GND    I43 @BASEBOARD_FAB2_LIB.BASEBOARD_FAB2(SCH_1):PAGE54
   178    GND @BASEBOARD_FAB2_LIB.BASEBOARD_FAB2(SCH_1):GND    I43 @BASEBOARD_FAB2_LIB.BASEBOARD_FAB2(SCH_1):PAGE54
   180    GND @BASEBOARD_FAB2_LIB.BASEBOARD_FAB2(SCH_1):GND    I43 @BASEBOARD_FAB2_LIB.BASEBOARD_FAB2(SCH_1):PAGE54
   182    GND @BASEBOARD_FAB2_LIB.BASEBOARD_FAB2(SCH_1):GND    I43 @BASEBOARD_FAB2_LIB.BASEBOARD_FAB2(SCH_1):PAGE54
   184    GND @BASEBOARD_FAB2_LIB.BASEBOARD_FAB2(SCH_1):GND    I43 @BASEBOARD_FAB2_LIB.BASEBOARD_FAB2(SCH_1):PAGE54
   187    GND @BASEBOARD_FAB2_LIB.BASEBOARD_FAB2(SCH_1):GND    I43 @BASEBOARD_FAB2_LIB.BASEBOARD_FAB2(SCH_1):PAGE54
   189    GND @BASEBOARD_FAB2_LIB.BASEBOARD_FAB2(SCH_1):GND    I43 @BASEBOARD_FAB2_LIB.BASEBOARD_FAB2(SCH_1):PAGE54
   191    GND @BASEBOARD_FAB2_LIB.BASEBOARD_FAB2(SCH_1):GND    I43 @BASEBOARD_FAB2_LIB.BASEBOARD_FAB2(SCH_1):PAGE54
   193    GND @BASEBOARD_FAB2_LIB.BASEBOARD_FAB2(SCH_1):GND    I43 @BASEBOARD_FAB2_LIB.BASEBOARD_FAB2(SCH_1):PAGE54
   195    GND @BASEBOARD_FAB2_LIB.BASEBOARD_FAB2(SCH_1):GND    I43 @BASEBOARD_FAB2_LIB.BASEBOARD_FAB2(SCH_1):PAGE54
   198    GND @BASEBOARD_FAB2_LIB.BASEBOARD_FAB2(SCH_1):GND    I43 @BASEBOARD_FAB2_LIB.BASEBOARD_FAB2(SCH_1):PAGE54
   200    GND @BASEBOARD_FAB2_LIB.BASEBOARD_FAB2(SCH_1):GND    I43 @BASEBOARD_FAB2_LIB.BASEBOARD_FAB2(SCH_1):PAGE54
   202    GND @BASEBOARD_FAB2_LIB.BASEBOARD_FAB2(SCH_1):GND    I43 @BASEBOARD_FAB2_LIB.BASEBOARD_FAB2(SCH_1):PAGE54
   239    GND @BASEBOARD_FAB2_LIB.BASEBOARD_FAB2(SCH_1):GND    I43 @BASEBOARD_FAB2_LIB.BASEBOARD_FAB2(SCH_1):PAGE54
   241    GND @BASEBOARD_FAB2_LIB.BASEBOARD_FAB2(SCH_1):GND    I43 @BASEBOARD_FAB2_LIB.BASEBOARD_FAB2(SCH_1):PAGE54
   243    GND @BASEBOARD_FAB2_LIB.BASEBOARD_FAB2(SCH_1):GND    I43 @BASEBOARD_FAB2_LIB.BASEBOARD_FAB2(SCH_1):PAGE54
   246    GND @BASEBOARD_FAB2_LIB.BASEBOARD_FAB2(SCH_1):GND    I43 @BASEBOARD_FAB2_LIB.BASEBOARD_FAB2(SCH_1):PAGE54
   248    GND @BASEBOARD_FAB2_LIB.BASEBOARD_FAB2(SCH_1):GND    I43 @BASEBOARD_FAB2_LIB.BASEBOARD_FAB2(SCH_1):PAGE54
   250    GND @BASEBOARD_FAB2_LIB.BASEBOARD_FAB2(SCH_1):GND    I43 @BASEBOARD_FAB2_LIB.BASEBOARD_FAB2(SCH_1):PAGE54
   252    GND @BASEBOARD_FAB2_LIB.BASEBOARD_FAB2(SCH_1):GND    I43 @BASEBOARD_FAB2_LIB.BASEBOARD_FAB2(SCH_1):PAGE54
   254    GND @BASEBOARD_FAB2_LIB.BASEBOARD_FAB2(SCH_1):GND    I43 @BASEBOARD_FAB2_LIB.BASEBOARD_FAB2(SCH_1):PAGE54
   257    GND @BASEBOARD_FAB2_LIB.BASEBOARD_FAB2(SCH_1):GND    I43 @BASEBOARD_FAB2_LIB.BASEBOARD_FAB2(SCH_1):PAGE54
   259    GND @BASEBOARD_FAB2_LIB.BASEBOARD_FAB2(SCH_1):GND    I43 @BASEBOARD_FAB2_LIB.BASEBOARD_FAB2(SCH_1):PAGE54
   261    GND @BASEBOARD_FAB2_LIB.BASEBOARD_FAB2(SCH_1):GND    I43 @BASEBOARD_FAB2_LIB.BASEBOARD_FAB2(SCH_1):PAGE54
   263    GND @BASEBOARD_FAB2_LIB.BASEBOARD_FAB2(SCH_1):GND    I43 @BASEBOARD_FAB2_LIB.BASEBOARD_FAB2(SCH_1):PAGE54
   265    GND @BASEBOARD_FAB2_LIB.BASEBOARD_FAB2(SCH_1):GND    I43 @BASEBOARD_FAB2_LIB.BASEBOARD_FAB2(SCH_1):PAGE54
   268    GND @BASEBOARD_FAB2_LIB.BASEBOARD_FAB2(SCH_1):GND    I43 @BASEBOARD_FAB2_LIB.BASEBOARD_FAB2(SCH_1):PAGE54
   270    GND @BASEBOARD_FAB2_LIB.BASEBOARD_FAB2(SCH_1):GND    I43 @BASEBOARD_FAB2_LIB.BASEBOARD_FAB2(SCH_1):PAGE54
   272    GND @BASEBOARD_FAB2_LIB.BASEBOARD_FAB2(SCH_1):GND    I43 @BASEBOARD_FAB2_LIB.BASEBOARD_FAB2(SCH_1):PAGE54
   274    GND @BASEBOARD_FAB2_LIB.BASEBOARD_FAB2(SCH_1):GND    I43 @BASEBOARD_FAB2_LIB.BASEBOARD_FAB2(SCH_1):PAGE54
   276    GND @BASEBOARD_FAB2_LIB.BASEBOARD_FAB2(SCH_1):GND    I43 @BASEBOARD_FAB2_LIB.BASEBOARD_FAB2(SCH_1):PAGE54
   279    GND @BASEBOARD_FAB2_LIB.BASEBOARD_FAB2(SCH_1):GND    I43 @BASEBOARD_FAB2_LIB.BASEBOARD_FAB2(SCH_1):PAGE54
   281    GND @BASEBOARD_FAB2_LIB.BASEBOARD_FAB2(SCH_1):GND    I43 @BASEBOARD_FAB2_LIB.BASEBOARD_FAB2(SCH_1):PAGE54
   283    GND @BASEBOARD_FAB2_LIB.BASEBOARD_FAB2(SCH_1):GND    I43 @BASEBOARD_FAB2_LIB.BASEBOARD_FAB2(SCH_1):PAGE54
     1 P12V_NVDIMM_DEF @BASEBOARD_FAB2_LIB.BASEBOARD_FAB2(SCH_1):P12V_NVDIMM_DEF   I170 @BASEBOARD_FAB2_LIB.BASEBOARD_FAB2(SCH_1):PAGE54
   145 P12V_NVDIMM_DEF @BASEBOARD_FAB2_LIB.BASEBOARD_FAB2(SCH_1):P12V_NVDIMM_DEF   I170 @BASEBOARD_FAB2_LIB.BASEBOARD_FAB2(SCH_1):PAGE54
    59 PVDDQ_DEF @BASEBOARD_FAB2_LIB.BASEBOARD_FAB2(SCH_1):PVDDQ_DEF   I170 @BASEBOARD_FAB2_LIB.BASEBOARD_FAB2(SCH_1):PAGE54
    61 PVDDQ_DEF @BASEBOARD_FAB2_LIB.BASEBOARD_FAB2(SCH_1):PVDDQ_DEF   I170 @BASEBOARD_FAB2_LIB.BASEBOARD_FAB2(SCH_1):PAGE54
    64 PVDDQ_DEF @BASEBOARD_FAB2_LIB.BASEBOARD_FAB2(SCH_1):PVDDQ_DEF   I170 @BASEBOARD_FAB2_LIB.BASEBOARD_FAB2(SCH_1):PAGE54
    67 PVDDQ_DEF @BASEBOARD_FAB2_LIB.BASEBOARD_FAB2(SCH_1):PVDDQ_DEF   I170 @BASEBOARD_FAB2_LIB.BASEBOARD_FAB2(SCH_1):PAGE54
    70 PVDDQ_DEF @BASEBOARD_FAB2_LIB.BASEBOARD_FAB2(SCH_1):PVDDQ_DEF   I170 @BASEBOARD_FAB2_LIB.BASEBOARD_FAB2(SCH_1):PAGE54
    73 PVDDQ_DEF @BASEBOARD_FAB2_LIB.BASEBOARD_FAB2(SCH_1):PVDDQ_DEF   I170 @BASEBOARD_FAB2_LIB.BASEBOARD_FAB2(SCH_1):PAGE54
    76 PVDDQ_DEF @BASEBOARD_FAB2_LIB.BASEBOARD_FAB2(SCH_1):PVDDQ_DEF   I170 @BASEBOARD_FAB2_LIB.BASEBOARD_FAB2(SCH_1):PAGE54
    80 PVDDQ_DEF @BASEBOARD_FAB2_LIB.BASEBOARD_FAB2(SCH_1):PVDDQ_DEF   I170 @BASEBOARD_FAB2_LIB.BASEBOARD_FAB2(SCH_1):PAGE54
    83 PVDDQ_DEF @BASEBOARD_FAB2_LIB.BASEBOARD_FAB2(SCH_1):PVDDQ_DEF   I170 @BASEBOARD_FAB2_LIB.BASEBOARD_FAB2(SCH_1):PAGE54
    85 PVDDQ_DEF @BASEBOARD_FAB2_LIB.BASEBOARD_FAB2(SCH_1):PVDDQ_DEF   I170 @BASEBOARD_FAB2_LIB.BASEBOARD_FAB2(SCH_1):PAGE54
    88 PVDDQ_DEF @BASEBOARD_FAB2_LIB.BASEBOARD_FAB2(SCH_1):PVDDQ_DEF   I170 @BASEBOARD_FAB2_LIB.BASEBOARD_FAB2(SCH_1):PAGE54
    90 PVDDQ_DEF @BASEBOARD_FAB2_LIB.BASEBOARD_FAB2(SCH_1):PVDDQ_DEF   I170 @BASEBOARD_FAB2_LIB.BASEBOARD_FAB2(SCH_1):PAGE54
    92 PVDDQ_DEF @BASEBOARD_FAB2_LIB.BASEBOARD_FAB2(SCH_1):PVDDQ_DEF   I170 @BASEBOARD_FAB2_LIB.BASEBOARD_FAB2(SCH_1):PAGE54
   204 PVDDQ_DEF @BASEBOARD_FAB2_LIB.BASEBOARD_FAB2(SCH_1):PVDDQ_DEF   I170 @BASEBOARD_FAB2_LIB.BASEBOARD_FAB2(SCH_1):PAGE54
   206 PVDDQ_DEF @BASEBOARD_FAB2_LIB.BASEBOARD_FAB2(SCH_1):PVDDQ_DEF   I170 @BASEBOARD_FAB2_LIB.BASEBOARD_FAB2(SCH_1):PAGE54
   209 PVDDQ_DEF @BASEBOARD_FAB2_LIB.BASEBOARD_FAB2(SCH_1):PVDDQ_DEF   I170 @BASEBOARD_FAB2_LIB.BASEBOARD_FAB2(SCH_1):PAGE54
   212 PVDDQ_DEF @BASEBOARD_FAB2_LIB.BASEBOARD_FAB2(SCH_1):PVDDQ_DEF   I170 @BASEBOARD_FAB2_LIB.BASEBOARD_FAB2(SCH_1):PAGE54
   215 PVDDQ_DEF @BASEBOARD_FAB2_LIB.BASEBOARD_FAB2(SCH_1):PVDDQ_DEF   I170 @BASEBOARD_FAB2_LIB.BASEBOARD_FAB2(SCH_1):PAGE54
   217 PVDDQ_DEF @BASEBOARD_FAB2_LIB.BASEBOARD_FAB2(SCH_1):PVDDQ_DEF   I170 @BASEBOARD_FAB2_LIB.BASEBOARD_FAB2(SCH_1):PAGE54
   220 PVDDQ_DEF @BASEBOARD_FAB2_LIB.BASEBOARD_FAB2(SCH_1):PVDDQ_DEF   I170 @BASEBOARD_FAB2_LIB.BASEBOARD_FAB2(SCH_1):PAGE54
   223 PVDDQ_DEF @BASEBOARD_FAB2_LIB.BASEBOARD_FAB2(SCH_1):PVDDQ_DEF   I170 @BASEBOARD_FAB2_LIB.BASEBOARD_FAB2(SCH_1):PAGE54
   226 PVDDQ_DEF @BASEBOARD_FAB2_LIB.BASEBOARD_FAB2(SCH_1):PVDDQ_DEF   I170 @BASEBOARD_FAB2_LIB.BASEBOARD_FAB2(SCH_1):PAGE54
   229 PVDDQ_DEF @BASEBOARD_FAB2_LIB.BASEBOARD_FAB2(SCH_1):PVDDQ_DEF   I170 @BASEBOARD_FAB2_LIB.BASEBOARD_FAB2(SCH_1):PAGE54
   231 PVDDQ_DEF @BASEBOARD_FAB2_LIB.BASEBOARD_FAB2(SCH_1):PVDDQ_DEF   I170 @BASEBOARD_FAB2_LIB.BASEBOARD_FAB2(SCH_1):PAGE54
   233 PVDDQ_DEF @BASEBOARD_FAB2_LIB.BASEBOARD_FAB2(SCH_1):PVDDQ_DEF   I170 @BASEBOARD_FAB2_LIB.BASEBOARD_FAB2(SCH_1):PAGE54
   236 PVDDQ_DEF @BASEBOARD_FAB2_LIB.BASEBOARD_FAB2(SCH_1):PVDDQ_DEF   I170 @BASEBOARD_FAB2_LIB.BASEBOARD_FAB2(SCH_1):PAGE54
   142 PVPP_DEF @BASEBOARD_FAB2_LIB.BASEBOARD_FAB2(SCH_1):PVPP_DEF   I170 @BASEBOARD_FAB2_LIB.BASEBOARD_FAB2(SCH_1):PAGE54
   143 PVPP_DEF @BASEBOARD_FAB2_LIB.BASEBOARD_FAB2(SCH_1):PVPP_DEF   I170 @BASEBOARD_FAB2_LIB.BASEBOARD_FAB2(SCH_1):PAGE54
   288 PVPP_DEF @BASEBOARD_FAB2_LIB.BASEBOARD_FAB2(SCH_1):PVPP_DEF   I170 @BASEBOARD_FAB2_LIB.BASEBOARD_FAB2(SCH_1):PAGE54
   286 PVPP_DEF @BASEBOARD_FAB2_LIB.BASEBOARD_FAB2(SCH_1):PVPP_DEF   I170 @BASEBOARD_FAB2_LIB.BASEBOARD_FAB2(SCH_1):PAGE54
   287 PVPP_DEF @BASEBOARD_FAB2_LIB.BASEBOARD_FAB2(SCH_1):PVPP_DEF   I170 @BASEBOARD_FAB2_LIB.BASEBOARD_FAB2(SCH_1):PAGE54
    77 PVTT_DEF @BASEBOARD_FAB2_LIB.BASEBOARD_FAB2(SCH_1):PVTT_DEF   I170 @BASEBOARD_FAB2_LIB.BASEBOARD_FAB2(SCH_1):PAGE54
   221 PVTT_DEF @BASEBOARD_FAB2_LIB.BASEBOARD_FAB2(SCH_1):PVTT_DEF   I170 @BASEBOARD_FAB2_LIB.BASEBOARD_FAB2(SCH_1):PAGE54

J6L2 SCONN288_H44441003_PIP-SCONN,HA
    79 M_E_MA<0> @BASEBOARD_FAB2_LIB.BASEBOARD_FAB2(SCH_1):M_E_MA(0)    I12 @BASEBOARD_FAB2_LIB.BASEBOARD_FAB2(SCH_1):PAGE52
    72 M_E_MA<1> @BASEBOARD_FAB2_LIB.BASEBOARD_FAB2(SCH_1):M_E_MA(1)    I12 @BASEBOARD_FAB2_LIB.BASEBOARD_FAB2(SCH_1):PAGE52
   225 M_E_MA<10> @BASEBOARD_FAB2_LIB.BASEBOARD_FAB2(SCH_1):M_E_MA(10)    I12 @BASEBOARD_FAB2_LIB.BASEBOARD_FAB2(SCH_1):PAGE52
   210 M_E_MA<11> @BASEBOARD_FAB2_LIB.BASEBOARD_FAB2(SCH_1):M_E_MA(11)    I12 @BASEBOARD_FAB2_LIB.BASEBOARD_FAB2(SCH_1):PAGE52
    65 M_E_MA<12> @BASEBOARD_FAB2_LIB.BASEBOARD_FAB2(SCH_1):M_E_MA(12)    I12 @BASEBOARD_FAB2_LIB.BASEBOARD_FAB2(SCH_1):PAGE52
   232 M_E_MA<13> @BASEBOARD_FAB2_LIB.BASEBOARD_FAB2(SCH_1):M_E_MA(13)    I12 @BASEBOARD_FAB2_LIB.BASEBOARD_FAB2(SCH_1):PAGE52
   228 M_E_MA<14> @BASEBOARD_FAB2_LIB.BASEBOARD_FAB2(SCH_1):M_E_MA(14)    I12 @BASEBOARD_FAB2_LIB.BASEBOARD_FAB2(SCH_1):PAGE52
    86 M_E_MA<15> @BASEBOARD_FAB2_LIB.BASEBOARD_FAB2(SCH_1):M_E_MA(15)    I12 @BASEBOARD_FAB2_LIB.BASEBOARD_FAB2(SCH_1):PAGE52
    82 M_E_MA<16> @BASEBOARD_FAB2_LIB.BASEBOARD_FAB2(SCH_1):M_E_MA(16)    I12 @BASEBOARD_FAB2_LIB.BASEBOARD_FAB2(SCH_1):PAGE52
   234 M_E_MA<17> @BASEBOARD_FAB2_LIB.BASEBOARD_FAB2(SCH_1):M_E_MA(17)    I12 @BASEBOARD_FAB2_LIB.BASEBOARD_FAB2(SCH_1):PAGE52
   216 M_E_MA<2> @BASEBOARD_FAB2_LIB.BASEBOARD_FAB2(SCH_1):M_E_MA(2)    I12 @BASEBOARD_FAB2_LIB.BASEBOARD_FAB2(SCH_1):PAGE52
    71 M_E_MA<3> @BASEBOARD_FAB2_LIB.BASEBOARD_FAB2(SCH_1):M_E_MA(3)    I12 @BASEBOARD_FAB2_LIB.BASEBOARD_FAB2(SCH_1):PAGE52
   214 M_E_MA<4> @BASEBOARD_FAB2_LIB.BASEBOARD_FAB2(SCH_1):M_E_MA(4)    I12 @BASEBOARD_FAB2_LIB.BASEBOARD_FAB2(SCH_1):PAGE52
   213 M_E_MA<5> @BASEBOARD_FAB2_LIB.BASEBOARD_FAB2(SCH_1):M_E_MA(5)    I12 @BASEBOARD_FAB2_LIB.BASEBOARD_FAB2(SCH_1):PAGE52
    69 M_E_MA<6> @BASEBOARD_FAB2_LIB.BASEBOARD_FAB2(SCH_1):M_E_MA(6)    I12 @BASEBOARD_FAB2_LIB.BASEBOARD_FAB2(SCH_1):PAGE52
   211 M_E_MA<7> @BASEBOARD_FAB2_LIB.BASEBOARD_FAB2(SCH_1):M_E_MA(7)    I12 @BASEBOARD_FAB2_LIB.BASEBOARD_FAB2(SCH_1):PAGE52
    68 M_E_MA<8> @BASEBOARD_FAB2_LIB.BASEBOARD_FAB2(SCH_1):M_E_MA(8)    I12 @BASEBOARD_FAB2_LIB.BASEBOARD_FAB2(SCH_1):PAGE52
    66 M_E_MA<9> @BASEBOARD_FAB2_LIB.BASEBOARD_FAB2(SCH_1):M_E_MA(9)    I12 @BASEBOARD_FAB2_LIB.BASEBOARD_FAB2(SCH_1):PAGE52
    62 M_E_ACT_N @BASEBOARD_FAB2_LIB.BASEBOARD_FAB2(SCH_1):M_E_ACT_N    I12 @BASEBOARD_FAB2_LIB.BASEBOARD_FAB2(SCH_1):PAGE52
   208 M_E_ALERT_N @BASEBOARD_FAB2_LIB.BASEBOARD_FAB2(SCH_1):M_E_ALERT_N    I12 @BASEBOARD_FAB2_LIB.BASEBOARD_FAB2(SCH_1):PAGE52
   224 M_E_BA<1> @BASEBOARD_FAB2_LIB.BASEBOARD_FAB2(SCH_1):M_E_BA(1)    I12 @BASEBOARD_FAB2_LIB.BASEBOARD_FAB2(SCH_1):PAGE52
    81 M_E_BA<0> @BASEBOARD_FAB2_LIB.BASEBOARD_FAB2(SCH_1):M_E_BA(0)    I12 @BASEBOARD_FAB2_LIB.BASEBOARD_FAB2(SCH_1):PAGE52
   207 M_E_BG<1> @BASEBOARD_FAB2_LIB.BASEBOARD_FAB2(SCH_1):M_E_BG(1)    I12 @BASEBOARD_FAB2_LIB.BASEBOARD_FAB2(SCH_1):PAGE52
    63 M_E_BG<0> @BASEBOARD_FAB2_LIB.BASEBOARD_FAB2(SCH_1):M_E_BG(0)    I12 @BASEBOARD_FAB2_LIB.BASEBOARD_FAB2(SCH_1):PAGE52
   235 M_E_C<2> @BASEBOARD_FAB2_LIB.BASEBOARD_FAB2(SCH_1):M_E_C(2)    I12 @BASEBOARD_FAB2_LIB.BASEBOARD_FAB2(SCH_1):PAGE52
   199 M_E_ECC<7> @BASEBOARD_FAB2_LIB.BASEBOARD_FAB2(SCH_1):M_E_ECC(7)    I12 @BASEBOARD_FAB2_LIB.BASEBOARD_FAB2(SCH_1):PAGE52
    54 M_E_ECC<6> @BASEBOARD_FAB2_LIB.BASEBOARD_FAB2(SCH_1):M_E_ECC(6)    I12 @BASEBOARD_FAB2_LIB.BASEBOARD_FAB2(SCH_1):PAGE52
   192 M_E_ECC<5> @BASEBOARD_FAB2_LIB.BASEBOARD_FAB2(SCH_1):M_E_ECC(5)    I12 @BASEBOARD_FAB2_LIB.BASEBOARD_FAB2(SCH_1):PAGE52
    47 M_E_ECC<4> @BASEBOARD_FAB2_LIB.BASEBOARD_FAB2(SCH_1):M_E_ECC(4)    I12 @BASEBOARD_FAB2_LIB.BASEBOARD_FAB2(SCH_1):PAGE52
   201 M_E_ECC<3> @BASEBOARD_FAB2_LIB.BASEBOARD_FAB2(SCH_1):M_E_ECC(3)    I12 @BASEBOARD_FAB2_LIB.BASEBOARD_FAB2(SCH_1):PAGE52
    56 M_E_ECC<2> @BASEBOARD_FAB2_LIB.BASEBOARD_FAB2(SCH_1):M_E_ECC(2)    I12 @BASEBOARD_FAB2_LIB.BASEBOARD_FAB2(SCH_1):PAGE52
   194 M_E_ECC<1> @BASEBOARD_FAB2_LIB.BASEBOARD_FAB2(SCH_1):M_E_ECC(1)    I12 @BASEBOARD_FAB2_LIB.BASEBOARD_FAB2(SCH_1):PAGE52
    49 M_E_ECC<0> @BASEBOARD_FAB2_LIB.BASEBOARD_FAB2(SCH_1):M_E_ECC(0)    I12 @BASEBOARD_FAB2_LIB.BASEBOARD_FAB2(SCH_1):PAGE52
    75 M_E_CLK_DN<2> @BASEBOARD_FAB2_LIB.BASEBOARD_FAB2(SCH_1):M_E_CLK_DN(2)    I12 @BASEBOARD_FAB2_LIB.BASEBOARD_FAB2(SCH_1):PAGE52
    74 M_E_CLK_DP<2> @BASEBOARD_FAB2_LIB.BASEBOARD_FAB2(SCH_1):M_E_CLK_DP(2)    I12 @BASEBOARD_FAB2_LIB.BASEBOARD_FAB2(SCH_1):PAGE52
   219 M_E_CLK_DN<3> @BASEBOARD_FAB2_LIB.BASEBOARD_FAB2(SCH_1):M_E_CLK_DN(3)    I12 @BASEBOARD_FAB2_LIB.BASEBOARD_FAB2(SCH_1):PAGE52
   218 M_E_CLK_DP<3> @BASEBOARD_FAB2_LIB.BASEBOARD_FAB2(SCH_1):M_E_CLK_DP(3)    I12 @BASEBOARD_FAB2_LIB.BASEBOARD_FAB2(SCH_1):PAGE52
   203 M_E_CKE<3> @BASEBOARD_FAB2_LIB.BASEBOARD_FAB2(SCH_1):M_E_CKE(3)    I12 @BASEBOARD_FAB2_LIB.BASEBOARD_FAB2(SCH_1):PAGE52
    60 M_E_CKE<2> @BASEBOARD_FAB2_LIB.BASEBOARD_FAB2(SCH_1):M_E_CKE(2)    I12 @BASEBOARD_FAB2_LIB.BASEBOARD_FAB2(SCH_1):PAGE52
   280 M_E_DQ<63> @BASEBOARD_FAB2_LIB.BASEBOARD_FAB2(SCH_1):M_E_DQ(63)    I12 @BASEBOARD_FAB2_LIB.BASEBOARD_FAB2(SCH_1):PAGE52
   135 M_E_DQ<62> @BASEBOARD_FAB2_LIB.BASEBOARD_FAB2(SCH_1):M_E_DQ(62)    I12 @BASEBOARD_FAB2_LIB.BASEBOARD_FAB2(SCH_1):PAGE52
   273 M_E_DQ<61> @BASEBOARD_FAB2_LIB.BASEBOARD_FAB2(SCH_1):M_E_DQ(61)    I12 @BASEBOARD_FAB2_LIB.BASEBOARD_FAB2(SCH_1):PAGE52
   128 M_E_DQ<60> @BASEBOARD_FAB2_LIB.BASEBOARD_FAB2(SCH_1):M_E_DQ(60)    I12 @BASEBOARD_FAB2_LIB.BASEBOARD_FAB2(SCH_1):PAGE52
   282 M_E_DQ<59> @BASEBOARD_FAB2_LIB.BASEBOARD_FAB2(SCH_1):M_E_DQ(59)    I12 @BASEBOARD_FAB2_LIB.BASEBOARD_FAB2(SCH_1):PAGE52
   137 M_E_DQ<58> @BASEBOARD_FAB2_LIB.BASEBOARD_FAB2(SCH_1):M_E_DQ(58)    I12 @BASEBOARD_FAB2_LIB.BASEBOARD_FAB2(SCH_1):PAGE52
   275 M_E_DQ<57> @BASEBOARD_FAB2_LIB.BASEBOARD_FAB2(SCH_1):M_E_DQ(57)    I12 @BASEBOARD_FAB2_LIB.BASEBOARD_FAB2(SCH_1):PAGE52
   130 M_E_DQ<56> @BASEBOARD_FAB2_LIB.BASEBOARD_FAB2(SCH_1):M_E_DQ(56)    I12 @BASEBOARD_FAB2_LIB.BASEBOARD_FAB2(SCH_1):PAGE52
   269 M_E_DQ<55> @BASEBOARD_FAB2_LIB.BASEBOARD_FAB2(SCH_1):M_E_DQ(55)    I12 @BASEBOARD_FAB2_LIB.BASEBOARD_FAB2(SCH_1):PAGE52
   124 M_E_DQ<54> @BASEBOARD_FAB2_LIB.BASEBOARD_FAB2(SCH_1):M_E_DQ(54)    I12 @BASEBOARD_FAB2_LIB.BASEBOARD_FAB2(SCH_1):PAGE52
   262 M_E_DQ<53> @BASEBOARD_FAB2_LIB.BASEBOARD_FAB2(SCH_1):M_E_DQ(53)    I12 @BASEBOARD_FAB2_LIB.BASEBOARD_FAB2(SCH_1):PAGE52
   117 M_E_DQ<52> @BASEBOARD_FAB2_LIB.BASEBOARD_FAB2(SCH_1):M_E_DQ(52)    I12 @BASEBOARD_FAB2_LIB.BASEBOARD_FAB2(SCH_1):PAGE52
   271 M_E_DQ<51> @BASEBOARD_FAB2_LIB.BASEBOARD_FAB2(SCH_1):M_E_DQ(51)    I12 @BASEBOARD_FAB2_LIB.BASEBOARD_FAB2(SCH_1):PAGE52
   126 M_E_DQ<50> @BASEBOARD_FAB2_LIB.BASEBOARD_FAB2(SCH_1):M_E_DQ(50)    I12 @BASEBOARD_FAB2_LIB.BASEBOARD_FAB2(SCH_1):PAGE52
   264 M_E_DQ<49> @BASEBOARD_FAB2_LIB.BASEBOARD_FAB2(SCH_1):M_E_DQ(49)    I12 @BASEBOARD_FAB2_LIB.BASEBOARD_FAB2(SCH_1):PAGE52
   119 M_E_DQ<48> @BASEBOARD_FAB2_LIB.BASEBOARD_FAB2(SCH_1):M_E_DQ(48)    I12 @BASEBOARD_FAB2_LIB.BASEBOARD_FAB2(SCH_1):PAGE52
   258 M_E_DQ<47> @BASEBOARD_FAB2_LIB.BASEBOARD_FAB2(SCH_1):M_E_DQ(47)    I12 @BASEBOARD_FAB2_LIB.BASEBOARD_FAB2(SCH_1):PAGE52
   113 M_E_DQ<46> @BASEBOARD_FAB2_LIB.BASEBOARD_FAB2(SCH_1):M_E_DQ(46)    I12 @BASEBOARD_FAB2_LIB.BASEBOARD_FAB2(SCH_1):PAGE52
   251 M_E_DQ<45> @BASEBOARD_FAB2_LIB.BASEBOARD_FAB2(SCH_1):M_E_DQ(45)    I12 @BASEBOARD_FAB2_LIB.BASEBOARD_FAB2(SCH_1):PAGE52
   106 M_E_DQ<44> @BASEBOARD_FAB2_LIB.BASEBOARD_FAB2(SCH_1):M_E_DQ(44)    I12 @BASEBOARD_FAB2_LIB.BASEBOARD_FAB2(SCH_1):PAGE52
   260 M_E_DQ<43> @BASEBOARD_FAB2_LIB.BASEBOARD_FAB2(SCH_1):M_E_DQ(43)    I12 @BASEBOARD_FAB2_LIB.BASEBOARD_FAB2(SCH_1):PAGE52
   115 M_E_DQ<42> @BASEBOARD_FAB2_LIB.BASEBOARD_FAB2(SCH_1):M_E_DQ(42)    I12 @BASEBOARD_FAB2_LIB.BASEBOARD_FAB2(SCH_1):PAGE52
   253 M_E_DQ<41> @BASEBOARD_FAB2_LIB.BASEBOARD_FAB2(SCH_1):M_E_DQ(41)    I12 @BASEBOARD_FAB2_LIB.BASEBOARD_FAB2(SCH_1):PAGE52
   108 M_E_DQ<40> @BASEBOARD_FAB2_LIB.BASEBOARD_FAB2(SCH_1):M_E_DQ(40)    I12 @BASEBOARD_FAB2_LIB.BASEBOARD_FAB2(SCH_1):PAGE52
   247 M_E_DQ<39> @BASEBOARD_FAB2_LIB.BASEBOARD_FAB2(SCH_1):M_E_DQ(39)    I12 @BASEBOARD_FAB2_LIB.BASEBOARD_FAB2(SCH_1):PAGE52
   102 M_E_DQ<38> @BASEBOARD_FAB2_LIB.BASEBOARD_FAB2(SCH_1):M_E_DQ(38)    I12 @BASEBOARD_FAB2_LIB.BASEBOARD_FAB2(SCH_1):PAGE52
   240 M_E_DQ<37> @BASEBOARD_FAB2_LIB.BASEBOARD_FAB2(SCH_1):M_E_DQ(37)    I12 @BASEBOARD_FAB2_LIB.BASEBOARD_FAB2(SCH_1):PAGE52
    95 M_E_DQ<36> @BASEBOARD_FAB2_LIB.BASEBOARD_FAB2(SCH_1):M_E_DQ(36)    I12 @BASEBOARD_FAB2_LIB.BASEBOARD_FAB2(SCH_1):PAGE52
   249 M_E_DQ<35> @BASEBOARD_FAB2_LIB.BASEBOARD_FAB2(SCH_1):M_E_DQ(35)    I12 @BASEBOARD_FAB2_LIB.BASEBOARD_FAB2(SCH_1):PAGE52
   104 M_E_DQ<34> @BASEBOARD_FAB2_LIB.BASEBOARD_FAB2(SCH_1):M_E_DQ(34)    I12 @BASEBOARD_FAB2_LIB.BASEBOARD_FAB2(SCH_1):PAGE52
   242 M_E_DQ<33> @BASEBOARD_FAB2_LIB.BASEBOARD_FAB2(SCH_1):M_E_DQ(33)    I12 @BASEBOARD_FAB2_LIB.BASEBOARD_FAB2(SCH_1):PAGE52
    97 M_E_DQ<32> @BASEBOARD_FAB2_LIB.BASEBOARD_FAB2(SCH_1):M_E_DQ(32)    I12 @BASEBOARD_FAB2_LIB.BASEBOARD_FAB2(SCH_1):PAGE52
   188 M_E_DQ<31> @BASEBOARD_FAB2_LIB.BASEBOARD_FAB2(SCH_1):M_E_DQ(31)    I12 @BASEBOARD_FAB2_LIB.BASEBOARD_FAB2(SCH_1):PAGE52
    43 M_E_DQ<30> @BASEBOARD_FAB2_LIB.BASEBOARD_FAB2(SCH_1):M_E_DQ(30)    I12 @BASEBOARD_FAB2_LIB.BASEBOARD_FAB2(SCH_1):PAGE52
   181 M_E_DQ<29> @BASEBOARD_FAB2_LIB.BASEBOARD_FAB2(SCH_1):M_E_DQ(29)    I12 @BASEBOARD_FAB2_LIB.BASEBOARD_FAB2(SCH_1):PAGE52
    36 M_E_DQ<28> @BASEBOARD_FAB2_LIB.BASEBOARD_FAB2(SCH_1):M_E_DQ(28)    I12 @BASEBOARD_FAB2_LIB.BASEBOARD_FAB2(SCH_1):PAGE52
   190 M_E_DQ<27> @BASEBOARD_FAB2_LIB.BASEBOARD_FAB2(SCH_1):M_E_DQ(27)    I12 @BASEBOARD_FAB2_LIB.BASEBOARD_FAB2(SCH_1):PAGE52
    45 M_E_DQ<26> @BASEBOARD_FAB2_LIB.BASEBOARD_FAB2(SCH_1):M_E_DQ(26)    I12 @BASEBOARD_FAB2_LIB.BASEBOARD_FAB2(SCH_1):PAGE52
   183 M_E_DQ<25> @BASEBOARD_FAB2_LIB.BASEBOARD_FAB2(SCH_1):M_E_DQ(25)    I12 @BASEBOARD_FAB2_LIB.BASEBOARD_FAB2(SCH_1):PAGE52
    38 M_E_DQ<24> @BASEBOARD_FAB2_LIB.BASEBOARD_FAB2(SCH_1):M_E_DQ(24)    I12 @BASEBOARD_FAB2_LIB.BASEBOARD_FAB2(SCH_1):PAGE52
   177 M_E_DQ<23> @BASEBOARD_FAB2_LIB.BASEBOARD_FAB2(SCH_1):M_E_DQ(23)    I12 @BASEBOARD_FAB2_LIB.BASEBOARD_FAB2(SCH_1):PAGE52
    32 M_E_DQ<22> @BASEBOARD_FAB2_LIB.BASEBOARD_FAB2(SCH_1):M_E_DQ(22)    I12 @BASEBOARD_FAB2_LIB.BASEBOARD_FAB2(SCH_1):PAGE52
   170 M_E_DQ<21> @BASEBOARD_FAB2_LIB.BASEBOARD_FAB2(SCH_1):M_E_DQ(21)    I12 @BASEBOARD_FAB2_LIB.BASEBOARD_FAB2(SCH_1):PAGE52
    25 M_E_DQ<20> @BASEBOARD_FAB2_LIB.BASEBOARD_FAB2(SCH_1):M_E_DQ(20)    I12 @BASEBOARD_FAB2_LIB.BASEBOARD_FAB2(SCH_1):PAGE52
   179 M_E_DQ<19> @BASEBOARD_FAB2_LIB.BASEBOARD_FAB2(SCH_1):M_E_DQ(19)    I12 @BASEBOARD_FAB2_LIB.BASEBOARD_FAB2(SCH_1):PAGE52
    34 M_E_DQ<18> @BASEBOARD_FAB2_LIB.BASEBOARD_FAB2(SCH_1):M_E_DQ(18)    I12 @BASEBOARD_FAB2_LIB.BASEBOARD_FAB2(SCH_1):PAGE52
   172 M_E_DQ<17> @BASEBOARD_FAB2_LIB.BASEBOARD_FAB2(SCH_1):M_E_DQ(17)    I12 @BASEBOARD_FAB2_LIB.BASEBOARD_FAB2(SCH_1):PAGE52
    27 M_E_DQ<16> @BASEBOARD_FAB2_LIB.BASEBOARD_FAB2(SCH_1):M_E_DQ(16)    I12 @BASEBOARD_FAB2_LIB.BASEBOARD_FAB2(SCH_1):PAGE52
   166 M_E_DQ<15> @BASEBOARD_FAB2_LIB.BASEBOARD_FAB2(SCH_1):M_E_DQ(15)    I12 @BASEBOARD_FAB2_LIB.BASEBOARD_FAB2(SCH_1):PAGE52
    21 M_E_DQ<14> @BASEBOARD_FAB2_LIB.BASEBOARD_FAB2(SCH_1):M_E_DQ(14)    I12 @BASEBOARD_FAB2_LIB.BASEBOARD_FAB2(SCH_1):PAGE52
   159 M_E_DQ<13> @BASEBOARD_FAB2_LIB.BASEBOARD_FAB2(SCH_1):M_E_DQ(13)    I12 @BASEBOARD_FAB2_LIB.BASEBOARD_FAB2(SCH_1):PAGE52
    14 M_E_DQ<12> @BASEBOARD_FAB2_LIB.BASEBOARD_FAB2(SCH_1):M_E_DQ(12)    I12 @BASEBOARD_FAB2_LIB.BASEBOARD_FAB2(SCH_1):PAGE52
   168 M_E_DQ<11> @BASEBOARD_FAB2_LIB.BASEBOARD_FAB2(SCH_1):M_E_DQ(11)    I12 @BASEBOARD_FAB2_LIB.BASEBOARD_FAB2(SCH_1):PAGE52
    23 M_E_DQ<10> @BASEBOARD_FAB2_LIB.BASEBOARD_FAB2(SCH_1):M_E_DQ(10)    I12 @BASEBOARD_FAB2_LIB.BASEBOARD_FAB2(SCH_1):PAGE52
   161 M_E_DQ<9> @BASEBOARD_FAB2_LIB.BASEBOARD_FAB2(SCH_1):M_E_DQ(9)    I12 @BASEBOARD_FAB2_LIB.BASEBOARD_FAB2(SCH_1):PAGE52
    16 M_E_DQ<8> @BASEBOARD_FAB2_LIB.BASEBOARD_FAB2(SCH_1):M_E_DQ(8)    I12 @BASEBOARD_FAB2_LIB.BASEBOARD_FAB2(SCH_1):PAGE52
   155 M_E_DQ<7> @BASEBOARD_FAB2_LIB.BASEBOARD_FAB2(SCH_1):M_E_DQ(7)    I12 @BASEBOARD_FAB2_LIB.BASEBOARD_FAB2(SCH_1):PAGE52
    10 M_E_DQ<6> @BASEBOARD_FAB2_LIB.BASEBOARD_FAB2(SCH_1):M_E_DQ(6)    I12 @BASEBOARD_FAB2_LIB.BASEBOARD_FAB2(SCH_1):PAGE52
   148 M_E_DQ<5> @BASEBOARD_FAB2_LIB.BASEBOARD_FAB2(SCH_1):M_E_DQ(5)    I12 @BASEBOARD_FAB2_LIB.BASEBOARD_FAB2(SCH_1):PAGE52
     3 M_E_DQ<4> @BASEBOARD_FAB2_LIB.BASEBOARD_FAB2(SCH_1):M_E_DQ(4)    I12 @BASEBOARD_FAB2_LIB.BASEBOARD_FAB2(SCH_1):PAGE52
   157 M_E_DQ<3> @BASEBOARD_FAB2_LIB.BASEBOARD_FAB2(SCH_1):M_E_DQ(3)    I12 @BASEBOARD_FAB2_LIB.BASEBOARD_FAB2(SCH_1):PAGE52
    12 M_E_DQ<2> @BASEBOARD_FAB2_LIB.BASEBOARD_FAB2(SCH_1):M_E_DQ(2)    I12 @BASEBOARD_FAB2_LIB.BASEBOARD_FAB2(SCH_1):PAGE52
   150 M_E_DQ<1> @BASEBOARD_FAB2_LIB.BASEBOARD_FAB2(SCH_1):M_E_DQ(1)    I12 @BASEBOARD_FAB2_LIB.BASEBOARD_FAB2(SCH_1):PAGE52
     5 M_E_DQ<0> @BASEBOARD_FAB2_LIB.BASEBOARD_FAB2(SCH_1):M_E_DQ(0)    I12 @BASEBOARD_FAB2_LIB.BASEBOARD_FAB2(SCH_1):PAGE52
    78 FM_DIMM_EVENT_COD_N @BASEBOARD_FAB2_LIB.BASEBOARD_FAB2(SCH_1):FM_DIMM_EVENT_COD_N    I12 @BASEBOARD_FAB2_LIB.BASEBOARD_FAB2(SCH_1):PAGE52
    91 M_E_ODT<3> @BASEBOARD_FAB2_LIB.BASEBOARD_FAB2(SCH_1):M_E_ODT(3)    I12 @BASEBOARD_FAB2_LIB.BASEBOARD_FAB2(SCH_1):PAGE52
    87 M_E_ODT<2> @BASEBOARD_FAB2_LIB.BASEBOARD_FAB2(SCH_1):M_E_ODT(2)    I12 @BASEBOARD_FAB2_LIB.BASEBOARD_FAB2(SCH_1):PAGE52
   222 M_E_PAR @BASEBOARD_FAB2_LIB.BASEBOARD_FAB2(SCH_1):M_E_PAR    I12 @BASEBOARD_FAB2_LIB.BASEBOARD_FAB2(SCH_1):PAGE52
    58 M_DEF_RST_N @BASEBOARD_FAB2_LIB.BASEBOARD_FAB2(SCH_1):M_DEF_RST_N    I12 @BASEBOARD_FAB2_LIB.BASEBOARD_FAB2(SCH_1):PAGE52
   144 TP_CH_E_DIMM_E1_RFU_2 @BASEBOARD_FAB2_LIB.BASEBOARD_FAB2(SCH_1):TP_CH_E_DIMM_E1_RFU_2    I12 @BASEBOARD_FAB2_LIB.BASEBOARD_FAB2(SCH_1):PAGE52
   227 TP_CH_E_DIMM_E1_RFU_1 @BASEBOARD_FAB2_LIB.BASEBOARD_FAB2(SCH_1):TP_CH_E_DIMM_E1_RFU_1    I12 @BASEBOARD_FAB2_LIB.BASEBOARD_FAB2(SCH_1):PAGE52
   205 TP_CH_E_DIMM_E1_RFU_0 @BASEBOARD_FAB2_LIB.BASEBOARD_FAB2(SCH_1):TP_CH_E_DIMM_E1_RFU_0    I12 @BASEBOARD_FAB2_LIB.BASEBOARD_FAB2(SCH_1):PAGE52
    84 M_E_CS_N<4> @BASEBOARD_FAB2_LIB.BASEBOARD_FAB2(SCH_1):M_E_CS_N(4)    I12 @BASEBOARD_FAB2_LIB.BASEBOARD_FAB2(SCH_1):PAGE52
    89 M_E_CS_N<5> @BASEBOARD_FAB2_LIB.BASEBOARD_FAB2(SCH_1):M_E_CS_N(5)    I12 @BASEBOARD_FAB2_LIB.BASEBOARD_FAB2(SCH_1):PAGE52
    93 M_E_CS_N<6> @BASEBOARD_FAB2_LIB.BASEBOARD_FAB2(SCH_1):M_E_CS_N(6)    I12 @BASEBOARD_FAB2_LIB.BASEBOARD_FAB2(SCH_1):PAGE52
   237 M_E_CS_N<7> @BASEBOARD_FAB2_LIB.BASEBOARD_FAB2(SCH_1):M_E_CS_N(7)    I12 @BASEBOARD_FAB2_LIB.BASEBOARD_FAB2(SCH_1):PAGE52
   238    GND @BASEBOARD_FAB2_LIB.BASEBOARD_FAB2(SCH_1):GND    I12 @BASEBOARD_FAB2_LIB.BASEBOARD_FAB2(SCH_1):PAGE52
   140 PVPP_DEF @BASEBOARD_FAB2_LIB.BASEBOARD_FAB2(SCH_1):PVPP_DEF    I12 @BASEBOARD_FAB2_LIB.BASEBOARD_FAB2(SCH_1):PAGE52
   139 PVPP_DEF @BASEBOARD_FAB2_LIB.BASEBOARD_FAB2(SCH_1):PVPP_DEF    I12 @BASEBOARD_FAB2_LIB.BASEBOARD_FAB2(SCH_1):PAGE52
   230 FM_ADR_COMPLETE_DEF_N @BASEBOARD_FAB2_LIB.BASEBOARD_FAB2(SCH_1):FM_ADR_COMPLETE_DEF_N    I12 @BASEBOARD_FAB2_LIB.BASEBOARD_FAB2(SCH_1):PAGE52
   141 SMB_DDR_DEF_VPP_SCL @BASEBOARD_FAB2_LIB.BASEBOARD_FAB2(SCH_1):SMB_DDR_DEF_VPP_SCL    I12 @BASEBOARD_FAB2_LIB.BASEBOARD_FAB2(SCH_1):PAGE52
   285 SMB_DDR_DEF_VPP_SDA @BASEBOARD_FAB2_LIB.BASEBOARD_FAB2(SCH_1):SMB_DDR_DEF_VPP_SDA    I12 @BASEBOARD_FAB2_LIB.BASEBOARD_FAB2(SCH_1):PAGE52
   284 PVPP_DEF @BASEBOARD_FAB2_LIB.BASEBOARD_FAB2(SCH_1):PVPP_DEF    I12 @BASEBOARD_FAB2_LIB.BASEBOARD_FAB2(SCH_1):PAGE52
   146 M_E_VREF @BASEBOARD_FAB2_LIB.BASEBOARD_FAB2(SCH_1):M_E_VREF    I12 @BASEBOARD_FAB2_LIB.BASEBOARD_FAB2(SCH_1):PAGE52
   152 M_E_DQS_DN<0> @BASEBOARD_FAB2_LIB.BASEBOARD_FAB2(SCH_1):M_E_DQS_DN(0)   I100 @BASEBOARD_FAB2_LIB.BASEBOARD_FAB2(SCH_1):PAGE52
   153 M_E_DQS_DP<0> @BASEBOARD_FAB2_LIB.BASEBOARD_FAB2(SCH_1):M_E_DQS_DP(0)   I100 @BASEBOARD_FAB2_LIB.BASEBOARD_FAB2(SCH_1):PAGE52
    19 M_E_DQS_DN<10> @BASEBOARD_FAB2_LIB.BASEBOARD_FAB2(SCH_1):M_E_DQS_DN(10)   I100 @BASEBOARD_FAB2_LIB.BASEBOARD_FAB2(SCH_1):PAGE52
    18 M_E_DQS_DP<10> @BASEBOARD_FAB2_LIB.BASEBOARD_FAB2(SCH_1):M_E_DQS_DP(10)   I100 @BASEBOARD_FAB2_LIB.BASEBOARD_FAB2(SCH_1):PAGE52
    30 M_E_DQS_DN<11> @BASEBOARD_FAB2_LIB.BASEBOARD_FAB2(SCH_1):M_E_DQS_DN(11)   I100 @BASEBOARD_FAB2_LIB.BASEBOARD_FAB2(SCH_1):PAGE52
    29 M_E_DQS_DP<11> @BASEBOARD_FAB2_LIB.BASEBOARD_FAB2(SCH_1):M_E_DQS_DP(11)   I100 @BASEBOARD_FAB2_LIB.BASEBOARD_FAB2(SCH_1):PAGE52
    41 M_E_DQS_DN<12> @BASEBOARD_FAB2_LIB.BASEBOARD_FAB2(SCH_1):M_E_DQS_DN(12)   I100 @BASEBOARD_FAB2_LIB.BASEBOARD_FAB2(SCH_1):PAGE52
    40 M_E_DQS_DP<12> @BASEBOARD_FAB2_LIB.BASEBOARD_FAB2(SCH_1):M_E_DQS_DP(12)   I100 @BASEBOARD_FAB2_LIB.BASEBOARD_FAB2(SCH_1):PAGE52
   100 M_E_DQS_DN<13> @BASEBOARD_FAB2_LIB.BASEBOARD_FAB2(SCH_1):M_E_DQS_DN(13)   I100 @BASEBOARD_FAB2_LIB.BASEBOARD_FAB2(SCH_1):PAGE52
    99 M_E_DQS_DP<13> @BASEBOARD_FAB2_LIB.BASEBOARD_FAB2(SCH_1):M_E_DQS_DP(13)   I100 @BASEBOARD_FAB2_LIB.BASEBOARD_FAB2(SCH_1):PAGE52
   111 M_E_DQS_DN<14> @BASEBOARD_FAB2_LIB.BASEBOARD_FAB2(SCH_1):M_E_DQS_DN(14)   I100 @BASEBOARD_FAB2_LIB.BASEBOARD_FAB2(SCH_1):PAGE52
   110 M_E_DQS_DP<14> @BASEBOARD_FAB2_LIB.BASEBOARD_FAB2(SCH_1):M_E_DQS_DP(14)   I100 @BASEBOARD_FAB2_LIB.BASEBOARD_FAB2(SCH_1):PAGE52
   122 M_E_DQS_DN<15> @BASEBOARD_FAB2_LIB.BASEBOARD_FAB2(SCH_1):M_E_DQS_DN(15)   I100 @BASEBOARD_FAB2_LIB.BASEBOARD_FAB2(SCH_1):PAGE52
   121 M_E_DQS_DP<15> @BASEBOARD_FAB2_LIB.BASEBOARD_FAB2(SCH_1):M_E_DQS_DP(15)   I100 @BASEBOARD_FAB2_LIB.BASEBOARD_FAB2(SCH_1):PAGE52
   133 M_E_DQS_DN<16> @BASEBOARD_FAB2_LIB.BASEBOARD_FAB2(SCH_1):M_E_DQS_DN(16)   I100 @BASEBOARD_FAB2_LIB.BASEBOARD_FAB2(SCH_1):PAGE52
   132 M_E_DQS_DP<16> @BASEBOARD_FAB2_LIB.BASEBOARD_FAB2(SCH_1):M_E_DQS_DP(16)   I100 @BASEBOARD_FAB2_LIB.BASEBOARD_FAB2(SCH_1):PAGE52
    52 M_E_DQS_DN<17> @BASEBOARD_FAB2_LIB.BASEBOARD_FAB2(SCH_1):M_E_DQS_DN(17)   I100 @BASEBOARD_FAB2_LIB.BASEBOARD_FAB2(SCH_1):PAGE52
    51 M_E_DQS_DP<17> @BASEBOARD_FAB2_LIB.BASEBOARD_FAB2(SCH_1):M_E_DQS_DP(17)   I100 @BASEBOARD_FAB2_LIB.BASEBOARD_FAB2(SCH_1):PAGE52
   163 M_E_DQS_DN<1> @BASEBOARD_FAB2_LIB.BASEBOARD_FAB2(SCH_1):M_E_DQS_DN(1)   I100 @BASEBOARD_FAB2_LIB.BASEBOARD_FAB2(SCH_1):PAGE52
   164 M_E_DQS_DP<1> @BASEBOARD_FAB2_LIB.BASEBOARD_FAB2(SCH_1):M_E_DQS_DP(1)   I100 @BASEBOARD_FAB2_LIB.BASEBOARD_FAB2(SCH_1):PAGE52
   174 M_E_DQS_DN<2> @BASEBOARD_FAB2_LIB.BASEBOARD_FAB2(SCH_1):M_E_DQS_DN(2)   I100 @BASEBOARD_FAB2_LIB.BASEBOARD_FAB2(SCH_1):PAGE52
   175 M_E_DQS_DP<2> @BASEBOARD_FAB2_LIB.BASEBOARD_FAB2(SCH_1):M_E_DQS_DP(2)   I100 @BASEBOARD_FAB2_LIB.BASEBOARD_FAB2(SCH_1):PAGE52
   185 M_E_DQS_DN<3> @BASEBOARD_FAB2_LIB.BASEBOARD_FAB2(SCH_1):M_E_DQS_DN(3)   I100 @BASEBOARD_FAB2_LIB.BASEBOARD_FAB2(SCH_1):PAGE52
   186 M_E_DQS_DP<3> @BASEBOARD_FAB2_LIB.BASEBOARD_FAB2(SCH_1):M_E_DQS_DP(3)   I100 @BASEBOARD_FAB2_LIB.BASEBOARD_FAB2(SCH_1):PAGE52
   244 M_E_DQS_DN<4> @BASEBOARD_FAB2_LIB.BASEBOARD_FAB2(SCH_1):M_E_DQS_DN(4)   I100 @BASEBOARD_FAB2_LIB.BASEBOARD_FAB2(SCH_1):PAGE52
   245 M_E_DQS_DP<4> @BASEBOARD_FAB2_LIB.BASEBOARD_FAB2(SCH_1):M_E_DQS_DP(4)   I100 @BASEBOARD_FAB2_LIB.BASEBOARD_FAB2(SCH_1):PAGE52
   255 M_E_DQS_DN<5> @BASEBOARD_FAB2_LIB.BASEBOARD_FAB2(SCH_1):M_E_DQS_DN(5)   I100 @BASEBOARD_FAB2_LIB.BASEBOARD_FAB2(SCH_1):PAGE52
   256 M_E_DQS_DP<5> @BASEBOARD_FAB2_LIB.BASEBOARD_FAB2(SCH_1):M_E_DQS_DP(5)   I100 @BASEBOARD_FAB2_LIB.BASEBOARD_FAB2(SCH_1):PAGE52
   266 M_E_DQS_DN<6> @BASEBOARD_FAB2_LIB.BASEBOARD_FAB2(SCH_1):M_E_DQS_DN(6)   I100 @BASEBOARD_FAB2_LIB.BASEBOARD_FAB2(SCH_1):PAGE52
   267 M_E_DQS_DP<6> @BASEBOARD_FAB2_LIB.BASEBOARD_FAB2(SCH_1):M_E_DQS_DP(6)   I100 @BASEBOARD_FAB2_LIB.BASEBOARD_FAB2(SCH_1):PAGE52
   277 M_E_DQS_DN<7> @BASEBOARD_FAB2_LIB.BASEBOARD_FAB2(SCH_1):M_E_DQS_DN(7)   I100 @BASEBOARD_FAB2_LIB.BASEBOARD_FAB2(SCH_1):PAGE52
   278 M_E_DQS_DP<7> @BASEBOARD_FAB2_LIB.BASEBOARD_FAB2(SCH_1):M_E_DQS_DP(7)   I100 @BASEBOARD_FAB2_LIB.BASEBOARD_FAB2(SCH_1):PAGE52
   196 M_E_DQS_DN<8> @BASEBOARD_FAB2_LIB.BASEBOARD_FAB2(SCH_1):M_E_DQS_DN(8)   I100 @BASEBOARD_FAB2_LIB.BASEBOARD_FAB2(SCH_1):PAGE52
   197 M_E_DQS_DP<8> @BASEBOARD_FAB2_LIB.BASEBOARD_FAB2(SCH_1):M_E_DQS_DP(8)   I100 @BASEBOARD_FAB2_LIB.BASEBOARD_FAB2(SCH_1):PAGE52
     8 M_E_DQS_DN<9> @BASEBOARD_FAB2_LIB.BASEBOARD_FAB2(SCH_1):M_E_DQS_DN(9)   I100 @BASEBOARD_FAB2_LIB.BASEBOARD_FAB2(SCH_1):PAGE52
     7 M_E_DQS_DP<9> @BASEBOARD_FAB2_LIB.BASEBOARD_FAB2(SCH_1):M_E_DQS_DP(9)   I100 @BASEBOARD_FAB2_LIB.BASEBOARD_FAB2(SCH_1):PAGE52
     2    GND @BASEBOARD_FAB2_LIB.BASEBOARD_FAB2(SCH_1):GND   I138 @BASEBOARD_FAB2_LIB.BASEBOARD_FAB2(SCH_1):PAGE52
     4    GND @BASEBOARD_FAB2_LIB.BASEBOARD_FAB2(SCH_1):GND   I138 @BASEBOARD_FAB2_LIB.BASEBOARD_FAB2(SCH_1):PAGE52
     6    GND @BASEBOARD_FAB2_LIB.BASEBOARD_FAB2(SCH_1):GND   I138 @BASEBOARD_FAB2_LIB.BASEBOARD_FAB2(SCH_1):PAGE52
     9    GND @BASEBOARD_FAB2_LIB.BASEBOARD_FAB2(SCH_1):GND   I138 @BASEBOARD_FAB2_LIB.BASEBOARD_FAB2(SCH_1):PAGE52
    11    GND @BASEBOARD_FAB2_LIB.BASEBOARD_FAB2(SCH_1):GND   I138 @BASEBOARD_FAB2_LIB.BASEBOARD_FAB2(SCH_1):PAGE52
    13    GND @BASEBOARD_FAB2_LIB.BASEBOARD_FAB2(SCH_1):GND   I138 @BASEBOARD_FAB2_LIB.BASEBOARD_FAB2(SCH_1):PAGE52
    15    GND @BASEBOARD_FAB2_LIB.BASEBOARD_FAB2(SCH_1):GND   I138 @BASEBOARD_FAB2_LIB.BASEBOARD_FAB2(SCH_1):PAGE52
    17    GND @BASEBOARD_FAB2_LIB.BASEBOARD_FAB2(SCH_1):GND   I138 @BASEBOARD_FAB2_LIB.BASEBOARD_FAB2(SCH_1):PAGE52
    20    GND @BASEBOARD_FAB2_LIB.BASEBOARD_FAB2(SCH_1):GND   I138 @BASEBOARD_FAB2_LIB.BASEBOARD_FAB2(SCH_1):PAGE52
    22    GND @BASEBOARD_FAB2_LIB.BASEBOARD_FAB2(SCH_1):GND   I138 @BASEBOARD_FAB2_LIB.BASEBOARD_FAB2(SCH_1):PAGE52
    24    GND @BASEBOARD_FAB2_LIB.BASEBOARD_FAB2(SCH_1):GND   I138 @BASEBOARD_FAB2_LIB.BASEBOARD_FAB2(SCH_1):PAGE52
    26    GND @BASEBOARD_FAB2_LIB.BASEBOARD_FAB2(SCH_1):GND   I138 @BASEBOARD_FAB2_LIB.BASEBOARD_FAB2(SCH_1):PAGE52
    28    GND @BASEBOARD_FAB2_LIB.BASEBOARD_FAB2(SCH_1):GND   I138 @BASEBOARD_FAB2_LIB.BASEBOARD_FAB2(SCH_1):PAGE52
    31    GND @BASEBOARD_FAB2_LIB.BASEBOARD_FAB2(SCH_1):GND   I138 @BASEBOARD_FAB2_LIB.BASEBOARD_FAB2(SCH_1):PAGE52
    33    GND @BASEBOARD_FAB2_LIB.BASEBOARD_FAB2(SCH_1):GND   I138 @BASEBOARD_FAB2_LIB.BASEBOARD_FAB2(SCH_1):PAGE52
    35    GND @BASEBOARD_FAB2_LIB.BASEBOARD_FAB2(SCH_1):GND   I138 @BASEBOARD_FAB2_LIB.BASEBOARD_FAB2(SCH_1):PAGE52
    37    GND @BASEBOARD_FAB2_LIB.BASEBOARD_FAB2(SCH_1):GND   I138 @BASEBOARD_FAB2_LIB.BASEBOARD_FAB2(SCH_1):PAGE52
    39    GND @BASEBOARD_FAB2_LIB.BASEBOARD_FAB2(SCH_1):GND   I138 @BASEBOARD_FAB2_LIB.BASEBOARD_FAB2(SCH_1):PAGE52
    42    GND @BASEBOARD_FAB2_LIB.BASEBOARD_FAB2(SCH_1):GND   I138 @BASEBOARD_FAB2_LIB.BASEBOARD_FAB2(SCH_1):PAGE52
    44    GND @BASEBOARD_FAB2_LIB.BASEBOARD_FAB2(SCH_1):GND   I138 @BASEBOARD_FAB2_LIB.BASEBOARD_FAB2(SCH_1):PAGE52
    46    GND @BASEBOARD_FAB2_LIB.BASEBOARD_FAB2(SCH_1):GND   I138 @BASEBOARD_FAB2_LIB.BASEBOARD_FAB2(SCH_1):PAGE52
    48    GND @BASEBOARD_FAB2_LIB.BASEBOARD_FAB2(SCH_1):GND   I138 @BASEBOARD_FAB2_LIB.BASEBOARD_FAB2(SCH_1):PAGE52
    50    GND @BASEBOARD_FAB2_LIB.BASEBOARD_FAB2(SCH_1):GND   I138 @BASEBOARD_FAB2_LIB.BASEBOARD_FAB2(SCH_1):PAGE52
    53    GND @BASEBOARD_FAB2_LIB.BASEBOARD_FAB2(SCH_1):GND   I138 @BASEBOARD_FAB2_LIB.BASEBOARD_FAB2(SCH_1):PAGE52
    55    GND @BASEBOARD_FAB2_LIB.BASEBOARD_FAB2(SCH_1):GND   I138 @BASEBOARD_FAB2_LIB.BASEBOARD_FAB2(SCH_1):PAGE52
    57    GND @BASEBOARD_FAB2_LIB.BASEBOARD_FAB2(SCH_1):GND   I138 @BASEBOARD_FAB2_LIB.BASEBOARD_FAB2(SCH_1):PAGE52
    94    GND @BASEBOARD_FAB2_LIB.BASEBOARD_FAB2(SCH_1):GND   I138 @BASEBOARD_FAB2_LIB.BASEBOARD_FAB2(SCH_1):PAGE52
    96    GND @BASEBOARD_FAB2_LIB.BASEBOARD_FAB2(SCH_1):GND   I138 @BASEBOARD_FAB2_LIB.BASEBOARD_FAB2(SCH_1):PAGE52
    98    GND @BASEBOARD_FAB2_LIB.BASEBOARD_FAB2(SCH_1):GND   I138 @BASEBOARD_FAB2_LIB.BASEBOARD_FAB2(SCH_1):PAGE52
   101    GND @BASEBOARD_FAB2_LIB.BASEBOARD_FAB2(SCH_1):GND   I138 @BASEBOARD_FAB2_LIB.BASEBOARD_FAB2(SCH_1):PAGE52
   103    GND @BASEBOARD_FAB2_LIB.BASEBOARD_FAB2(SCH_1):GND   I138 @BASEBOARD_FAB2_LIB.BASEBOARD_FAB2(SCH_1):PAGE52
   105    GND @BASEBOARD_FAB2_LIB.BASEBOARD_FAB2(SCH_1):GND   I138 @BASEBOARD_FAB2_LIB.BASEBOARD_FAB2(SCH_1):PAGE52
   107    GND @BASEBOARD_FAB2_LIB.BASEBOARD_FAB2(SCH_1):GND   I138 @BASEBOARD_FAB2_LIB.BASEBOARD_FAB2(SCH_1):PAGE52
   109    GND @BASEBOARD_FAB2_LIB.BASEBOARD_FAB2(SCH_1):GND   I138 @BASEBOARD_FAB2_LIB.BASEBOARD_FAB2(SCH_1):PAGE52
   112    GND @BASEBOARD_FAB2_LIB.BASEBOARD_FAB2(SCH_1):GND   I138 @BASEBOARD_FAB2_LIB.BASEBOARD_FAB2(SCH_1):PAGE52
   114    GND @BASEBOARD_FAB2_LIB.BASEBOARD_FAB2(SCH_1):GND   I138 @BASEBOARD_FAB2_LIB.BASEBOARD_FAB2(SCH_1):PAGE52
   116    GND @BASEBOARD_FAB2_LIB.BASEBOARD_FAB2(SCH_1):GND   I138 @BASEBOARD_FAB2_LIB.BASEBOARD_FAB2(SCH_1):PAGE52
   118    GND @BASEBOARD_FAB2_LIB.BASEBOARD_FAB2(SCH_1):GND   I138 @BASEBOARD_FAB2_LIB.BASEBOARD_FAB2(SCH_1):PAGE52
   120    GND @BASEBOARD_FAB2_LIB.BASEBOARD_FAB2(SCH_1):GND   I138 @BASEBOARD_FAB2_LIB.BASEBOARD_FAB2(SCH_1):PAGE52
   123    GND @BASEBOARD_FAB2_LIB.BASEBOARD_FAB2(SCH_1):GND   I138 @BASEBOARD_FAB2_LIB.BASEBOARD_FAB2(SCH_1):PAGE52
   125    GND @BASEBOARD_FAB2_LIB.BASEBOARD_FAB2(SCH_1):GND   I138 @BASEBOARD_FAB2_LIB.BASEBOARD_FAB2(SCH_1):PAGE52
   127    GND @BASEBOARD_FAB2_LIB.BASEBOARD_FAB2(SCH_1):GND   I138 @BASEBOARD_FAB2_LIB.BASEBOARD_FAB2(SCH_1):PAGE52
   129    GND @BASEBOARD_FAB2_LIB.BASEBOARD_FAB2(SCH_1):GND   I138 @BASEBOARD_FAB2_LIB.BASEBOARD_FAB2(SCH_1):PAGE52
   131    GND @BASEBOARD_FAB2_LIB.BASEBOARD_FAB2(SCH_1):GND   I138 @BASEBOARD_FAB2_LIB.BASEBOARD_FAB2(SCH_1):PAGE52
   134    GND @BASEBOARD_FAB2_LIB.BASEBOARD_FAB2(SCH_1):GND   I138 @BASEBOARD_FAB2_LIB.BASEBOARD_FAB2(SCH_1):PAGE52
   136    GND @BASEBOARD_FAB2_LIB.BASEBOARD_FAB2(SCH_1):GND   I138 @BASEBOARD_FAB2_LIB.BASEBOARD_FAB2(SCH_1):PAGE52
   138    GND @BASEBOARD_FAB2_LIB.BASEBOARD_FAB2(SCH_1):GND   I138 @BASEBOARD_FAB2_LIB.BASEBOARD_FAB2(SCH_1):PAGE52
   147    GND @BASEBOARD_FAB2_LIB.BASEBOARD_FAB2(SCH_1):GND   I138 @BASEBOARD_FAB2_LIB.BASEBOARD_FAB2(SCH_1):PAGE52
   149    GND @BASEBOARD_FAB2_LIB.BASEBOARD_FAB2(SCH_1):GND   I138 @BASEBOARD_FAB2_LIB.BASEBOARD_FAB2(SCH_1):PAGE52
   151    GND @BASEBOARD_FAB2_LIB.BASEBOARD_FAB2(SCH_1):GND   I138 @BASEBOARD_FAB2_LIB.BASEBOARD_FAB2(SCH_1):PAGE52
   154    GND @BASEBOARD_FAB2_LIB.BASEBOARD_FAB2(SCH_1):GND   I138 @BASEBOARD_FAB2_LIB.BASEBOARD_FAB2(SCH_1):PAGE52
   156    GND @BASEBOARD_FAB2_LIB.BASEBOARD_FAB2(SCH_1):GND   I138 @BASEBOARD_FAB2_LIB.BASEBOARD_FAB2(SCH_1):PAGE52
   158    GND @BASEBOARD_FAB2_LIB.BASEBOARD_FAB2(SCH_1):GND   I138 @BASEBOARD_FAB2_LIB.BASEBOARD_FAB2(SCH_1):PAGE52
   160    GND @BASEBOARD_FAB2_LIB.BASEBOARD_FAB2(SCH_1):GND   I138 @BASEBOARD_FAB2_LIB.BASEBOARD_FAB2(SCH_1):PAGE52
   162    GND @BASEBOARD_FAB2_LIB.BASEBOARD_FAB2(SCH_1):GND   I138 @BASEBOARD_FAB2_LIB.BASEBOARD_FAB2(SCH_1):PAGE52
   165    GND @BASEBOARD_FAB2_LIB.BASEBOARD_FAB2(SCH_1):GND   I138 @BASEBOARD_FAB2_LIB.BASEBOARD_FAB2(SCH_1):PAGE52
   167    GND @BASEBOARD_FAB2_LIB.BASEBOARD_FAB2(SCH_1):GND   I138 @BASEBOARD_FAB2_LIB.BASEBOARD_FAB2(SCH_1):PAGE52
   169    GND @BASEBOARD_FAB2_LIB.BASEBOARD_FAB2(SCH_1):GND   I138 @BASEBOARD_FAB2_LIB.BASEBOARD_FAB2(SCH_1):PAGE52
   171    GND @BASEBOARD_FAB2_LIB.BASEBOARD_FAB2(SCH_1):GND   I138 @BASEBOARD_FAB2_LIB.BASEBOARD_FAB2(SCH_1):PAGE52
   173    GND @BASEBOARD_FAB2_LIB.BASEBOARD_FAB2(SCH_1):GND   I138 @BASEBOARD_FAB2_LIB.BASEBOARD_FAB2(SCH_1):PAGE52
   176    GND @BASEBOARD_FAB2_LIB.BASEBOARD_FAB2(SCH_1):GND   I138 @BASEBOARD_FAB2_LIB.BASEBOARD_FAB2(SCH_1):PAGE52
   178    GND @BASEBOARD_FAB2_LIB.BASEBOARD_FAB2(SCH_1):GND   I138 @BASEBOARD_FAB2_LIB.BASEBOARD_FAB2(SCH_1):PAGE52
   180    GND @BASEBOARD_FAB2_LIB.BASEBOARD_FAB2(SCH_1):GND   I138 @BASEBOARD_FAB2_LIB.BASEBOARD_FAB2(SCH_1):PAGE52
   182    GND @BASEBOARD_FAB2_LIB.BASEBOARD_FAB2(SCH_1):GND   I138 @BASEBOARD_FAB2_LIB.BASEBOARD_FAB2(SCH_1):PAGE52
   184    GND @BASEBOARD_FAB2_LIB.BASEBOARD_FAB2(SCH_1):GND   I138 @BASEBOARD_FAB2_LIB.BASEBOARD_FAB2(SCH_1):PAGE52
   187    GND @BASEBOARD_FAB2_LIB.BASEBOARD_FAB2(SCH_1):GND   I138 @BASEBOARD_FAB2_LIB.BASEBOARD_FAB2(SCH_1):PAGE52
   189    GND @BASEBOARD_FAB2_LIB.BASEBOARD_FAB2(SCH_1):GND   I138 @BASEBOARD_FAB2_LIB.BASEBOARD_FAB2(SCH_1):PAGE52
   191    GND @BASEBOARD_FAB2_LIB.BASEBOARD_FAB2(SCH_1):GND   I138 @BASEBOARD_FAB2_LIB.BASEBOARD_FAB2(SCH_1):PAGE52
   193    GND @BASEBOARD_FAB2_LIB.BASEBOARD_FAB2(SCH_1):GND   I138 @BASEBOARD_FAB2_LIB.BASEBOARD_FAB2(SCH_1):PAGE52
   195    GND @BASEBOARD_FAB2_LIB.BASEBOARD_FAB2(SCH_1):GND   I138 @BASEBOARD_FAB2_LIB.BASEBOARD_FAB2(SCH_1):PAGE52
   198    GND @BASEBOARD_FAB2_LIB.BASEBOARD_FAB2(SCH_1):GND   I138 @BASEBOARD_FAB2_LIB.BASEBOARD_FAB2(SCH_1):PAGE52
   200    GND @BASEBOARD_FAB2_LIB.BASEBOARD_FAB2(SCH_1):GND   I138 @BASEBOARD_FAB2_LIB.BASEBOARD_FAB2(SCH_1):PAGE52
   202    GND @BASEBOARD_FAB2_LIB.BASEBOARD_FAB2(SCH_1):GND   I138 @BASEBOARD_FAB2_LIB.BASEBOARD_FAB2(SCH_1):PAGE52
   239    GND @BASEBOARD_FAB2_LIB.BASEBOARD_FAB2(SCH_1):GND   I138 @BASEBOARD_FAB2_LIB.BASEBOARD_FAB2(SCH_1):PAGE52
   241    GND @BASEBOARD_FAB2_LIB.BASEBOARD_FAB2(SCH_1):GND   I138 @BASEBOARD_FAB2_LIB.BASEBOARD_FAB2(SCH_1):PAGE52
   243    GND @BASEBOARD_FAB2_LIB.BASEBOARD_FAB2(SCH_1):GND   I138 @BASEBOARD_FAB2_LIB.BASEBOARD_FAB2(SCH_1):PAGE52
   246    GND @BASEBOARD_FAB2_LIB.BASEBOARD_FAB2(SCH_1):GND   I138 @BASEBOARD_FAB2_LIB.BASEBOARD_FAB2(SCH_1):PAGE52
   248    GND @BASEBOARD_FAB2_LIB.BASEBOARD_FAB2(SCH_1):GND   I138 @BASEBOARD_FAB2_LIB.BASEBOARD_FAB2(SCH_1):PAGE52
   250    GND @BASEBOARD_FAB2_LIB.BASEBOARD_FAB2(SCH_1):GND   I138 @BASEBOARD_FAB2_LIB.BASEBOARD_FAB2(SCH_1):PAGE52
   252    GND @BASEBOARD_FAB2_LIB.BASEBOARD_FAB2(SCH_1):GND   I138 @BASEBOARD_FAB2_LIB.BASEBOARD_FAB2(SCH_1):PAGE52
   254    GND @BASEBOARD_FAB2_LIB.BASEBOARD_FAB2(SCH_1):GND   I138 @BASEBOARD_FAB2_LIB.BASEBOARD_FAB2(SCH_1):PAGE52
   257    GND @BASEBOARD_FAB2_LIB.BASEBOARD_FAB2(SCH_1):GND   I138 @BASEBOARD_FAB2_LIB.BASEBOARD_FAB2(SCH_1):PAGE52
   259    GND @BASEBOARD_FAB2_LIB.BASEBOARD_FAB2(SCH_1):GND   I138 @BASEBOARD_FAB2_LIB.BASEBOARD_FAB2(SCH_1):PAGE52
   261    GND @BASEBOARD_FAB2_LIB.BASEBOARD_FAB2(SCH_1):GND   I138 @BASEBOARD_FAB2_LIB.BASEBOARD_FAB2(SCH_1):PAGE52
   263    GND @BASEBOARD_FAB2_LIB.BASEBOARD_FAB2(SCH_1):GND   I138 @BASEBOARD_FAB2_LIB.BASEBOARD_FAB2(SCH_1):PAGE52
   265    GND @BASEBOARD_FAB2_LIB.BASEBOARD_FAB2(SCH_1):GND   I138 @BASEBOARD_FAB2_LIB.BASEBOARD_FAB2(SCH_1):PAGE52
   268    GND @BASEBOARD_FAB2_LIB.BASEBOARD_FAB2(SCH_1):GND   I138 @BASEBOARD_FAB2_LIB.BASEBOARD_FAB2(SCH_1):PAGE52
   270    GND @BASEBOARD_FAB2_LIB.BASEBOARD_FAB2(SCH_1):GND   I138 @BASEBOARD_FAB2_LIB.BASEBOARD_FAB2(SCH_1):PAGE52
   272    GND @BASEBOARD_FAB2_LIB.BASEBOARD_FAB2(SCH_1):GND   I138 @BASEBOARD_FAB2_LIB.BASEBOARD_FAB2(SCH_1):PAGE52
   274    GND @BASEBOARD_FAB2_LIB.BASEBOARD_FAB2(SCH_1):GND   I138 @BASEBOARD_FAB2_LIB.BASEBOARD_FAB2(SCH_1):PAGE52
   276    GND @BASEBOARD_FAB2_LIB.BASEBOARD_FAB2(SCH_1):GND   I138 @BASEBOARD_FAB2_LIB.BASEBOARD_FAB2(SCH_1):PAGE52
   279    GND @BASEBOARD_FAB2_LIB.BASEBOARD_FAB2(SCH_1):GND   I138 @BASEBOARD_FAB2_LIB.BASEBOARD_FAB2(SCH_1):PAGE52
   281    GND @BASEBOARD_FAB2_LIB.BASEBOARD_FAB2(SCH_1):GND   I138 @BASEBOARD_FAB2_LIB.BASEBOARD_FAB2(SCH_1):PAGE52
   283    GND @BASEBOARD_FAB2_LIB.BASEBOARD_FAB2(SCH_1):GND   I138 @BASEBOARD_FAB2_LIB.BASEBOARD_FAB2(SCH_1):PAGE52
     1 P12V_NVDIMM_DEF @BASEBOARD_FAB2_LIB.BASEBOARD_FAB2(SCH_1):P12V_NVDIMM_DEF    I55 @BASEBOARD_FAB2_LIB.BASEBOARD_FAB2(SCH_1):PAGE52
   145 P12V_NVDIMM_DEF @BASEBOARD_FAB2_LIB.BASEBOARD_FAB2(SCH_1):P12V_NVDIMM_DEF    I55 @BASEBOARD_FAB2_LIB.BASEBOARD_FAB2(SCH_1):PAGE52
    59 PVDDQ_DEF @BASEBOARD_FAB2_LIB.BASEBOARD_FAB2(SCH_1):PVDDQ_DEF    I55 @BASEBOARD_FAB2_LIB.BASEBOARD_FAB2(SCH_1):PAGE52
    61 PVDDQ_DEF @BASEBOARD_FAB2_LIB.BASEBOARD_FAB2(SCH_1):PVDDQ_DEF    I55 @BASEBOARD_FAB2_LIB.BASEBOARD_FAB2(SCH_1):PAGE52
    64 PVDDQ_DEF @BASEBOARD_FAB2_LIB.BASEBOARD_FAB2(SCH_1):PVDDQ_DEF    I55 @BASEBOARD_FAB2_LIB.BASEBOARD_FAB2(SCH_1):PAGE52
    67 PVDDQ_DEF @BASEBOARD_FAB2_LIB.BASEBOARD_FAB2(SCH_1):PVDDQ_DEF    I55 @BASEBOARD_FAB2_LIB.BASEBOARD_FAB2(SCH_1):PAGE52
    70 PVDDQ_DEF @BASEBOARD_FAB2_LIB.BASEBOARD_FAB2(SCH_1):PVDDQ_DEF    I55 @BASEBOARD_FAB2_LIB.BASEBOARD_FAB2(SCH_1):PAGE52
    73 PVDDQ_DEF @BASEBOARD_FAB2_LIB.BASEBOARD_FAB2(SCH_1):PVDDQ_DEF    I55 @BASEBOARD_FAB2_LIB.BASEBOARD_FAB2(SCH_1):PAGE52
    76 PVDDQ_DEF @BASEBOARD_FAB2_LIB.BASEBOARD_FAB2(SCH_1):PVDDQ_DEF    I55 @BASEBOARD_FAB2_LIB.BASEBOARD_FAB2(SCH_1):PAGE52
    80 PVDDQ_DEF @BASEBOARD_FAB2_LIB.BASEBOARD_FAB2(SCH_1):PVDDQ_DEF    I55 @BASEBOARD_FAB2_LIB.BASEBOARD_FAB2(SCH_1):PAGE52
    83 PVDDQ_DEF @BASEBOARD_FAB2_LIB.BASEBOARD_FAB2(SCH_1):PVDDQ_DEF    I55 @BASEBOARD_FAB2_LIB.BASEBOARD_FAB2(SCH_1):PAGE52
    85 PVDDQ_DEF @BASEBOARD_FAB2_LIB.BASEBOARD_FAB2(SCH_1):PVDDQ_DEF    I55 @BASEBOARD_FAB2_LIB.BASEBOARD_FAB2(SCH_1):PAGE52
    88 PVDDQ_DEF @BASEBOARD_FAB2_LIB.BASEBOARD_FAB2(SCH_1):PVDDQ_DEF    I55 @BASEBOARD_FAB2_LIB.BASEBOARD_FAB2(SCH_1):PAGE52
    90 PVDDQ_DEF @BASEBOARD_FAB2_LIB.BASEBOARD_FAB2(SCH_1):PVDDQ_DEF    I55 @BASEBOARD_FAB2_LIB.BASEBOARD_FAB2(SCH_1):PAGE52
    92 PVDDQ_DEF @BASEBOARD_FAB2_LIB.BASEBOARD_FAB2(SCH_1):PVDDQ_DEF    I55 @BASEBOARD_FAB2_LIB.BASEBOARD_FAB2(SCH_1):PAGE52
   204 PVDDQ_DEF @BASEBOARD_FAB2_LIB.BASEBOARD_FAB2(SCH_1):PVDDQ_DEF    I55 @BASEBOARD_FAB2_LIB.BASEBOARD_FAB2(SCH_1):PAGE52
   206 PVDDQ_DEF @BASEBOARD_FAB2_LIB.BASEBOARD_FAB2(SCH_1):PVDDQ_DEF    I55 @BASEBOARD_FAB2_LIB.BASEBOARD_FAB2(SCH_1):PAGE52
   209 PVDDQ_DEF @BASEBOARD_FAB2_LIB.BASEBOARD_FAB2(SCH_1):PVDDQ_DEF    I55 @BASEBOARD_FAB2_LIB.BASEBOARD_FAB2(SCH_1):PAGE52
   212 PVDDQ_DEF @BASEBOARD_FAB2_LIB.BASEBOARD_FAB2(SCH_1):PVDDQ_DEF    I55 @BASEBOARD_FAB2_LIB.BASEBOARD_FAB2(SCH_1):PAGE52
   215 PVDDQ_DEF @BASEBOARD_FAB2_LIB.BASEBOARD_FAB2(SCH_1):PVDDQ_DEF    I55 @BASEBOARD_FAB2_LIB.BASEBOARD_FAB2(SCH_1):PAGE52
   217 PVDDQ_DEF @BASEBOARD_FAB2_LIB.BASEBOARD_FAB2(SCH_1):PVDDQ_DEF    I55 @BASEBOARD_FAB2_LIB.BASEBOARD_FAB2(SCH_1):PAGE52
   220 PVDDQ_DEF @BASEBOARD_FAB2_LIB.BASEBOARD_FAB2(SCH_1):PVDDQ_DEF    I55 @BASEBOARD_FAB2_LIB.BASEBOARD_FAB2(SCH_1):PAGE52
   223 PVDDQ_DEF @BASEBOARD_FAB2_LIB.BASEBOARD_FAB2(SCH_1):PVDDQ_DEF    I55 @BASEBOARD_FAB2_LIB.BASEBOARD_FAB2(SCH_1):PAGE52
   226 PVDDQ_DEF @BASEBOARD_FAB2_LIB.BASEBOARD_FAB2(SCH_1):PVDDQ_DEF    I55 @BASEBOARD_FAB2_LIB.BASEBOARD_FAB2(SCH_1):PAGE52
   229 PVDDQ_DEF @BASEBOARD_FAB2_LIB.BASEBOARD_FAB2(SCH_1):PVDDQ_DEF    I55 @BASEBOARD_FAB2_LIB.BASEBOARD_FAB2(SCH_1):PAGE52
   231 PVDDQ_DEF @BASEBOARD_FAB2_LIB.BASEBOARD_FAB2(SCH_1):PVDDQ_DEF    I55 @BASEBOARD_FAB2_LIB.BASEBOARD_FAB2(SCH_1):PAGE52
   233 PVDDQ_DEF @BASEBOARD_FAB2_LIB.BASEBOARD_FAB2(SCH_1):PVDDQ_DEF    I55 @BASEBOARD_FAB2_LIB.BASEBOARD_FAB2(SCH_1):PAGE52
   236 PVDDQ_DEF @BASEBOARD_FAB2_LIB.BASEBOARD_FAB2(SCH_1):PVDDQ_DEF    I55 @BASEBOARD_FAB2_LIB.BASEBOARD_FAB2(SCH_1):PAGE52
   142 PVPP_DEF @BASEBOARD_FAB2_LIB.BASEBOARD_FAB2(SCH_1):PVPP_DEF    I55 @BASEBOARD_FAB2_LIB.BASEBOARD_FAB2(SCH_1):PAGE52
   143 PVPP_DEF @BASEBOARD_FAB2_LIB.BASEBOARD_FAB2(SCH_1):PVPP_DEF    I55 @BASEBOARD_FAB2_LIB.BASEBOARD_FAB2(SCH_1):PAGE52
   288 PVPP_DEF @BASEBOARD_FAB2_LIB.BASEBOARD_FAB2(SCH_1):PVPP_DEF    I55 @BASEBOARD_FAB2_LIB.BASEBOARD_FAB2(SCH_1):PAGE52
   286 PVPP_DEF @BASEBOARD_FAB2_LIB.BASEBOARD_FAB2(SCH_1):PVPP_DEF    I55 @BASEBOARD_FAB2_LIB.BASEBOARD_FAB2(SCH_1):PAGE52
   287 PVPP_DEF @BASEBOARD_FAB2_LIB.BASEBOARD_FAB2(SCH_1):PVPP_DEF    I55 @BASEBOARD_FAB2_LIB.BASEBOARD_FAB2(SCH_1):PAGE52
    77 PVTT_DEF @BASEBOARD_FAB2_LIB.BASEBOARD_FAB2(SCH_1):PVTT_DEF    I55 @BASEBOARD_FAB2_LIB.BASEBOARD_FAB2(SCH_1):PAGE52
   221 PVTT_DEF @BASEBOARD_FAB2_LIB.BASEBOARD_FAB2(SCH_1):PVTT_DEF    I55 @BASEBOARD_FAB2_LIB.BASEBOARD_FAB2(SCH_1):PAGE52

J6M1 SCONN288_H44441003_PIP-SCONN,HA
    79 M_D_MA<0> @BASEBOARD_FAB2_LIB.BASEBOARD_FAB2(SCH_1):M_D_MA(0)   I158 @BASEBOARD_FAB2_LIB.BASEBOARD_FAB2(SCH_1):PAGE50
    72 M_D_MA<1> @BASEBOARD_FAB2_LIB.BASEBOARD_FAB2(SCH_1):M_D_MA(1)   I158 @BASEBOARD_FAB2_LIB.BASEBOARD_FAB2(SCH_1):PAGE50
   225 M_D_MA<10> @BASEBOARD_FAB2_LIB.BASEBOARD_FAB2(SCH_1):M_D_MA(10)   I158 @BASEBOARD_FAB2_LIB.BASEBOARD_FAB2(SCH_1):PAGE50
   210 M_D_MA<11> @BASEBOARD_FAB2_LIB.BASEBOARD_FAB2(SCH_1):M_D_MA(11)   I158 @BASEBOARD_FAB2_LIB.BASEBOARD_FAB2(SCH_1):PAGE50
    65 M_D_MA<12> @BASEBOARD_FAB2_LIB.BASEBOARD_FAB2(SCH_1):M_D_MA(12)   I158 @BASEBOARD_FAB2_LIB.BASEBOARD_FAB2(SCH_1):PAGE50
   232 M_D_MA<13> @BASEBOARD_FAB2_LIB.BASEBOARD_FAB2(SCH_1):M_D_MA(13)   I158 @BASEBOARD_FAB2_LIB.BASEBOARD_FAB2(SCH_1):PAGE50
   228 M_D_MA<14> @BASEBOARD_FAB2_LIB.BASEBOARD_FAB2(SCH_1):M_D_MA(14)   I158 @BASEBOARD_FAB2_LIB.BASEBOARD_FAB2(SCH_1):PAGE50
    86 M_D_MA<15> @BASEBOARD_FAB2_LIB.BASEBOARD_FAB2(SCH_1):M_D_MA(15)   I158 @BASEBOARD_FAB2_LIB.BASEBOARD_FAB2(SCH_1):PAGE50
    82 M_D_MA<16> @BASEBOARD_FAB2_LIB.BASEBOARD_FAB2(SCH_1):M_D_MA(16)   I158 @BASEBOARD_FAB2_LIB.BASEBOARD_FAB2(SCH_1):PAGE50
   234 M_D_MA<17> @BASEBOARD_FAB2_LIB.BASEBOARD_FAB2(SCH_1):M_D_MA(17)   I158 @BASEBOARD_FAB2_LIB.BASEBOARD_FAB2(SCH_1):PAGE50
   216 M_D_MA<2> @BASEBOARD_FAB2_LIB.BASEBOARD_FAB2(SCH_1):M_D_MA(2)   I158 @BASEBOARD_FAB2_LIB.BASEBOARD_FAB2(SCH_1):PAGE50
    71 M_D_MA<3> @BASEBOARD_FAB2_LIB.BASEBOARD_FAB2(SCH_1):M_D_MA(3)   I158 @BASEBOARD_FAB2_LIB.BASEBOARD_FAB2(SCH_1):PAGE50
   214 M_D_MA<4> @BASEBOARD_FAB2_LIB.BASEBOARD_FAB2(SCH_1):M_D_MA(4)   I158 @BASEBOARD_FAB2_LIB.BASEBOARD_FAB2(SCH_1):PAGE50
   213 M_D_MA<5> @BASEBOARD_FAB2_LIB.BASEBOARD_FAB2(SCH_1):M_D_MA(5)   I158 @BASEBOARD_FAB2_LIB.BASEBOARD_FAB2(SCH_1):PAGE50
    69 M_D_MA<6> @BASEBOARD_FAB2_LIB.BASEBOARD_FAB2(SCH_1):M_D_MA(6)   I158 @BASEBOARD_FAB2_LIB.BASEBOARD_FAB2(SCH_1):PAGE50
   211 M_D_MA<7> @BASEBOARD_FAB2_LIB.BASEBOARD_FAB2(SCH_1):M_D_MA(7)   I158 @BASEBOARD_FAB2_LIB.BASEBOARD_FAB2(SCH_1):PAGE50
    68 M_D_MA<8> @BASEBOARD_FAB2_LIB.BASEBOARD_FAB2(SCH_1):M_D_MA(8)   I158 @BASEBOARD_FAB2_LIB.BASEBOARD_FAB2(SCH_1):PAGE50
    66 M_D_MA<9> @BASEBOARD_FAB2_LIB.BASEBOARD_FAB2(SCH_1):M_D_MA(9)   I158 @BASEBOARD_FAB2_LIB.BASEBOARD_FAB2(SCH_1):PAGE50
    62 M_D_ACT_N @BASEBOARD_FAB2_LIB.BASEBOARD_FAB2(SCH_1):M_D_ACT_N   I158 @BASEBOARD_FAB2_LIB.BASEBOARD_FAB2(SCH_1):PAGE50
   208 M_D_ALERT_N @BASEBOARD_FAB2_LIB.BASEBOARD_FAB2(SCH_1):M_D_ALERT_N   I158 @BASEBOARD_FAB2_LIB.BASEBOARD_FAB2(SCH_1):PAGE50
   224 M_D_BA<1> @BASEBOARD_FAB2_LIB.BASEBOARD_FAB2(SCH_1):M_D_BA(1)   I158 @BASEBOARD_FAB2_LIB.BASEBOARD_FAB2(SCH_1):PAGE50
    81 M_D_BA<0> @BASEBOARD_FAB2_LIB.BASEBOARD_FAB2(SCH_1):M_D_BA(0)   I158 @BASEBOARD_FAB2_LIB.BASEBOARD_FAB2(SCH_1):PAGE50
   207 M_D_BG<1> @BASEBOARD_FAB2_LIB.BASEBOARD_FAB2(SCH_1):M_D_BG(1)   I158 @BASEBOARD_FAB2_LIB.BASEBOARD_FAB2(SCH_1):PAGE50
    63 M_D_BG<0> @BASEBOARD_FAB2_LIB.BASEBOARD_FAB2(SCH_1):M_D_BG(0)   I158 @BASEBOARD_FAB2_LIB.BASEBOARD_FAB2(SCH_1):PAGE50
   235 M_D_C<2> @BASEBOARD_FAB2_LIB.BASEBOARD_FAB2(SCH_1):M_D_C(2)   I158 @BASEBOARD_FAB2_LIB.BASEBOARD_FAB2(SCH_1):PAGE50
   199 M_D_ECC<7> @BASEBOARD_FAB2_LIB.BASEBOARD_FAB2(SCH_1):M_D_ECC(7)   I158 @BASEBOARD_FAB2_LIB.BASEBOARD_FAB2(SCH_1):PAGE50
    54 M_D_ECC<6> @BASEBOARD_FAB2_LIB.BASEBOARD_FAB2(SCH_1):M_D_ECC(6)   I158 @BASEBOARD_FAB2_LIB.BASEBOARD_FAB2(SCH_1):PAGE50
   192 M_D_ECC<5> @BASEBOARD_FAB2_LIB.BASEBOARD_FAB2(SCH_1):M_D_ECC(5)   I158 @BASEBOARD_FAB2_LIB.BASEBOARD_FAB2(SCH_1):PAGE50
    47 M_D_ECC<4> @BASEBOARD_FAB2_LIB.BASEBOARD_FAB2(SCH_1):M_D_ECC(4)   I158 @BASEBOARD_FAB2_LIB.BASEBOARD_FAB2(SCH_1):PAGE50
   201 M_D_ECC<3> @BASEBOARD_FAB2_LIB.BASEBOARD_FAB2(SCH_1):M_D_ECC(3)   I158 @BASEBOARD_FAB2_LIB.BASEBOARD_FAB2(SCH_1):PAGE50
    56 M_D_ECC<2> @BASEBOARD_FAB2_LIB.BASEBOARD_FAB2(SCH_1):M_D_ECC(2)   I158 @BASEBOARD_FAB2_LIB.BASEBOARD_FAB2(SCH_1):PAGE50
   194 M_D_ECC<1> @BASEBOARD_FAB2_LIB.BASEBOARD_FAB2(SCH_1):M_D_ECC(1)   I158 @BASEBOARD_FAB2_LIB.BASEBOARD_FAB2(SCH_1):PAGE50
    49 M_D_ECC<0> @BASEBOARD_FAB2_LIB.BASEBOARD_FAB2(SCH_1):M_D_ECC(0)   I158 @BASEBOARD_FAB2_LIB.BASEBOARD_FAB2(SCH_1):PAGE50
    75 M_D_CLK_DN<2> @BASEBOARD_FAB2_LIB.BASEBOARD_FAB2(SCH_1):M_D_CLK_DN(2)   I158 @BASEBOARD_FAB2_LIB.BASEBOARD_FAB2(SCH_1):PAGE50
    74 M_D_CLK_DP<2> @BASEBOARD_FAB2_LIB.BASEBOARD_FAB2(SCH_1):M_D_CLK_DP(2)   I158 @BASEBOARD_FAB2_LIB.BASEBOARD_FAB2(SCH_1):PAGE50
   219 M_D_CLK_DN<3> @BASEBOARD_FAB2_LIB.BASEBOARD_FAB2(SCH_1):M_D_CLK_DN(3)   I158 @BASEBOARD_FAB2_LIB.BASEBOARD_FAB2(SCH_1):PAGE50
   218 M_D_CLK_DP<3> @BASEBOARD_FAB2_LIB.BASEBOARD_FAB2(SCH_1):M_D_CLK_DP(3)   I158 @BASEBOARD_FAB2_LIB.BASEBOARD_FAB2(SCH_1):PAGE50
   203 M_D_CKE<3> @BASEBOARD_FAB2_LIB.BASEBOARD_FAB2(SCH_1):M_D_CKE(3)   I158 @BASEBOARD_FAB2_LIB.BASEBOARD_FAB2(SCH_1):PAGE50
    60 M_D_CKE<2> @BASEBOARD_FAB2_LIB.BASEBOARD_FAB2(SCH_1):M_D_CKE(2)   I158 @BASEBOARD_FAB2_LIB.BASEBOARD_FAB2(SCH_1):PAGE50
   280 M_D_DQ<63> @BASEBOARD_FAB2_LIB.BASEBOARD_FAB2(SCH_1):M_D_DQ(63)   I158 @BASEBOARD_FAB2_LIB.BASEBOARD_FAB2(SCH_1):PAGE50
   135 M_D_DQ<62> @BASEBOARD_FAB2_LIB.BASEBOARD_FAB2(SCH_1):M_D_DQ(62)   I158 @BASEBOARD_FAB2_LIB.BASEBOARD_FAB2(SCH_1):PAGE50
   273 M_D_DQ<61> @BASEBOARD_FAB2_LIB.BASEBOARD_FAB2(SCH_1):M_D_DQ(61)   I158 @BASEBOARD_FAB2_LIB.BASEBOARD_FAB2(SCH_1):PAGE50
   128 M_D_DQ<60> @BASEBOARD_FAB2_LIB.BASEBOARD_FAB2(SCH_1):M_D_DQ(60)   I158 @BASEBOARD_FAB2_LIB.BASEBOARD_FAB2(SCH_1):PAGE50
   282 M_D_DQ<59> @BASEBOARD_FAB2_LIB.BASEBOARD_FAB2(SCH_1):M_D_DQ(59)   I158 @BASEBOARD_FAB2_LIB.BASEBOARD_FAB2(SCH_1):PAGE50
   137 M_D_DQ<58> @BASEBOARD_FAB2_LIB.BASEBOARD_FAB2(SCH_1):M_D_DQ(58)   I158 @BASEBOARD_FAB2_LIB.BASEBOARD_FAB2(SCH_1):PAGE50
   275 M_D_DQ<57> @BASEBOARD_FAB2_LIB.BASEBOARD_FAB2(SCH_1):M_D_DQ(57)   I158 @BASEBOARD_FAB2_LIB.BASEBOARD_FAB2(SCH_1):PAGE50
   130 M_D_DQ<56> @BASEBOARD_FAB2_LIB.BASEBOARD_FAB2(SCH_1):M_D_DQ(56)   I158 @BASEBOARD_FAB2_LIB.BASEBOARD_FAB2(SCH_1):PAGE50
   269 M_D_DQ<55> @BASEBOARD_FAB2_LIB.BASEBOARD_FAB2(SCH_1):M_D_DQ(55)   I158 @BASEBOARD_FAB2_LIB.BASEBOARD_FAB2(SCH_1):PAGE50
   124 M_D_DQ<54> @BASEBOARD_FAB2_LIB.BASEBOARD_FAB2(SCH_1):M_D_DQ(54)   I158 @BASEBOARD_FAB2_LIB.BASEBOARD_FAB2(SCH_1):PAGE50
   262 M_D_DQ<53> @BASEBOARD_FAB2_LIB.BASEBOARD_FAB2(SCH_1):M_D_DQ(53)   I158 @BASEBOARD_FAB2_LIB.BASEBOARD_FAB2(SCH_1):PAGE50
   117 M_D_DQ<52> @BASEBOARD_FAB2_LIB.BASEBOARD_FAB2(SCH_1):M_D_DQ(52)   I158 @BASEBOARD_FAB2_LIB.BASEBOARD_FAB2(SCH_1):PAGE50
   271 M_D_DQ<51> @BASEBOARD_FAB2_LIB.BASEBOARD_FAB2(SCH_1):M_D_DQ(51)   I158 @BASEBOARD_FAB2_LIB.BASEBOARD_FAB2(SCH_1):PAGE50
   126 M_D_DQ<50> @BASEBOARD_FAB2_LIB.BASEBOARD_FAB2(SCH_1):M_D_DQ(50)   I158 @BASEBOARD_FAB2_LIB.BASEBOARD_FAB2(SCH_1):PAGE50
   264 M_D_DQ<49> @BASEBOARD_FAB2_LIB.BASEBOARD_FAB2(SCH_1):M_D_DQ(49)   I158 @BASEBOARD_FAB2_LIB.BASEBOARD_FAB2(SCH_1):PAGE50
   119 M_D_DQ<48> @BASEBOARD_FAB2_LIB.BASEBOARD_FAB2(SCH_1):M_D_DQ(48)   I158 @BASEBOARD_FAB2_LIB.BASEBOARD_FAB2(SCH_1):PAGE50
   258 M_D_DQ<47> @BASEBOARD_FAB2_LIB.BASEBOARD_FAB2(SCH_1):M_D_DQ(47)   I158 @BASEBOARD_FAB2_LIB.BASEBOARD_FAB2(SCH_1):PAGE50
   113 M_D_DQ<46> @BASEBOARD_FAB2_LIB.BASEBOARD_FAB2(SCH_1):M_D_DQ(46)   I158 @BASEBOARD_FAB2_LIB.BASEBOARD_FAB2(SCH_1):PAGE50
   251 M_D_DQ<45> @BASEBOARD_FAB2_LIB.BASEBOARD_FAB2(SCH_1):M_D_DQ(45)   I158 @BASEBOARD_FAB2_LIB.BASEBOARD_FAB2(SCH_1):PAGE50
   106 M_D_DQ<44> @BASEBOARD_FAB2_LIB.BASEBOARD_FAB2(SCH_1):M_D_DQ(44)   I158 @BASEBOARD_FAB2_LIB.BASEBOARD_FAB2(SCH_1):PAGE50
   260 M_D_DQ<43> @BASEBOARD_FAB2_LIB.BASEBOARD_FAB2(SCH_1):M_D_DQ(43)   I158 @BASEBOARD_FAB2_LIB.BASEBOARD_FAB2(SCH_1):PAGE50
   115 M_D_DQ<42> @BASEBOARD_FAB2_LIB.BASEBOARD_FAB2(SCH_1):M_D_DQ(42)   I158 @BASEBOARD_FAB2_LIB.BASEBOARD_FAB2(SCH_1):PAGE50
   253 M_D_DQ<41> @BASEBOARD_FAB2_LIB.BASEBOARD_FAB2(SCH_1):M_D_DQ(41)   I158 @BASEBOARD_FAB2_LIB.BASEBOARD_FAB2(SCH_1):PAGE50
   108 M_D_DQ<40> @BASEBOARD_FAB2_LIB.BASEBOARD_FAB2(SCH_1):M_D_DQ(40)   I158 @BASEBOARD_FAB2_LIB.BASEBOARD_FAB2(SCH_1):PAGE50
   247 M_D_DQ<39> @BASEBOARD_FAB2_LIB.BASEBOARD_FAB2(SCH_1):M_D_DQ(39)   I158 @BASEBOARD_FAB2_LIB.BASEBOARD_FAB2(SCH_1):PAGE50
   102 M_D_DQ<38> @BASEBOARD_FAB2_LIB.BASEBOARD_FAB2(SCH_1):M_D_DQ(38)   I158 @BASEBOARD_FAB2_LIB.BASEBOARD_FAB2(SCH_1):PAGE50
   240 M_D_DQ<37> @BASEBOARD_FAB2_LIB.BASEBOARD_FAB2(SCH_1):M_D_DQ(37)   I158 @BASEBOARD_FAB2_LIB.BASEBOARD_FAB2(SCH_1):PAGE50
    95 M_D_DQ<36> @BASEBOARD_FAB2_LIB.BASEBOARD_FAB2(SCH_1):M_D_DQ(36)   I158 @BASEBOARD_FAB2_LIB.BASEBOARD_FAB2(SCH_1):PAGE50
   249 M_D_DQ<35> @BASEBOARD_FAB2_LIB.BASEBOARD_FAB2(SCH_1):M_D_DQ(35)   I158 @BASEBOARD_FAB2_LIB.BASEBOARD_FAB2(SCH_1):PAGE50
   104 M_D_DQ<34> @BASEBOARD_FAB2_LIB.BASEBOARD_FAB2(SCH_1):M_D_DQ(34)   I158 @BASEBOARD_FAB2_LIB.BASEBOARD_FAB2(SCH_1):PAGE50
   242 M_D_DQ<33> @BASEBOARD_FAB2_LIB.BASEBOARD_FAB2(SCH_1):M_D_DQ(33)   I158 @BASEBOARD_FAB2_LIB.BASEBOARD_FAB2(SCH_1):PAGE50
    97 M_D_DQ<32> @BASEBOARD_FAB2_LIB.BASEBOARD_FAB2(SCH_1):M_D_DQ(32)   I158 @BASEBOARD_FAB2_LIB.BASEBOARD_FAB2(SCH_1):PAGE50
   188 M_D_DQ<31> @BASEBOARD_FAB2_LIB.BASEBOARD_FAB2(SCH_1):M_D_DQ(31)   I158 @BASEBOARD_FAB2_LIB.BASEBOARD_FAB2(SCH_1):PAGE50
    43 M_D_DQ<30> @BASEBOARD_FAB2_LIB.BASEBOARD_FAB2(SCH_1):M_D_DQ(30)   I158 @BASEBOARD_FAB2_LIB.BASEBOARD_FAB2(SCH_1):PAGE50
   181 M_D_DQ<29> @BASEBOARD_FAB2_LIB.BASEBOARD_FAB2(SCH_1):M_D_DQ(29)   I158 @BASEBOARD_FAB2_LIB.BASEBOARD_FAB2(SCH_1):PAGE50
    36 M_D_DQ<28> @BASEBOARD_FAB2_LIB.BASEBOARD_FAB2(SCH_1):M_D_DQ(28)   I158 @BASEBOARD_FAB2_LIB.BASEBOARD_FAB2(SCH_1):PAGE50
   190 M_D_DQ<27> @BASEBOARD_FAB2_LIB.BASEBOARD_FAB2(SCH_1):M_D_DQ(27)   I158 @BASEBOARD_FAB2_LIB.BASEBOARD_FAB2(SCH_1):PAGE50
    45 M_D_DQ<26> @BASEBOARD_FAB2_LIB.BASEBOARD_FAB2(SCH_1):M_D_DQ(26)   I158 @BASEBOARD_FAB2_LIB.BASEBOARD_FAB2(SCH_1):PAGE50
   183 M_D_DQ<25> @BASEBOARD_FAB2_LIB.BASEBOARD_FAB2(SCH_1):M_D_DQ(25)   I158 @BASEBOARD_FAB2_LIB.BASEBOARD_FAB2(SCH_1):PAGE50
    38 M_D_DQ<24> @BASEBOARD_FAB2_LIB.BASEBOARD_FAB2(SCH_1):M_D_DQ(24)   I158 @BASEBOARD_FAB2_LIB.BASEBOARD_FAB2(SCH_1):PAGE50
   177 M_D_DQ<23> @BASEBOARD_FAB2_LIB.BASEBOARD_FAB2(SCH_1):M_D_DQ(23)   I158 @BASEBOARD_FAB2_LIB.BASEBOARD_FAB2(SCH_1):PAGE50
    32 M_D_DQ<22> @BASEBOARD_FAB2_LIB.BASEBOARD_FAB2(SCH_1):M_D_DQ(22)   I158 @BASEBOARD_FAB2_LIB.BASEBOARD_FAB2(SCH_1):PAGE50
   170 M_D_DQ<21> @BASEBOARD_FAB2_LIB.BASEBOARD_FAB2(SCH_1):M_D_DQ(21)   I158 @BASEBOARD_FAB2_LIB.BASEBOARD_FAB2(SCH_1):PAGE50
    25 M_D_DQ<20> @BASEBOARD_FAB2_LIB.BASEBOARD_FAB2(SCH_1):M_D_DQ(20)   I158 @BASEBOARD_FAB2_LIB.BASEBOARD_FAB2(SCH_1):PAGE50
   179 M_D_DQ<19> @BASEBOARD_FAB2_LIB.BASEBOARD_FAB2(SCH_1):M_D_DQ(19)   I158 @BASEBOARD_FAB2_LIB.BASEBOARD_FAB2(SCH_1):PAGE50
    34 M_D_DQ<18> @BASEBOARD_FAB2_LIB.BASEBOARD_FAB2(SCH_1):M_D_DQ(18)   I158 @BASEBOARD_FAB2_LIB.BASEBOARD_FAB2(SCH_1):PAGE50
   172 M_D_DQ<17> @BASEBOARD_FAB2_LIB.BASEBOARD_FAB2(SCH_1):M_D_DQ(17)   I158 @BASEBOARD_FAB2_LIB.BASEBOARD_FAB2(SCH_1):PAGE50
    27 M_D_DQ<16> @BASEBOARD_FAB2_LIB.BASEBOARD_FAB2(SCH_1):M_D_DQ(16)   I158 @BASEBOARD_FAB2_LIB.BASEBOARD_FAB2(SCH_1):PAGE50
   166 M_D_DQ<15> @BASEBOARD_FAB2_LIB.BASEBOARD_FAB2(SCH_1):M_D_DQ(15)   I158 @BASEBOARD_FAB2_LIB.BASEBOARD_FAB2(SCH_1):PAGE50
    21 M_D_DQ<14> @BASEBOARD_FAB2_LIB.BASEBOARD_FAB2(SCH_1):M_D_DQ(14)   I158 @BASEBOARD_FAB2_LIB.BASEBOARD_FAB2(SCH_1):PAGE50
   159 M_D_DQ<13> @BASEBOARD_FAB2_LIB.BASEBOARD_FAB2(SCH_1):M_D_DQ(13)   I158 @BASEBOARD_FAB2_LIB.BASEBOARD_FAB2(SCH_1):PAGE50
    14 M_D_DQ<12> @BASEBOARD_FAB2_LIB.BASEBOARD_FAB2(SCH_1):M_D_DQ(12)   I158 @BASEBOARD_FAB2_LIB.BASEBOARD_FAB2(SCH_1):PAGE50
   168 M_D_DQ<11> @BASEBOARD_FAB2_LIB.BASEBOARD_FAB2(SCH_1):M_D_DQ(11)   I158 @BASEBOARD_FAB2_LIB.BASEBOARD_FAB2(SCH_1):PAGE50
    23 M_D_DQ<10> @BASEBOARD_FAB2_LIB.BASEBOARD_FAB2(SCH_1):M_D_DQ(10)   I158 @BASEBOARD_FAB2_LIB.BASEBOARD_FAB2(SCH_1):PAGE50
   161 M_D_DQ<9> @BASEBOARD_FAB2_LIB.BASEBOARD_FAB2(SCH_1):M_D_DQ(9)   I158 @BASEBOARD_FAB2_LIB.BASEBOARD_FAB2(SCH_1):PAGE50
    16 M_D_DQ<8> @BASEBOARD_FAB2_LIB.BASEBOARD_FAB2(SCH_1):M_D_DQ(8)   I158 @BASEBOARD_FAB2_LIB.BASEBOARD_FAB2(SCH_1):PAGE50
   155 M_D_DQ<7> @BASEBOARD_FAB2_LIB.BASEBOARD_FAB2(SCH_1):M_D_DQ(7)   I158 @BASEBOARD_FAB2_LIB.BASEBOARD_FAB2(SCH_1):PAGE50
    10 M_D_DQ<6> @BASEBOARD_FAB2_LIB.BASEBOARD_FAB2(SCH_1):M_D_DQ(6)   I158 @BASEBOARD_FAB2_LIB.BASEBOARD_FAB2(SCH_1):PAGE50
   148 M_D_DQ<5> @BASEBOARD_FAB2_LIB.BASEBOARD_FAB2(SCH_1):M_D_DQ(5)   I158 @BASEBOARD_FAB2_LIB.BASEBOARD_FAB2(SCH_1):PAGE50
     3 M_D_DQ<4> @BASEBOARD_FAB2_LIB.BASEBOARD_FAB2(SCH_1):M_D_DQ(4)   I158 @BASEBOARD_FAB2_LIB.BASEBOARD_FAB2(SCH_1):PAGE50
   157 M_D_DQ<3> @BASEBOARD_FAB2_LIB.BASEBOARD_FAB2(SCH_1):M_D_DQ(3)   I158 @BASEBOARD_FAB2_LIB.BASEBOARD_FAB2(SCH_1):PAGE50
    12 M_D_DQ<2> @BASEBOARD_FAB2_LIB.BASEBOARD_FAB2(SCH_1):M_D_DQ(2)   I158 @BASEBOARD_FAB2_LIB.BASEBOARD_FAB2(SCH_1):PAGE50
   150 M_D_DQ<1> @BASEBOARD_FAB2_LIB.BASEBOARD_FAB2(SCH_1):M_D_DQ(1)   I158 @BASEBOARD_FAB2_LIB.BASEBOARD_FAB2(SCH_1):PAGE50
     5 M_D_DQ<0> @BASEBOARD_FAB2_LIB.BASEBOARD_FAB2(SCH_1):M_D_DQ(0)   I158 @BASEBOARD_FAB2_LIB.BASEBOARD_FAB2(SCH_1):PAGE50
    78 FM_DIMM_EVENT_COD_N @BASEBOARD_FAB2_LIB.BASEBOARD_FAB2(SCH_1):FM_DIMM_EVENT_COD_N   I158 @BASEBOARD_FAB2_LIB.BASEBOARD_FAB2(SCH_1):PAGE50
    91 M_D_ODT<3> @BASEBOARD_FAB2_LIB.BASEBOARD_FAB2(SCH_1):M_D_ODT(3)   I158 @BASEBOARD_FAB2_LIB.BASEBOARD_FAB2(SCH_1):PAGE50
    87 M_D_ODT<2> @BASEBOARD_FAB2_LIB.BASEBOARD_FAB2(SCH_1):M_D_ODT(2)   I158 @BASEBOARD_FAB2_LIB.BASEBOARD_FAB2(SCH_1):PAGE50
   222 M_D_PAR @BASEBOARD_FAB2_LIB.BASEBOARD_FAB2(SCH_1):M_D_PAR   I158 @BASEBOARD_FAB2_LIB.BASEBOARD_FAB2(SCH_1):PAGE50
    58 M_DEF_RST_N @BASEBOARD_FAB2_LIB.BASEBOARD_FAB2(SCH_1):M_DEF_RST_N   I158 @BASEBOARD_FAB2_LIB.BASEBOARD_FAB2(SCH_1):PAGE50
   144 TP_CH_D_DIMM_D1_RFU_2 @BASEBOARD_FAB2_LIB.BASEBOARD_FAB2(SCH_1):TP_CH_D_DIMM_D1_RFU_2   I158 @BASEBOARD_FAB2_LIB.BASEBOARD_FAB2(SCH_1):PAGE50
   227 TP_CH_D_DIMM_D1_RFU_1 @BASEBOARD_FAB2_LIB.BASEBOARD_FAB2(SCH_1):TP_CH_D_DIMM_D1_RFU_1   I158 @BASEBOARD_FAB2_LIB.BASEBOARD_FAB2(SCH_1):PAGE50
   205 TP_CH_D_DIMM_D1_RFU_0 @BASEBOARD_FAB2_LIB.BASEBOARD_FAB2(SCH_1):TP_CH_D_DIMM_D1_RFU_0   I158 @BASEBOARD_FAB2_LIB.BASEBOARD_FAB2(SCH_1):PAGE50
    84 M_D_CS_N<4> @BASEBOARD_FAB2_LIB.BASEBOARD_FAB2(SCH_1):M_D_CS_N(4)   I158 @BASEBOARD_FAB2_LIB.BASEBOARD_FAB2(SCH_1):PAGE50
    89 M_D_CS_N<5> @BASEBOARD_FAB2_LIB.BASEBOARD_FAB2(SCH_1):M_D_CS_N(5)   I158 @BASEBOARD_FAB2_LIB.BASEBOARD_FAB2(SCH_1):PAGE50
    93 M_D_CS_N<6> @BASEBOARD_FAB2_LIB.BASEBOARD_FAB2(SCH_1):M_D_CS_N(6)   I158 @BASEBOARD_FAB2_LIB.BASEBOARD_FAB2(SCH_1):PAGE50
   237 M_D_CS_N<7> @BASEBOARD_FAB2_LIB.BASEBOARD_FAB2(SCH_1):M_D_CS_N(7)   I158 @BASEBOARD_FAB2_LIB.BASEBOARD_FAB2(SCH_1):PAGE50
   238    GND @BASEBOARD_FAB2_LIB.BASEBOARD_FAB2(SCH_1):GND   I158 @BASEBOARD_FAB2_LIB.BASEBOARD_FAB2(SCH_1):PAGE50
   140    GND @BASEBOARD_FAB2_LIB.BASEBOARD_FAB2(SCH_1):GND   I158 @BASEBOARD_FAB2_LIB.BASEBOARD_FAB2(SCH_1):PAGE50
   139 PVPP_DEF @BASEBOARD_FAB2_LIB.BASEBOARD_FAB2(SCH_1):PVPP_DEF   I158 @BASEBOARD_FAB2_LIB.BASEBOARD_FAB2(SCH_1):PAGE50
   230 FM_ADR_COMPLETE_DEF_N @BASEBOARD_FAB2_LIB.BASEBOARD_FAB2(SCH_1):FM_ADR_COMPLETE_DEF_N   I158 @BASEBOARD_FAB2_LIB.BASEBOARD_FAB2(SCH_1):PAGE50
   141 SMB_DDR_DEF_VPP_SCL @BASEBOARD_FAB2_LIB.BASEBOARD_FAB2(SCH_1):SMB_DDR_DEF_VPP_SCL   I158 @BASEBOARD_FAB2_LIB.BASEBOARD_FAB2(SCH_1):PAGE50
   285 SMB_DDR_DEF_VPP_SDA @BASEBOARD_FAB2_LIB.BASEBOARD_FAB2(SCH_1):SMB_DDR_DEF_VPP_SDA   I158 @BASEBOARD_FAB2_LIB.BASEBOARD_FAB2(SCH_1):PAGE50
   284 PVPP_DEF @BASEBOARD_FAB2_LIB.BASEBOARD_FAB2(SCH_1):PVPP_DEF   I158 @BASEBOARD_FAB2_LIB.BASEBOARD_FAB2(SCH_1):PAGE50
   146 M_D_VREF @BASEBOARD_FAB2_LIB.BASEBOARD_FAB2(SCH_1):M_D_VREF   I158 @BASEBOARD_FAB2_LIB.BASEBOARD_FAB2(SCH_1):PAGE50
   152 M_D_DQS_DN<0> @BASEBOARD_FAB2_LIB.BASEBOARD_FAB2(SCH_1):M_D_DQS_DN(0)    I46 @BASEBOARD_FAB2_LIB.BASEBOARD_FAB2(SCH_1):PAGE50
   153 M_D_DQS_DP<0> @BASEBOARD_FAB2_LIB.BASEBOARD_FAB2(SCH_1):M_D_DQS_DP(0)    I46 @BASEBOARD_FAB2_LIB.BASEBOARD_FAB2(SCH_1):PAGE50
    19 M_D_DQS_DN<10> @BASEBOARD_FAB2_LIB.BASEBOARD_FAB2(SCH_1):M_D_DQS_DN(10)    I46 @BASEBOARD_FAB2_LIB.BASEBOARD_FAB2(SCH_1):PAGE50
    18 M_D_DQS_DP<10> @BASEBOARD_FAB2_LIB.BASEBOARD_FAB2(SCH_1):M_D_DQS_DP(10)    I46 @BASEBOARD_FAB2_LIB.BASEBOARD_FAB2(SCH_1):PAGE50
    30 M_D_DQS_DN<11> @BASEBOARD_FAB2_LIB.BASEBOARD_FAB2(SCH_1):M_D_DQS_DN(11)    I46 @BASEBOARD_FAB2_LIB.BASEBOARD_FAB2(SCH_1):PAGE50
    29 M_D_DQS_DP<11> @BASEBOARD_FAB2_LIB.BASEBOARD_FAB2(SCH_1):M_D_DQS_DP(11)    I46 @BASEBOARD_FAB2_LIB.BASEBOARD_FAB2(SCH_1):PAGE50
    41 M_D_DQS_DN<12> @BASEBOARD_FAB2_LIB.BASEBOARD_FAB2(SCH_1):M_D_DQS_DN(12)    I46 @BASEBOARD_FAB2_LIB.BASEBOARD_FAB2(SCH_1):PAGE50
    40 M_D_DQS_DP<12> @BASEBOARD_FAB2_LIB.BASEBOARD_FAB2(SCH_1):M_D_DQS_DP(12)    I46 @BASEBOARD_FAB2_LIB.BASEBOARD_FAB2(SCH_1):PAGE50
   100 M_D_DQS_DN<13> @BASEBOARD_FAB2_LIB.BASEBOARD_FAB2(SCH_1):M_D_DQS_DN(13)    I46 @BASEBOARD_FAB2_LIB.BASEBOARD_FAB2(SCH_1):PAGE50
    99 M_D_DQS_DP<13> @BASEBOARD_FAB2_LIB.BASEBOARD_FAB2(SCH_1):M_D_DQS_DP(13)    I46 @BASEBOARD_FAB2_LIB.BASEBOARD_FAB2(SCH_1):PAGE50
   111 M_D_DQS_DN<14> @BASEBOARD_FAB2_LIB.BASEBOARD_FAB2(SCH_1):M_D_DQS_DN(14)    I46 @BASEBOARD_FAB2_LIB.BASEBOARD_FAB2(SCH_1):PAGE50
   110 M_D_DQS_DP<14> @BASEBOARD_FAB2_LIB.BASEBOARD_FAB2(SCH_1):M_D_DQS_DP(14)    I46 @BASEBOARD_FAB2_LIB.BASEBOARD_FAB2(SCH_1):PAGE50
   122 M_D_DQS_DN<15> @BASEBOARD_FAB2_LIB.BASEBOARD_FAB2(SCH_1):M_D_DQS_DN(15)    I46 @BASEBOARD_FAB2_LIB.BASEBOARD_FAB2(SCH_1):PAGE50
   121 M_D_DQS_DP<15> @BASEBOARD_FAB2_LIB.BASEBOARD_FAB2(SCH_1):M_D_DQS_DP(15)    I46 @BASEBOARD_FAB2_LIB.BASEBOARD_FAB2(SCH_1):PAGE50
   133 M_D_DQS_DN<16> @BASEBOARD_FAB2_LIB.BASEBOARD_FAB2(SCH_1):M_D_DQS_DN(16)    I46 @BASEBOARD_FAB2_LIB.BASEBOARD_FAB2(SCH_1):PAGE50
   132 M_D_DQS_DP<16> @BASEBOARD_FAB2_LIB.BASEBOARD_FAB2(SCH_1):M_D_DQS_DP(16)    I46 @BASEBOARD_FAB2_LIB.BASEBOARD_FAB2(SCH_1):PAGE50
    52 M_D_DQS_DN<17> @BASEBOARD_FAB2_LIB.BASEBOARD_FAB2(SCH_1):M_D_DQS_DN(17)    I46 @BASEBOARD_FAB2_LIB.BASEBOARD_FAB2(SCH_1):PAGE50
    51 M_D_DQS_DP<17> @BASEBOARD_FAB2_LIB.BASEBOARD_FAB2(SCH_1):M_D_DQS_DP(17)    I46 @BASEBOARD_FAB2_LIB.BASEBOARD_FAB2(SCH_1):PAGE50
   163 M_D_DQS_DN<1> @BASEBOARD_FAB2_LIB.BASEBOARD_FAB2(SCH_1):M_D_DQS_DN(1)    I46 @BASEBOARD_FAB2_LIB.BASEBOARD_FAB2(SCH_1):PAGE50
   164 M_D_DQS_DP<1> @BASEBOARD_FAB2_LIB.BASEBOARD_FAB2(SCH_1):M_D_DQS_DP(1)    I46 @BASEBOARD_FAB2_LIB.BASEBOARD_FAB2(SCH_1):PAGE50
   174 M_D_DQS_DN<2> @BASEBOARD_FAB2_LIB.BASEBOARD_FAB2(SCH_1):M_D_DQS_DN(2)    I46 @BASEBOARD_FAB2_LIB.BASEBOARD_FAB2(SCH_1):PAGE50
   175 M_D_DQS_DP<2> @BASEBOARD_FAB2_LIB.BASEBOARD_FAB2(SCH_1):M_D_DQS_DP(2)    I46 @BASEBOARD_FAB2_LIB.BASEBOARD_FAB2(SCH_1):PAGE50
   185 M_D_DQS_DN<3> @BASEBOARD_FAB2_LIB.BASEBOARD_FAB2(SCH_1):M_D_DQS_DN(3)    I46 @BASEBOARD_FAB2_LIB.BASEBOARD_FAB2(SCH_1):PAGE50
   186 M_D_DQS_DP<3> @BASEBOARD_FAB2_LIB.BASEBOARD_FAB2(SCH_1):M_D_DQS_DP(3)    I46 @BASEBOARD_FAB2_LIB.BASEBOARD_FAB2(SCH_1):PAGE50
   244 M_D_DQS_DN<4> @BASEBOARD_FAB2_LIB.BASEBOARD_FAB2(SCH_1):M_D_DQS_DN(4)    I46 @BASEBOARD_FAB2_LIB.BASEBOARD_FAB2(SCH_1):PAGE50
   245 M_D_DQS_DP<4> @BASEBOARD_FAB2_LIB.BASEBOARD_FAB2(SCH_1):M_D_DQS_DP(4)    I46 @BASEBOARD_FAB2_LIB.BASEBOARD_FAB2(SCH_1):PAGE50
   255 M_D_DQS_DN<5> @BASEBOARD_FAB2_LIB.BASEBOARD_FAB2(SCH_1):M_D_DQS_DN(5)    I46 @BASEBOARD_FAB2_LIB.BASEBOARD_FAB2(SCH_1):PAGE50
   256 M_D_DQS_DP<5> @BASEBOARD_FAB2_LIB.BASEBOARD_FAB2(SCH_1):M_D_DQS_DP(5)    I46 @BASEBOARD_FAB2_LIB.BASEBOARD_FAB2(SCH_1):PAGE50
   266 M_D_DQS_DN<6> @BASEBOARD_FAB2_LIB.BASEBOARD_FAB2(SCH_1):M_D_DQS_DN(6)    I46 @BASEBOARD_FAB2_LIB.BASEBOARD_FAB2(SCH_1):PAGE50
   267 M_D_DQS_DP<6> @BASEBOARD_FAB2_LIB.BASEBOARD_FAB2(SCH_1):M_D_DQS_DP(6)    I46 @BASEBOARD_FAB2_LIB.BASEBOARD_FAB2(SCH_1):PAGE50
   277 M_D_DQS_DN<7> @BASEBOARD_FAB2_LIB.BASEBOARD_FAB2(SCH_1):M_D_DQS_DN(7)    I46 @BASEBOARD_FAB2_LIB.BASEBOARD_FAB2(SCH_1):PAGE50
   278 M_D_DQS_DP<7> @BASEBOARD_FAB2_LIB.BASEBOARD_FAB2(SCH_1):M_D_DQS_DP(7)    I46 @BASEBOARD_FAB2_LIB.BASEBOARD_FAB2(SCH_1):PAGE50
   196 M_D_DQS_DN<8> @BASEBOARD_FAB2_LIB.BASEBOARD_FAB2(SCH_1):M_D_DQS_DN(8)    I46 @BASEBOARD_FAB2_LIB.BASEBOARD_FAB2(SCH_1):PAGE50
   197 M_D_DQS_DP<8> @BASEBOARD_FAB2_LIB.BASEBOARD_FAB2(SCH_1):M_D_DQS_DP(8)    I46 @BASEBOARD_FAB2_LIB.BASEBOARD_FAB2(SCH_1):PAGE50
     8 M_D_DQS_DN<9> @BASEBOARD_FAB2_LIB.BASEBOARD_FAB2(SCH_1):M_D_DQS_DN(9)    I46 @BASEBOARD_FAB2_LIB.BASEBOARD_FAB2(SCH_1):PAGE50
     7 M_D_DQS_DP<9> @BASEBOARD_FAB2_LIB.BASEBOARD_FAB2(SCH_1):M_D_DQS_DP(9)    I46 @BASEBOARD_FAB2_LIB.BASEBOARD_FAB2(SCH_1):PAGE50
     2    GND @BASEBOARD_FAB2_LIB.BASEBOARD_FAB2(SCH_1):GND    I44 @BASEBOARD_FAB2_LIB.BASEBOARD_FAB2(SCH_1):PAGE50
     4    GND @BASEBOARD_FAB2_LIB.BASEBOARD_FAB2(SCH_1):GND    I44 @BASEBOARD_FAB2_LIB.BASEBOARD_FAB2(SCH_1):PAGE50
     6    GND @BASEBOARD_FAB2_LIB.BASEBOARD_FAB2(SCH_1):GND    I44 @BASEBOARD_FAB2_LIB.BASEBOARD_FAB2(SCH_1):PAGE50
     9    GND @BASEBOARD_FAB2_LIB.BASEBOARD_FAB2(SCH_1):GND    I44 @BASEBOARD_FAB2_LIB.BASEBOARD_FAB2(SCH_1):PAGE50
    11    GND @BASEBOARD_FAB2_LIB.BASEBOARD_FAB2(SCH_1):GND    I44 @BASEBOARD_FAB2_LIB.BASEBOARD_FAB2(SCH_1):PAGE50
    13    GND @BASEBOARD_FAB2_LIB.BASEBOARD_FAB2(SCH_1):GND    I44 @BASEBOARD_FAB2_LIB.BASEBOARD_FAB2(SCH_1):PAGE50
    15    GND @BASEBOARD_FAB2_LIB.BASEBOARD_FAB2(SCH_1):GND    I44 @BASEBOARD_FAB2_LIB.BASEBOARD_FAB2(SCH_1):PAGE50
    17    GND @BASEBOARD_FAB2_LIB.BASEBOARD_FAB2(SCH_1):GND    I44 @BASEBOARD_FAB2_LIB.BASEBOARD_FAB2(SCH_1):PAGE50
    20    GND @BASEBOARD_FAB2_LIB.BASEBOARD_FAB2(SCH_1):GND    I44 @BASEBOARD_FAB2_LIB.BASEBOARD_FAB2(SCH_1):PAGE50
    22    GND @BASEBOARD_FAB2_LIB.BASEBOARD_FAB2(SCH_1):GND    I44 @BASEBOARD_FAB2_LIB.BASEBOARD_FAB2(SCH_1):PAGE50
    24    GND @BASEBOARD_FAB2_LIB.BASEBOARD_FAB2(SCH_1):GND    I44 @BASEBOARD_FAB2_LIB.BASEBOARD_FAB2(SCH_1):PAGE50
    26    GND @BASEBOARD_FAB2_LIB.BASEBOARD_FAB2(SCH_1):GND    I44 @BASEBOARD_FAB2_LIB.BASEBOARD_FAB2(SCH_1):PAGE50
    28    GND @BASEBOARD_FAB2_LIB.BASEBOARD_FAB2(SCH_1):GND    I44 @BASEBOARD_FAB2_LIB.BASEBOARD_FAB2(SCH_1):PAGE50
    31    GND @BASEBOARD_FAB2_LIB.BASEBOARD_FAB2(SCH_1):GND    I44 @BASEBOARD_FAB2_LIB.BASEBOARD_FAB2(SCH_1):PAGE50
    33    GND @BASEBOARD_FAB2_LIB.BASEBOARD_FAB2(SCH_1):GND    I44 @BASEBOARD_FAB2_LIB.BASEBOARD_FAB2(SCH_1):PAGE50
    35    GND @BASEBOARD_FAB2_LIB.BASEBOARD_FAB2(SCH_1):GND    I44 @BASEBOARD_FAB2_LIB.BASEBOARD_FAB2(SCH_1):PAGE50
    37    GND @BASEBOARD_FAB2_LIB.BASEBOARD_FAB2(SCH_1):GND    I44 @BASEBOARD_FAB2_LIB.BASEBOARD_FAB2(SCH_1):PAGE50
    39    GND @BASEBOARD_FAB2_LIB.BASEBOARD_FAB2(SCH_1):GND    I44 @BASEBOARD_FAB2_LIB.BASEBOARD_FAB2(SCH_1):PAGE50
    42    GND @BASEBOARD_FAB2_LIB.BASEBOARD_FAB2(SCH_1):GND    I44 @BASEBOARD_FAB2_LIB.BASEBOARD_FAB2(SCH_1):PAGE50
    44    GND @BASEBOARD_FAB2_LIB.BASEBOARD_FAB2(SCH_1):GND    I44 @BASEBOARD_FAB2_LIB.BASEBOARD_FAB2(SCH_1):PAGE50
    46    GND @BASEBOARD_FAB2_LIB.BASEBOARD_FAB2(SCH_1):GND    I44 @BASEBOARD_FAB2_LIB.BASEBOARD_FAB2(SCH_1):PAGE50
    48    GND @BASEBOARD_FAB2_LIB.BASEBOARD_FAB2(SCH_1):GND    I44 @BASEBOARD_FAB2_LIB.BASEBOARD_FAB2(SCH_1):PAGE50
    50    GND @BASEBOARD_FAB2_LIB.BASEBOARD_FAB2(SCH_1):GND    I44 @BASEBOARD_FAB2_LIB.BASEBOARD_FAB2(SCH_1):PAGE50
    53    GND @BASEBOARD_FAB2_LIB.BASEBOARD_FAB2(SCH_1):GND    I44 @BASEBOARD_FAB2_LIB.BASEBOARD_FAB2(SCH_1):PAGE50
    55    GND @BASEBOARD_FAB2_LIB.BASEBOARD_FAB2(SCH_1):GND    I44 @BASEBOARD_FAB2_LIB.BASEBOARD_FAB2(SCH_1):PAGE50
    57    GND @BASEBOARD_FAB2_LIB.BASEBOARD_FAB2(SCH_1):GND    I44 @BASEBOARD_FAB2_LIB.BASEBOARD_FAB2(SCH_1):PAGE50
    94    GND @BASEBOARD_FAB2_LIB.BASEBOARD_FAB2(SCH_1):GND    I44 @BASEBOARD_FAB2_LIB.BASEBOARD_FAB2(SCH_1):PAGE50
    96    GND @BASEBOARD_FAB2_LIB.BASEBOARD_FAB2(SCH_1):GND    I44 @BASEBOARD_FAB2_LIB.BASEBOARD_FAB2(SCH_1):PAGE50
    98    GND @BASEBOARD_FAB2_LIB.BASEBOARD_FAB2(SCH_1):GND    I44 @BASEBOARD_FAB2_LIB.BASEBOARD_FAB2(SCH_1):PAGE50
   101    GND @BASEBOARD_FAB2_LIB.BASEBOARD_FAB2(SCH_1):GND    I44 @BASEBOARD_FAB2_LIB.BASEBOARD_FAB2(SCH_1):PAGE50
   103    GND @BASEBOARD_FAB2_LIB.BASEBOARD_FAB2(SCH_1):GND    I44 @BASEBOARD_FAB2_LIB.BASEBOARD_FAB2(SCH_1):PAGE50
   105    GND @BASEBOARD_FAB2_LIB.BASEBOARD_FAB2(SCH_1):GND    I44 @BASEBOARD_FAB2_LIB.BASEBOARD_FAB2(SCH_1):PAGE50
   107    GND @BASEBOARD_FAB2_LIB.BASEBOARD_FAB2(SCH_1):GND    I44 @BASEBOARD_FAB2_LIB.BASEBOARD_FAB2(SCH_1):PAGE50
   109    GND @BASEBOARD_FAB2_LIB.BASEBOARD_FAB2(SCH_1):GND    I44 @BASEBOARD_FAB2_LIB.BASEBOARD_FAB2(SCH_1):PAGE50
   112    GND @BASEBOARD_FAB2_LIB.BASEBOARD_FAB2(SCH_1):GND    I44 @BASEBOARD_FAB2_LIB.BASEBOARD_FAB2(SCH_1):PAGE50
   114    GND @BASEBOARD_FAB2_LIB.BASEBOARD_FAB2(SCH_1):GND    I44 @BASEBOARD_FAB2_LIB.BASEBOARD_FAB2(SCH_1):PAGE50
   116    GND @BASEBOARD_FAB2_LIB.BASEBOARD_FAB2(SCH_1):GND    I44 @BASEBOARD_FAB2_LIB.BASEBOARD_FAB2(SCH_1):PAGE50
   118    GND @BASEBOARD_FAB2_LIB.BASEBOARD_FAB2(SCH_1):GND    I44 @BASEBOARD_FAB2_LIB.BASEBOARD_FAB2(SCH_1):PAGE50
   120    GND @BASEBOARD_FAB2_LIB.BASEBOARD_FAB2(SCH_1):GND    I44 @BASEBOARD_FAB2_LIB.BASEBOARD_FAB2(SCH_1):PAGE50
   123    GND @BASEBOARD_FAB2_LIB.BASEBOARD_FAB2(SCH_1):GND    I44 @BASEBOARD_FAB2_LIB.BASEBOARD_FAB2(SCH_1):PAGE50
   125    GND @BASEBOARD_FAB2_LIB.BASEBOARD_FAB2(SCH_1):GND    I44 @BASEBOARD_FAB2_LIB.BASEBOARD_FAB2(SCH_1):PAGE50
   127    GND @BASEBOARD_FAB2_LIB.BASEBOARD_FAB2(SCH_1):GND    I44 @BASEBOARD_FAB2_LIB.BASEBOARD_FAB2(SCH_1):PAGE50
   129    GND @BASEBOARD_FAB2_LIB.BASEBOARD_FAB2(SCH_1):GND    I44 @BASEBOARD_FAB2_LIB.BASEBOARD_FAB2(SCH_1):PAGE50
   131    GND @BASEBOARD_FAB2_LIB.BASEBOARD_FAB2(SCH_1):GND    I44 @BASEBOARD_FAB2_LIB.BASEBOARD_FAB2(SCH_1):PAGE50
   134    GND @BASEBOARD_FAB2_LIB.BASEBOARD_FAB2(SCH_1):GND    I44 @BASEBOARD_FAB2_LIB.BASEBOARD_FAB2(SCH_1):PAGE50
   136    GND @BASEBOARD_FAB2_LIB.BASEBOARD_FAB2(SCH_1):GND    I44 @BASEBOARD_FAB2_LIB.BASEBOARD_FAB2(SCH_1):PAGE50
   138    GND @BASEBOARD_FAB2_LIB.BASEBOARD_FAB2(SCH_1):GND    I44 @BASEBOARD_FAB2_LIB.BASEBOARD_FAB2(SCH_1):PAGE50
   147    GND @BASEBOARD_FAB2_LIB.BASEBOARD_FAB2(SCH_1):GND    I44 @BASEBOARD_FAB2_LIB.BASEBOARD_FAB2(SCH_1):PAGE50
   149    GND @BASEBOARD_FAB2_LIB.BASEBOARD_FAB2(SCH_1):GND    I44 @BASEBOARD_FAB2_LIB.BASEBOARD_FAB2(SCH_1):PAGE50
   151    GND @BASEBOARD_FAB2_LIB.BASEBOARD_FAB2(SCH_1):GND    I44 @BASEBOARD_FAB2_LIB.BASEBOARD_FAB2(SCH_1):PAGE50
   154    GND @BASEBOARD_FAB2_LIB.BASEBOARD_FAB2(SCH_1):GND    I44 @BASEBOARD_FAB2_LIB.BASEBOARD_FAB2(SCH_1):PAGE50
   156    GND @BASEBOARD_FAB2_LIB.BASEBOARD_FAB2(SCH_1):GND    I44 @BASEBOARD_FAB2_LIB.BASEBOARD_FAB2(SCH_1):PAGE50
   158    GND @BASEBOARD_FAB2_LIB.BASEBOARD_FAB2(SCH_1):GND    I44 @BASEBOARD_FAB2_LIB.BASEBOARD_FAB2(SCH_1):PAGE50
   160    GND @BASEBOARD_FAB2_LIB.BASEBOARD_FAB2(SCH_1):GND    I44 @BASEBOARD_FAB2_LIB.BASEBOARD_FAB2(SCH_1):PAGE50
   162    GND @BASEBOARD_FAB2_LIB.BASEBOARD_FAB2(SCH_1):GND    I44 @BASEBOARD_FAB2_LIB.BASEBOARD_FAB2(SCH_1):PAGE50
   165    GND @BASEBOARD_FAB2_LIB.BASEBOARD_FAB2(SCH_1):GND    I44 @BASEBOARD_FAB2_LIB.BASEBOARD_FAB2(SCH_1):PAGE50
   167    GND @BASEBOARD_FAB2_LIB.BASEBOARD_FAB2(SCH_1):GND    I44 @BASEBOARD_FAB2_LIB.BASEBOARD_FAB2(SCH_1):PAGE50
   169    GND @BASEBOARD_FAB2_LIB.BASEBOARD_FAB2(SCH_1):GND    I44 @BASEBOARD_FAB2_LIB.BASEBOARD_FAB2(SCH_1):PAGE50
   171    GND @BASEBOARD_FAB2_LIB.BASEBOARD_FAB2(SCH_1):GND    I44 @BASEBOARD_FAB2_LIB.BASEBOARD_FAB2(SCH_1):PAGE50
   173    GND @BASEBOARD_FAB2_LIB.BASEBOARD_FAB2(SCH_1):GND    I44 @BASEBOARD_FAB2_LIB.BASEBOARD_FAB2(SCH_1):PAGE50
   176    GND @BASEBOARD_FAB2_LIB.BASEBOARD_FAB2(SCH_1):GND    I44 @BASEBOARD_FAB2_LIB.BASEBOARD_FAB2(SCH_1):PAGE50
   178    GND @BASEBOARD_FAB2_LIB.BASEBOARD_FAB2(SCH_1):GND    I44 @BASEBOARD_FAB2_LIB.BASEBOARD_FAB2(SCH_1):PAGE50
   180    GND @BASEBOARD_FAB2_LIB.BASEBOARD_FAB2(SCH_1):GND    I44 @BASEBOARD_FAB2_LIB.BASEBOARD_FAB2(SCH_1):PAGE50
   182    GND @BASEBOARD_FAB2_LIB.BASEBOARD_FAB2(SCH_1):GND    I44 @BASEBOARD_FAB2_LIB.BASEBOARD_FAB2(SCH_1):PAGE50
   184    GND @BASEBOARD_FAB2_LIB.BASEBOARD_FAB2(SCH_1):GND    I44 @BASEBOARD_FAB2_LIB.BASEBOARD_FAB2(SCH_1):PAGE50
   187    GND @BASEBOARD_FAB2_LIB.BASEBOARD_FAB2(SCH_1):GND    I44 @BASEBOARD_FAB2_LIB.BASEBOARD_FAB2(SCH_1):PAGE50
   189    GND @BASEBOARD_FAB2_LIB.BASEBOARD_FAB2(SCH_1):GND    I44 @BASEBOARD_FAB2_LIB.BASEBOARD_FAB2(SCH_1):PAGE50
   191    GND @BASEBOARD_FAB2_LIB.BASEBOARD_FAB2(SCH_1):GND    I44 @BASEBOARD_FAB2_LIB.BASEBOARD_FAB2(SCH_1):PAGE50
   193    GND @BASEBOARD_FAB2_LIB.BASEBOARD_FAB2(SCH_1):GND    I44 @BASEBOARD_FAB2_LIB.BASEBOARD_FAB2(SCH_1):PAGE50
   195    GND @BASEBOARD_FAB2_LIB.BASEBOARD_FAB2(SCH_1):GND    I44 @BASEBOARD_FAB2_LIB.BASEBOARD_FAB2(SCH_1):PAGE50
   198    GND @BASEBOARD_FAB2_LIB.BASEBOARD_FAB2(SCH_1):GND    I44 @BASEBOARD_FAB2_LIB.BASEBOARD_FAB2(SCH_1):PAGE50
   200    GND @BASEBOARD_FAB2_LIB.BASEBOARD_FAB2(SCH_1):GND    I44 @BASEBOARD_FAB2_LIB.BASEBOARD_FAB2(SCH_1):PAGE50
   202    GND @BASEBOARD_FAB2_LIB.BASEBOARD_FAB2(SCH_1):GND    I44 @BASEBOARD_FAB2_LIB.BASEBOARD_FAB2(SCH_1):PAGE50
   239    GND @BASEBOARD_FAB2_LIB.BASEBOARD_FAB2(SCH_1):GND    I44 @BASEBOARD_FAB2_LIB.BASEBOARD_FAB2(SCH_1):PAGE50
   241    GND @BASEBOARD_FAB2_LIB.BASEBOARD_FAB2(SCH_1):GND    I44 @BASEBOARD_FAB2_LIB.BASEBOARD_FAB2(SCH_1):PAGE50
   243    GND @BASEBOARD_FAB2_LIB.BASEBOARD_FAB2(SCH_1):GND    I44 @BASEBOARD_FAB2_LIB.BASEBOARD_FAB2(SCH_1):PAGE50
   246    GND @BASEBOARD_FAB2_LIB.BASEBOARD_FAB2(SCH_1):GND    I44 @BASEBOARD_FAB2_LIB.BASEBOARD_FAB2(SCH_1):PAGE50
   248    GND @BASEBOARD_FAB2_LIB.BASEBOARD_FAB2(SCH_1):GND    I44 @BASEBOARD_FAB2_LIB.BASEBOARD_FAB2(SCH_1):PAGE50
   250    GND @BASEBOARD_FAB2_LIB.BASEBOARD_FAB2(SCH_1):GND    I44 @BASEBOARD_FAB2_LIB.BASEBOARD_FAB2(SCH_1):PAGE50
   252    GND @BASEBOARD_FAB2_LIB.BASEBOARD_FAB2(SCH_1):GND    I44 @BASEBOARD_FAB2_LIB.BASEBOARD_FAB2(SCH_1):PAGE50
   254    GND @BASEBOARD_FAB2_LIB.BASEBOARD_FAB2(SCH_1):GND    I44 @BASEBOARD_FAB2_LIB.BASEBOARD_FAB2(SCH_1):PAGE50
   257    GND @BASEBOARD_FAB2_LIB.BASEBOARD_FAB2(SCH_1):GND    I44 @BASEBOARD_FAB2_LIB.BASEBOARD_FAB2(SCH_1):PAGE50
   259    GND @BASEBOARD_FAB2_LIB.BASEBOARD_FAB2(SCH_1):GND    I44 @BASEBOARD_FAB2_LIB.BASEBOARD_FAB2(SCH_1):PAGE50
   261    GND @BASEBOARD_FAB2_LIB.BASEBOARD_FAB2(SCH_1):GND    I44 @BASEBOARD_FAB2_LIB.BASEBOARD_FAB2(SCH_1):PAGE50
   263    GND @BASEBOARD_FAB2_LIB.BASEBOARD_FAB2(SCH_1):GND    I44 @BASEBOARD_FAB2_LIB.BASEBOARD_FAB2(SCH_1):PAGE50
   265    GND @BASEBOARD_FAB2_LIB.BASEBOARD_FAB2(SCH_1):GND    I44 @BASEBOARD_FAB2_LIB.BASEBOARD_FAB2(SCH_1):PAGE50
   268    GND @BASEBOARD_FAB2_LIB.BASEBOARD_FAB2(SCH_1):GND    I44 @BASEBOARD_FAB2_LIB.BASEBOARD_FAB2(SCH_1):PAGE50
   270    GND @BASEBOARD_FAB2_LIB.BASEBOARD_FAB2(SCH_1):GND    I44 @BASEBOARD_FAB2_LIB.BASEBOARD_FAB2(SCH_1):PAGE50
   272    GND @BASEBOARD_FAB2_LIB.BASEBOARD_FAB2(SCH_1):GND    I44 @BASEBOARD_FAB2_LIB.BASEBOARD_FAB2(SCH_1):PAGE50
   274    GND @BASEBOARD_FAB2_LIB.BASEBOARD_FAB2(SCH_1):GND    I44 @BASEBOARD_FAB2_LIB.BASEBOARD_FAB2(SCH_1):PAGE50
   276    GND @BASEBOARD_FAB2_LIB.BASEBOARD_FAB2(SCH_1):GND    I44 @BASEBOARD_FAB2_LIB.BASEBOARD_FAB2(SCH_1):PAGE50
   279    GND @BASEBOARD_FAB2_LIB.BASEBOARD_FAB2(SCH_1):GND    I44 @BASEBOARD_FAB2_LIB.BASEBOARD_FAB2(SCH_1):PAGE50
   281    GND @BASEBOARD_FAB2_LIB.BASEBOARD_FAB2(SCH_1):GND    I44 @BASEBOARD_FAB2_LIB.BASEBOARD_FAB2(SCH_1):PAGE50
   283    GND @BASEBOARD_FAB2_LIB.BASEBOARD_FAB2(SCH_1):GND    I44 @BASEBOARD_FAB2_LIB.BASEBOARD_FAB2(SCH_1):PAGE50
     1 P12V_NVDIMM_DEF @BASEBOARD_FAB2_LIB.BASEBOARD_FAB2(SCH_1):P12V_NVDIMM_DEF    I50 @BASEBOARD_FAB2_LIB.BASEBOARD_FAB2(SCH_1):PAGE50
   145 P12V_NVDIMM_DEF @BASEBOARD_FAB2_LIB.BASEBOARD_FAB2(SCH_1):P12V_NVDIMM_DEF    I50 @BASEBOARD_FAB2_LIB.BASEBOARD_FAB2(SCH_1):PAGE50
    59 PVDDQ_DEF @BASEBOARD_FAB2_LIB.BASEBOARD_FAB2(SCH_1):PVDDQ_DEF    I50 @BASEBOARD_FAB2_LIB.BASEBOARD_FAB2(SCH_1):PAGE50
    61 PVDDQ_DEF @BASEBOARD_FAB2_LIB.BASEBOARD_FAB2(SCH_1):PVDDQ_DEF    I50 @BASEBOARD_FAB2_LIB.BASEBOARD_FAB2(SCH_1):PAGE50
    64 PVDDQ_DEF @BASEBOARD_FAB2_LIB.BASEBOARD_FAB2(SCH_1):PVDDQ_DEF    I50 @BASEBOARD_FAB2_LIB.BASEBOARD_FAB2(SCH_1):PAGE50
    67 PVDDQ_DEF @BASEBOARD_FAB2_LIB.BASEBOARD_FAB2(SCH_1):PVDDQ_DEF    I50 @BASEBOARD_FAB2_LIB.BASEBOARD_FAB2(SCH_1):PAGE50
    70 PVDDQ_DEF @BASEBOARD_FAB2_LIB.BASEBOARD_FAB2(SCH_1):PVDDQ_DEF    I50 @BASEBOARD_FAB2_LIB.BASEBOARD_FAB2(SCH_1):PAGE50
    73 PVDDQ_DEF @BASEBOARD_FAB2_LIB.BASEBOARD_FAB2(SCH_1):PVDDQ_DEF    I50 @BASEBOARD_FAB2_LIB.BASEBOARD_FAB2(SCH_1):PAGE50
    76 PVDDQ_DEF @BASEBOARD_FAB2_LIB.BASEBOARD_FAB2(SCH_1):PVDDQ_DEF    I50 @BASEBOARD_FAB2_LIB.BASEBOARD_FAB2(SCH_1):PAGE50
    80 PVDDQ_DEF @BASEBOARD_FAB2_LIB.BASEBOARD_FAB2(SCH_1):PVDDQ_DEF    I50 @BASEBOARD_FAB2_LIB.BASEBOARD_FAB2(SCH_1):PAGE50
    83 PVDDQ_DEF @BASEBOARD_FAB2_LIB.BASEBOARD_FAB2(SCH_1):PVDDQ_DEF    I50 @BASEBOARD_FAB2_LIB.BASEBOARD_FAB2(SCH_1):PAGE50
    85 PVDDQ_DEF @BASEBOARD_FAB2_LIB.BASEBOARD_FAB2(SCH_1):PVDDQ_DEF    I50 @BASEBOARD_FAB2_LIB.BASEBOARD_FAB2(SCH_1):PAGE50
    88 PVDDQ_DEF @BASEBOARD_FAB2_LIB.BASEBOARD_FAB2(SCH_1):PVDDQ_DEF    I50 @BASEBOARD_FAB2_LIB.BASEBOARD_FAB2(SCH_1):PAGE50
    90 PVDDQ_DEF @BASEBOARD_FAB2_LIB.BASEBOARD_FAB2(SCH_1):PVDDQ_DEF    I50 @BASEBOARD_FAB2_LIB.BASEBOARD_FAB2(SCH_1):PAGE50
    92 PVDDQ_DEF @BASEBOARD_FAB2_LIB.BASEBOARD_FAB2(SCH_1):PVDDQ_DEF    I50 @BASEBOARD_FAB2_LIB.BASEBOARD_FAB2(SCH_1):PAGE50
   204 PVDDQ_DEF @BASEBOARD_FAB2_LIB.BASEBOARD_FAB2(SCH_1):PVDDQ_DEF    I50 @BASEBOARD_FAB2_LIB.BASEBOARD_FAB2(SCH_1):PAGE50
   206 PVDDQ_DEF @BASEBOARD_FAB2_LIB.BASEBOARD_FAB2(SCH_1):PVDDQ_DEF    I50 @BASEBOARD_FAB2_LIB.BASEBOARD_FAB2(SCH_1):PAGE50
   209 PVDDQ_DEF @BASEBOARD_FAB2_LIB.BASEBOARD_FAB2(SCH_1):PVDDQ_DEF    I50 @BASEBOARD_FAB2_LIB.BASEBOARD_FAB2(SCH_1):PAGE50
   212 PVDDQ_DEF @BASEBOARD_FAB2_LIB.BASEBOARD_FAB2(SCH_1):PVDDQ_DEF    I50 @BASEBOARD_FAB2_LIB.BASEBOARD_FAB2(SCH_1):PAGE50
   215 PVDDQ_DEF @BASEBOARD_FAB2_LIB.BASEBOARD_FAB2(SCH_1):PVDDQ_DEF    I50 @BASEBOARD_FAB2_LIB.BASEBOARD_FAB2(SCH_1):PAGE50
   217 PVDDQ_DEF @BASEBOARD_FAB2_LIB.BASEBOARD_FAB2(SCH_1):PVDDQ_DEF    I50 @BASEBOARD_FAB2_LIB.BASEBOARD_FAB2(SCH_1):PAGE50
   220 PVDDQ_DEF @BASEBOARD_FAB2_LIB.BASEBOARD_FAB2(SCH_1):PVDDQ_DEF    I50 @BASEBOARD_FAB2_LIB.BASEBOARD_FAB2(SCH_1):PAGE50
   223 PVDDQ_DEF @BASEBOARD_FAB2_LIB.BASEBOARD_FAB2(SCH_1):PVDDQ_DEF    I50 @BASEBOARD_FAB2_LIB.BASEBOARD_FAB2(SCH_1):PAGE50
   226 PVDDQ_DEF @BASEBOARD_FAB2_LIB.BASEBOARD_FAB2(SCH_1):PVDDQ_DEF    I50 @BASEBOARD_FAB2_LIB.BASEBOARD_FAB2(SCH_1):PAGE50
   229 PVDDQ_DEF @BASEBOARD_FAB2_LIB.BASEBOARD_FAB2(SCH_1):PVDDQ_DEF    I50 @BASEBOARD_FAB2_LIB.BASEBOARD_FAB2(SCH_1):PAGE50
   231 PVDDQ_DEF @BASEBOARD_FAB2_LIB.BASEBOARD_FAB2(SCH_1):PVDDQ_DEF    I50 @BASEBOARD_FAB2_LIB.BASEBOARD_FAB2(SCH_1):PAGE50
   233 PVDDQ_DEF @BASEBOARD_FAB2_LIB.BASEBOARD_FAB2(SCH_1):PVDDQ_DEF    I50 @BASEBOARD_FAB2_LIB.BASEBOARD_FAB2(SCH_1):PAGE50
   236 PVDDQ_DEF @BASEBOARD_FAB2_LIB.BASEBOARD_FAB2(SCH_1):PVDDQ_DEF    I50 @BASEBOARD_FAB2_LIB.BASEBOARD_FAB2(SCH_1):PAGE50
   142 PVPP_DEF @BASEBOARD_FAB2_LIB.BASEBOARD_FAB2(SCH_1):PVPP_DEF    I50 @BASEBOARD_FAB2_LIB.BASEBOARD_FAB2(SCH_1):PAGE50
   143 PVPP_DEF @BASEBOARD_FAB2_LIB.BASEBOARD_FAB2(SCH_1):PVPP_DEF    I50 @BASEBOARD_FAB2_LIB.BASEBOARD_FAB2(SCH_1):PAGE50
   288 PVPP_DEF @BASEBOARD_FAB2_LIB.BASEBOARD_FAB2(SCH_1):PVPP_DEF    I50 @BASEBOARD_FAB2_LIB.BASEBOARD_FAB2(SCH_1):PAGE50
   286 PVPP_DEF @BASEBOARD_FAB2_LIB.BASEBOARD_FAB2(SCH_1):PVPP_DEF    I50 @BASEBOARD_FAB2_LIB.BASEBOARD_FAB2(SCH_1):PAGE50
   287 PVPP_DEF @BASEBOARD_FAB2_LIB.BASEBOARD_FAB2(SCH_1):PVPP_DEF    I50 @BASEBOARD_FAB2_LIB.BASEBOARD_FAB2(SCH_1):PAGE50
    77 PVTT_DEF @BASEBOARD_FAB2_LIB.BASEBOARD_FAB2(SCH_1):PVTT_DEF    I50 @BASEBOARD_FAB2_LIB.BASEBOARD_FAB2(SCH_1):PAGE50
   221 PVTT_DEF @BASEBOARD_FAB2_LIB.BASEBOARD_FAB2(SCH_1):PVTT_DEF    I50 @BASEBOARD_FAB2_LIB.BASEBOARD_FAB2(SCH_1):PAGE50

J6T1 SCONN288_H44441003_PIP-SCONN,HA
    79 M_A_MA<0> @BASEBOARD_FAB2_LIB.BASEBOARD_FAB2(SCH_1):M_A_MA(0)    I13 @BASEBOARD_FAB2_LIB.BASEBOARD_FAB2(SCH_1):PAGE44
    72 M_A_MA<1> @BASEBOARD_FAB2_LIB.BASEBOARD_FAB2(SCH_1):M_A_MA(1)    I13 @BASEBOARD_FAB2_LIB.BASEBOARD_FAB2(SCH_1):PAGE44
   225 M_A_MA<10> @BASEBOARD_FAB2_LIB.BASEBOARD_FAB2(SCH_1):M_A_MA(10)    I13 @BASEBOARD_FAB2_LIB.BASEBOARD_FAB2(SCH_1):PAGE44
   210 M_A_MA<11> @BASEBOARD_FAB2_LIB.BASEBOARD_FAB2(SCH_1):M_A_MA(11)    I13 @BASEBOARD_FAB2_LIB.BASEBOARD_FAB2(SCH_1):PAGE44
    65 M_A_MA<12> @BASEBOARD_FAB2_LIB.BASEBOARD_FAB2(SCH_1):M_A_MA(12)    I13 @BASEBOARD_FAB2_LIB.BASEBOARD_FAB2(SCH_1):PAGE44
   232 M_A_MA<13> @BASEBOARD_FAB2_LIB.BASEBOARD_FAB2(SCH_1):M_A_MA(13)    I13 @BASEBOARD_FAB2_LIB.BASEBOARD_FAB2(SCH_1):PAGE44
   228 M_A_MA<14> @BASEBOARD_FAB2_LIB.BASEBOARD_FAB2(SCH_1):M_A_MA(14)    I13 @BASEBOARD_FAB2_LIB.BASEBOARD_FAB2(SCH_1):PAGE44
    86 M_A_MA<15> @BASEBOARD_FAB2_LIB.BASEBOARD_FAB2(SCH_1):M_A_MA(15)    I13 @BASEBOARD_FAB2_LIB.BASEBOARD_FAB2(SCH_1):PAGE44
    82 M_A_MA<16> @BASEBOARD_FAB2_LIB.BASEBOARD_FAB2(SCH_1):M_A_MA(16)    I13 @BASEBOARD_FAB2_LIB.BASEBOARD_FAB2(SCH_1):PAGE44
   234 M_A_MA<17> @BASEBOARD_FAB2_LIB.BASEBOARD_FAB2(SCH_1):M_A_MA(17)    I13 @BASEBOARD_FAB2_LIB.BASEBOARD_FAB2(SCH_1):PAGE44
   216 M_A_MA<2> @BASEBOARD_FAB2_LIB.BASEBOARD_FAB2(SCH_1):M_A_MA(2)    I13 @BASEBOARD_FAB2_LIB.BASEBOARD_FAB2(SCH_1):PAGE44
    71 M_A_MA<3> @BASEBOARD_FAB2_LIB.BASEBOARD_FAB2(SCH_1):M_A_MA(3)    I13 @BASEBOARD_FAB2_LIB.BASEBOARD_FAB2(SCH_1):PAGE44
   214 M_A_MA<4> @BASEBOARD_FAB2_LIB.BASEBOARD_FAB2(SCH_1):M_A_MA(4)    I13 @BASEBOARD_FAB2_LIB.BASEBOARD_FAB2(SCH_1):PAGE44
   213 M_A_MA<5> @BASEBOARD_FAB2_LIB.BASEBOARD_FAB2(SCH_1):M_A_MA(5)    I13 @BASEBOARD_FAB2_LIB.BASEBOARD_FAB2(SCH_1):PAGE44
    69 M_A_MA<6> @BASEBOARD_FAB2_LIB.BASEBOARD_FAB2(SCH_1):M_A_MA(6)    I13 @BASEBOARD_FAB2_LIB.BASEBOARD_FAB2(SCH_1):PAGE44
   211 M_A_MA<7> @BASEBOARD_FAB2_LIB.BASEBOARD_FAB2(SCH_1):M_A_MA(7)    I13 @BASEBOARD_FAB2_LIB.BASEBOARD_FAB2(SCH_1):PAGE44
    68 M_A_MA<8> @BASEBOARD_FAB2_LIB.BASEBOARD_FAB2(SCH_1):M_A_MA(8)    I13 @BASEBOARD_FAB2_LIB.BASEBOARD_FAB2(SCH_1):PAGE44
    66 M_A_MA<9> @BASEBOARD_FAB2_LIB.BASEBOARD_FAB2(SCH_1):M_A_MA(9)    I13 @BASEBOARD_FAB2_LIB.BASEBOARD_FAB2(SCH_1):PAGE44
    62 M_A_ACT_N @BASEBOARD_FAB2_LIB.BASEBOARD_FAB2(SCH_1):M_A_ACT_N    I13 @BASEBOARD_FAB2_LIB.BASEBOARD_FAB2(SCH_1):PAGE44
   208 M_A_ALERT_N @BASEBOARD_FAB2_LIB.BASEBOARD_FAB2(SCH_1):M_A_ALERT_N    I13 @BASEBOARD_FAB2_LIB.BASEBOARD_FAB2(SCH_1):PAGE44
   224 M_A_BA<1> @BASEBOARD_FAB2_LIB.BASEBOARD_FAB2(SCH_1):M_A_BA(1)    I13 @BASEBOARD_FAB2_LIB.BASEBOARD_FAB2(SCH_1):PAGE44
    81 M_A_BA<0> @BASEBOARD_FAB2_LIB.BASEBOARD_FAB2(SCH_1):M_A_BA(0)    I13 @BASEBOARD_FAB2_LIB.BASEBOARD_FAB2(SCH_1):PAGE44
   207 M_A_BG<1> @BASEBOARD_FAB2_LIB.BASEBOARD_FAB2(SCH_1):M_A_BG(1)    I13 @BASEBOARD_FAB2_LIB.BASEBOARD_FAB2(SCH_1):PAGE44
    63 M_A_BG<0> @BASEBOARD_FAB2_LIB.BASEBOARD_FAB2(SCH_1):M_A_BG(0)    I13 @BASEBOARD_FAB2_LIB.BASEBOARD_FAB2(SCH_1):PAGE44
   235 M_A_C<2> @BASEBOARD_FAB2_LIB.BASEBOARD_FAB2(SCH_1):M_A_C(2)    I13 @BASEBOARD_FAB2_LIB.BASEBOARD_FAB2(SCH_1):PAGE44
   199 M_A_ECC<7> @BASEBOARD_FAB2_LIB.BASEBOARD_FAB2(SCH_1):M_A_ECC(7)    I13 @BASEBOARD_FAB2_LIB.BASEBOARD_FAB2(SCH_1):PAGE44
    54 M_A_ECC<6> @BASEBOARD_FAB2_LIB.BASEBOARD_FAB2(SCH_1):M_A_ECC(6)    I13 @BASEBOARD_FAB2_LIB.BASEBOARD_FAB2(SCH_1):PAGE44
   192 M_A_ECC<5> @BASEBOARD_FAB2_LIB.BASEBOARD_FAB2(SCH_1):M_A_ECC(5)    I13 @BASEBOARD_FAB2_LIB.BASEBOARD_FAB2(SCH_1):PAGE44
    47 M_A_ECC<4> @BASEBOARD_FAB2_LIB.BASEBOARD_FAB2(SCH_1):M_A_ECC(4)    I13 @BASEBOARD_FAB2_LIB.BASEBOARD_FAB2(SCH_1):PAGE44
   201 M_A_ECC<3> @BASEBOARD_FAB2_LIB.BASEBOARD_FAB2(SCH_1):M_A_ECC(3)    I13 @BASEBOARD_FAB2_LIB.BASEBOARD_FAB2(SCH_1):PAGE44
    56 M_A_ECC<2> @BASEBOARD_FAB2_LIB.BASEBOARD_FAB2(SCH_1):M_A_ECC(2)    I13 @BASEBOARD_FAB2_LIB.BASEBOARD_FAB2(SCH_1):PAGE44
   194 M_A_ECC<1> @BASEBOARD_FAB2_LIB.BASEBOARD_FAB2(SCH_1):M_A_ECC(1)    I13 @BASEBOARD_FAB2_LIB.BASEBOARD_FAB2(SCH_1):PAGE44
    49 M_A_ECC<0> @BASEBOARD_FAB2_LIB.BASEBOARD_FAB2(SCH_1):M_A_ECC(0)    I13 @BASEBOARD_FAB2_LIB.BASEBOARD_FAB2(SCH_1):PAGE44
    75 M_A_CLK_DN<2> @BASEBOARD_FAB2_LIB.BASEBOARD_FAB2(SCH_1):M_A_CLK_DN(2)    I13 @BASEBOARD_FAB2_LIB.BASEBOARD_FAB2(SCH_1):PAGE44
    74 M_A_CLK_DP<2> @BASEBOARD_FAB2_LIB.BASEBOARD_FAB2(SCH_1):M_A_CLK_DP(2)    I13 @BASEBOARD_FAB2_LIB.BASEBOARD_FAB2(SCH_1):PAGE44
   219 M_A_CLK_DN<3> @BASEBOARD_FAB2_LIB.BASEBOARD_FAB2(SCH_1):M_A_CLK_DN(3)    I13 @BASEBOARD_FAB2_LIB.BASEBOARD_FAB2(SCH_1):PAGE44
   218 M_A_CLK_DP<3> @BASEBOARD_FAB2_LIB.BASEBOARD_FAB2(SCH_1):M_A_CLK_DP(3)    I13 @BASEBOARD_FAB2_LIB.BASEBOARD_FAB2(SCH_1):PAGE44
   203 M_A_CKE<3> @BASEBOARD_FAB2_LIB.BASEBOARD_FAB2(SCH_1):M_A_CKE(3)    I13 @BASEBOARD_FAB2_LIB.BASEBOARD_FAB2(SCH_1):PAGE44
    60 M_A_CKE<2> @BASEBOARD_FAB2_LIB.BASEBOARD_FAB2(SCH_1):M_A_CKE(2)    I13 @BASEBOARD_FAB2_LIB.BASEBOARD_FAB2(SCH_1):PAGE44
   280 M_A_DQ<63> @BASEBOARD_FAB2_LIB.BASEBOARD_FAB2(SCH_1):M_A_DQ(63)    I13 @BASEBOARD_FAB2_LIB.BASEBOARD_FAB2(SCH_1):PAGE44
   135 M_A_DQ<62> @BASEBOARD_FAB2_LIB.BASEBOARD_FAB2(SCH_1):M_A_DQ(62)    I13 @BASEBOARD_FAB2_LIB.BASEBOARD_FAB2(SCH_1):PAGE44
   273 M_A_DQ<61> @BASEBOARD_FAB2_LIB.BASEBOARD_FAB2(SCH_1):M_A_DQ(61)    I13 @BASEBOARD_FAB2_LIB.BASEBOARD_FAB2(SCH_1):PAGE44
   128 M_A_DQ<60> @BASEBOARD_FAB2_LIB.BASEBOARD_FAB2(SCH_1):M_A_DQ(60)    I13 @BASEBOARD_FAB2_LIB.BASEBOARD_FAB2(SCH_1):PAGE44
   282 M_A_DQ<59> @BASEBOARD_FAB2_LIB.BASEBOARD_FAB2(SCH_1):M_A_DQ(59)    I13 @BASEBOARD_FAB2_LIB.BASEBOARD_FAB2(SCH_1):PAGE44
   137 M_A_DQ<58> @BASEBOARD_FAB2_LIB.BASEBOARD_FAB2(SCH_1):M_A_DQ(58)    I13 @BASEBOARD_FAB2_LIB.BASEBOARD_FAB2(SCH_1):PAGE44
   275 M_A_DQ<57> @BASEBOARD_FAB2_LIB.BASEBOARD_FAB2(SCH_1):M_A_DQ(57)    I13 @BASEBOARD_FAB2_LIB.BASEBOARD_FAB2(SCH_1):PAGE44
   130 M_A_DQ<56> @BASEBOARD_FAB2_LIB.BASEBOARD_FAB2(SCH_1):M_A_DQ(56)    I13 @BASEBOARD_FAB2_LIB.BASEBOARD_FAB2(SCH_1):PAGE44
   269 M_A_DQ<55> @BASEBOARD_FAB2_LIB.BASEBOARD_FAB2(SCH_1):M_A_DQ(55)    I13 @BASEBOARD_FAB2_LIB.BASEBOARD_FAB2(SCH_1):PAGE44
   124 M_A_DQ<54> @BASEBOARD_FAB2_LIB.BASEBOARD_FAB2(SCH_1):M_A_DQ(54)    I13 @BASEBOARD_FAB2_LIB.BASEBOARD_FAB2(SCH_1):PAGE44
   262 M_A_DQ<53> @BASEBOARD_FAB2_LIB.BASEBOARD_FAB2(SCH_1):M_A_DQ(53)    I13 @BASEBOARD_FAB2_LIB.BASEBOARD_FAB2(SCH_1):PAGE44
   117 M_A_DQ<52> @BASEBOARD_FAB2_LIB.BASEBOARD_FAB2(SCH_1):M_A_DQ(52)    I13 @BASEBOARD_FAB2_LIB.BASEBOARD_FAB2(SCH_1):PAGE44
   271 M_A_DQ<51> @BASEBOARD_FAB2_LIB.BASEBOARD_FAB2(SCH_1):M_A_DQ(51)    I13 @BASEBOARD_FAB2_LIB.BASEBOARD_FAB2(SCH_1):PAGE44
   126 M_A_DQ<50> @BASEBOARD_FAB2_LIB.BASEBOARD_FAB2(SCH_1):M_A_DQ(50)    I13 @BASEBOARD_FAB2_LIB.BASEBOARD_FAB2(SCH_1):PAGE44
   264 M_A_DQ<49> @BASEBOARD_FAB2_LIB.BASEBOARD_FAB2(SCH_1):M_A_DQ(49)    I13 @BASEBOARD_FAB2_LIB.BASEBOARD_FAB2(SCH_1):PAGE44
   119 M_A_DQ<48> @BASEBOARD_FAB2_LIB.BASEBOARD_FAB2(SCH_1):M_A_DQ(48)    I13 @BASEBOARD_FAB2_LIB.BASEBOARD_FAB2(SCH_1):PAGE44
   258 M_A_DQ<47> @BASEBOARD_FAB2_LIB.BASEBOARD_FAB2(SCH_1):M_A_DQ(47)    I13 @BASEBOARD_FAB2_LIB.BASEBOARD_FAB2(SCH_1):PAGE44
   113 M_A_DQ<46> @BASEBOARD_FAB2_LIB.BASEBOARD_FAB2(SCH_1):M_A_DQ(46)    I13 @BASEBOARD_FAB2_LIB.BASEBOARD_FAB2(SCH_1):PAGE44
   251 M_A_DQ<45> @BASEBOARD_FAB2_LIB.BASEBOARD_FAB2(SCH_1):M_A_DQ(45)    I13 @BASEBOARD_FAB2_LIB.BASEBOARD_FAB2(SCH_1):PAGE44
   106 M_A_DQ<44> @BASEBOARD_FAB2_LIB.BASEBOARD_FAB2(SCH_1):M_A_DQ(44)    I13 @BASEBOARD_FAB2_LIB.BASEBOARD_FAB2(SCH_1):PAGE44
   260 M_A_DQ<43> @BASEBOARD_FAB2_LIB.BASEBOARD_FAB2(SCH_1):M_A_DQ(43)    I13 @BASEBOARD_FAB2_LIB.BASEBOARD_FAB2(SCH_1):PAGE44
   115 M_A_DQ<42> @BASEBOARD_FAB2_LIB.BASEBOARD_FAB2(SCH_1):M_A_DQ(42)    I13 @BASEBOARD_FAB2_LIB.BASEBOARD_FAB2(SCH_1):PAGE44
   253 M_A_DQ<41> @BASEBOARD_FAB2_LIB.BASEBOARD_FAB2(SCH_1):M_A_DQ(41)    I13 @BASEBOARD_FAB2_LIB.BASEBOARD_FAB2(SCH_1):PAGE44
   108 M_A_DQ<40> @BASEBOARD_FAB2_LIB.BASEBOARD_FAB2(SCH_1):M_A_DQ(40)    I13 @BASEBOARD_FAB2_LIB.BASEBOARD_FAB2(SCH_1):PAGE44
   247 M_A_DQ<39> @BASEBOARD_FAB2_LIB.BASEBOARD_FAB2(SCH_1):M_A_DQ(39)    I13 @BASEBOARD_FAB2_LIB.BASEBOARD_FAB2(SCH_1):PAGE44
   102 M_A_DQ<38> @BASEBOARD_FAB2_LIB.BASEBOARD_FAB2(SCH_1):M_A_DQ(38)    I13 @BASEBOARD_FAB2_LIB.BASEBOARD_FAB2(SCH_1):PAGE44
   240 M_A_DQ<37> @BASEBOARD_FAB2_LIB.BASEBOARD_FAB2(SCH_1):M_A_DQ(37)    I13 @BASEBOARD_FAB2_LIB.BASEBOARD_FAB2(SCH_1):PAGE44
    95 M_A_DQ<36> @BASEBOARD_FAB2_LIB.BASEBOARD_FAB2(SCH_1):M_A_DQ(36)    I13 @BASEBOARD_FAB2_LIB.BASEBOARD_FAB2(SCH_1):PAGE44
   249 M_A_DQ<35> @BASEBOARD_FAB2_LIB.BASEBOARD_FAB2(SCH_1):M_A_DQ(35)    I13 @BASEBOARD_FAB2_LIB.BASEBOARD_FAB2(SCH_1):PAGE44
   104 M_A_DQ<34> @BASEBOARD_FAB2_LIB.BASEBOARD_FAB2(SCH_1):M_A_DQ(34)    I13 @BASEBOARD_FAB2_LIB.BASEBOARD_FAB2(SCH_1):PAGE44
   242 M_A_DQ<33> @BASEBOARD_FAB2_LIB.BASEBOARD_FAB2(SCH_1):M_A_DQ(33)    I13 @BASEBOARD_FAB2_LIB.BASEBOARD_FAB2(SCH_1):PAGE44
    97 M_A_DQ<32> @BASEBOARD_FAB2_LIB.BASEBOARD_FAB2(SCH_1):M_A_DQ(32)    I13 @BASEBOARD_FAB2_LIB.BASEBOARD_FAB2(SCH_1):PAGE44
   188 M_A_DQ<31> @BASEBOARD_FAB2_LIB.BASEBOARD_FAB2(SCH_1):M_A_DQ(31)    I13 @BASEBOARD_FAB2_LIB.BASEBOARD_FAB2(SCH_1):PAGE44
    43 M_A_DQ<30> @BASEBOARD_FAB2_LIB.BASEBOARD_FAB2(SCH_1):M_A_DQ(30)    I13 @BASEBOARD_FAB2_LIB.BASEBOARD_FAB2(SCH_1):PAGE44
   181 M_A_DQ<29> @BASEBOARD_FAB2_LIB.BASEBOARD_FAB2(SCH_1):M_A_DQ(29)    I13 @BASEBOARD_FAB2_LIB.BASEBOARD_FAB2(SCH_1):PAGE44
    36 M_A_DQ<28> @BASEBOARD_FAB2_LIB.BASEBOARD_FAB2(SCH_1):M_A_DQ(28)    I13 @BASEBOARD_FAB2_LIB.BASEBOARD_FAB2(SCH_1):PAGE44
   190 M_A_DQ<27> @BASEBOARD_FAB2_LIB.BASEBOARD_FAB2(SCH_1):M_A_DQ(27)    I13 @BASEBOARD_FAB2_LIB.BASEBOARD_FAB2(SCH_1):PAGE44
    45 M_A_DQ<26> @BASEBOARD_FAB2_LIB.BASEBOARD_FAB2(SCH_1):M_A_DQ(26)    I13 @BASEBOARD_FAB2_LIB.BASEBOARD_FAB2(SCH_1):PAGE44
   183 M_A_DQ<25> @BASEBOARD_FAB2_LIB.BASEBOARD_FAB2(SCH_1):M_A_DQ(25)    I13 @BASEBOARD_FAB2_LIB.BASEBOARD_FAB2(SCH_1):PAGE44
    38 M_A_DQ<24> @BASEBOARD_FAB2_LIB.BASEBOARD_FAB2(SCH_1):M_A_DQ(24)    I13 @BASEBOARD_FAB2_LIB.BASEBOARD_FAB2(SCH_1):PAGE44
   177 M_A_DQ<23> @BASEBOARD_FAB2_LIB.BASEBOARD_FAB2(SCH_1):M_A_DQ(23)    I13 @BASEBOARD_FAB2_LIB.BASEBOARD_FAB2(SCH_1):PAGE44
    32 M_A_DQ<22> @BASEBOARD_FAB2_LIB.BASEBOARD_FAB2(SCH_1):M_A_DQ(22)    I13 @BASEBOARD_FAB2_LIB.BASEBOARD_FAB2(SCH_1):PAGE44
   170 M_A_DQ<21> @BASEBOARD_FAB2_LIB.BASEBOARD_FAB2(SCH_1):M_A_DQ(21)    I13 @BASEBOARD_FAB2_LIB.BASEBOARD_FAB2(SCH_1):PAGE44
    25 M_A_DQ<20> @BASEBOARD_FAB2_LIB.BASEBOARD_FAB2(SCH_1):M_A_DQ(20)    I13 @BASEBOARD_FAB2_LIB.BASEBOARD_FAB2(SCH_1):PAGE44
   179 M_A_DQ<19> @BASEBOARD_FAB2_LIB.BASEBOARD_FAB2(SCH_1):M_A_DQ(19)    I13 @BASEBOARD_FAB2_LIB.BASEBOARD_FAB2(SCH_1):PAGE44
    34 M_A_DQ<18> @BASEBOARD_FAB2_LIB.BASEBOARD_FAB2(SCH_1):M_A_DQ(18)    I13 @BASEBOARD_FAB2_LIB.BASEBOARD_FAB2(SCH_1):PAGE44
   172 M_A_DQ<17> @BASEBOARD_FAB2_LIB.BASEBOARD_FAB2(SCH_1):M_A_DQ(17)    I13 @BASEBOARD_FAB2_LIB.BASEBOARD_FAB2(SCH_1):PAGE44
    27 M_A_DQ<16> @BASEBOARD_FAB2_LIB.BASEBOARD_FAB2(SCH_1):M_A_DQ(16)    I13 @BASEBOARD_FAB2_LIB.BASEBOARD_FAB2(SCH_1):PAGE44
   166 M_A_DQ<15> @BASEBOARD_FAB2_LIB.BASEBOARD_FAB2(SCH_1):M_A_DQ(15)    I13 @BASEBOARD_FAB2_LIB.BASEBOARD_FAB2(SCH_1):PAGE44
    21 M_A_DQ<14> @BASEBOARD_FAB2_LIB.BASEBOARD_FAB2(SCH_1):M_A_DQ(14)    I13 @BASEBOARD_FAB2_LIB.BASEBOARD_FAB2(SCH_1):PAGE44
   159 M_A_DQ<13> @BASEBOARD_FAB2_LIB.BASEBOARD_FAB2(SCH_1):M_A_DQ(13)    I13 @BASEBOARD_FAB2_LIB.BASEBOARD_FAB2(SCH_1):PAGE44
    14 M_A_DQ<12> @BASEBOARD_FAB2_LIB.BASEBOARD_FAB2(SCH_1):M_A_DQ(12)    I13 @BASEBOARD_FAB2_LIB.BASEBOARD_FAB2(SCH_1):PAGE44
   168 M_A_DQ<11> @BASEBOARD_FAB2_LIB.BASEBOARD_FAB2(SCH_1):M_A_DQ(11)    I13 @BASEBOARD_FAB2_LIB.BASEBOARD_FAB2(SCH_1):PAGE44
    23 M_A_DQ<10> @BASEBOARD_FAB2_LIB.BASEBOARD_FAB2(SCH_1):M_A_DQ(10)    I13 @BASEBOARD_FAB2_LIB.BASEBOARD_FAB2(SCH_1):PAGE44
   161 M_A_DQ<9> @BASEBOARD_FAB2_LIB.BASEBOARD_FAB2(SCH_1):M_A_DQ(9)    I13 @BASEBOARD_FAB2_LIB.BASEBOARD_FAB2(SCH_1):PAGE44
    16 M_A_DQ<8> @BASEBOARD_FAB2_LIB.BASEBOARD_FAB2(SCH_1):M_A_DQ(8)    I13 @BASEBOARD_FAB2_LIB.BASEBOARD_FAB2(SCH_1):PAGE44
   155 M_A_DQ<7> @BASEBOARD_FAB2_LIB.BASEBOARD_FAB2(SCH_1):M_A_DQ(7)    I13 @BASEBOARD_FAB2_LIB.BASEBOARD_FAB2(SCH_1):PAGE44
    10 M_A_DQ<6> @BASEBOARD_FAB2_LIB.BASEBOARD_FAB2(SCH_1):M_A_DQ(6)    I13 @BASEBOARD_FAB2_LIB.BASEBOARD_FAB2(SCH_1):PAGE44
   148 M_A_DQ<5> @BASEBOARD_FAB2_LIB.BASEBOARD_FAB2(SCH_1):M_A_DQ(5)    I13 @BASEBOARD_FAB2_LIB.BASEBOARD_FAB2(SCH_1):PAGE44
     3 M_A_DQ<4> @BASEBOARD_FAB2_LIB.BASEBOARD_FAB2(SCH_1):M_A_DQ(4)    I13 @BASEBOARD_FAB2_LIB.BASEBOARD_FAB2(SCH_1):PAGE44
   157 M_A_DQ<3> @BASEBOARD_FAB2_LIB.BASEBOARD_FAB2(SCH_1):M_A_DQ(3)    I13 @BASEBOARD_FAB2_LIB.BASEBOARD_FAB2(SCH_1):PAGE44
    12 M_A_DQ<2> @BASEBOARD_FAB2_LIB.BASEBOARD_FAB2(SCH_1):M_A_DQ(2)    I13 @BASEBOARD_FAB2_LIB.BASEBOARD_FAB2(SCH_1):PAGE44
   150 M_A_DQ<1> @BASEBOARD_FAB2_LIB.BASEBOARD_FAB2(SCH_1):M_A_DQ(1)    I13 @BASEBOARD_FAB2_LIB.BASEBOARD_FAB2(SCH_1):PAGE44
     5 M_A_DQ<0> @BASEBOARD_FAB2_LIB.BASEBOARD_FAB2(SCH_1):M_A_DQ(0)    I13 @BASEBOARD_FAB2_LIB.BASEBOARD_FAB2(SCH_1):PAGE44
    78 FM_DIMM_EVENT_COD_N @BASEBOARD_FAB2_LIB.BASEBOARD_FAB2(SCH_1):FM_DIMM_EVENT_COD_N    I13 @BASEBOARD_FAB2_LIB.BASEBOARD_FAB2(SCH_1):PAGE44
    91 M_A_ODT<3> @BASEBOARD_FAB2_LIB.BASEBOARD_FAB2(SCH_1):M_A_ODT(3)    I13 @BASEBOARD_FAB2_LIB.BASEBOARD_FAB2(SCH_1):PAGE44
    87 M_A_ODT<2> @BASEBOARD_FAB2_LIB.BASEBOARD_FAB2(SCH_1):M_A_ODT(2)    I13 @BASEBOARD_FAB2_LIB.BASEBOARD_FAB2(SCH_1):PAGE44
   222 M_A_PAR @BASEBOARD_FAB2_LIB.BASEBOARD_FAB2(SCH_1):M_A_PAR    I13 @BASEBOARD_FAB2_LIB.BASEBOARD_FAB2(SCH_1):PAGE44
    58 M_ABC_RST_N @BASEBOARD_FAB2_LIB.BASEBOARD_FAB2(SCH_1):M_ABC_RST_N    I13 @BASEBOARD_FAB2_LIB.BASEBOARD_FAB2(SCH_1):PAGE44
   144 TP_CH_A_DIMM_A1_RFU_2 @BASEBOARD_FAB2_LIB.BASEBOARD_FAB2(SCH_1):TP_CH_A_DIMM_A1_RFU_2    I13 @BASEBOARD_FAB2_LIB.BASEBOARD_FAB2(SCH_1):PAGE44
   227 TP_CH_A_DIMM_A1_RFU_1 @BASEBOARD_FAB2_LIB.BASEBOARD_FAB2(SCH_1):TP_CH_A_DIMM_A1_RFU_1    I13 @BASEBOARD_FAB2_LIB.BASEBOARD_FAB2(SCH_1):PAGE44
   205 TP_CH_A_DIMM_A1_RFU_0 @BASEBOARD_FAB2_LIB.BASEBOARD_FAB2(SCH_1):TP_CH_A_DIMM_A1_RFU_0    I13 @BASEBOARD_FAB2_LIB.BASEBOARD_FAB2(SCH_1):PAGE44
    84 M_A_CS_N<4> @BASEBOARD_FAB2_LIB.BASEBOARD_FAB2(SCH_1):M_A_CS_N(4)    I13 @BASEBOARD_FAB2_LIB.BASEBOARD_FAB2(SCH_1):PAGE44
    89 M_A_CS_N<5> @BASEBOARD_FAB2_LIB.BASEBOARD_FAB2(SCH_1):M_A_CS_N(5)    I13 @BASEBOARD_FAB2_LIB.BASEBOARD_FAB2(SCH_1):PAGE44
    93 M_A_CS_N<6> @BASEBOARD_FAB2_LIB.BASEBOARD_FAB2(SCH_1):M_A_CS_N(6)    I13 @BASEBOARD_FAB2_LIB.BASEBOARD_FAB2(SCH_1):PAGE44
   237 M_A_CS_N<7> @BASEBOARD_FAB2_LIB.BASEBOARD_FAB2(SCH_1):M_A_CS_N(7)    I13 @BASEBOARD_FAB2_LIB.BASEBOARD_FAB2(SCH_1):PAGE44
   238    GND @BASEBOARD_FAB2_LIB.BASEBOARD_FAB2(SCH_1):GND    I13 @BASEBOARD_FAB2_LIB.BASEBOARD_FAB2(SCH_1):PAGE44
   140    GND @BASEBOARD_FAB2_LIB.BASEBOARD_FAB2(SCH_1):GND    I13 @BASEBOARD_FAB2_LIB.BASEBOARD_FAB2(SCH_1):PAGE44
   139 PVPP_ABC @BASEBOARD_FAB2_LIB.BASEBOARD_FAB2(SCH_1):PVPP_ABC    I13 @BASEBOARD_FAB2_LIB.BASEBOARD_FAB2(SCH_1):PAGE44
   230 FM_ADR_COMPLETE_ABC_N @BASEBOARD_FAB2_LIB.BASEBOARD_FAB2(SCH_1):FM_ADR_COMPLETE_ABC_N    I13 @BASEBOARD_FAB2_LIB.BASEBOARD_FAB2(SCH_1):PAGE44
   141 SMB_DDR_ABC_VPP_SCL @BASEBOARD_FAB2_LIB.BASEBOARD_FAB2(SCH_1):SMB_DDR_ABC_VPP_SCL    I13 @BASEBOARD_FAB2_LIB.BASEBOARD_FAB2(SCH_1):PAGE44
   285 SMB_DDR_ABC_VPP_SDA @BASEBOARD_FAB2_LIB.BASEBOARD_FAB2(SCH_1):SMB_DDR_ABC_VPP_SDA    I13 @BASEBOARD_FAB2_LIB.BASEBOARD_FAB2(SCH_1):PAGE44
   284 PVPP_ABC @BASEBOARD_FAB2_LIB.BASEBOARD_FAB2(SCH_1):PVPP_ABC    I13 @BASEBOARD_FAB2_LIB.BASEBOARD_FAB2(SCH_1):PAGE44
   146 M_A_VREF @BASEBOARD_FAB2_LIB.BASEBOARD_FAB2(SCH_1):M_A_VREF    I13 @BASEBOARD_FAB2_LIB.BASEBOARD_FAB2(SCH_1):PAGE44
   152 M_A_DQS_DN<0> @BASEBOARD_FAB2_LIB.BASEBOARD_FAB2(SCH_1):M_A_DQS_DN(0)   I120 @BASEBOARD_FAB2_LIB.BASEBOARD_FAB2(SCH_1):PAGE44
   153 M_A_DQS_DP<0> @BASEBOARD_FAB2_LIB.BASEBOARD_FAB2(SCH_1):M_A_DQS_DP(0)   I120 @BASEBOARD_FAB2_LIB.BASEBOARD_FAB2(SCH_1):PAGE44
    19 M_A_DQS_DN<10> @BASEBOARD_FAB2_LIB.BASEBOARD_FAB2(SCH_1):M_A_DQS_DN(10)   I120 @BASEBOARD_FAB2_LIB.BASEBOARD_FAB2(SCH_1):PAGE44
    18 M_A_DQS_DP<10> @BASEBOARD_FAB2_LIB.BASEBOARD_FAB2(SCH_1):M_A_DQS_DP(10)   I120 @BASEBOARD_FAB2_LIB.BASEBOARD_FAB2(SCH_1):PAGE44
    30 M_A_DQS_DN<11> @BASEBOARD_FAB2_LIB.BASEBOARD_FAB2(SCH_1):M_A_DQS_DN(11)   I120 @BASEBOARD_FAB2_LIB.BASEBOARD_FAB2(SCH_1):PAGE44
    29 M_A_DQS_DP<11> @BASEBOARD_FAB2_LIB.BASEBOARD_FAB2(SCH_1):M_A_DQS_DP(11)   I120 @BASEBOARD_FAB2_LIB.BASEBOARD_FAB2(SCH_1):PAGE44
    41 M_A_DQS_DN<12> @BASEBOARD_FAB2_LIB.BASEBOARD_FAB2(SCH_1):M_A_DQS_DN(12)   I120 @BASEBOARD_FAB2_LIB.BASEBOARD_FAB2(SCH_1):PAGE44
    40 M_A_DQS_DP<12> @BASEBOARD_FAB2_LIB.BASEBOARD_FAB2(SCH_1):M_A_DQS_DP(12)   I120 @BASEBOARD_FAB2_LIB.BASEBOARD_FAB2(SCH_1):PAGE44
   100 M_A_DQS_DN<13> @BASEBOARD_FAB2_LIB.BASEBOARD_FAB2(SCH_1):M_A_DQS_DN(13)   I120 @BASEBOARD_FAB2_LIB.BASEBOARD_FAB2(SCH_1):PAGE44
    99 M_A_DQS_DP<13> @BASEBOARD_FAB2_LIB.BASEBOARD_FAB2(SCH_1):M_A_DQS_DP(13)   I120 @BASEBOARD_FAB2_LIB.BASEBOARD_FAB2(SCH_1):PAGE44
   111 M_A_DQS_DN<14> @BASEBOARD_FAB2_LIB.BASEBOARD_FAB2(SCH_1):M_A_DQS_DN(14)   I120 @BASEBOARD_FAB2_LIB.BASEBOARD_FAB2(SCH_1):PAGE44
   110 M_A_DQS_DP<14> @BASEBOARD_FAB2_LIB.BASEBOARD_FAB2(SCH_1):M_A_DQS_DP(14)   I120 @BASEBOARD_FAB2_LIB.BASEBOARD_FAB2(SCH_1):PAGE44
   122 M_A_DQS_DN<15> @BASEBOARD_FAB2_LIB.BASEBOARD_FAB2(SCH_1):M_A_DQS_DN(15)   I120 @BASEBOARD_FAB2_LIB.BASEBOARD_FAB2(SCH_1):PAGE44
   121 M_A_DQS_DP<15> @BASEBOARD_FAB2_LIB.BASEBOARD_FAB2(SCH_1):M_A_DQS_DP(15)   I120 @BASEBOARD_FAB2_LIB.BASEBOARD_FAB2(SCH_1):PAGE44
   133 M_A_DQS_DN<16> @BASEBOARD_FAB2_LIB.BASEBOARD_FAB2(SCH_1):M_A_DQS_DN(16)   I120 @BASEBOARD_FAB2_LIB.BASEBOARD_FAB2(SCH_1):PAGE44
   132 M_A_DQS_DP<16> @BASEBOARD_FAB2_LIB.BASEBOARD_FAB2(SCH_1):M_A_DQS_DP(16)   I120 @BASEBOARD_FAB2_LIB.BASEBOARD_FAB2(SCH_1):PAGE44
    52 M_A_DQS_DN<17> @BASEBOARD_FAB2_LIB.BASEBOARD_FAB2(SCH_1):M_A_DQS_DN(17)   I120 @BASEBOARD_FAB2_LIB.BASEBOARD_FAB2(SCH_1):PAGE44
    51 M_A_DQS_DP<17> @BASEBOARD_FAB2_LIB.BASEBOARD_FAB2(SCH_1):M_A_DQS_DP(17)   I120 @BASEBOARD_FAB2_LIB.BASEBOARD_FAB2(SCH_1):PAGE44
   163 M_A_DQS_DN<1> @BASEBOARD_FAB2_LIB.BASEBOARD_FAB2(SCH_1):M_A_DQS_DN(1)   I120 @BASEBOARD_FAB2_LIB.BASEBOARD_FAB2(SCH_1):PAGE44
   164 M_A_DQS_DP<1> @BASEBOARD_FAB2_LIB.BASEBOARD_FAB2(SCH_1):M_A_DQS_DP(1)   I120 @BASEBOARD_FAB2_LIB.BASEBOARD_FAB2(SCH_1):PAGE44
   174 M_A_DQS_DN<2> @BASEBOARD_FAB2_LIB.BASEBOARD_FAB2(SCH_1):M_A_DQS_DN(2)   I120 @BASEBOARD_FAB2_LIB.BASEBOARD_FAB2(SCH_1):PAGE44
   175 M_A_DQS_DP<2> @BASEBOARD_FAB2_LIB.BASEBOARD_FAB2(SCH_1):M_A_DQS_DP(2)   I120 @BASEBOARD_FAB2_LIB.BASEBOARD_FAB2(SCH_1):PAGE44
   185 M_A_DQS_DN<3> @BASEBOARD_FAB2_LIB.BASEBOARD_FAB2(SCH_1):M_A_DQS_DN(3)   I120 @BASEBOARD_FAB2_LIB.BASEBOARD_FAB2(SCH_1):PAGE44
   186 M_A_DQS_DP<3> @BASEBOARD_FAB2_LIB.BASEBOARD_FAB2(SCH_1):M_A_DQS_DP(3)   I120 @BASEBOARD_FAB2_LIB.BASEBOARD_FAB2(SCH_1):PAGE44
   244 M_A_DQS_DN<4> @BASEBOARD_FAB2_LIB.BASEBOARD_FAB2(SCH_1):M_A_DQS_DN(4)   I120 @BASEBOARD_FAB2_LIB.BASEBOARD_FAB2(SCH_1):PAGE44
   245 M_A_DQS_DP<4> @BASEBOARD_FAB2_LIB.BASEBOARD_FAB2(SCH_1):M_A_DQS_DP(4)   I120 @BASEBOARD_FAB2_LIB.BASEBOARD_FAB2(SCH_1):PAGE44
   255 M_A_DQS_DN<5> @BASEBOARD_FAB2_LIB.BASEBOARD_FAB2(SCH_1):M_A_DQS_DN(5)   I120 @BASEBOARD_FAB2_LIB.BASEBOARD_FAB2(SCH_1):PAGE44
   256 M_A_DQS_DP<5> @BASEBOARD_FAB2_LIB.BASEBOARD_FAB2(SCH_1):M_A_DQS_DP(5)   I120 @BASEBOARD_FAB2_LIB.BASEBOARD_FAB2(SCH_1):PAGE44
   266 M_A_DQS_DN<6> @BASEBOARD_FAB2_LIB.BASEBOARD_FAB2(SCH_1):M_A_DQS_DN(6)   I120 @BASEBOARD_FAB2_LIB.BASEBOARD_FAB2(SCH_1):PAGE44
   267 M_A_DQS_DP<6> @BASEBOARD_FAB2_LIB.BASEBOARD_FAB2(SCH_1):M_A_DQS_DP(6)   I120 @BASEBOARD_FAB2_LIB.BASEBOARD_FAB2(SCH_1):PAGE44
   277 M_A_DQS_DN<7> @BASEBOARD_FAB2_LIB.BASEBOARD_FAB2(SCH_1):M_A_DQS_DN(7)   I120 @BASEBOARD_FAB2_LIB.BASEBOARD_FAB2(SCH_1):PAGE44
   278 M_A_DQS_DP<7> @BASEBOARD_FAB2_LIB.BASEBOARD_FAB2(SCH_1):M_A_DQS_DP(7)   I120 @BASEBOARD_FAB2_LIB.BASEBOARD_FAB2(SCH_1):PAGE44
   196 M_A_DQS_DN<8> @BASEBOARD_FAB2_LIB.BASEBOARD_FAB2(SCH_1):M_A_DQS_DN(8)   I120 @BASEBOARD_FAB2_LIB.BASEBOARD_FAB2(SCH_1):PAGE44
   197 M_A_DQS_DP<8> @BASEBOARD_FAB2_LIB.BASEBOARD_FAB2(SCH_1):M_A_DQS_DP(8)   I120 @BASEBOARD_FAB2_LIB.BASEBOARD_FAB2(SCH_1):PAGE44
     8 M_A_DQS_DN<9> @BASEBOARD_FAB2_LIB.BASEBOARD_FAB2(SCH_1):M_A_DQS_DN(9)   I120 @BASEBOARD_FAB2_LIB.BASEBOARD_FAB2(SCH_1):PAGE44
     7 M_A_DQS_DP<9> @BASEBOARD_FAB2_LIB.BASEBOARD_FAB2(SCH_1):M_A_DQS_DP(9)   I120 @BASEBOARD_FAB2_LIB.BASEBOARD_FAB2(SCH_1):PAGE44
     2    GND @BASEBOARD_FAB2_LIB.BASEBOARD_FAB2(SCH_1):GND   I139 @BASEBOARD_FAB2_LIB.BASEBOARD_FAB2(SCH_1):PAGE44
     4    GND @BASEBOARD_FAB2_LIB.BASEBOARD_FAB2(SCH_1):GND   I139 @BASEBOARD_FAB2_LIB.BASEBOARD_FAB2(SCH_1):PAGE44
     6    GND @BASEBOARD_FAB2_LIB.BASEBOARD_FAB2(SCH_1):GND   I139 @BASEBOARD_FAB2_LIB.BASEBOARD_FAB2(SCH_1):PAGE44
     9    GND @BASEBOARD_FAB2_LIB.BASEBOARD_FAB2(SCH_1):GND   I139 @BASEBOARD_FAB2_LIB.BASEBOARD_FAB2(SCH_1):PAGE44
    11    GND @BASEBOARD_FAB2_LIB.BASEBOARD_FAB2(SCH_1):GND   I139 @BASEBOARD_FAB2_LIB.BASEBOARD_FAB2(SCH_1):PAGE44
    13    GND @BASEBOARD_FAB2_LIB.BASEBOARD_FAB2(SCH_1):GND   I139 @BASEBOARD_FAB2_LIB.BASEBOARD_FAB2(SCH_1):PAGE44
    15    GND @BASEBOARD_FAB2_LIB.BASEBOARD_FAB2(SCH_1):GND   I139 @BASEBOARD_FAB2_LIB.BASEBOARD_FAB2(SCH_1):PAGE44
    17    GND @BASEBOARD_FAB2_LIB.BASEBOARD_FAB2(SCH_1):GND   I139 @BASEBOARD_FAB2_LIB.BASEBOARD_FAB2(SCH_1):PAGE44
    20    GND @BASEBOARD_FAB2_LIB.BASEBOARD_FAB2(SCH_1):GND   I139 @BASEBOARD_FAB2_LIB.BASEBOARD_FAB2(SCH_1):PAGE44
    22    GND @BASEBOARD_FAB2_LIB.BASEBOARD_FAB2(SCH_1):GND   I139 @BASEBOARD_FAB2_LIB.BASEBOARD_FAB2(SCH_1):PAGE44
    24    GND @BASEBOARD_FAB2_LIB.BASEBOARD_FAB2(SCH_1):GND   I139 @BASEBOARD_FAB2_LIB.BASEBOARD_FAB2(SCH_1):PAGE44
    26    GND @BASEBOARD_FAB2_LIB.BASEBOARD_FAB2(SCH_1):GND   I139 @BASEBOARD_FAB2_LIB.BASEBOARD_FAB2(SCH_1):PAGE44
    28    GND @BASEBOARD_FAB2_LIB.BASEBOARD_FAB2(SCH_1):GND   I139 @BASEBOARD_FAB2_LIB.BASEBOARD_FAB2(SCH_1):PAGE44
    31    GND @BASEBOARD_FAB2_LIB.BASEBOARD_FAB2(SCH_1):GND   I139 @BASEBOARD_FAB2_LIB.BASEBOARD_FAB2(SCH_1):PAGE44
    33    GND @BASEBOARD_FAB2_LIB.BASEBOARD_FAB2(SCH_1):GND   I139 @BASEBOARD_FAB2_LIB.BASEBOARD_FAB2(SCH_1):PAGE44
    35    GND @BASEBOARD_FAB2_LIB.BASEBOARD_FAB2(SCH_1):GND   I139 @BASEBOARD_FAB2_LIB.BASEBOARD_FAB2(SCH_1):PAGE44
    37    GND @BASEBOARD_FAB2_LIB.BASEBOARD_FAB2(SCH_1):GND   I139 @BASEBOARD_FAB2_LIB.BASEBOARD_FAB2(SCH_1):PAGE44
    39    GND @BASEBOARD_FAB2_LIB.BASEBOARD_FAB2(SCH_1):GND   I139 @BASEBOARD_FAB2_LIB.BASEBOARD_FAB2(SCH_1):PAGE44
    42    GND @BASEBOARD_FAB2_LIB.BASEBOARD_FAB2(SCH_1):GND   I139 @BASEBOARD_FAB2_LIB.BASEBOARD_FAB2(SCH_1):PAGE44
    44    GND @BASEBOARD_FAB2_LIB.BASEBOARD_FAB2(SCH_1):GND   I139 @BASEBOARD_FAB2_LIB.BASEBOARD_FAB2(SCH_1):PAGE44
    46    GND @BASEBOARD_FAB2_LIB.BASEBOARD_FAB2(SCH_1):GND   I139 @BASEBOARD_FAB2_LIB.BASEBOARD_FAB2(SCH_1):PAGE44
    48    GND @BASEBOARD_FAB2_LIB.BASEBOARD_FAB2(SCH_1):GND   I139 @BASEBOARD_FAB2_LIB.BASEBOARD_FAB2(SCH_1):PAGE44
    50    GND @BASEBOARD_FAB2_LIB.BASEBOARD_FAB2(SCH_1):GND   I139 @BASEBOARD_FAB2_LIB.BASEBOARD_FAB2(SCH_1):PAGE44
    53    GND @BASEBOARD_FAB2_LIB.BASEBOARD_FAB2(SCH_1):GND   I139 @BASEBOARD_FAB2_LIB.BASEBOARD_FAB2(SCH_1):PAGE44
    55    GND @BASEBOARD_FAB2_LIB.BASEBOARD_FAB2(SCH_1):GND   I139 @BASEBOARD_FAB2_LIB.BASEBOARD_FAB2(SCH_1):PAGE44
    57    GND @BASEBOARD_FAB2_LIB.BASEBOARD_FAB2(SCH_1):GND   I139 @BASEBOARD_FAB2_LIB.BASEBOARD_FAB2(SCH_1):PAGE44
    94    GND @BASEBOARD_FAB2_LIB.BASEBOARD_FAB2(SCH_1):GND   I139 @BASEBOARD_FAB2_LIB.BASEBOARD_FAB2(SCH_1):PAGE44
    96    GND @BASEBOARD_FAB2_LIB.BASEBOARD_FAB2(SCH_1):GND   I139 @BASEBOARD_FAB2_LIB.BASEBOARD_FAB2(SCH_1):PAGE44
    98    GND @BASEBOARD_FAB2_LIB.BASEBOARD_FAB2(SCH_1):GND   I139 @BASEBOARD_FAB2_LIB.BASEBOARD_FAB2(SCH_1):PAGE44
   101    GND @BASEBOARD_FAB2_LIB.BASEBOARD_FAB2(SCH_1):GND   I139 @BASEBOARD_FAB2_LIB.BASEBOARD_FAB2(SCH_1):PAGE44
   103    GND @BASEBOARD_FAB2_LIB.BASEBOARD_FAB2(SCH_1):GND   I139 @BASEBOARD_FAB2_LIB.BASEBOARD_FAB2(SCH_1):PAGE44
   105    GND @BASEBOARD_FAB2_LIB.BASEBOARD_FAB2(SCH_1):GND   I139 @BASEBOARD_FAB2_LIB.BASEBOARD_FAB2(SCH_1):PAGE44
   107    GND @BASEBOARD_FAB2_LIB.BASEBOARD_FAB2(SCH_1):GND   I139 @BASEBOARD_FAB2_LIB.BASEBOARD_FAB2(SCH_1):PAGE44
   109    GND @BASEBOARD_FAB2_LIB.BASEBOARD_FAB2(SCH_1):GND   I139 @BASEBOARD_FAB2_LIB.BASEBOARD_FAB2(SCH_1):PAGE44
   112    GND @BASEBOARD_FAB2_LIB.BASEBOARD_FAB2(SCH_1):GND   I139 @BASEBOARD_FAB2_LIB.BASEBOARD_FAB2(SCH_1):PAGE44
   114    GND @BASEBOARD_FAB2_LIB.BASEBOARD_FAB2(SCH_1):GND   I139 @BASEBOARD_FAB2_LIB.BASEBOARD_FAB2(SCH_1):PAGE44
   116    GND @BASEBOARD_FAB2_LIB.BASEBOARD_FAB2(SCH_1):GND   I139 @BASEBOARD_FAB2_LIB.BASEBOARD_FAB2(SCH_1):PAGE44
   118    GND @BASEBOARD_FAB2_LIB.BASEBOARD_FAB2(SCH_1):GND   I139 @BASEBOARD_FAB2_LIB.BASEBOARD_FAB2(SCH_1):PAGE44
   120    GND @BASEBOARD_FAB2_LIB.BASEBOARD_FAB2(SCH_1):GND   I139 @BASEBOARD_FAB2_LIB.BASEBOARD_FAB2(SCH_1):PAGE44
   123    GND @BASEBOARD_FAB2_LIB.BASEBOARD_FAB2(SCH_1):GND   I139 @BASEBOARD_FAB2_LIB.BASEBOARD_FAB2(SCH_1):PAGE44
   125    GND @BASEBOARD_FAB2_LIB.BASEBOARD_FAB2(SCH_1):GND   I139 @BASEBOARD_FAB2_LIB.BASEBOARD_FAB2(SCH_1):PAGE44
   127    GND @BASEBOARD_FAB2_LIB.BASEBOARD_FAB2(SCH_1):GND   I139 @BASEBOARD_FAB2_LIB.BASEBOARD_FAB2(SCH_1):PAGE44
   129    GND @BASEBOARD_FAB2_LIB.BASEBOARD_FAB2(SCH_1):GND   I139 @BASEBOARD_FAB2_LIB.BASEBOARD_FAB2(SCH_1):PAGE44
   131    GND @BASEBOARD_FAB2_LIB.BASEBOARD_FAB2(SCH_1):GND   I139 @BASEBOARD_FAB2_LIB.BASEBOARD_FAB2(SCH_1):PAGE44
   134    GND @BASEBOARD_FAB2_LIB.BASEBOARD_FAB2(SCH_1):GND   I139 @BASEBOARD_FAB2_LIB.BASEBOARD_FAB2(SCH_1):PAGE44
   136    GND @BASEBOARD_FAB2_LIB.BASEBOARD_FAB2(SCH_1):GND   I139 @BASEBOARD_FAB2_LIB.BASEBOARD_FAB2(SCH_1):PAGE44
   138    GND @BASEBOARD_FAB2_LIB.BASEBOARD_FAB2(SCH_1):GND   I139 @BASEBOARD_FAB2_LIB.BASEBOARD_FAB2(SCH_1):PAGE44
   147    GND @BASEBOARD_FAB2_LIB.BASEBOARD_FAB2(SCH_1):GND   I139 @BASEBOARD_FAB2_LIB.BASEBOARD_FAB2(SCH_1):PAGE44
   149    GND @BASEBOARD_FAB2_LIB.BASEBOARD_FAB2(SCH_1):GND   I139 @BASEBOARD_FAB2_LIB.BASEBOARD_FAB2(SCH_1):PAGE44
   151    GND @BASEBOARD_FAB2_LIB.BASEBOARD_FAB2(SCH_1):GND   I139 @BASEBOARD_FAB2_LIB.BASEBOARD_FAB2(SCH_1):PAGE44
   154    GND @BASEBOARD_FAB2_LIB.BASEBOARD_FAB2(SCH_1):GND   I139 @BASEBOARD_FAB2_LIB.BASEBOARD_FAB2(SCH_1):PAGE44
   156    GND @BASEBOARD_FAB2_LIB.BASEBOARD_FAB2(SCH_1):GND   I139 @BASEBOARD_FAB2_LIB.BASEBOARD_FAB2(SCH_1):PAGE44
   158    GND @BASEBOARD_FAB2_LIB.BASEBOARD_FAB2(SCH_1):GND   I139 @BASEBOARD_FAB2_LIB.BASEBOARD_FAB2(SCH_1):PAGE44
   160    GND @BASEBOARD_FAB2_LIB.BASEBOARD_FAB2(SCH_1):GND   I139 @BASEBOARD_FAB2_LIB.BASEBOARD_FAB2(SCH_1):PAGE44
   162    GND @BASEBOARD_FAB2_LIB.BASEBOARD_FAB2(SCH_1):GND   I139 @BASEBOARD_FAB2_LIB.BASEBOARD_FAB2(SCH_1):PAGE44
   165    GND @BASEBOARD_FAB2_LIB.BASEBOARD_FAB2(SCH_1):GND   I139 @BASEBOARD_FAB2_LIB.BASEBOARD_FAB2(SCH_1):PAGE44
   167    GND @BASEBOARD_FAB2_LIB.BASEBOARD_FAB2(SCH_1):GND   I139 @BASEBOARD_FAB2_LIB.BASEBOARD_FAB2(SCH_1):PAGE44
   169    GND @BASEBOARD_FAB2_LIB.BASEBOARD_FAB2(SCH_1):GND   I139 @BASEBOARD_FAB2_LIB.BASEBOARD_FAB2(SCH_1):PAGE44
   171    GND @BASEBOARD_FAB2_LIB.BASEBOARD_FAB2(SCH_1):GND   I139 @BASEBOARD_FAB2_LIB.BASEBOARD_FAB2(SCH_1):PAGE44
   173    GND @BASEBOARD_FAB2_LIB.BASEBOARD_FAB2(SCH_1):GND   I139 @BASEBOARD_FAB2_LIB.BASEBOARD_FAB2(SCH_1):PAGE44
   176    GND @BASEBOARD_FAB2_LIB.BASEBOARD_FAB2(SCH_1):GND   I139 @BASEBOARD_FAB2_LIB.BASEBOARD_FAB2(SCH_1):PAGE44
   178    GND @BASEBOARD_FAB2_LIB.BASEBOARD_FAB2(SCH_1):GND   I139 @BASEBOARD_FAB2_LIB.BASEBOARD_FAB2(SCH_1):PAGE44
   180    GND @BASEBOARD_FAB2_LIB.BASEBOARD_FAB2(SCH_1):GND   I139 @BASEBOARD_FAB2_LIB.BASEBOARD_FAB2(SCH_1):PAGE44
   182    GND @BASEBOARD_FAB2_LIB.BASEBOARD_FAB2(SCH_1):GND   I139 @BASEBOARD_FAB2_LIB.BASEBOARD_FAB2(SCH_1):PAGE44
   184    GND @BASEBOARD_FAB2_LIB.BASEBOARD_FAB2(SCH_1):GND   I139 @BASEBOARD_FAB2_LIB.BASEBOARD_FAB2(SCH_1):PAGE44
   187    GND @BASEBOARD_FAB2_LIB.BASEBOARD_FAB2(SCH_1):GND   I139 @BASEBOARD_FAB2_LIB.BASEBOARD_FAB2(SCH_1):PAGE44
   189    GND @BASEBOARD_FAB2_LIB.BASEBOARD_FAB2(SCH_1):GND   I139 @BASEBOARD_FAB2_LIB.BASEBOARD_FAB2(SCH_1):PAGE44
   191    GND @BASEBOARD_FAB2_LIB.BASEBOARD_FAB2(SCH_1):GND   I139 @BASEBOARD_FAB2_LIB.BASEBOARD_FAB2(SCH_1):PAGE44
   193    GND @BASEBOARD_FAB2_LIB.BASEBOARD_FAB2(SCH_1):GND   I139 @BASEBOARD_FAB2_LIB.BASEBOARD_FAB2(SCH_1):PAGE44
   195    GND @BASEBOARD_FAB2_LIB.BASEBOARD_FAB2(SCH_1):GND   I139 @BASEBOARD_FAB2_LIB.BASEBOARD_FAB2(SCH_1):PAGE44
   198    GND @BASEBOARD_FAB2_LIB.BASEBOARD_FAB2(SCH_1):GND   I139 @BASEBOARD_FAB2_LIB.BASEBOARD_FAB2(SCH_1):PAGE44
   200    GND @BASEBOARD_FAB2_LIB.BASEBOARD_FAB2(SCH_1):GND   I139 @BASEBOARD_FAB2_LIB.BASEBOARD_FAB2(SCH_1):PAGE44
   202    GND @BASEBOARD_FAB2_LIB.BASEBOARD_FAB2(SCH_1):GND   I139 @BASEBOARD_FAB2_LIB.BASEBOARD_FAB2(SCH_1):PAGE44
   239    GND @BASEBOARD_FAB2_LIB.BASEBOARD_FAB2(SCH_1):GND   I139 @BASEBOARD_FAB2_LIB.BASEBOARD_FAB2(SCH_1):PAGE44
   241    GND @BASEBOARD_FAB2_LIB.BASEBOARD_FAB2(SCH_1):GND   I139 @BASEBOARD_FAB2_LIB.BASEBOARD_FAB2(SCH_1):PAGE44
   243    GND @BASEBOARD_FAB2_LIB.BASEBOARD_FAB2(SCH_1):GND   I139 @BASEBOARD_FAB2_LIB.BASEBOARD_FAB2(SCH_1):PAGE44
   246    GND @BASEBOARD_FAB2_LIB.BASEBOARD_FAB2(SCH_1):GND   I139 @BASEBOARD_FAB2_LIB.BASEBOARD_FAB2(SCH_1):PAGE44
   248    GND @BASEBOARD_FAB2_LIB.BASEBOARD_FAB2(SCH_1):GND   I139 @BASEBOARD_FAB2_LIB.BASEBOARD_FAB2(SCH_1):PAGE44
   250    GND @BASEBOARD_FAB2_LIB.BASEBOARD_FAB2(SCH_1):GND   I139 @BASEBOARD_FAB2_LIB.BASEBOARD_FAB2(SCH_1):PAGE44
   252    GND @BASEBOARD_FAB2_LIB.BASEBOARD_FAB2(SCH_1):GND   I139 @BASEBOARD_FAB2_LIB.BASEBOARD_FAB2(SCH_1):PAGE44
   254    GND @BASEBOARD_FAB2_LIB.BASEBOARD_FAB2(SCH_1):GND   I139 @BASEBOARD_FAB2_LIB.BASEBOARD_FAB2(SCH_1):PAGE44
   257    GND @BASEBOARD_FAB2_LIB.BASEBOARD_FAB2(SCH_1):GND   I139 @BASEBOARD_FAB2_LIB.BASEBOARD_FAB2(SCH_1):PAGE44
   259    GND @BASEBOARD_FAB2_LIB.BASEBOARD_FAB2(SCH_1):GND   I139 @BASEBOARD_FAB2_LIB.BASEBOARD_FAB2(SCH_1):PAGE44
   261    GND @BASEBOARD_FAB2_LIB.BASEBOARD_FAB2(SCH_1):GND   I139 @BASEBOARD_FAB2_LIB.BASEBOARD_FAB2(SCH_1):PAGE44
   263    GND @BASEBOARD_FAB2_LIB.BASEBOARD_FAB2(SCH_1):GND   I139 @BASEBOARD_FAB2_LIB.BASEBOARD_FAB2(SCH_1):PAGE44
   265    GND @BASEBOARD_FAB2_LIB.BASEBOARD_FAB2(SCH_1):GND   I139 @BASEBOARD_FAB2_LIB.BASEBOARD_FAB2(SCH_1):PAGE44
   268    GND @BASEBOARD_FAB2_LIB.BASEBOARD_FAB2(SCH_1):GND   I139 @BASEBOARD_FAB2_LIB.BASEBOARD_FAB2(SCH_1):PAGE44
   270    GND @BASEBOARD_FAB2_LIB.BASEBOARD_FAB2(SCH_1):GND   I139 @BASEBOARD_FAB2_LIB.BASEBOARD_FAB2(SCH_1):PAGE44
   272    GND @BASEBOARD_FAB2_LIB.BASEBOARD_FAB2(SCH_1):GND   I139 @BASEBOARD_FAB2_LIB.BASEBOARD_FAB2(SCH_1):PAGE44
   274    GND @BASEBOARD_FAB2_LIB.BASEBOARD_FAB2(SCH_1):GND   I139 @BASEBOARD_FAB2_LIB.BASEBOARD_FAB2(SCH_1):PAGE44
   276    GND @BASEBOARD_FAB2_LIB.BASEBOARD_FAB2(SCH_1):GND   I139 @BASEBOARD_FAB2_LIB.BASEBOARD_FAB2(SCH_1):PAGE44
   279    GND @BASEBOARD_FAB2_LIB.BASEBOARD_FAB2(SCH_1):GND   I139 @BASEBOARD_FAB2_LIB.BASEBOARD_FAB2(SCH_1):PAGE44
   281    GND @BASEBOARD_FAB2_LIB.BASEBOARD_FAB2(SCH_1):GND   I139 @BASEBOARD_FAB2_LIB.BASEBOARD_FAB2(SCH_1):PAGE44
   283    GND @BASEBOARD_FAB2_LIB.BASEBOARD_FAB2(SCH_1):GND   I139 @BASEBOARD_FAB2_LIB.BASEBOARD_FAB2(SCH_1):PAGE44
     1 P12V_NVDIMM_ABC @BASEBOARD_FAB2_LIB.BASEBOARD_FAB2(SCH_1):P12V_NVDIMM_ABC    I75 @BASEBOARD_FAB2_LIB.BASEBOARD_FAB2(SCH_1):PAGE44
   145 P12V_NVDIMM_ABC @BASEBOARD_FAB2_LIB.BASEBOARD_FAB2(SCH_1):P12V_NVDIMM_ABC    I75 @BASEBOARD_FAB2_LIB.BASEBOARD_FAB2(SCH_1):PAGE44
    59 PVDDQ_ABC @BASEBOARD_FAB2_LIB.BASEBOARD_FAB2(SCH_1):PVDDQ_ABC    I75 @BASEBOARD_FAB2_LIB.BASEBOARD_FAB2(SCH_1):PAGE44
    61 PVDDQ_ABC @BASEBOARD_FAB2_LIB.BASEBOARD_FAB2(SCH_1):PVDDQ_ABC    I75 @BASEBOARD_FAB2_LIB.BASEBOARD_FAB2(SCH_1):PAGE44
    64 PVDDQ_ABC @BASEBOARD_FAB2_LIB.BASEBOARD_FAB2(SCH_1):PVDDQ_ABC    I75 @BASEBOARD_FAB2_LIB.BASEBOARD_FAB2(SCH_1):PAGE44
    67 PVDDQ_ABC @BASEBOARD_FAB2_LIB.BASEBOARD_FAB2(SCH_1):PVDDQ_ABC    I75 @BASEBOARD_FAB2_LIB.BASEBOARD_FAB2(SCH_1):PAGE44
    70 PVDDQ_ABC @BASEBOARD_FAB2_LIB.BASEBOARD_FAB2(SCH_1):PVDDQ_ABC    I75 @BASEBOARD_FAB2_LIB.BASEBOARD_FAB2(SCH_1):PAGE44
    73 PVDDQ_ABC @BASEBOARD_FAB2_LIB.BASEBOARD_FAB2(SCH_1):PVDDQ_ABC    I75 @BASEBOARD_FAB2_LIB.BASEBOARD_FAB2(SCH_1):PAGE44
    76 PVDDQ_ABC @BASEBOARD_FAB2_LIB.BASEBOARD_FAB2(SCH_1):PVDDQ_ABC    I75 @BASEBOARD_FAB2_LIB.BASEBOARD_FAB2(SCH_1):PAGE44
    80 PVDDQ_ABC @BASEBOARD_FAB2_LIB.BASEBOARD_FAB2(SCH_1):PVDDQ_ABC    I75 @BASEBOARD_FAB2_LIB.BASEBOARD_FAB2(SCH_1):PAGE44
    83 PVDDQ_ABC @BASEBOARD_FAB2_LIB.BASEBOARD_FAB2(SCH_1):PVDDQ_ABC    I75 @BASEBOARD_FAB2_LIB.BASEBOARD_FAB2(SCH_1):PAGE44
    85 PVDDQ_ABC @BASEBOARD_FAB2_LIB.BASEBOARD_FAB2(SCH_1):PVDDQ_ABC    I75 @BASEBOARD_FAB2_LIB.BASEBOARD_FAB2(SCH_1):PAGE44
    88 PVDDQ_ABC @BASEBOARD_FAB2_LIB.BASEBOARD_FAB2(SCH_1):PVDDQ_ABC    I75 @BASEBOARD_FAB2_LIB.BASEBOARD_FAB2(SCH_1):PAGE44
    90 PVDDQ_ABC @BASEBOARD_FAB2_LIB.BASEBOARD_FAB2(SCH_1):PVDDQ_ABC    I75 @BASEBOARD_FAB2_LIB.BASEBOARD_FAB2(SCH_1):PAGE44
    92 PVDDQ_ABC @BASEBOARD_FAB2_LIB.BASEBOARD_FAB2(SCH_1):PVDDQ_ABC    I75 @BASEBOARD_FAB2_LIB.BASEBOARD_FAB2(SCH_1):PAGE44
   204 PVDDQ_ABC @BASEBOARD_FAB2_LIB.BASEBOARD_FAB2(SCH_1):PVDDQ_ABC    I75 @BASEBOARD_FAB2_LIB.BASEBOARD_FAB2(SCH_1):PAGE44
   206 PVDDQ_ABC @BASEBOARD_FAB2_LIB.BASEBOARD_FAB2(SCH_1):PVDDQ_ABC    I75 @BASEBOARD_FAB2_LIB.BASEBOARD_FAB2(SCH_1):PAGE44
   209 PVDDQ_ABC @BASEBOARD_FAB2_LIB.BASEBOARD_FAB2(SCH_1):PVDDQ_ABC    I75 @BASEBOARD_FAB2_LIB.BASEBOARD_FAB2(SCH_1):PAGE44
   212 PVDDQ_ABC @BASEBOARD_FAB2_LIB.BASEBOARD_FAB2(SCH_1):PVDDQ_ABC    I75 @BASEBOARD_FAB2_LIB.BASEBOARD_FAB2(SCH_1):PAGE44
   215 PVDDQ_ABC @BASEBOARD_FAB2_LIB.BASEBOARD_FAB2(SCH_1):PVDDQ_ABC    I75 @BASEBOARD_FAB2_LIB.BASEBOARD_FAB2(SCH_1):PAGE44
   217 PVDDQ_ABC @BASEBOARD_FAB2_LIB.BASEBOARD_FAB2(SCH_1):PVDDQ_ABC    I75 @BASEBOARD_FAB2_LIB.BASEBOARD_FAB2(SCH_1):PAGE44
   220 PVDDQ_ABC @BASEBOARD_FAB2_LIB.BASEBOARD_FAB2(SCH_1):PVDDQ_ABC    I75 @BASEBOARD_FAB2_LIB.BASEBOARD_FAB2(SCH_1):PAGE44
   223 PVDDQ_ABC @BASEBOARD_FAB2_LIB.BASEBOARD_FAB2(SCH_1):PVDDQ_ABC    I75 @BASEBOARD_FAB2_LIB.BASEBOARD_FAB2(SCH_1):PAGE44
   226 PVDDQ_ABC @BASEBOARD_FAB2_LIB.BASEBOARD_FAB2(SCH_1):PVDDQ_ABC    I75 @BASEBOARD_FAB2_LIB.BASEBOARD_FAB2(SCH_1):PAGE44
   229 PVDDQ_ABC @BASEBOARD_FAB2_LIB.BASEBOARD_FAB2(SCH_1):PVDDQ_ABC    I75 @BASEBOARD_FAB2_LIB.BASEBOARD_FAB2(SCH_1):PAGE44
   231 PVDDQ_ABC @BASEBOARD_FAB2_LIB.BASEBOARD_FAB2(SCH_1):PVDDQ_ABC    I75 @BASEBOARD_FAB2_LIB.BASEBOARD_FAB2(SCH_1):PAGE44
   233 PVDDQ_ABC @BASEBOARD_FAB2_LIB.BASEBOARD_FAB2(SCH_1):PVDDQ_ABC    I75 @BASEBOARD_FAB2_LIB.BASEBOARD_FAB2(SCH_1):PAGE44
   236 PVDDQ_ABC @BASEBOARD_FAB2_LIB.BASEBOARD_FAB2(SCH_1):PVDDQ_ABC    I75 @BASEBOARD_FAB2_LIB.BASEBOARD_FAB2(SCH_1):PAGE44
   142 PVPP_ABC @BASEBOARD_FAB2_LIB.BASEBOARD_FAB2(SCH_1):PVPP_ABC    I75 @BASEBOARD_FAB2_LIB.BASEBOARD_FAB2(SCH_1):PAGE44
   143 PVPP_ABC @BASEBOARD_FAB2_LIB.BASEBOARD_FAB2(SCH_1):PVPP_ABC    I75 @BASEBOARD_FAB2_LIB.BASEBOARD_FAB2(SCH_1):PAGE44
   288 PVPP_ABC @BASEBOARD_FAB2_LIB.BASEBOARD_FAB2(SCH_1):PVPP_ABC    I75 @BASEBOARD_FAB2_LIB.BASEBOARD_FAB2(SCH_1):PAGE44
   286 PVPP_ABC @BASEBOARD_FAB2_LIB.BASEBOARD_FAB2(SCH_1):PVPP_ABC    I75 @BASEBOARD_FAB2_LIB.BASEBOARD_FAB2(SCH_1):PAGE44
   287 PVPP_ABC @BASEBOARD_FAB2_LIB.BASEBOARD_FAB2(SCH_1):PVPP_ABC    I75 @BASEBOARD_FAB2_LIB.BASEBOARD_FAB2(SCH_1):PAGE44
    77 PVTT_ABC @BASEBOARD_FAB2_LIB.BASEBOARD_FAB2(SCH_1):PVTT_ABC    I75 @BASEBOARD_FAB2_LIB.BASEBOARD_FAB2(SCH_1):PAGE44
   221 PVTT_ABC @BASEBOARD_FAB2_LIB.BASEBOARD_FAB2(SCH_1):PVTT_ABC    I75 @BASEBOARD_FAB2_LIB.BASEBOARD_FAB2(SCH_1):PAGE44

J6U1 SCONN288_H44441003_PIP-SCONN,HA
    79 M_B_MA<0> @BASEBOARD_FAB2_LIB.BASEBOARD_FAB2(SCH_1):M_B_MA(0)    I14 @BASEBOARD_FAB2_LIB.BASEBOARD_FAB2(SCH_1):PAGE46
    72 M_B_MA<1> @BASEBOARD_FAB2_LIB.BASEBOARD_FAB2(SCH_1):M_B_MA(1)    I14 @BASEBOARD_FAB2_LIB.BASEBOARD_FAB2(SCH_1):PAGE46
   225 M_B_MA<10> @BASEBOARD_FAB2_LIB.BASEBOARD_FAB2(SCH_1):M_B_MA(10)    I14 @BASEBOARD_FAB2_LIB.BASEBOARD_FAB2(SCH_1):PAGE46
   210 M_B_MA<11> @BASEBOARD_FAB2_LIB.BASEBOARD_FAB2(SCH_1):M_B_MA(11)    I14 @BASEBOARD_FAB2_LIB.BASEBOARD_FAB2(SCH_1):PAGE46
    65 M_B_MA<12> @BASEBOARD_FAB2_LIB.BASEBOARD_FAB2(SCH_1):M_B_MA(12)    I14 @BASEBOARD_FAB2_LIB.BASEBOARD_FAB2(SCH_1):PAGE46
   232 M_B_MA<13> @BASEBOARD_FAB2_LIB.BASEBOARD_FAB2(SCH_1):M_B_MA(13)    I14 @BASEBOARD_FAB2_LIB.BASEBOARD_FAB2(SCH_1):PAGE46
   228 M_B_MA<14> @BASEBOARD_FAB2_LIB.BASEBOARD_FAB2(SCH_1):M_B_MA(14)    I14 @BASEBOARD_FAB2_LIB.BASEBOARD_FAB2(SCH_1):PAGE46
    86 M_B_MA<15> @BASEBOARD_FAB2_LIB.BASEBOARD_FAB2(SCH_1):M_B_MA(15)    I14 @BASEBOARD_FAB2_LIB.BASEBOARD_FAB2(SCH_1):PAGE46
    82 M_B_MA<16> @BASEBOARD_FAB2_LIB.BASEBOARD_FAB2(SCH_1):M_B_MA(16)    I14 @BASEBOARD_FAB2_LIB.BASEBOARD_FAB2(SCH_1):PAGE46
   234 M_B_MA<17> @BASEBOARD_FAB2_LIB.BASEBOARD_FAB2(SCH_1):M_B_MA(17)    I14 @BASEBOARD_FAB2_LIB.BASEBOARD_FAB2(SCH_1):PAGE46
   216 M_B_MA<2> @BASEBOARD_FAB2_LIB.BASEBOARD_FAB2(SCH_1):M_B_MA(2)    I14 @BASEBOARD_FAB2_LIB.BASEBOARD_FAB2(SCH_1):PAGE46
    71 M_B_MA<3> @BASEBOARD_FAB2_LIB.BASEBOARD_FAB2(SCH_1):M_B_MA(3)    I14 @BASEBOARD_FAB2_LIB.BASEBOARD_FAB2(SCH_1):PAGE46
   214 M_B_MA<4> @BASEBOARD_FAB2_LIB.BASEBOARD_FAB2(SCH_1):M_B_MA(4)    I14 @BASEBOARD_FAB2_LIB.BASEBOARD_FAB2(SCH_1):PAGE46
   213 M_B_MA<5> @BASEBOARD_FAB2_LIB.BASEBOARD_FAB2(SCH_1):M_B_MA(5)    I14 @BASEBOARD_FAB2_LIB.BASEBOARD_FAB2(SCH_1):PAGE46
    69 M_B_MA<6> @BASEBOARD_FAB2_LIB.BASEBOARD_FAB2(SCH_1):M_B_MA(6)    I14 @BASEBOARD_FAB2_LIB.BASEBOARD_FAB2(SCH_1):PAGE46
   211 M_B_MA<7> @BASEBOARD_FAB2_LIB.BASEBOARD_FAB2(SCH_1):M_B_MA(7)    I14 @BASEBOARD_FAB2_LIB.BASEBOARD_FAB2(SCH_1):PAGE46
    68 M_B_MA<8> @BASEBOARD_FAB2_LIB.BASEBOARD_FAB2(SCH_1):M_B_MA(8)    I14 @BASEBOARD_FAB2_LIB.BASEBOARD_FAB2(SCH_1):PAGE46
    66 M_B_MA<9> @BASEBOARD_FAB2_LIB.BASEBOARD_FAB2(SCH_1):M_B_MA(9)    I14 @BASEBOARD_FAB2_LIB.BASEBOARD_FAB2(SCH_1):PAGE46
    62 M_B_ACT_N @BASEBOARD_FAB2_LIB.BASEBOARD_FAB2(SCH_1):M_B_ACT_N    I14 @BASEBOARD_FAB2_LIB.BASEBOARD_FAB2(SCH_1):PAGE46
   208 M_B_ALERT_N @BASEBOARD_FAB2_LIB.BASEBOARD_FAB2(SCH_1):M_B_ALERT_N    I14 @BASEBOARD_FAB2_LIB.BASEBOARD_FAB2(SCH_1):PAGE46
   224 M_B_BA<1> @BASEBOARD_FAB2_LIB.BASEBOARD_FAB2(SCH_1):M_B_BA(1)    I14 @BASEBOARD_FAB2_LIB.BASEBOARD_FAB2(SCH_1):PAGE46
    81 M_B_BA<0> @BASEBOARD_FAB2_LIB.BASEBOARD_FAB2(SCH_1):M_B_BA(0)    I14 @BASEBOARD_FAB2_LIB.BASEBOARD_FAB2(SCH_1):PAGE46
   207 M_B_BG<1> @BASEBOARD_FAB2_LIB.BASEBOARD_FAB2(SCH_1):M_B_BG(1)    I14 @BASEBOARD_FAB2_LIB.BASEBOARD_FAB2(SCH_1):PAGE46
    63 M_B_BG<0> @BASEBOARD_FAB2_LIB.BASEBOARD_FAB2(SCH_1):M_B_BG(0)    I14 @BASEBOARD_FAB2_LIB.BASEBOARD_FAB2(SCH_1):PAGE46
   235 M_B_C<2> @BASEBOARD_FAB2_LIB.BASEBOARD_FAB2(SCH_1):M_B_C(2)    I14 @BASEBOARD_FAB2_LIB.BASEBOARD_FAB2(SCH_1):PAGE46
   199 M_B_ECC<7> @BASEBOARD_FAB2_LIB.BASEBOARD_FAB2(SCH_1):M_B_ECC(7)    I14 @BASEBOARD_FAB2_LIB.BASEBOARD_FAB2(SCH_1):PAGE46
    54 M_B_ECC<6> @BASEBOARD_FAB2_LIB.BASEBOARD_FAB2(SCH_1):M_B_ECC(6)    I14 @BASEBOARD_FAB2_LIB.BASEBOARD_FAB2(SCH_1):PAGE46
   192 M_B_ECC<5> @BASEBOARD_FAB2_LIB.BASEBOARD_FAB2(SCH_1):M_B_ECC(5)    I14 @BASEBOARD_FAB2_LIB.BASEBOARD_FAB2(SCH_1):PAGE46
    47 M_B_ECC<4> @BASEBOARD_FAB2_LIB.BASEBOARD_FAB2(SCH_1):M_B_ECC(4)    I14 @BASEBOARD_FAB2_LIB.BASEBOARD_FAB2(SCH_1):PAGE46
   201 M_B_ECC<3> @BASEBOARD_FAB2_LIB.BASEBOARD_FAB2(SCH_1):M_B_ECC(3)    I14 @BASEBOARD_FAB2_LIB.BASEBOARD_FAB2(SCH_1):PAGE46
    56 M_B_ECC<2> @BASEBOARD_FAB2_LIB.BASEBOARD_FAB2(SCH_1):M_B_ECC(2)    I14 @BASEBOARD_FAB2_LIB.BASEBOARD_FAB2(SCH_1):PAGE46
   194 M_B_ECC<1> @BASEBOARD_FAB2_LIB.BASEBOARD_FAB2(SCH_1):M_B_ECC(1)    I14 @BASEBOARD_FAB2_LIB.BASEBOARD_FAB2(SCH_1):PAGE46
    49 M_B_ECC<0> @BASEBOARD_FAB2_LIB.BASEBOARD_FAB2(SCH_1):M_B_ECC(0)    I14 @BASEBOARD_FAB2_LIB.BASEBOARD_FAB2(SCH_1):PAGE46
    75 M_B_CLK_DN<2> @BASEBOARD_FAB2_LIB.BASEBOARD_FAB2(SCH_1):M_B_CLK_DN(2)    I14 @BASEBOARD_FAB2_LIB.BASEBOARD_FAB2(SCH_1):PAGE46
    74 M_B_CLK_DP<2> @BASEBOARD_FAB2_LIB.BASEBOARD_FAB2(SCH_1):M_B_CLK_DP(2)    I14 @BASEBOARD_FAB2_LIB.BASEBOARD_FAB2(SCH_1):PAGE46
   219 M_B_CLK_DN<3> @BASEBOARD_FAB2_LIB.BASEBOARD_FAB2(SCH_1):M_B_CLK_DN(3)    I14 @BASEBOARD_FAB2_LIB.BASEBOARD_FAB2(SCH_1):PAGE46
   218 M_B_CLK_DP<3> @BASEBOARD_FAB2_LIB.BASEBOARD_FAB2(SCH_1):M_B_CLK_DP(3)    I14 @BASEBOARD_FAB2_LIB.BASEBOARD_FAB2(SCH_1):PAGE46
   203 M_B_CKE<3> @BASEBOARD_FAB2_LIB.BASEBOARD_FAB2(SCH_1):M_B_CKE(3)    I14 @BASEBOARD_FAB2_LIB.BASEBOARD_FAB2(SCH_1):PAGE46
    60 M_B_CKE<2> @BASEBOARD_FAB2_LIB.BASEBOARD_FAB2(SCH_1):M_B_CKE(2)    I14 @BASEBOARD_FAB2_LIB.BASEBOARD_FAB2(SCH_1):PAGE46
   280 M_B_DQ<63> @BASEBOARD_FAB2_LIB.BASEBOARD_FAB2(SCH_1):M_B_DQ(63)    I14 @BASEBOARD_FAB2_LIB.BASEBOARD_FAB2(SCH_1):PAGE46
   135 M_B_DQ<62> @BASEBOARD_FAB2_LIB.BASEBOARD_FAB2(SCH_1):M_B_DQ(62)    I14 @BASEBOARD_FAB2_LIB.BASEBOARD_FAB2(SCH_1):PAGE46
   273 M_B_DQ<61> @BASEBOARD_FAB2_LIB.BASEBOARD_FAB2(SCH_1):M_B_DQ(61)    I14 @BASEBOARD_FAB2_LIB.BASEBOARD_FAB2(SCH_1):PAGE46
   128 M_B_DQ<60> @BASEBOARD_FAB2_LIB.BASEBOARD_FAB2(SCH_1):M_B_DQ(60)    I14 @BASEBOARD_FAB2_LIB.BASEBOARD_FAB2(SCH_1):PAGE46
   282 M_B_DQ<59> @BASEBOARD_FAB2_LIB.BASEBOARD_FAB2(SCH_1):M_B_DQ(59)    I14 @BASEBOARD_FAB2_LIB.BASEBOARD_FAB2(SCH_1):PAGE46
   137 M_B_DQ<58> @BASEBOARD_FAB2_LIB.BASEBOARD_FAB2(SCH_1):M_B_DQ(58)    I14 @BASEBOARD_FAB2_LIB.BASEBOARD_FAB2(SCH_1):PAGE46
   275 M_B_DQ<57> @BASEBOARD_FAB2_LIB.BASEBOARD_FAB2(SCH_1):M_B_DQ(57)    I14 @BASEBOARD_FAB2_LIB.BASEBOARD_FAB2(SCH_1):PAGE46
   130 M_B_DQ<56> @BASEBOARD_FAB2_LIB.BASEBOARD_FAB2(SCH_1):M_B_DQ(56)    I14 @BASEBOARD_FAB2_LIB.BASEBOARD_FAB2(SCH_1):PAGE46
   269 M_B_DQ<55> @BASEBOARD_FAB2_LIB.BASEBOARD_FAB2(SCH_1):M_B_DQ(55)    I14 @BASEBOARD_FAB2_LIB.BASEBOARD_FAB2(SCH_1):PAGE46
   124 M_B_DQ<54> @BASEBOARD_FAB2_LIB.BASEBOARD_FAB2(SCH_1):M_B_DQ(54)    I14 @BASEBOARD_FAB2_LIB.BASEBOARD_FAB2(SCH_1):PAGE46
   262 M_B_DQ<53> @BASEBOARD_FAB2_LIB.BASEBOARD_FAB2(SCH_1):M_B_DQ(53)    I14 @BASEBOARD_FAB2_LIB.BASEBOARD_FAB2(SCH_1):PAGE46
   117 M_B_DQ<52> @BASEBOARD_FAB2_LIB.BASEBOARD_FAB2(SCH_1):M_B_DQ(52)    I14 @BASEBOARD_FAB2_LIB.BASEBOARD_FAB2(SCH_1):PAGE46
   271 M_B_DQ<51> @BASEBOARD_FAB2_LIB.BASEBOARD_FAB2(SCH_1):M_B_DQ(51)    I14 @BASEBOARD_FAB2_LIB.BASEBOARD_FAB2(SCH_1):PAGE46
   126 M_B_DQ<50> @BASEBOARD_FAB2_LIB.BASEBOARD_FAB2(SCH_1):M_B_DQ(50)    I14 @BASEBOARD_FAB2_LIB.BASEBOARD_FAB2(SCH_1):PAGE46
   264 M_B_DQ<49> @BASEBOARD_FAB2_LIB.BASEBOARD_FAB2(SCH_1):M_B_DQ(49)    I14 @BASEBOARD_FAB2_LIB.BASEBOARD_FAB2(SCH_1):PAGE46
   119 M_B_DQ<48> @BASEBOARD_FAB2_LIB.BASEBOARD_FAB2(SCH_1):M_B_DQ(48)    I14 @BASEBOARD_FAB2_LIB.BASEBOARD_FAB2(SCH_1):PAGE46
   258 M_B_DQ<47> @BASEBOARD_FAB2_LIB.BASEBOARD_FAB2(SCH_1):M_B_DQ(47)    I14 @BASEBOARD_FAB2_LIB.BASEBOARD_FAB2(SCH_1):PAGE46
   113 M_B_DQ<46> @BASEBOARD_FAB2_LIB.BASEBOARD_FAB2(SCH_1):M_B_DQ(46)    I14 @BASEBOARD_FAB2_LIB.BASEBOARD_FAB2(SCH_1):PAGE46
   251 M_B_DQ<45> @BASEBOARD_FAB2_LIB.BASEBOARD_FAB2(SCH_1):M_B_DQ(45)    I14 @BASEBOARD_FAB2_LIB.BASEBOARD_FAB2(SCH_1):PAGE46
   106 M_B_DQ<44> @BASEBOARD_FAB2_LIB.BASEBOARD_FAB2(SCH_1):M_B_DQ(44)    I14 @BASEBOARD_FAB2_LIB.BASEBOARD_FAB2(SCH_1):PAGE46
   260 M_B_DQ<43> @BASEBOARD_FAB2_LIB.BASEBOARD_FAB2(SCH_1):M_B_DQ(43)    I14 @BASEBOARD_FAB2_LIB.BASEBOARD_FAB2(SCH_1):PAGE46
   115 M_B_DQ<42> @BASEBOARD_FAB2_LIB.BASEBOARD_FAB2(SCH_1):M_B_DQ(42)    I14 @BASEBOARD_FAB2_LIB.BASEBOARD_FAB2(SCH_1):PAGE46
   253 M_B_DQ<41> @BASEBOARD_FAB2_LIB.BASEBOARD_FAB2(SCH_1):M_B_DQ(41)    I14 @BASEBOARD_FAB2_LIB.BASEBOARD_FAB2(SCH_1):PAGE46
   108 M_B_DQ<40> @BASEBOARD_FAB2_LIB.BASEBOARD_FAB2(SCH_1):M_B_DQ(40)    I14 @BASEBOARD_FAB2_LIB.BASEBOARD_FAB2(SCH_1):PAGE46
   247 M_B_DQ<39> @BASEBOARD_FAB2_LIB.BASEBOARD_FAB2(SCH_1):M_B_DQ(39)    I14 @BASEBOARD_FAB2_LIB.BASEBOARD_FAB2(SCH_1):PAGE46
   102 M_B_DQ<38> @BASEBOARD_FAB2_LIB.BASEBOARD_FAB2(SCH_1):M_B_DQ(38)    I14 @BASEBOARD_FAB2_LIB.BASEBOARD_FAB2(SCH_1):PAGE46
   240 M_B_DQ<37> @BASEBOARD_FAB2_LIB.BASEBOARD_FAB2(SCH_1):M_B_DQ(37)    I14 @BASEBOARD_FAB2_LIB.BASEBOARD_FAB2(SCH_1):PAGE46
    95 M_B_DQ<36> @BASEBOARD_FAB2_LIB.BASEBOARD_FAB2(SCH_1):M_B_DQ(36)    I14 @BASEBOARD_FAB2_LIB.BASEBOARD_FAB2(SCH_1):PAGE46
   249 M_B_DQ<35> @BASEBOARD_FAB2_LIB.BASEBOARD_FAB2(SCH_1):M_B_DQ(35)    I14 @BASEBOARD_FAB2_LIB.BASEBOARD_FAB2(SCH_1):PAGE46
   104 M_B_DQ<34> @BASEBOARD_FAB2_LIB.BASEBOARD_FAB2(SCH_1):M_B_DQ(34)    I14 @BASEBOARD_FAB2_LIB.BASEBOARD_FAB2(SCH_1):PAGE46
   242 M_B_DQ<33> @BASEBOARD_FAB2_LIB.BASEBOARD_FAB2(SCH_1):M_B_DQ(33)    I14 @BASEBOARD_FAB2_LIB.BASEBOARD_FAB2(SCH_1):PAGE46
    97 M_B_DQ<32> @BASEBOARD_FAB2_LIB.BASEBOARD_FAB2(SCH_1):M_B_DQ(32)    I14 @BASEBOARD_FAB2_LIB.BASEBOARD_FAB2(SCH_1):PAGE46
   188 M_B_DQ<31> @BASEBOARD_FAB2_LIB.BASEBOARD_FAB2(SCH_1):M_B_DQ(31)    I14 @BASEBOARD_FAB2_LIB.BASEBOARD_FAB2(SCH_1):PAGE46
    43 M_B_DQ<30> @BASEBOARD_FAB2_LIB.BASEBOARD_FAB2(SCH_1):M_B_DQ(30)    I14 @BASEBOARD_FAB2_LIB.BASEBOARD_FAB2(SCH_1):PAGE46
   181 M_B_DQ<29> @BASEBOARD_FAB2_LIB.BASEBOARD_FAB2(SCH_1):M_B_DQ(29)    I14 @BASEBOARD_FAB2_LIB.BASEBOARD_FAB2(SCH_1):PAGE46
    36 M_B_DQ<28> @BASEBOARD_FAB2_LIB.BASEBOARD_FAB2(SCH_1):M_B_DQ(28)    I14 @BASEBOARD_FAB2_LIB.BASEBOARD_FAB2(SCH_1):PAGE46
   190 M_B_DQ<27> @BASEBOARD_FAB2_LIB.BASEBOARD_FAB2(SCH_1):M_B_DQ(27)    I14 @BASEBOARD_FAB2_LIB.BASEBOARD_FAB2(SCH_1):PAGE46
    45 M_B_DQ<26> @BASEBOARD_FAB2_LIB.BASEBOARD_FAB2(SCH_1):M_B_DQ(26)    I14 @BASEBOARD_FAB2_LIB.BASEBOARD_FAB2(SCH_1):PAGE46
   183 M_B_DQ<25> @BASEBOARD_FAB2_LIB.BASEBOARD_FAB2(SCH_1):M_B_DQ(25)    I14 @BASEBOARD_FAB2_LIB.BASEBOARD_FAB2(SCH_1):PAGE46
    38 M_B_DQ<24> @BASEBOARD_FAB2_LIB.BASEBOARD_FAB2(SCH_1):M_B_DQ(24)    I14 @BASEBOARD_FAB2_LIB.BASEBOARD_FAB2(SCH_1):PAGE46
   177 M_B_DQ<23> @BASEBOARD_FAB2_LIB.BASEBOARD_FAB2(SCH_1):M_B_DQ(23)    I14 @BASEBOARD_FAB2_LIB.BASEBOARD_FAB2(SCH_1):PAGE46
    32 M_B_DQ<22> @BASEBOARD_FAB2_LIB.BASEBOARD_FAB2(SCH_1):M_B_DQ(22)    I14 @BASEBOARD_FAB2_LIB.BASEBOARD_FAB2(SCH_1):PAGE46
   170 M_B_DQ<21> @BASEBOARD_FAB2_LIB.BASEBOARD_FAB2(SCH_1):M_B_DQ(21)    I14 @BASEBOARD_FAB2_LIB.BASEBOARD_FAB2(SCH_1):PAGE46
    25 M_B_DQ<20> @BASEBOARD_FAB2_LIB.BASEBOARD_FAB2(SCH_1):M_B_DQ(20)    I14 @BASEBOARD_FAB2_LIB.BASEBOARD_FAB2(SCH_1):PAGE46
   179 M_B_DQ<19> @BASEBOARD_FAB2_LIB.BASEBOARD_FAB2(SCH_1):M_B_DQ(19)    I14 @BASEBOARD_FAB2_LIB.BASEBOARD_FAB2(SCH_1):PAGE46
    34 M_B_DQ<18> @BASEBOARD_FAB2_LIB.BASEBOARD_FAB2(SCH_1):M_B_DQ(18)    I14 @BASEBOARD_FAB2_LIB.BASEBOARD_FAB2(SCH_1):PAGE46
   172 M_B_DQ<17> @BASEBOARD_FAB2_LIB.BASEBOARD_FAB2(SCH_1):M_B_DQ(17)    I14 @BASEBOARD_FAB2_LIB.BASEBOARD_FAB2(SCH_1):PAGE46
    27 M_B_DQ<16> @BASEBOARD_FAB2_LIB.BASEBOARD_FAB2(SCH_1):M_B_DQ(16)    I14 @BASEBOARD_FAB2_LIB.BASEBOARD_FAB2(SCH_1):PAGE46
   166 M_B_DQ<15> @BASEBOARD_FAB2_LIB.BASEBOARD_FAB2(SCH_1):M_B_DQ(15)    I14 @BASEBOARD_FAB2_LIB.BASEBOARD_FAB2(SCH_1):PAGE46
    21 M_B_DQ<14> @BASEBOARD_FAB2_LIB.BASEBOARD_FAB2(SCH_1):M_B_DQ(14)    I14 @BASEBOARD_FAB2_LIB.BASEBOARD_FAB2(SCH_1):PAGE46
   159 M_B_DQ<13> @BASEBOARD_FAB2_LIB.BASEBOARD_FAB2(SCH_1):M_B_DQ(13)    I14 @BASEBOARD_FAB2_LIB.BASEBOARD_FAB2(SCH_1):PAGE46
    14 M_B_DQ<12> @BASEBOARD_FAB2_LIB.BASEBOARD_FAB2(SCH_1):M_B_DQ(12)    I14 @BASEBOARD_FAB2_LIB.BASEBOARD_FAB2(SCH_1):PAGE46
   168 M_B_DQ<11> @BASEBOARD_FAB2_LIB.BASEBOARD_FAB2(SCH_1):M_B_DQ(11)    I14 @BASEBOARD_FAB2_LIB.BASEBOARD_FAB2(SCH_1):PAGE46
    23 M_B_DQ<10> @BASEBOARD_FAB2_LIB.BASEBOARD_FAB2(SCH_1):M_B_DQ(10)    I14 @BASEBOARD_FAB2_LIB.BASEBOARD_FAB2(SCH_1):PAGE46
   161 M_B_DQ<9> @BASEBOARD_FAB2_LIB.BASEBOARD_FAB2(SCH_1):M_B_DQ(9)    I14 @BASEBOARD_FAB2_LIB.BASEBOARD_FAB2(SCH_1):PAGE46
    16 M_B_DQ<8> @BASEBOARD_FAB2_LIB.BASEBOARD_FAB2(SCH_1):M_B_DQ(8)    I14 @BASEBOARD_FAB2_LIB.BASEBOARD_FAB2(SCH_1):PAGE46
   155 M_B_DQ<7> @BASEBOARD_FAB2_LIB.BASEBOARD_FAB2(SCH_1):M_B_DQ(7)    I14 @BASEBOARD_FAB2_LIB.BASEBOARD_FAB2(SCH_1):PAGE46
    10 M_B_DQ<6> @BASEBOARD_FAB2_LIB.BASEBOARD_FAB2(SCH_1):M_B_DQ(6)    I14 @BASEBOARD_FAB2_LIB.BASEBOARD_FAB2(SCH_1):PAGE46
   148 M_B_DQ<5> @BASEBOARD_FAB2_LIB.BASEBOARD_FAB2(SCH_1):M_B_DQ(5)    I14 @BASEBOARD_FAB2_LIB.BASEBOARD_FAB2(SCH_1):PAGE46
     3 M_B_DQ<4> @BASEBOARD_FAB2_LIB.BASEBOARD_FAB2(SCH_1):M_B_DQ(4)    I14 @BASEBOARD_FAB2_LIB.BASEBOARD_FAB2(SCH_1):PAGE46
   157 M_B_DQ<3> @BASEBOARD_FAB2_LIB.BASEBOARD_FAB2(SCH_1):M_B_DQ(3)    I14 @BASEBOARD_FAB2_LIB.BASEBOARD_FAB2(SCH_1):PAGE46
    12 M_B_DQ<2> @BASEBOARD_FAB2_LIB.BASEBOARD_FAB2(SCH_1):M_B_DQ(2)    I14 @BASEBOARD_FAB2_LIB.BASEBOARD_FAB2(SCH_1):PAGE46
   150 M_B_DQ<1> @BASEBOARD_FAB2_LIB.BASEBOARD_FAB2(SCH_1):M_B_DQ(1)    I14 @BASEBOARD_FAB2_LIB.BASEBOARD_FAB2(SCH_1):PAGE46
     5 M_B_DQ<0> @BASEBOARD_FAB2_LIB.BASEBOARD_FAB2(SCH_1):M_B_DQ(0)    I14 @BASEBOARD_FAB2_LIB.BASEBOARD_FAB2(SCH_1):PAGE46
    78 FM_DIMM_EVENT_COD_N @BASEBOARD_FAB2_LIB.BASEBOARD_FAB2(SCH_1):FM_DIMM_EVENT_COD_N    I14 @BASEBOARD_FAB2_LIB.BASEBOARD_FAB2(SCH_1):PAGE46
    91 M_B_ODT<3> @BASEBOARD_FAB2_LIB.BASEBOARD_FAB2(SCH_1):M_B_ODT(3)    I14 @BASEBOARD_FAB2_LIB.BASEBOARD_FAB2(SCH_1):PAGE46
    87 M_B_ODT<2> @BASEBOARD_FAB2_LIB.BASEBOARD_FAB2(SCH_1):M_B_ODT(2)    I14 @BASEBOARD_FAB2_LIB.BASEBOARD_FAB2(SCH_1):PAGE46
   222 M_B_PAR @BASEBOARD_FAB2_LIB.BASEBOARD_FAB2(SCH_1):M_B_PAR    I14 @BASEBOARD_FAB2_LIB.BASEBOARD_FAB2(SCH_1):PAGE46
    58 M_ABC_RST_N @BASEBOARD_FAB2_LIB.BASEBOARD_FAB2(SCH_1):M_ABC_RST_N    I14 @BASEBOARD_FAB2_LIB.BASEBOARD_FAB2(SCH_1):PAGE46
   144 TP_CH_B_DIMM_B1_RFU_2 @BASEBOARD_FAB2_LIB.BASEBOARD_FAB2(SCH_1):TP_CH_B_DIMM_B1_RFU_2    I14 @BASEBOARD_FAB2_LIB.BASEBOARD_FAB2(SCH_1):PAGE46
   227 TP_CH_B_DIMM_B1_RFU_1 @BASEBOARD_FAB2_LIB.BASEBOARD_FAB2(SCH_1):TP_CH_B_DIMM_B1_RFU_1    I14 @BASEBOARD_FAB2_LIB.BASEBOARD_FAB2(SCH_1):PAGE46
   205 TP_CH_B_DIMM_B1_RFU_0 @BASEBOARD_FAB2_LIB.BASEBOARD_FAB2(SCH_1):TP_CH_B_DIMM_B1_RFU_0    I14 @BASEBOARD_FAB2_LIB.BASEBOARD_FAB2(SCH_1):PAGE46
    84 M_B_CS_N<4> @BASEBOARD_FAB2_LIB.BASEBOARD_FAB2(SCH_1):M_B_CS_N(4)    I14 @BASEBOARD_FAB2_LIB.BASEBOARD_FAB2(SCH_1):PAGE46
    89 M_B_CS_N<5> @BASEBOARD_FAB2_LIB.BASEBOARD_FAB2(SCH_1):M_B_CS_N(5)    I14 @BASEBOARD_FAB2_LIB.BASEBOARD_FAB2(SCH_1):PAGE46
    93 M_B_CS_N<6> @BASEBOARD_FAB2_LIB.BASEBOARD_FAB2(SCH_1):M_B_CS_N(6)    I14 @BASEBOARD_FAB2_LIB.BASEBOARD_FAB2(SCH_1):PAGE46
   237 M_B_CS_N<7> @BASEBOARD_FAB2_LIB.BASEBOARD_FAB2(SCH_1):M_B_CS_N(7)    I14 @BASEBOARD_FAB2_LIB.BASEBOARD_FAB2(SCH_1):PAGE46
   238    GND @BASEBOARD_FAB2_LIB.BASEBOARD_FAB2(SCH_1):GND    I14 @BASEBOARD_FAB2_LIB.BASEBOARD_FAB2(SCH_1):PAGE46
   140 PVPP_ABC @BASEBOARD_FAB2_LIB.BASEBOARD_FAB2(SCH_1):PVPP_ABC    I14 @BASEBOARD_FAB2_LIB.BASEBOARD_FAB2(SCH_1):PAGE46
   139 PVPP_ABC @BASEBOARD_FAB2_LIB.BASEBOARD_FAB2(SCH_1):PVPP_ABC    I14 @BASEBOARD_FAB2_LIB.BASEBOARD_FAB2(SCH_1):PAGE46
   230 FM_ADR_COMPLETE_ABC_N @BASEBOARD_FAB2_LIB.BASEBOARD_FAB2(SCH_1):FM_ADR_COMPLETE_ABC_N    I14 @BASEBOARD_FAB2_LIB.BASEBOARD_FAB2(SCH_1):PAGE46
   141 SMB_DDR_ABC_VPP_SCL @BASEBOARD_FAB2_LIB.BASEBOARD_FAB2(SCH_1):SMB_DDR_ABC_VPP_SCL    I14 @BASEBOARD_FAB2_LIB.BASEBOARD_FAB2(SCH_1):PAGE46
   285 SMB_DDR_ABC_VPP_SDA @BASEBOARD_FAB2_LIB.BASEBOARD_FAB2(SCH_1):SMB_DDR_ABC_VPP_SDA    I14 @BASEBOARD_FAB2_LIB.BASEBOARD_FAB2(SCH_1):PAGE46
   284 PVPP_ABC @BASEBOARD_FAB2_LIB.BASEBOARD_FAB2(SCH_1):PVPP_ABC    I14 @BASEBOARD_FAB2_LIB.BASEBOARD_FAB2(SCH_1):PAGE46
   146 M_B_VREF @BASEBOARD_FAB2_LIB.BASEBOARD_FAB2(SCH_1):M_B_VREF    I14 @BASEBOARD_FAB2_LIB.BASEBOARD_FAB2(SCH_1):PAGE46
   152 M_B_DQS_DN<0> @BASEBOARD_FAB2_LIB.BASEBOARD_FAB2(SCH_1):M_B_DQS_DN(0)   I112 @BASEBOARD_FAB2_LIB.BASEBOARD_FAB2(SCH_1):PAGE46
   153 M_B_DQS_DP<0> @BASEBOARD_FAB2_LIB.BASEBOARD_FAB2(SCH_1):M_B_DQS_DP(0)   I112 @BASEBOARD_FAB2_LIB.BASEBOARD_FAB2(SCH_1):PAGE46
    19 M_B_DQS_DN<10> @BASEBOARD_FAB2_LIB.BASEBOARD_FAB2(SCH_1):M_B_DQS_DN(10)   I112 @BASEBOARD_FAB2_LIB.BASEBOARD_FAB2(SCH_1):PAGE46
    18 M_B_DQS_DP<10> @BASEBOARD_FAB2_LIB.BASEBOARD_FAB2(SCH_1):M_B_DQS_DP(10)   I112 @BASEBOARD_FAB2_LIB.BASEBOARD_FAB2(SCH_1):PAGE46
    30 M_B_DQS_DN<11> @BASEBOARD_FAB2_LIB.BASEBOARD_FAB2(SCH_1):M_B_DQS_DN(11)   I112 @BASEBOARD_FAB2_LIB.BASEBOARD_FAB2(SCH_1):PAGE46
    29 M_B_DQS_DP<11> @BASEBOARD_FAB2_LIB.BASEBOARD_FAB2(SCH_1):M_B_DQS_DP(11)   I112 @BASEBOARD_FAB2_LIB.BASEBOARD_FAB2(SCH_1):PAGE46
    41 M_B_DQS_DN<12> @BASEBOARD_FAB2_LIB.BASEBOARD_FAB2(SCH_1):M_B_DQS_DN(12)   I112 @BASEBOARD_FAB2_LIB.BASEBOARD_FAB2(SCH_1):PAGE46
    40 M_B_DQS_DP<12> @BASEBOARD_FAB2_LIB.BASEBOARD_FAB2(SCH_1):M_B_DQS_DP(12)   I112 @BASEBOARD_FAB2_LIB.BASEBOARD_FAB2(SCH_1):PAGE46
   100 M_B_DQS_DN<13> @BASEBOARD_FAB2_LIB.BASEBOARD_FAB2(SCH_1):M_B_DQS_DN(13)   I112 @BASEBOARD_FAB2_LIB.BASEBOARD_FAB2(SCH_1):PAGE46
    99 M_B_DQS_DP<13> @BASEBOARD_FAB2_LIB.BASEBOARD_FAB2(SCH_1):M_B_DQS_DP(13)   I112 @BASEBOARD_FAB2_LIB.BASEBOARD_FAB2(SCH_1):PAGE46
   111 M_B_DQS_DN<14> @BASEBOARD_FAB2_LIB.BASEBOARD_FAB2(SCH_1):M_B_DQS_DN(14)   I112 @BASEBOARD_FAB2_LIB.BASEBOARD_FAB2(SCH_1):PAGE46
   110 M_B_DQS_DP<14> @BASEBOARD_FAB2_LIB.BASEBOARD_FAB2(SCH_1):M_B_DQS_DP(14)   I112 @BASEBOARD_FAB2_LIB.BASEBOARD_FAB2(SCH_1):PAGE46
   122 M_B_DQS_DN<15> @BASEBOARD_FAB2_LIB.BASEBOARD_FAB2(SCH_1):M_B_DQS_DN(15)   I112 @BASEBOARD_FAB2_LIB.BASEBOARD_FAB2(SCH_1):PAGE46
   121 M_B_DQS_DP<15> @BASEBOARD_FAB2_LIB.BASEBOARD_FAB2(SCH_1):M_B_DQS_DP(15)   I112 @BASEBOARD_FAB2_LIB.BASEBOARD_FAB2(SCH_1):PAGE46
   133 M_B_DQS_DN<16> @BASEBOARD_FAB2_LIB.BASEBOARD_FAB2(SCH_1):M_B_DQS_DN(16)   I112 @BASEBOARD_FAB2_LIB.BASEBOARD_FAB2(SCH_1):PAGE46
   132 M_B_DQS_DP<16> @BASEBOARD_FAB2_LIB.BASEBOARD_FAB2(SCH_1):M_B_DQS_DP(16)   I112 @BASEBOARD_FAB2_LIB.BASEBOARD_FAB2(SCH_1):PAGE46
    52 M_B_DQS_DN<17> @BASEBOARD_FAB2_LIB.BASEBOARD_FAB2(SCH_1):M_B_DQS_DN(17)   I112 @BASEBOARD_FAB2_LIB.BASEBOARD_FAB2(SCH_1):PAGE46
    51 M_B_DQS_DP<17> @BASEBOARD_FAB2_LIB.BASEBOARD_FAB2(SCH_1):M_B_DQS_DP(17)   I112 @BASEBOARD_FAB2_LIB.BASEBOARD_FAB2(SCH_1):PAGE46
   163 M_B_DQS_DN<1> @BASEBOARD_FAB2_LIB.BASEBOARD_FAB2(SCH_1):M_B_DQS_DN(1)   I112 @BASEBOARD_FAB2_LIB.BASEBOARD_FAB2(SCH_1):PAGE46
   164 M_B_DQS_DP<1> @BASEBOARD_FAB2_LIB.BASEBOARD_FAB2(SCH_1):M_B_DQS_DP(1)   I112 @BASEBOARD_FAB2_LIB.BASEBOARD_FAB2(SCH_1):PAGE46
   174 M_B_DQS_DN<2> @BASEBOARD_FAB2_LIB.BASEBOARD_FAB2(SCH_1):M_B_DQS_DN(2)   I112 @BASEBOARD_FAB2_LIB.BASEBOARD_FAB2(SCH_1):PAGE46
   175 M_B_DQS_DP<2> @BASEBOARD_FAB2_LIB.BASEBOARD_FAB2(SCH_1):M_B_DQS_DP(2)   I112 @BASEBOARD_FAB2_LIB.BASEBOARD_FAB2(SCH_1):PAGE46
   185 M_B_DQS_DN<3> @BASEBOARD_FAB2_LIB.BASEBOARD_FAB2(SCH_1):M_B_DQS_DN(3)   I112 @BASEBOARD_FAB2_LIB.BASEBOARD_FAB2(SCH_1):PAGE46
   186 M_B_DQS_DP<3> @BASEBOARD_FAB2_LIB.BASEBOARD_FAB2(SCH_1):M_B_DQS_DP(3)   I112 @BASEBOARD_FAB2_LIB.BASEBOARD_FAB2(SCH_1):PAGE46
   244 M_B_DQS_DN<4> @BASEBOARD_FAB2_LIB.BASEBOARD_FAB2(SCH_1):M_B_DQS_DN(4)   I112 @BASEBOARD_FAB2_LIB.BASEBOARD_FAB2(SCH_1):PAGE46
   245 M_B_DQS_DP<4> @BASEBOARD_FAB2_LIB.BASEBOARD_FAB2(SCH_1):M_B_DQS_DP(4)   I112 @BASEBOARD_FAB2_LIB.BASEBOARD_FAB2(SCH_1):PAGE46
   255 M_B_DQS_DN<5> @BASEBOARD_FAB2_LIB.BASEBOARD_FAB2(SCH_1):M_B_DQS_DN(5)   I112 @BASEBOARD_FAB2_LIB.BASEBOARD_FAB2(SCH_1):PAGE46
   256 M_B_DQS_DP<5> @BASEBOARD_FAB2_LIB.BASEBOARD_FAB2(SCH_1):M_B_DQS_DP(5)   I112 @BASEBOARD_FAB2_LIB.BASEBOARD_FAB2(SCH_1):PAGE46
   266 M_B_DQS_DN<6> @BASEBOARD_FAB2_LIB.BASEBOARD_FAB2(SCH_1):M_B_DQS_DN(6)   I112 @BASEBOARD_FAB2_LIB.BASEBOARD_FAB2(SCH_1):PAGE46
   267 M_B_DQS_DP<6> @BASEBOARD_FAB2_LIB.BASEBOARD_FAB2(SCH_1):M_B_DQS_DP(6)   I112 @BASEBOARD_FAB2_LIB.BASEBOARD_FAB2(SCH_1):PAGE46
   277 M_B_DQS_DN<7> @BASEBOARD_FAB2_LIB.BASEBOARD_FAB2(SCH_1):M_B_DQS_DN(7)   I112 @BASEBOARD_FAB2_LIB.BASEBOARD_FAB2(SCH_1):PAGE46
   278 M_B_DQS_DP<7> @BASEBOARD_FAB2_LIB.BASEBOARD_FAB2(SCH_1):M_B_DQS_DP(7)   I112 @BASEBOARD_FAB2_LIB.BASEBOARD_FAB2(SCH_1):PAGE46
   196 M_B_DQS_DN<8> @BASEBOARD_FAB2_LIB.BASEBOARD_FAB2(SCH_1):M_B_DQS_DN(8)   I112 @BASEBOARD_FAB2_LIB.BASEBOARD_FAB2(SCH_1):PAGE46
   197 M_B_DQS_DP<8> @BASEBOARD_FAB2_LIB.BASEBOARD_FAB2(SCH_1):M_B_DQS_DP(8)   I112 @BASEBOARD_FAB2_LIB.BASEBOARD_FAB2(SCH_1):PAGE46
     8 M_B_DQS_DN<9> @BASEBOARD_FAB2_LIB.BASEBOARD_FAB2(SCH_1):M_B_DQS_DN(9)   I112 @BASEBOARD_FAB2_LIB.BASEBOARD_FAB2(SCH_1):PAGE46
     7 M_B_DQS_DP<9> @BASEBOARD_FAB2_LIB.BASEBOARD_FAB2(SCH_1):M_B_DQS_DP(9)   I112 @BASEBOARD_FAB2_LIB.BASEBOARD_FAB2(SCH_1):PAGE46
     2    GND @BASEBOARD_FAB2_LIB.BASEBOARD_FAB2(SCH_1):GND   I138 @BASEBOARD_FAB2_LIB.BASEBOARD_FAB2(SCH_1):PAGE46
     4    GND @BASEBOARD_FAB2_LIB.BASEBOARD_FAB2(SCH_1):GND   I138 @BASEBOARD_FAB2_LIB.BASEBOARD_FAB2(SCH_1):PAGE46
     6    GND @BASEBOARD_FAB2_LIB.BASEBOARD_FAB2(SCH_1):GND   I138 @BASEBOARD_FAB2_LIB.BASEBOARD_FAB2(SCH_1):PAGE46
     9    GND @BASEBOARD_FAB2_LIB.BASEBOARD_FAB2(SCH_1):GND   I138 @BASEBOARD_FAB2_LIB.BASEBOARD_FAB2(SCH_1):PAGE46
    11    GND @BASEBOARD_FAB2_LIB.BASEBOARD_FAB2(SCH_1):GND   I138 @BASEBOARD_FAB2_LIB.BASEBOARD_FAB2(SCH_1):PAGE46
    13    GND @BASEBOARD_FAB2_LIB.BASEBOARD_FAB2(SCH_1):GND   I138 @BASEBOARD_FAB2_LIB.BASEBOARD_FAB2(SCH_1):PAGE46
    15    GND @BASEBOARD_FAB2_LIB.BASEBOARD_FAB2(SCH_1):GND   I138 @BASEBOARD_FAB2_LIB.BASEBOARD_FAB2(SCH_1):PAGE46
    17    GND @BASEBOARD_FAB2_LIB.BASEBOARD_FAB2(SCH_1):GND   I138 @BASEBOARD_FAB2_LIB.BASEBOARD_FAB2(SCH_1):PAGE46
    20    GND @BASEBOARD_FAB2_LIB.BASEBOARD_FAB2(SCH_1):GND   I138 @BASEBOARD_FAB2_LIB.BASEBOARD_FAB2(SCH_1):PAGE46
    22    GND @BASEBOARD_FAB2_LIB.BASEBOARD_FAB2(SCH_1):GND   I138 @BASEBOARD_FAB2_LIB.BASEBOARD_FAB2(SCH_1):PAGE46
    24    GND @BASEBOARD_FAB2_LIB.BASEBOARD_FAB2(SCH_1):GND   I138 @BASEBOARD_FAB2_LIB.BASEBOARD_FAB2(SCH_1):PAGE46
    26    GND @BASEBOARD_FAB2_LIB.BASEBOARD_FAB2(SCH_1):GND   I138 @BASEBOARD_FAB2_LIB.BASEBOARD_FAB2(SCH_1):PAGE46
    28    GND @BASEBOARD_FAB2_LIB.BASEBOARD_FAB2(SCH_1):GND   I138 @BASEBOARD_FAB2_LIB.BASEBOARD_FAB2(SCH_1):PAGE46
    31    GND @BASEBOARD_FAB2_LIB.BASEBOARD_FAB2(SCH_1):GND   I138 @BASEBOARD_FAB2_LIB.BASEBOARD_FAB2(SCH_1):PAGE46
    33    GND @BASEBOARD_FAB2_LIB.BASEBOARD_FAB2(SCH_1):GND   I138 @BASEBOARD_FAB2_LIB.BASEBOARD_FAB2(SCH_1):PAGE46
    35    GND @BASEBOARD_FAB2_LIB.BASEBOARD_FAB2(SCH_1):GND   I138 @BASEBOARD_FAB2_LIB.BASEBOARD_FAB2(SCH_1):PAGE46
    37    GND @BASEBOARD_FAB2_LIB.BASEBOARD_FAB2(SCH_1):GND   I138 @BASEBOARD_FAB2_LIB.BASEBOARD_FAB2(SCH_1):PAGE46
    39    GND @BASEBOARD_FAB2_LIB.BASEBOARD_FAB2(SCH_1):GND   I138 @BASEBOARD_FAB2_LIB.BASEBOARD_FAB2(SCH_1):PAGE46
    42    GND @BASEBOARD_FAB2_LIB.BASEBOARD_FAB2(SCH_1):GND   I138 @BASEBOARD_FAB2_LIB.BASEBOARD_FAB2(SCH_1):PAGE46
    44    GND @BASEBOARD_FAB2_LIB.BASEBOARD_FAB2(SCH_1):GND   I138 @BASEBOARD_FAB2_LIB.BASEBOARD_FAB2(SCH_1):PAGE46
    46    GND @BASEBOARD_FAB2_LIB.BASEBOARD_FAB2(SCH_1):GND   I138 @BASEBOARD_FAB2_LIB.BASEBOARD_FAB2(SCH_1):PAGE46
    48    GND @BASEBOARD_FAB2_LIB.BASEBOARD_FAB2(SCH_1):GND   I138 @BASEBOARD_FAB2_LIB.BASEBOARD_FAB2(SCH_1):PAGE46
    50    GND @BASEBOARD_FAB2_LIB.BASEBOARD_FAB2(SCH_1):GND   I138 @BASEBOARD_FAB2_LIB.BASEBOARD_FAB2(SCH_1):PAGE46
    53    GND @BASEBOARD_FAB2_LIB.BASEBOARD_FAB2(SCH_1):GND   I138 @BASEBOARD_FAB2_LIB.BASEBOARD_FAB2(SCH_1):PAGE46
    55    GND @BASEBOARD_FAB2_LIB.BASEBOARD_FAB2(SCH_1):GND   I138 @BASEBOARD_FAB2_LIB.BASEBOARD_FAB2(SCH_1):PAGE46
    57    GND @BASEBOARD_FAB2_LIB.BASEBOARD_FAB2(SCH_1):GND   I138 @BASEBOARD_FAB2_LIB.BASEBOARD_FAB2(SCH_1):PAGE46
    94    GND @BASEBOARD_FAB2_LIB.BASEBOARD_FAB2(SCH_1):GND   I138 @BASEBOARD_FAB2_LIB.BASEBOARD_FAB2(SCH_1):PAGE46
    96    GND @BASEBOARD_FAB2_LIB.BASEBOARD_FAB2(SCH_1):GND   I138 @BASEBOARD_FAB2_LIB.BASEBOARD_FAB2(SCH_1):PAGE46
    98    GND @BASEBOARD_FAB2_LIB.BASEBOARD_FAB2(SCH_1):GND   I138 @BASEBOARD_FAB2_LIB.BASEBOARD_FAB2(SCH_1):PAGE46
   101    GND @BASEBOARD_FAB2_LIB.BASEBOARD_FAB2(SCH_1):GND   I138 @BASEBOARD_FAB2_LIB.BASEBOARD_FAB2(SCH_1):PAGE46
   103    GND @BASEBOARD_FAB2_LIB.BASEBOARD_FAB2(SCH_1):GND   I138 @BASEBOARD_FAB2_LIB.BASEBOARD_FAB2(SCH_1):PAGE46
   105    GND @BASEBOARD_FAB2_LIB.BASEBOARD_FAB2(SCH_1):GND   I138 @BASEBOARD_FAB2_LIB.BASEBOARD_FAB2(SCH_1):PAGE46
   107    GND @BASEBOARD_FAB2_LIB.BASEBOARD_FAB2(SCH_1):GND   I138 @BASEBOARD_FAB2_LIB.BASEBOARD_FAB2(SCH_1):PAGE46
   109    GND @BASEBOARD_FAB2_LIB.BASEBOARD_FAB2(SCH_1):GND   I138 @BASEBOARD_FAB2_LIB.BASEBOARD_FAB2(SCH_1):PAGE46
   112    GND @BASEBOARD_FAB2_LIB.BASEBOARD_FAB2(SCH_1):GND   I138 @BASEBOARD_FAB2_LIB.BASEBOARD_FAB2(SCH_1):PAGE46
   114    GND @BASEBOARD_FAB2_LIB.BASEBOARD_FAB2(SCH_1):GND   I138 @BASEBOARD_FAB2_LIB.BASEBOARD_FAB2(SCH_1):PAGE46
   116    GND @BASEBOARD_FAB2_LIB.BASEBOARD_FAB2(SCH_1):GND   I138 @BASEBOARD_FAB2_LIB.BASEBOARD_FAB2(SCH_1):PAGE46
   118    GND @BASEBOARD_FAB2_LIB.BASEBOARD_FAB2(SCH_1):GND   I138 @BASEBOARD_FAB2_LIB.BASEBOARD_FAB2(SCH_1):PAGE46
   120    GND @BASEBOARD_FAB2_LIB.BASEBOARD_FAB2(SCH_1):GND   I138 @BASEBOARD_FAB2_LIB.BASEBOARD_FAB2(SCH_1):PAGE46
   123    GND @BASEBOARD_FAB2_LIB.BASEBOARD_FAB2(SCH_1):GND   I138 @BASEBOARD_FAB2_LIB.BASEBOARD_FAB2(SCH_1):PAGE46
   125    GND @BASEBOARD_FAB2_LIB.BASEBOARD_FAB2(SCH_1):GND   I138 @BASEBOARD_FAB2_LIB.BASEBOARD_FAB2(SCH_1):PAGE46
   127    GND @BASEBOARD_FAB2_LIB.BASEBOARD_FAB2(SCH_1):GND   I138 @BASEBOARD_FAB2_LIB.BASEBOARD_FAB2(SCH_1):PAGE46
   129    GND @BASEBOARD_FAB2_LIB.BASEBOARD_FAB2(SCH_1):GND   I138 @BASEBOARD_FAB2_LIB.BASEBOARD_FAB2(SCH_1):PAGE46
   131    GND @BASEBOARD_FAB2_LIB.BASEBOARD_FAB2(SCH_1):GND   I138 @BASEBOARD_FAB2_LIB.BASEBOARD_FAB2(SCH_1):PAGE46
   134    GND @BASEBOARD_FAB2_LIB.BASEBOARD_FAB2(SCH_1):GND   I138 @BASEBOARD_FAB2_LIB.BASEBOARD_FAB2(SCH_1):PAGE46
   136    GND @BASEBOARD_FAB2_LIB.BASEBOARD_FAB2(SCH_1):GND   I138 @BASEBOARD_FAB2_LIB.BASEBOARD_FAB2(SCH_1):PAGE46
   138    GND @BASEBOARD_FAB2_LIB.BASEBOARD_FAB2(SCH_1):GND   I138 @BASEBOARD_FAB2_LIB.BASEBOARD_FAB2(SCH_1):PAGE46
   147    GND @BASEBOARD_FAB2_LIB.BASEBOARD_FAB2(SCH_1):GND   I138 @BASEBOARD_FAB2_LIB.BASEBOARD_FAB2(SCH_1):PAGE46
   149    GND @BASEBOARD_FAB2_LIB.BASEBOARD_FAB2(SCH_1):GND   I138 @BASEBOARD_FAB2_LIB.BASEBOARD_FAB2(SCH_1):PAGE46
   151    GND @BASEBOARD_FAB2_LIB.BASEBOARD_FAB2(SCH_1):GND   I138 @BASEBOARD_FAB2_LIB.BASEBOARD_FAB2(SCH_1):PAGE46
   154    GND @BASEBOARD_FAB2_LIB.BASEBOARD_FAB2(SCH_1):GND   I138 @BASEBOARD_FAB2_LIB.BASEBOARD_FAB2(SCH_1):PAGE46
   156    GND @BASEBOARD_FAB2_LIB.BASEBOARD_FAB2(SCH_1):GND   I138 @BASEBOARD_FAB2_LIB.BASEBOARD_FAB2(SCH_1):PAGE46
   158    GND @BASEBOARD_FAB2_LIB.BASEBOARD_FAB2(SCH_1):GND   I138 @BASEBOARD_FAB2_LIB.BASEBOARD_FAB2(SCH_1):PAGE46
   160    GND @BASEBOARD_FAB2_LIB.BASEBOARD_FAB2(SCH_1):GND   I138 @BASEBOARD_FAB2_LIB.BASEBOARD_FAB2(SCH_1):PAGE46
   162    GND @BASEBOARD_FAB2_LIB.BASEBOARD_FAB2(SCH_1):GND   I138 @BASEBOARD_FAB2_LIB.BASEBOARD_FAB2(SCH_1):PAGE46
   165    GND @BASEBOARD_FAB2_LIB.BASEBOARD_FAB2(SCH_1):GND   I138 @BASEBOARD_FAB2_LIB.BASEBOARD_FAB2(SCH_1):PAGE46
   167    GND @BASEBOARD_FAB2_LIB.BASEBOARD_FAB2(SCH_1):GND   I138 @BASEBOARD_FAB2_LIB.BASEBOARD_FAB2(SCH_1):PAGE46
   169    GND @BASEBOARD_FAB2_LIB.BASEBOARD_FAB2(SCH_1):GND   I138 @BASEBOARD_FAB2_LIB.BASEBOARD_FAB2(SCH_1):PAGE46
   171    GND @BASEBOARD_FAB2_LIB.BASEBOARD_FAB2(SCH_1):GND   I138 @BASEBOARD_FAB2_LIB.BASEBOARD_FAB2(SCH_1):PAGE46
   173    GND @BASEBOARD_FAB2_LIB.BASEBOARD_FAB2(SCH_1):GND   I138 @BASEBOARD_FAB2_LIB.BASEBOARD_FAB2(SCH_1):PAGE46
   176    GND @BASEBOARD_FAB2_LIB.BASEBOARD_FAB2(SCH_1):GND   I138 @BASEBOARD_FAB2_LIB.BASEBOARD_FAB2(SCH_1):PAGE46
   178    GND @BASEBOARD_FAB2_LIB.BASEBOARD_FAB2(SCH_1):GND   I138 @BASEBOARD_FAB2_LIB.BASEBOARD_FAB2(SCH_1):PAGE46
   180    GND @BASEBOARD_FAB2_LIB.BASEBOARD_FAB2(SCH_1):GND   I138 @BASEBOARD_FAB2_LIB.BASEBOARD_FAB2(SCH_1):PAGE46
   182    GND @BASEBOARD_FAB2_LIB.BASEBOARD_FAB2(SCH_1):GND   I138 @BASEBOARD_FAB2_LIB.BASEBOARD_FAB2(SCH_1):PAGE46
   184    GND @BASEBOARD_FAB2_LIB.BASEBOARD_FAB2(SCH_1):GND   I138 @BASEBOARD_FAB2_LIB.BASEBOARD_FAB2(SCH_1):PAGE46
   187    GND @BASEBOARD_FAB2_LIB.BASEBOARD_FAB2(SCH_1):GND   I138 @BASEBOARD_FAB2_LIB.BASEBOARD_FAB2(SCH_1):PAGE46
   189    GND @BASEBOARD_FAB2_LIB.BASEBOARD_FAB2(SCH_1):GND   I138 @BASEBOARD_FAB2_LIB.BASEBOARD_FAB2(SCH_1):PAGE46
   191    GND @BASEBOARD_FAB2_LIB.BASEBOARD_FAB2(SCH_1):GND   I138 @BASEBOARD_FAB2_LIB.BASEBOARD_FAB2(SCH_1):PAGE46
   193    GND @BASEBOARD_FAB2_LIB.BASEBOARD_FAB2(SCH_1):GND   I138 @BASEBOARD_FAB2_LIB.BASEBOARD_FAB2(SCH_1):PAGE46
   195    GND @BASEBOARD_FAB2_LIB.BASEBOARD_FAB2(SCH_1):GND   I138 @BASEBOARD_FAB2_LIB.BASEBOARD_FAB2(SCH_1):PAGE46
   198    GND @BASEBOARD_FAB2_LIB.BASEBOARD_FAB2(SCH_1):GND   I138 @BASEBOARD_FAB2_LIB.BASEBOARD_FAB2(SCH_1):PAGE46
   200    GND @BASEBOARD_FAB2_LIB.BASEBOARD_FAB2(SCH_1):GND   I138 @BASEBOARD_FAB2_LIB.BASEBOARD_FAB2(SCH_1):PAGE46
   202    GND @BASEBOARD_FAB2_LIB.BASEBOARD_FAB2(SCH_1):GND   I138 @BASEBOARD_FAB2_LIB.BASEBOARD_FAB2(SCH_1):PAGE46
   239    GND @BASEBOARD_FAB2_LIB.BASEBOARD_FAB2(SCH_1):GND   I138 @BASEBOARD_FAB2_LIB.BASEBOARD_FAB2(SCH_1):PAGE46
   241    GND @BASEBOARD_FAB2_LIB.BASEBOARD_FAB2(SCH_1):GND   I138 @BASEBOARD_FAB2_LIB.BASEBOARD_FAB2(SCH_1):PAGE46
   243    GND @BASEBOARD_FAB2_LIB.BASEBOARD_FAB2(SCH_1):GND   I138 @BASEBOARD_FAB2_LIB.BASEBOARD_FAB2(SCH_1):PAGE46
   246    GND @BASEBOARD_FAB2_LIB.BASEBOARD_FAB2(SCH_1):GND   I138 @BASEBOARD_FAB2_LIB.BASEBOARD_FAB2(SCH_1):PAGE46
   248    GND @BASEBOARD_FAB2_LIB.BASEBOARD_FAB2(SCH_1):GND   I138 @BASEBOARD_FAB2_LIB.BASEBOARD_FAB2(SCH_1):PAGE46
   250    GND @BASEBOARD_FAB2_LIB.BASEBOARD_FAB2(SCH_1):GND   I138 @BASEBOARD_FAB2_LIB.BASEBOARD_FAB2(SCH_1):PAGE46
   252    GND @BASEBOARD_FAB2_LIB.BASEBOARD_FAB2(SCH_1):GND   I138 @BASEBOARD_FAB2_LIB.BASEBOARD_FAB2(SCH_1):PAGE46
   254    GND @BASEBOARD_FAB2_LIB.BASEBOARD_FAB2(SCH_1):GND   I138 @BASEBOARD_FAB2_LIB.BASEBOARD_FAB2(SCH_1):PAGE46
   257    GND @BASEBOARD_FAB2_LIB.BASEBOARD_FAB2(SCH_1):GND   I138 @BASEBOARD_FAB2_LIB.BASEBOARD_FAB2(SCH_1):PAGE46
   259    GND @BASEBOARD_FAB2_LIB.BASEBOARD_FAB2(SCH_1):GND   I138 @BASEBOARD_FAB2_LIB.BASEBOARD_FAB2(SCH_1):PAGE46
   261    GND @BASEBOARD_FAB2_LIB.BASEBOARD_FAB2(SCH_1):GND   I138 @BASEBOARD_FAB2_LIB.BASEBOARD_FAB2(SCH_1):PAGE46
   263    GND @BASEBOARD_FAB2_LIB.BASEBOARD_FAB2(SCH_1):GND   I138 @BASEBOARD_FAB2_LIB.BASEBOARD_FAB2(SCH_1):PAGE46
   265    GND @BASEBOARD_FAB2_LIB.BASEBOARD_FAB2(SCH_1):GND   I138 @BASEBOARD_FAB2_LIB.BASEBOARD_FAB2(SCH_1):PAGE46
   268    GND @BASEBOARD_FAB2_LIB.BASEBOARD_FAB2(SCH_1):GND   I138 @BASEBOARD_FAB2_LIB.BASEBOARD_FAB2(SCH_1):PAGE46
   270    GND @BASEBOARD_FAB2_LIB.BASEBOARD_FAB2(SCH_1):GND   I138 @BASEBOARD_FAB2_LIB.BASEBOARD_FAB2(SCH_1):PAGE46
   272    GND @BASEBOARD_FAB2_LIB.BASEBOARD_FAB2(SCH_1):GND   I138 @BASEBOARD_FAB2_LIB.BASEBOARD_FAB2(SCH_1):PAGE46
   274    GND @BASEBOARD_FAB2_LIB.BASEBOARD_FAB2(SCH_1):GND   I138 @BASEBOARD_FAB2_LIB.BASEBOARD_FAB2(SCH_1):PAGE46
   276    GND @BASEBOARD_FAB2_LIB.BASEBOARD_FAB2(SCH_1):GND   I138 @BASEBOARD_FAB2_LIB.BASEBOARD_FAB2(SCH_1):PAGE46
   279    GND @BASEBOARD_FAB2_LIB.BASEBOARD_FAB2(SCH_1):GND   I138 @BASEBOARD_FAB2_LIB.BASEBOARD_FAB2(SCH_1):PAGE46
   281    GND @BASEBOARD_FAB2_LIB.BASEBOARD_FAB2(SCH_1):GND   I138 @BASEBOARD_FAB2_LIB.BASEBOARD_FAB2(SCH_1):PAGE46
   283    GND @BASEBOARD_FAB2_LIB.BASEBOARD_FAB2(SCH_1):GND   I138 @BASEBOARD_FAB2_LIB.BASEBOARD_FAB2(SCH_1):PAGE46
     1 P12V_NVDIMM_ABC @BASEBOARD_FAB2_LIB.BASEBOARD_FAB2(SCH_1):P12V_NVDIMM_ABC    I67 @BASEBOARD_FAB2_LIB.BASEBOARD_FAB2(SCH_1):PAGE46
   145 P12V_NVDIMM_ABC @BASEBOARD_FAB2_LIB.BASEBOARD_FAB2(SCH_1):P12V_NVDIMM_ABC    I67 @BASEBOARD_FAB2_LIB.BASEBOARD_FAB2(SCH_1):PAGE46
    59 PVDDQ_ABC @BASEBOARD_FAB2_LIB.BASEBOARD_FAB2(SCH_1):PVDDQ_ABC    I67 @BASEBOARD_FAB2_LIB.BASEBOARD_FAB2(SCH_1):PAGE46
    61 PVDDQ_ABC @BASEBOARD_FAB2_LIB.BASEBOARD_FAB2(SCH_1):PVDDQ_ABC    I67 @BASEBOARD_FAB2_LIB.BASEBOARD_FAB2(SCH_1):PAGE46
    64 PVDDQ_ABC @BASEBOARD_FAB2_LIB.BASEBOARD_FAB2(SCH_1):PVDDQ_ABC    I67 @BASEBOARD_FAB2_LIB.BASEBOARD_FAB2(SCH_1):PAGE46
    67 PVDDQ_ABC @BASEBOARD_FAB2_LIB.BASEBOARD_FAB2(SCH_1):PVDDQ_ABC    I67 @BASEBOARD_FAB2_LIB.BASEBOARD_FAB2(SCH_1):PAGE46
    70 PVDDQ_ABC @BASEBOARD_FAB2_LIB.BASEBOARD_FAB2(SCH_1):PVDDQ_ABC    I67 @BASEBOARD_FAB2_LIB.BASEBOARD_FAB2(SCH_1):PAGE46
    73 PVDDQ_ABC @BASEBOARD_FAB2_LIB.BASEBOARD_FAB2(SCH_1):PVDDQ_ABC    I67 @BASEBOARD_FAB2_LIB.BASEBOARD_FAB2(SCH_1):PAGE46
    76 PVDDQ_ABC @BASEBOARD_FAB2_LIB.BASEBOARD_FAB2(SCH_1):PVDDQ_ABC    I67 @BASEBOARD_FAB2_LIB.BASEBOARD_FAB2(SCH_1):PAGE46
    80 PVDDQ_ABC @BASEBOARD_FAB2_LIB.BASEBOARD_FAB2(SCH_1):PVDDQ_ABC    I67 @BASEBOARD_FAB2_LIB.BASEBOARD_FAB2(SCH_1):PAGE46
    83 PVDDQ_ABC @BASEBOARD_FAB2_LIB.BASEBOARD_FAB2(SCH_1):PVDDQ_ABC    I67 @BASEBOARD_FAB2_LIB.BASEBOARD_FAB2(SCH_1):PAGE46
    85 PVDDQ_ABC @BASEBOARD_FAB2_LIB.BASEBOARD_FAB2(SCH_1):PVDDQ_ABC    I67 @BASEBOARD_FAB2_LIB.BASEBOARD_FAB2(SCH_1):PAGE46
    88 PVDDQ_ABC @BASEBOARD_FAB2_LIB.BASEBOARD_FAB2(SCH_1):PVDDQ_ABC    I67 @BASEBOARD_FAB2_LIB.BASEBOARD_FAB2(SCH_1):PAGE46
    90 PVDDQ_ABC @BASEBOARD_FAB2_LIB.BASEBOARD_FAB2(SCH_1):PVDDQ_ABC    I67 @BASEBOARD_FAB2_LIB.BASEBOARD_FAB2(SCH_1):PAGE46
    92 PVDDQ_ABC @BASEBOARD_FAB2_LIB.BASEBOARD_FAB2(SCH_1):PVDDQ_ABC    I67 @BASEBOARD_FAB2_LIB.BASEBOARD_FAB2(SCH_1):PAGE46
   204 PVDDQ_ABC @BASEBOARD_FAB2_LIB.BASEBOARD_FAB2(SCH_1):PVDDQ_ABC    I67 @BASEBOARD_FAB2_LIB.BASEBOARD_FAB2(SCH_1):PAGE46
   206 PVDDQ_ABC @BASEBOARD_FAB2_LIB.BASEBOARD_FAB2(SCH_1):PVDDQ_ABC    I67 @BASEBOARD_FAB2_LIB.BASEBOARD_FAB2(SCH_1):PAGE46
   209 PVDDQ_ABC @BASEBOARD_FAB2_LIB.BASEBOARD_FAB2(SCH_1):PVDDQ_ABC    I67 @BASEBOARD_FAB2_LIB.BASEBOARD_FAB2(SCH_1):PAGE46
   212 PVDDQ_ABC @BASEBOARD_FAB2_LIB.BASEBOARD_FAB2(SCH_1):PVDDQ_ABC    I67 @BASEBOARD_FAB2_LIB.BASEBOARD_FAB2(SCH_1):PAGE46
   215 PVDDQ_ABC @BASEBOARD_FAB2_LIB.BASEBOARD_FAB2(SCH_1):PVDDQ_ABC    I67 @BASEBOARD_FAB2_LIB.BASEBOARD_FAB2(SCH_1):PAGE46
   217 PVDDQ_ABC @BASEBOARD_FAB2_LIB.BASEBOARD_FAB2(SCH_1):PVDDQ_ABC    I67 @BASEBOARD_FAB2_LIB.BASEBOARD_FAB2(SCH_1):PAGE46
   220 PVDDQ_ABC @BASEBOARD_FAB2_LIB.BASEBOARD_FAB2(SCH_1):PVDDQ_ABC    I67 @BASEBOARD_FAB2_LIB.BASEBOARD_FAB2(SCH_1):PAGE46
   223 PVDDQ_ABC @BASEBOARD_FAB2_LIB.BASEBOARD_FAB2(SCH_1):PVDDQ_ABC    I67 @BASEBOARD_FAB2_LIB.BASEBOARD_FAB2(SCH_1):PAGE46
   226 PVDDQ_ABC @BASEBOARD_FAB2_LIB.BASEBOARD_FAB2(SCH_1):PVDDQ_ABC    I67 @BASEBOARD_FAB2_LIB.BASEBOARD_FAB2(SCH_1):PAGE46
   229 PVDDQ_ABC @BASEBOARD_FAB2_LIB.BASEBOARD_FAB2(SCH_1):PVDDQ_ABC    I67 @BASEBOARD_FAB2_LIB.BASEBOARD_FAB2(SCH_1):PAGE46
   231 PVDDQ_ABC @BASEBOARD_FAB2_LIB.BASEBOARD_FAB2(SCH_1):PVDDQ_ABC    I67 @BASEBOARD_FAB2_LIB.BASEBOARD_FAB2(SCH_1):PAGE46
   233 PVDDQ_ABC @BASEBOARD_FAB2_LIB.BASEBOARD_FAB2(SCH_1):PVDDQ_ABC    I67 @BASEBOARD_FAB2_LIB.BASEBOARD_FAB2(SCH_1):PAGE46
   236 PVDDQ_ABC @BASEBOARD_FAB2_LIB.BASEBOARD_FAB2(SCH_1):PVDDQ_ABC    I67 @BASEBOARD_FAB2_LIB.BASEBOARD_FAB2(SCH_1):PAGE46
   142 PVPP_ABC @BASEBOARD_FAB2_LIB.BASEBOARD_FAB2(SCH_1):PVPP_ABC    I67 @BASEBOARD_FAB2_LIB.BASEBOARD_FAB2(SCH_1):PAGE46
   143 PVPP_ABC @BASEBOARD_FAB2_LIB.BASEBOARD_FAB2(SCH_1):PVPP_ABC    I67 @BASEBOARD_FAB2_LIB.BASEBOARD_FAB2(SCH_1):PAGE46
   288 PVPP_ABC @BASEBOARD_FAB2_LIB.BASEBOARD_FAB2(SCH_1):PVPP_ABC    I67 @BASEBOARD_FAB2_LIB.BASEBOARD_FAB2(SCH_1):PAGE46
   286 PVPP_ABC @BASEBOARD_FAB2_LIB.BASEBOARD_FAB2(SCH_1):PVPP_ABC    I67 @BASEBOARD_FAB2_LIB.BASEBOARD_FAB2(SCH_1):PAGE46
   287 PVPP_ABC @BASEBOARD_FAB2_LIB.BASEBOARD_FAB2(SCH_1):PVPP_ABC    I67 @BASEBOARD_FAB2_LIB.BASEBOARD_FAB2(SCH_1):PAGE46
    77 PVTT_ABC @BASEBOARD_FAB2_LIB.BASEBOARD_FAB2(SCH_1):PVTT_ABC    I67 @BASEBOARD_FAB2_LIB.BASEBOARD_FAB2(SCH_1):PAGE46
   221 PVTT_ABC @BASEBOARD_FAB2_LIB.BASEBOARD_FAB2(SCH_1):PVTT_ABC    I67 @BASEBOARD_FAB2_LIB.BASEBOARD_FAB2(SCH_1):PAGE46

J6U2 SCONN288_H44441003_PIP-SCONN,HA
    79 M_C_MA<0> @BASEBOARD_FAB2_LIB.BASEBOARD_FAB2(SCH_1):M_C_MA(0)   I111 @BASEBOARD_FAB2_LIB.BASEBOARD_FAB2(SCH_1):PAGE48
    72 M_C_MA<1> @BASEBOARD_FAB2_LIB.BASEBOARD_FAB2(SCH_1):M_C_MA(1)   I111 @BASEBOARD_FAB2_LIB.BASEBOARD_FAB2(SCH_1):PAGE48
   225 M_C_MA<10> @BASEBOARD_FAB2_LIB.BASEBOARD_FAB2(SCH_1):M_C_MA(10)   I111 @BASEBOARD_FAB2_LIB.BASEBOARD_FAB2(SCH_1):PAGE48
   210 M_C_MA<11> @BASEBOARD_FAB2_LIB.BASEBOARD_FAB2(SCH_1):M_C_MA(11)   I111 @BASEBOARD_FAB2_LIB.BASEBOARD_FAB2(SCH_1):PAGE48
    65 M_C_MA<12> @BASEBOARD_FAB2_LIB.BASEBOARD_FAB2(SCH_1):M_C_MA(12)   I111 @BASEBOARD_FAB2_LIB.BASEBOARD_FAB2(SCH_1):PAGE48
   232 M_C_MA<13> @BASEBOARD_FAB2_LIB.BASEBOARD_FAB2(SCH_1):M_C_MA(13)   I111 @BASEBOARD_FAB2_LIB.BASEBOARD_FAB2(SCH_1):PAGE48
   228 M_C_MA<14> @BASEBOARD_FAB2_LIB.BASEBOARD_FAB2(SCH_1):M_C_MA(14)   I111 @BASEBOARD_FAB2_LIB.BASEBOARD_FAB2(SCH_1):PAGE48
    86 M_C_MA<15> @BASEBOARD_FAB2_LIB.BASEBOARD_FAB2(SCH_1):M_C_MA(15)   I111 @BASEBOARD_FAB2_LIB.BASEBOARD_FAB2(SCH_1):PAGE48
    82 M_C_MA<16> @BASEBOARD_FAB2_LIB.BASEBOARD_FAB2(SCH_1):M_C_MA(16)   I111 @BASEBOARD_FAB2_LIB.BASEBOARD_FAB2(SCH_1):PAGE48
   234 M_C_MA<17> @BASEBOARD_FAB2_LIB.BASEBOARD_FAB2(SCH_1):M_C_MA(17)   I111 @BASEBOARD_FAB2_LIB.BASEBOARD_FAB2(SCH_1):PAGE48
   216 M_C_MA<2> @BASEBOARD_FAB2_LIB.BASEBOARD_FAB2(SCH_1):M_C_MA(2)   I111 @BASEBOARD_FAB2_LIB.BASEBOARD_FAB2(SCH_1):PAGE48
    71 M_C_MA<3> @BASEBOARD_FAB2_LIB.BASEBOARD_FAB2(SCH_1):M_C_MA(3)   I111 @BASEBOARD_FAB2_LIB.BASEBOARD_FAB2(SCH_1):PAGE48
   214 M_C_MA<4> @BASEBOARD_FAB2_LIB.BASEBOARD_FAB2(SCH_1):M_C_MA(4)   I111 @BASEBOARD_FAB2_LIB.BASEBOARD_FAB2(SCH_1):PAGE48
   213 M_C_MA<5> @BASEBOARD_FAB2_LIB.BASEBOARD_FAB2(SCH_1):M_C_MA(5)   I111 @BASEBOARD_FAB2_LIB.BASEBOARD_FAB2(SCH_1):PAGE48
    69 M_C_MA<6> @BASEBOARD_FAB2_LIB.BASEBOARD_FAB2(SCH_1):M_C_MA(6)   I111 @BASEBOARD_FAB2_LIB.BASEBOARD_FAB2(SCH_1):PAGE48
   211 M_C_MA<7> @BASEBOARD_FAB2_LIB.BASEBOARD_FAB2(SCH_1):M_C_MA(7)   I111 @BASEBOARD_FAB2_LIB.BASEBOARD_FAB2(SCH_1):PAGE48
    68 M_C_MA<8> @BASEBOARD_FAB2_LIB.BASEBOARD_FAB2(SCH_1):M_C_MA(8)   I111 @BASEBOARD_FAB2_LIB.BASEBOARD_FAB2(SCH_1):PAGE48
    66 M_C_MA<9> @BASEBOARD_FAB2_LIB.BASEBOARD_FAB2(SCH_1):M_C_MA(9)   I111 @BASEBOARD_FAB2_LIB.BASEBOARD_FAB2(SCH_1):PAGE48
    62 M_C_ACT_N @BASEBOARD_FAB2_LIB.BASEBOARD_FAB2(SCH_1):M_C_ACT_N   I111 @BASEBOARD_FAB2_LIB.BASEBOARD_FAB2(SCH_1):PAGE48
   208 M_C_ALERT_N @BASEBOARD_FAB2_LIB.BASEBOARD_FAB2(SCH_1):M_C_ALERT_N   I111 @BASEBOARD_FAB2_LIB.BASEBOARD_FAB2(SCH_1):PAGE48
   224 M_C_BA<1> @BASEBOARD_FAB2_LIB.BASEBOARD_FAB2(SCH_1):M_C_BA(1)   I111 @BASEBOARD_FAB2_LIB.BASEBOARD_FAB2(SCH_1):PAGE48
    81 M_C_BA<0> @BASEBOARD_FAB2_LIB.BASEBOARD_FAB2(SCH_1):M_C_BA(0)   I111 @BASEBOARD_FAB2_LIB.BASEBOARD_FAB2(SCH_1):PAGE48
   207 M_C_BG<1> @BASEBOARD_FAB2_LIB.BASEBOARD_FAB2(SCH_1):M_C_BG(1)   I111 @BASEBOARD_FAB2_LIB.BASEBOARD_FAB2(SCH_1):PAGE48
    63 M_C_BG<0> @BASEBOARD_FAB2_LIB.BASEBOARD_FAB2(SCH_1):M_C_BG(0)   I111 @BASEBOARD_FAB2_LIB.BASEBOARD_FAB2(SCH_1):PAGE48
   235 M_C_C<2> @BASEBOARD_FAB2_LIB.BASEBOARD_FAB2(SCH_1):M_C_C(2)   I111 @BASEBOARD_FAB2_LIB.BASEBOARD_FAB2(SCH_1):PAGE48
   199 M_C_ECC<7> @BASEBOARD_FAB2_LIB.BASEBOARD_FAB2(SCH_1):M_C_ECC(7)   I111 @BASEBOARD_FAB2_LIB.BASEBOARD_FAB2(SCH_1):PAGE48
    54 M_C_ECC<6> @BASEBOARD_FAB2_LIB.BASEBOARD_FAB2(SCH_1):M_C_ECC(6)   I111 @BASEBOARD_FAB2_LIB.BASEBOARD_FAB2(SCH_1):PAGE48
   192 M_C_ECC<5> @BASEBOARD_FAB2_LIB.BASEBOARD_FAB2(SCH_1):M_C_ECC(5)   I111 @BASEBOARD_FAB2_LIB.BASEBOARD_FAB2(SCH_1):PAGE48
    47 M_C_ECC<4> @BASEBOARD_FAB2_LIB.BASEBOARD_FAB2(SCH_1):M_C_ECC(4)   I111 @BASEBOARD_FAB2_LIB.BASEBOARD_FAB2(SCH_1):PAGE48
   201 M_C_ECC<3> @BASEBOARD_FAB2_LIB.BASEBOARD_FAB2(SCH_1):M_C_ECC(3)   I111 @BASEBOARD_FAB2_LIB.BASEBOARD_FAB2(SCH_1):PAGE48
    56 M_C_ECC<2> @BASEBOARD_FAB2_LIB.BASEBOARD_FAB2(SCH_1):M_C_ECC(2)   I111 @BASEBOARD_FAB2_LIB.BASEBOARD_FAB2(SCH_1):PAGE48
   194 M_C_ECC<1> @BASEBOARD_FAB2_LIB.BASEBOARD_FAB2(SCH_1):M_C_ECC(1)   I111 @BASEBOARD_FAB2_LIB.BASEBOARD_FAB2(SCH_1):PAGE48
    49 M_C_ECC<0> @BASEBOARD_FAB2_LIB.BASEBOARD_FAB2(SCH_1):M_C_ECC(0)   I111 @BASEBOARD_FAB2_LIB.BASEBOARD_FAB2(SCH_1):PAGE48
    75 M_C_CLK_DN<2> @BASEBOARD_FAB2_LIB.BASEBOARD_FAB2(SCH_1):M_C_CLK_DN(2)   I111 @BASEBOARD_FAB2_LIB.BASEBOARD_FAB2(SCH_1):PAGE48
    74 M_C_CLK_DP<2> @BASEBOARD_FAB2_LIB.BASEBOARD_FAB2(SCH_1):M_C_CLK_DP(2)   I111 @BASEBOARD_FAB2_LIB.BASEBOARD_FAB2(SCH_1):PAGE48
   219 M_C_CLK_DN<3> @BASEBOARD_FAB2_LIB.BASEBOARD_FAB2(SCH_1):M_C_CLK_DN(3)   I111 @BASEBOARD_FAB2_LIB.BASEBOARD_FAB2(SCH_1):PAGE48
   218 M_C_CLK_DP<3> @BASEBOARD_FAB2_LIB.BASEBOARD_FAB2(SCH_1):M_C_CLK_DP(3)   I111 @BASEBOARD_FAB2_LIB.BASEBOARD_FAB2(SCH_1):PAGE48
   203 M_C_CKE<3> @BASEBOARD_FAB2_LIB.BASEBOARD_FAB2(SCH_1):M_C_CKE(3)   I111 @BASEBOARD_FAB2_LIB.BASEBOARD_FAB2(SCH_1):PAGE48
    60 M_C_CKE<2> @BASEBOARD_FAB2_LIB.BASEBOARD_FAB2(SCH_1):M_C_CKE(2)   I111 @BASEBOARD_FAB2_LIB.BASEBOARD_FAB2(SCH_1):PAGE48
   280 M_C_DQ<63> @BASEBOARD_FAB2_LIB.BASEBOARD_FAB2(SCH_1):M_C_DQ(63)   I111 @BASEBOARD_FAB2_LIB.BASEBOARD_FAB2(SCH_1):PAGE48
   135 M_C_DQ<62> @BASEBOARD_FAB2_LIB.BASEBOARD_FAB2(SCH_1):M_C_DQ(62)   I111 @BASEBOARD_FAB2_LIB.BASEBOARD_FAB2(SCH_1):PAGE48
   273 M_C_DQ<61> @BASEBOARD_FAB2_LIB.BASEBOARD_FAB2(SCH_1):M_C_DQ(61)   I111 @BASEBOARD_FAB2_LIB.BASEBOARD_FAB2(SCH_1):PAGE48
   128 M_C_DQ<60> @BASEBOARD_FAB2_LIB.BASEBOARD_FAB2(SCH_1):M_C_DQ(60)   I111 @BASEBOARD_FAB2_LIB.BASEBOARD_FAB2(SCH_1):PAGE48
   282 M_C_DQ<59> @BASEBOARD_FAB2_LIB.BASEBOARD_FAB2(SCH_1):M_C_DQ(59)   I111 @BASEBOARD_FAB2_LIB.BASEBOARD_FAB2(SCH_1):PAGE48
   137 M_C_DQ<58> @BASEBOARD_FAB2_LIB.BASEBOARD_FAB2(SCH_1):M_C_DQ(58)   I111 @BASEBOARD_FAB2_LIB.BASEBOARD_FAB2(SCH_1):PAGE48
   275 M_C_DQ<57> @BASEBOARD_FAB2_LIB.BASEBOARD_FAB2(SCH_1):M_C_DQ(57)   I111 @BASEBOARD_FAB2_LIB.BASEBOARD_FAB2(SCH_1):PAGE48
   130 M_C_DQ<56> @BASEBOARD_FAB2_LIB.BASEBOARD_FAB2(SCH_1):M_C_DQ(56)   I111 @BASEBOARD_FAB2_LIB.BASEBOARD_FAB2(SCH_1):PAGE48
   269 M_C_DQ<55> @BASEBOARD_FAB2_LIB.BASEBOARD_FAB2(SCH_1):M_C_DQ(55)   I111 @BASEBOARD_FAB2_LIB.BASEBOARD_FAB2(SCH_1):PAGE48
   124 M_C_DQ<54> @BASEBOARD_FAB2_LIB.BASEBOARD_FAB2(SCH_1):M_C_DQ(54)   I111 @BASEBOARD_FAB2_LIB.BASEBOARD_FAB2(SCH_1):PAGE48
   262 M_C_DQ<53> @BASEBOARD_FAB2_LIB.BASEBOARD_FAB2(SCH_1):M_C_DQ(53)   I111 @BASEBOARD_FAB2_LIB.BASEBOARD_FAB2(SCH_1):PAGE48
   117 M_C_DQ<52> @BASEBOARD_FAB2_LIB.BASEBOARD_FAB2(SCH_1):M_C_DQ(52)   I111 @BASEBOARD_FAB2_LIB.BASEBOARD_FAB2(SCH_1):PAGE48
   271 M_C_DQ<51> @BASEBOARD_FAB2_LIB.BASEBOARD_FAB2(SCH_1):M_C_DQ(51)   I111 @BASEBOARD_FAB2_LIB.BASEBOARD_FAB2(SCH_1):PAGE48
   126 M_C_DQ<50> @BASEBOARD_FAB2_LIB.BASEBOARD_FAB2(SCH_1):M_C_DQ(50)   I111 @BASEBOARD_FAB2_LIB.BASEBOARD_FAB2(SCH_1):PAGE48
   264 M_C_DQ<49> @BASEBOARD_FAB2_LIB.BASEBOARD_FAB2(SCH_1):M_C_DQ(49)   I111 @BASEBOARD_FAB2_LIB.BASEBOARD_FAB2(SCH_1):PAGE48
   119 M_C_DQ<48> @BASEBOARD_FAB2_LIB.BASEBOARD_FAB2(SCH_1):M_C_DQ(48)   I111 @BASEBOARD_FAB2_LIB.BASEBOARD_FAB2(SCH_1):PAGE48
   258 M_C_DQ<47> @BASEBOARD_FAB2_LIB.BASEBOARD_FAB2(SCH_1):M_C_DQ(47)   I111 @BASEBOARD_FAB2_LIB.BASEBOARD_FAB2(SCH_1):PAGE48
   113 M_C_DQ<46> @BASEBOARD_FAB2_LIB.BASEBOARD_FAB2(SCH_1):M_C_DQ(46)   I111 @BASEBOARD_FAB2_LIB.BASEBOARD_FAB2(SCH_1):PAGE48
   251 M_C_DQ<45> @BASEBOARD_FAB2_LIB.BASEBOARD_FAB2(SCH_1):M_C_DQ(45)   I111 @BASEBOARD_FAB2_LIB.BASEBOARD_FAB2(SCH_1):PAGE48
   106 M_C_DQ<44> @BASEBOARD_FAB2_LIB.BASEBOARD_FAB2(SCH_1):M_C_DQ(44)   I111 @BASEBOARD_FAB2_LIB.BASEBOARD_FAB2(SCH_1):PAGE48
   260 M_C_DQ<43> @BASEBOARD_FAB2_LIB.BASEBOARD_FAB2(SCH_1):M_C_DQ(43)   I111 @BASEBOARD_FAB2_LIB.BASEBOARD_FAB2(SCH_1):PAGE48
   115 M_C_DQ<42> @BASEBOARD_FAB2_LIB.BASEBOARD_FAB2(SCH_1):M_C_DQ(42)   I111 @BASEBOARD_FAB2_LIB.BASEBOARD_FAB2(SCH_1):PAGE48
   253 M_C_DQ<41> @BASEBOARD_FAB2_LIB.BASEBOARD_FAB2(SCH_1):M_C_DQ(41)   I111 @BASEBOARD_FAB2_LIB.BASEBOARD_FAB2(SCH_1):PAGE48
   108 M_C_DQ<40> @BASEBOARD_FAB2_LIB.BASEBOARD_FAB2(SCH_1):M_C_DQ(40)   I111 @BASEBOARD_FAB2_LIB.BASEBOARD_FAB2(SCH_1):PAGE48
   247 M_C_DQ<39> @BASEBOARD_FAB2_LIB.BASEBOARD_FAB2(SCH_1):M_C_DQ(39)   I111 @BASEBOARD_FAB2_LIB.BASEBOARD_FAB2(SCH_1):PAGE48
   102 M_C_DQ<38> @BASEBOARD_FAB2_LIB.BASEBOARD_FAB2(SCH_1):M_C_DQ(38)   I111 @BASEBOARD_FAB2_LIB.BASEBOARD_FAB2(SCH_1):PAGE48
   240 M_C_DQ<37> @BASEBOARD_FAB2_LIB.BASEBOARD_FAB2(SCH_1):M_C_DQ(37)   I111 @BASEBOARD_FAB2_LIB.BASEBOARD_FAB2(SCH_1):PAGE48
    95 M_C_DQ<36> @BASEBOARD_FAB2_LIB.BASEBOARD_FAB2(SCH_1):M_C_DQ(36)   I111 @BASEBOARD_FAB2_LIB.BASEBOARD_FAB2(SCH_1):PAGE48
   249 M_C_DQ<35> @BASEBOARD_FAB2_LIB.BASEBOARD_FAB2(SCH_1):M_C_DQ(35)   I111 @BASEBOARD_FAB2_LIB.BASEBOARD_FAB2(SCH_1):PAGE48
   104 M_C_DQ<34> @BASEBOARD_FAB2_LIB.BASEBOARD_FAB2(SCH_1):M_C_DQ(34)   I111 @BASEBOARD_FAB2_LIB.BASEBOARD_FAB2(SCH_1):PAGE48
   242 M_C_DQ<33> @BASEBOARD_FAB2_LIB.BASEBOARD_FAB2(SCH_1):M_C_DQ(33)   I111 @BASEBOARD_FAB2_LIB.BASEBOARD_FAB2(SCH_1):PAGE48
    97 M_C_DQ<32> @BASEBOARD_FAB2_LIB.BASEBOARD_FAB2(SCH_1):M_C_DQ(32)   I111 @BASEBOARD_FAB2_LIB.BASEBOARD_FAB2(SCH_1):PAGE48
   188 M_C_DQ<31> @BASEBOARD_FAB2_LIB.BASEBOARD_FAB2(SCH_1):M_C_DQ(31)   I111 @BASEBOARD_FAB2_LIB.BASEBOARD_FAB2(SCH_1):PAGE48
    43 M_C_DQ<30> @BASEBOARD_FAB2_LIB.BASEBOARD_FAB2(SCH_1):M_C_DQ(30)   I111 @BASEBOARD_FAB2_LIB.BASEBOARD_FAB2(SCH_1):PAGE48
   181 M_C_DQ<29> @BASEBOARD_FAB2_LIB.BASEBOARD_FAB2(SCH_1):M_C_DQ(29)   I111 @BASEBOARD_FAB2_LIB.BASEBOARD_FAB2(SCH_1):PAGE48
    36 M_C_DQ<28> @BASEBOARD_FAB2_LIB.BASEBOARD_FAB2(SCH_1):M_C_DQ(28)   I111 @BASEBOARD_FAB2_LIB.BASEBOARD_FAB2(SCH_1):PAGE48
   190 M_C_DQ<27> @BASEBOARD_FAB2_LIB.BASEBOARD_FAB2(SCH_1):M_C_DQ(27)   I111 @BASEBOARD_FAB2_LIB.BASEBOARD_FAB2(SCH_1):PAGE48
    45 M_C_DQ<26> @BASEBOARD_FAB2_LIB.BASEBOARD_FAB2(SCH_1):M_C_DQ(26)   I111 @BASEBOARD_FAB2_LIB.BASEBOARD_FAB2(SCH_1):PAGE48
   183 M_C_DQ<25> @BASEBOARD_FAB2_LIB.BASEBOARD_FAB2(SCH_1):M_C_DQ(25)   I111 @BASEBOARD_FAB2_LIB.BASEBOARD_FAB2(SCH_1):PAGE48
    38 M_C_DQ<24> @BASEBOARD_FAB2_LIB.BASEBOARD_FAB2(SCH_1):M_C_DQ(24)   I111 @BASEBOARD_FAB2_LIB.BASEBOARD_FAB2(SCH_1):PAGE48
   177 M_C_DQ<23> @BASEBOARD_FAB2_LIB.BASEBOARD_FAB2(SCH_1):M_C_DQ(23)   I111 @BASEBOARD_FAB2_LIB.BASEBOARD_FAB2(SCH_1):PAGE48
    32 M_C_DQ<22> @BASEBOARD_FAB2_LIB.BASEBOARD_FAB2(SCH_1):M_C_DQ(22)   I111 @BASEBOARD_FAB2_LIB.BASEBOARD_FAB2(SCH_1):PAGE48
   170 M_C_DQ<21> @BASEBOARD_FAB2_LIB.BASEBOARD_FAB2(SCH_1):M_C_DQ(21)   I111 @BASEBOARD_FAB2_LIB.BASEBOARD_FAB2(SCH_1):PAGE48
    25 M_C_DQ<20> @BASEBOARD_FAB2_LIB.BASEBOARD_FAB2(SCH_1):M_C_DQ(20)   I111 @BASEBOARD_FAB2_LIB.BASEBOARD_FAB2(SCH_1):PAGE48
   179 M_C_DQ<19> @BASEBOARD_FAB2_LIB.BASEBOARD_FAB2(SCH_1):M_C_DQ(19)   I111 @BASEBOARD_FAB2_LIB.BASEBOARD_FAB2(SCH_1):PAGE48
    34 M_C_DQ<18> @BASEBOARD_FAB2_LIB.BASEBOARD_FAB2(SCH_1):M_C_DQ(18)   I111 @BASEBOARD_FAB2_LIB.BASEBOARD_FAB2(SCH_1):PAGE48
   172 M_C_DQ<17> @BASEBOARD_FAB2_LIB.BASEBOARD_FAB2(SCH_1):M_C_DQ(17)   I111 @BASEBOARD_FAB2_LIB.BASEBOARD_FAB2(SCH_1):PAGE48
    27 M_C_DQ<16> @BASEBOARD_FAB2_LIB.BASEBOARD_FAB2(SCH_1):M_C_DQ(16)   I111 @BASEBOARD_FAB2_LIB.BASEBOARD_FAB2(SCH_1):PAGE48
   166 M_C_DQ<15> @BASEBOARD_FAB2_LIB.BASEBOARD_FAB2(SCH_1):M_C_DQ(15)   I111 @BASEBOARD_FAB2_LIB.BASEBOARD_FAB2(SCH_1):PAGE48
    21 M_C_DQ<14> @BASEBOARD_FAB2_LIB.BASEBOARD_FAB2(SCH_1):M_C_DQ(14)   I111 @BASEBOARD_FAB2_LIB.BASEBOARD_FAB2(SCH_1):PAGE48
   159 M_C_DQ<13> @BASEBOARD_FAB2_LIB.BASEBOARD_FAB2(SCH_1):M_C_DQ(13)   I111 @BASEBOARD_FAB2_LIB.BASEBOARD_FAB2(SCH_1):PAGE48
    14 M_C_DQ<12> @BASEBOARD_FAB2_LIB.BASEBOARD_FAB2(SCH_1):M_C_DQ(12)   I111 @BASEBOARD_FAB2_LIB.BASEBOARD_FAB2(SCH_1):PAGE48
   168 M_C_DQ<11> @BASEBOARD_FAB2_LIB.BASEBOARD_FAB2(SCH_1):M_C_DQ(11)   I111 @BASEBOARD_FAB2_LIB.BASEBOARD_FAB2(SCH_1):PAGE48
    23 M_C_DQ<10> @BASEBOARD_FAB2_LIB.BASEBOARD_FAB2(SCH_1):M_C_DQ(10)   I111 @BASEBOARD_FAB2_LIB.BASEBOARD_FAB2(SCH_1):PAGE48
   161 M_C_DQ<9> @BASEBOARD_FAB2_LIB.BASEBOARD_FAB2(SCH_1):M_C_DQ(9)   I111 @BASEBOARD_FAB2_LIB.BASEBOARD_FAB2(SCH_1):PAGE48
    16 M_C_DQ<8> @BASEBOARD_FAB2_LIB.BASEBOARD_FAB2(SCH_1):M_C_DQ(8)   I111 @BASEBOARD_FAB2_LIB.BASEBOARD_FAB2(SCH_1):PAGE48
   155 M_C_DQ<7> @BASEBOARD_FAB2_LIB.BASEBOARD_FAB2(SCH_1):M_C_DQ(7)   I111 @BASEBOARD_FAB2_LIB.BASEBOARD_FAB2(SCH_1):PAGE48
    10 M_C_DQ<6> @BASEBOARD_FAB2_LIB.BASEBOARD_FAB2(SCH_1):M_C_DQ(6)   I111 @BASEBOARD_FAB2_LIB.BASEBOARD_FAB2(SCH_1):PAGE48
   148 M_C_DQ<5> @BASEBOARD_FAB2_LIB.BASEBOARD_FAB2(SCH_1):M_C_DQ(5)   I111 @BASEBOARD_FAB2_LIB.BASEBOARD_FAB2(SCH_1):PAGE48
     3 M_C_DQ<4> @BASEBOARD_FAB2_LIB.BASEBOARD_FAB2(SCH_1):M_C_DQ(4)   I111 @BASEBOARD_FAB2_LIB.BASEBOARD_FAB2(SCH_1):PAGE48
   157 M_C_DQ<3> @BASEBOARD_FAB2_LIB.BASEBOARD_FAB2(SCH_1):M_C_DQ(3)   I111 @BASEBOARD_FAB2_LIB.BASEBOARD_FAB2(SCH_1):PAGE48
    12 M_C_DQ<2> @BASEBOARD_FAB2_LIB.BASEBOARD_FAB2(SCH_1):M_C_DQ(2)   I111 @BASEBOARD_FAB2_LIB.BASEBOARD_FAB2(SCH_1):PAGE48
   150 M_C_DQ<1> @BASEBOARD_FAB2_LIB.BASEBOARD_FAB2(SCH_1):M_C_DQ(1)   I111 @BASEBOARD_FAB2_LIB.BASEBOARD_FAB2(SCH_1):PAGE48
     5 M_C_DQ<0> @BASEBOARD_FAB2_LIB.BASEBOARD_FAB2(SCH_1):M_C_DQ(0)   I111 @BASEBOARD_FAB2_LIB.BASEBOARD_FAB2(SCH_1):PAGE48
    78 FM_DIMM_EVENT_COD_N @BASEBOARD_FAB2_LIB.BASEBOARD_FAB2(SCH_1):FM_DIMM_EVENT_COD_N   I111 @BASEBOARD_FAB2_LIB.BASEBOARD_FAB2(SCH_1):PAGE48
    91 M_C_ODT<3> @BASEBOARD_FAB2_LIB.BASEBOARD_FAB2(SCH_1):M_C_ODT(3)   I111 @BASEBOARD_FAB2_LIB.BASEBOARD_FAB2(SCH_1):PAGE48
    87 M_C_ODT<2> @BASEBOARD_FAB2_LIB.BASEBOARD_FAB2(SCH_1):M_C_ODT(2)   I111 @BASEBOARD_FAB2_LIB.BASEBOARD_FAB2(SCH_1):PAGE48
   222 M_C_PAR @BASEBOARD_FAB2_LIB.BASEBOARD_FAB2(SCH_1):M_C_PAR   I111 @BASEBOARD_FAB2_LIB.BASEBOARD_FAB2(SCH_1):PAGE48
    58 M_ABC_RST_N @BASEBOARD_FAB2_LIB.BASEBOARD_FAB2(SCH_1):M_ABC_RST_N   I111 @BASEBOARD_FAB2_LIB.BASEBOARD_FAB2(SCH_1):PAGE48
   144 TP_CH_C_DIMM_C1_RFU_2 @BASEBOARD_FAB2_LIB.BASEBOARD_FAB2(SCH_1):TP_CH_C_DIMM_C1_RFU_2   I111 @BASEBOARD_FAB2_LIB.BASEBOARD_FAB2(SCH_1):PAGE48
   227 TP_CH_C_DIMM_C1_RFU_1 @BASEBOARD_FAB2_LIB.BASEBOARD_FAB2(SCH_1):TP_CH_C_DIMM_C1_RFU_1   I111 @BASEBOARD_FAB2_LIB.BASEBOARD_FAB2(SCH_1):PAGE48
   205 TP_CH_C_DIMM_C1_RFU_0 @BASEBOARD_FAB2_LIB.BASEBOARD_FAB2(SCH_1):TP_CH_C_DIMM_C1_RFU_0   I111 @BASEBOARD_FAB2_LIB.BASEBOARD_FAB2(SCH_1):PAGE48
    84 M_C_CS_N<4> @BASEBOARD_FAB2_LIB.BASEBOARD_FAB2(SCH_1):M_C_CS_N(4)   I111 @BASEBOARD_FAB2_LIB.BASEBOARD_FAB2(SCH_1):PAGE48
    89 M_C_CS_N<5> @BASEBOARD_FAB2_LIB.BASEBOARD_FAB2(SCH_1):M_C_CS_N(5)   I111 @BASEBOARD_FAB2_LIB.BASEBOARD_FAB2(SCH_1):PAGE48
    93 M_C_CS_N<6> @BASEBOARD_FAB2_LIB.BASEBOARD_FAB2(SCH_1):M_C_CS_N(6)   I111 @BASEBOARD_FAB2_LIB.BASEBOARD_FAB2(SCH_1):PAGE48
   237 M_C_CS_N<7> @BASEBOARD_FAB2_LIB.BASEBOARD_FAB2(SCH_1):M_C_CS_N(7)   I111 @BASEBOARD_FAB2_LIB.BASEBOARD_FAB2(SCH_1):PAGE48
   238 PVPP_ABC @BASEBOARD_FAB2_LIB.BASEBOARD_FAB2(SCH_1):PVPP_ABC   I111 @BASEBOARD_FAB2_LIB.BASEBOARD_FAB2(SCH_1):PAGE48
   140    GND @BASEBOARD_FAB2_LIB.BASEBOARD_FAB2(SCH_1):GND   I111 @BASEBOARD_FAB2_LIB.BASEBOARD_FAB2(SCH_1):PAGE48
   139 PVPP_ABC @BASEBOARD_FAB2_LIB.BASEBOARD_FAB2(SCH_1):PVPP_ABC   I111 @BASEBOARD_FAB2_LIB.BASEBOARD_FAB2(SCH_1):PAGE48
   230 FM_ADR_COMPLETE_ABC_N @BASEBOARD_FAB2_LIB.BASEBOARD_FAB2(SCH_1):FM_ADR_COMPLETE_ABC_N   I111 @BASEBOARD_FAB2_LIB.BASEBOARD_FAB2(SCH_1):PAGE48
   141 SMB_DDR_ABC_VPP_SCL @BASEBOARD_FAB2_LIB.BASEBOARD_FAB2(SCH_1):SMB_DDR_ABC_VPP_SCL   I111 @BASEBOARD_FAB2_LIB.BASEBOARD_FAB2(SCH_1):PAGE48
   285 SMB_DDR_ABC_VPP_SDA @BASEBOARD_FAB2_LIB.BASEBOARD_FAB2(SCH_1):SMB_DDR_ABC_VPP_SDA   I111 @BASEBOARD_FAB2_LIB.BASEBOARD_FAB2(SCH_1):PAGE48
   284 PVPP_ABC @BASEBOARD_FAB2_LIB.BASEBOARD_FAB2(SCH_1):PVPP_ABC   I111 @BASEBOARD_FAB2_LIB.BASEBOARD_FAB2(SCH_1):PAGE48
   146 M_C_VREF @BASEBOARD_FAB2_LIB.BASEBOARD_FAB2(SCH_1):M_C_VREF   I111 @BASEBOARD_FAB2_LIB.BASEBOARD_FAB2(SCH_1):PAGE48
   152 M_C_DQS_DN<0> @BASEBOARD_FAB2_LIB.BASEBOARD_FAB2(SCH_1):M_C_DQS_DN(0)    I61 @BASEBOARD_FAB2_LIB.BASEBOARD_FAB2(SCH_1):PAGE48
   153 M_C_DQS_DP<0> @BASEBOARD_FAB2_LIB.BASEBOARD_FAB2(SCH_1):M_C_DQS_DP(0)    I61 @BASEBOARD_FAB2_LIB.BASEBOARD_FAB2(SCH_1):PAGE48
    19 M_C_DQS_DN<10> @BASEBOARD_FAB2_LIB.BASEBOARD_FAB2(SCH_1):M_C_DQS_DN(10)    I61 @BASEBOARD_FAB2_LIB.BASEBOARD_FAB2(SCH_1):PAGE48
    18 M_C_DQS_DP<10> @BASEBOARD_FAB2_LIB.BASEBOARD_FAB2(SCH_1):M_C_DQS_DP(10)    I61 @BASEBOARD_FAB2_LIB.BASEBOARD_FAB2(SCH_1):PAGE48
    30 M_C_DQS_DN<11> @BASEBOARD_FAB2_LIB.BASEBOARD_FAB2(SCH_1):M_C_DQS_DN(11)    I61 @BASEBOARD_FAB2_LIB.BASEBOARD_FAB2(SCH_1):PAGE48
    29 M_C_DQS_DP<11> @BASEBOARD_FAB2_LIB.BASEBOARD_FAB2(SCH_1):M_C_DQS_DP(11)    I61 @BASEBOARD_FAB2_LIB.BASEBOARD_FAB2(SCH_1):PAGE48
    41 M_C_DQS_DN<12> @BASEBOARD_FAB2_LIB.BASEBOARD_FAB2(SCH_1):M_C_DQS_DN(12)    I61 @BASEBOARD_FAB2_LIB.BASEBOARD_FAB2(SCH_1):PAGE48
    40 M_C_DQS_DP<12> @BASEBOARD_FAB2_LIB.BASEBOARD_FAB2(SCH_1):M_C_DQS_DP(12)    I61 @BASEBOARD_FAB2_LIB.BASEBOARD_FAB2(SCH_1):PAGE48
   100 M_C_DQS_DN<13> @BASEBOARD_FAB2_LIB.BASEBOARD_FAB2(SCH_1):M_C_DQS_DN(13)    I61 @BASEBOARD_FAB2_LIB.BASEBOARD_FAB2(SCH_1):PAGE48
    99 M_C_DQS_DP<13> @BASEBOARD_FAB2_LIB.BASEBOARD_FAB2(SCH_1):M_C_DQS_DP(13)    I61 @BASEBOARD_FAB2_LIB.BASEBOARD_FAB2(SCH_1):PAGE48
   111 M_C_DQS_DN<14> @BASEBOARD_FAB2_LIB.BASEBOARD_FAB2(SCH_1):M_C_DQS_DN(14)    I61 @BASEBOARD_FAB2_LIB.BASEBOARD_FAB2(SCH_1):PAGE48
   110 M_C_DQS_DP<14> @BASEBOARD_FAB2_LIB.BASEBOARD_FAB2(SCH_1):M_C_DQS_DP(14)    I61 @BASEBOARD_FAB2_LIB.BASEBOARD_FAB2(SCH_1):PAGE48
   122 M_C_DQS_DN<15> @BASEBOARD_FAB2_LIB.BASEBOARD_FAB2(SCH_1):M_C_DQS_DN(15)    I61 @BASEBOARD_FAB2_LIB.BASEBOARD_FAB2(SCH_1):PAGE48
   121 M_C_DQS_DP<15> @BASEBOARD_FAB2_LIB.BASEBOARD_FAB2(SCH_1):M_C_DQS_DP(15)    I61 @BASEBOARD_FAB2_LIB.BASEBOARD_FAB2(SCH_1):PAGE48
   133 M_C_DQS_DN<16> @BASEBOARD_FAB2_LIB.BASEBOARD_FAB2(SCH_1):M_C_DQS_DN(16)    I61 @BASEBOARD_FAB2_LIB.BASEBOARD_FAB2(SCH_1):PAGE48
   132 M_C_DQS_DP<16> @BASEBOARD_FAB2_LIB.BASEBOARD_FAB2(SCH_1):M_C_DQS_DP(16)    I61 @BASEBOARD_FAB2_LIB.BASEBOARD_FAB2(SCH_1):PAGE48
    52 M_C_DQS_DN<17> @BASEBOARD_FAB2_LIB.BASEBOARD_FAB2(SCH_1):M_C_DQS_DN(17)    I61 @BASEBOARD_FAB2_LIB.BASEBOARD_FAB2(SCH_1):PAGE48
    51 M_C_DQS_DP<17> @BASEBOARD_FAB2_LIB.BASEBOARD_FAB2(SCH_1):M_C_DQS_DP(17)    I61 @BASEBOARD_FAB2_LIB.BASEBOARD_FAB2(SCH_1):PAGE48
   163 M_C_DQS_DN<1> @BASEBOARD_FAB2_LIB.BASEBOARD_FAB2(SCH_1):M_C_DQS_DN(1)    I61 @BASEBOARD_FAB2_LIB.BASEBOARD_FAB2(SCH_1):PAGE48
   164 M_C_DQS_DP<1> @BASEBOARD_FAB2_LIB.BASEBOARD_FAB2(SCH_1):M_C_DQS_DP(1)    I61 @BASEBOARD_FAB2_LIB.BASEBOARD_FAB2(SCH_1):PAGE48
   174 M_C_DQS_DN<2> @BASEBOARD_FAB2_LIB.BASEBOARD_FAB2(SCH_1):M_C_DQS_DN(2)    I61 @BASEBOARD_FAB2_LIB.BASEBOARD_FAB2(SCH_1):PAGE48
   175 M_C_DQS_DP<2> @BASEBOARD_FAB2_LIB.BASEBOARD_FAB2(SCH_1):M_C_DQS_DP(2)    I61 @BASEBOARD_FAB2_LIB.BASEBOARD_FAB2(SCH_1):PAGE48
   185 M_C_DQS_DN<3> @BASEBOARD_FAB2_LIB.BASEBOARD_FAB2(SCH_1):M_C_DQS_DN(3)    I61 @BASEBOARD_FAB2_LIB.BASEBOARD_FAB2(SCH_1):PAGE48
   186 M_C_DQS_DP<3> @BASEBOARD_FAB2_LIB.BASEBOARD_FAB2(SCH_1):M_C_DQS_DP(3)    I61 @BASEBOARD_FAB2_LIB.BASEBOARD_FAB2(SCH_1):PAGE48
   244 M_C_DQS_DN<4> @BASEBOARD_FAB2_LIB.BASEBOARD_FAB2(SCH_1):M_C_DQS_DN(4)    I61 @BASEBOARD_FAB2_LIB.BASEBOARD_FAB2(SCH_1):PAGE48
   245 M_C_DQS_DP<4> @BASEBOARD_FAB2_LIB.BASEBOARD_FAB2(SCH_1):M_C_DQS_DP(4)    I61 @BASEBOARD_FAB2_LIB.BASEBOARD_FAB2(SCH_1):PAGE48
   255 M_C_DQS_DN<5> @BASEBOARD_FAB2_LIB.BASEBOARD_FAB2(SCH_1):M_C_DQS_DN(5)    I61 @BASEBOARD_FAB2_LIB.BASEBOARD_FAB2(SCH_1):PAGE48
   256 M_C_DQS_DP<5> @BASEBOARD_FAB2_LIB.BASEBOARD_FAB2(SCH_1):M_C_DQS_DP(5)    I61 @BASEBOARD_FAB2_LIB.BASEBOARD_FAB2(SCH_1):PAGE48
   266 M_C_DQS_DN<6> @BASEBOARD_FAB2_LIB.BASEBOARD_FAB2(SCH_1):M_C_DQS_DN(6)    I61 @BASEBOARD_FAB2_LIB.BASEBOARD_FAB2(SCH_1):PAGE48
   267 M_C_DQS_DP<6> @BASEBOARD_FAB2_LIB.BASEBOARD_FAB2(SCH_1):M_C_DQS_DP(6)    I61 @BASEBOARD_FAB2_LIB.BASEBOARD_FAB2(SCH_1):PAGE48
   277 M_C_DQS_DN<7> @BASEBOARD_FAB2_LIB.BASEBOARD_FAB2(SCH_1):M_C_DQS_DN(7)    I61 @BASEBOARD_FAB2_LIB.BASEBOARD_FAB2(SCH_1):PAGE48
   278 M_C_DQS_DP<7> @BASEBOARD_FAB2_LIB.BASEBOARD_FAB2(SCH_1):M_C_DQS_DP(7)    I61 @BASEBOARD_FAB2_LIB.BASEBOARD_FAB2(SCH_1):PAGE48
   196 M_C_DQS_DN<8> @BASEBOARD_FAB2_LIB.BASEBOARD_FAB2(SCH_1):M_C_DQS_DN(8)    I61 @BASEBOARD_FAB2_LIB.BASEBOARD_FAB2(SCH_1):PAGE48
   197 M_C_DQS_DP<8> @BASEBOARD_FAB2_LIB.BASEBOARD_FAB2(SCH_1):M_C_DQS_DP(8)    I61 @BASEBOARD_FAB2_LIB.BASEBOARD_FAB2(SCH_1):PAGE48
     8 M_C_DQS_DN<9> @BASEBOARD_FAB2_LIB.BASEBOARD_FAB2(SCH_1):M_C_DQS_DN(9)    I61 @BASEBOARD_FAB2_LIB.BASEBOARD_FAB2(SCH_1):PAGE48
     7 M_C_DQS_DP<9> @BASEBOARD_FAB2_LIB.BASEBOARD_FAB2(SCH_1):M_C_DQS_DP(9)    I61 @BASEBOARD_FAB2_LIB.BASEBOARD_FAB2(SCH_1):PAGE48
     2    GND @BASEBOARD_FAB2_LIB.BASEBOARD_FAB2(SCH_1):GND    I43 @BASEBOARD_FAB2_LIB.BASEBOARD_FAB2(SCH_1):PAGE48
     4    GND @BASEBOARD_FAB2_LIB.BASEBOARD_FAB2(SCH_1):GND    I43 @BASEBOARD_FAB2_LIB.BASEBOARD_FAB2(SCH_1):PAGE48
     6    GND @BASEBOARD_FAB2_LIB.BASEBOARD_FAB2(SCH_1):GND    I43 @BASEBOARD_FAB2_LIB.BASEBOARD_FAB2(SCH_1):PAGE48
     9    GND @BASEBOARD_FAB2_LIB.BASEBOARD_FAB2(SCH_1):GND    I43 @BASEBOARD_FAB2_LIB.BASEBOARD_FAB2(SCH_1):PAGE48
    11    GND @BASEBOARD_FAB2_LIB.BASEBOARD_FAB2(SCH_1):GND    I43 @BASEBOARD_FAB2_LIB.BASEBOARD_FAB2(SCH_1):PAGE48
    13    GND @BASEBOARD_FAB2_LIB.BASEBOARD_FAB2(SCH_1):GND    I43 @BASEBOARD_FAB2_LIB.BASEBOARD_FAB2(SCH_1):PAGE48
    15    GND @BASEBOARD_FAB2_LIB.BASEBOARD_FAB2(SCH_1):GND    I43 @BASEBOARD_FAB2_LIB.BASEBOARD_FAB2(SCH_1):PAGE48
    17    GND @BASEBOARD_FAB2_LIB.BASEBOARD_FAB2(SCH_1):GND    I43 @BASEBOARD_FAB2_LIB.BASEBOARD_FAB2(SCH_1):PAGE48
    20    GND @BASEBOARD_FAB2_LIB.BASEBOARD_FAB2(SCH_1):GND    I43 @BASEBOARD_FAB2_LIB.BASEBOARD_FAB2(SCH_1):PAGE48
    22    GND @BASEBOARD_FAB2_LIB.BASEBOARD_FAB2(SCH_1):GND    I43 @BASEBOARD_FAB2_LIB.BASEBOARD_FAB2(SCH_1):PAGE48
    24    GND @BASEBOARD_FAB2_LIB.BASEBOARD_FAB2(SCH_1):GND    I43 @BASEBOARD_FAB2_LIB.BASEBOARD_FAB2(SCH_1):PAGE48
    26    GND @BASEBOARD_FAB2_LIB.BASEBOARD_FAB2(SCH_1):GND    I43 @BASEBOARD_FAB2_LIB.BASEBOARD_FAB2(SCH_1):PAGE48
    28    GND @BASEBOARD_FAB2_LIB.BASEBOARD_FAB2(SCH_1):GND    I43 @BASEBOARD_FAB2_LIB.BASEBOARD_FAB2(SCH_1):PAGE48
    31    GND @BASEBOARD_FAB2_LIB.BASEBOARD_FAB2(SCH_1):GND    I43 @BASEBOARD_FAB2_LIB.BASEBOARD_FAB2(SCH_1):PAGE48
    33    GND @BASEBOARD_FAB2_LIB.BASEBOARD_FAB2(SCH_1):GND    I43 @BASEBOARD_FAB2_LIB.BASEBOARD_FAB2(SCH_1):PAGE48
    35    GND @BASEBOARD_FAB2_LIB.BASEBOARD_FAB2(SCH_1):GND    I43 @BASEBOARD_FAB2_LIB.BASEBOARD_FAB2(SCH_1):PAGE48
    37    GND @BASEBOARD_FAB2_LIB.BASEBOARD_FAB2(SCH_1):GND    I43 @BASEBOARD_FAB2_LIB.BASEBOARD_FAB2(SCH_1):PAGE48
    39    GND @BASEBOARD_FAB2_LIB.BASEBOARD_FAB2(SCH_1):GND    I43 @BASEBOARD_FAB2_LIB.BASEBOARD_FAB2(SCH_1):PAGE48
    42    GND @BASEBOARD_FAB2_LIB.BASEBOARD_FAB2(SCH_1):GND    I43 @BASEBOARD_FAB2_LIB.BASEBOARD_FAB2(SCH_1):PAGE48
    44    GND @BASEBOARD_FAB2_LIB.BASEBOARD_FAB2(SCH_1):GND    I43 @BASEBOARD_FAB2_LIB.BASEBOARD_FAB2(SCH_1):PAGE48
    46    GND @BASEBOARD_FAB2_LIB.BASEBOARD_FAB2(SCH_1):GND    I43 @BASEBOARD_FAB2_LIB.BASEBOARD_FAB2(SCH_1):PAGE48
    48    GND @BASEBOARD_FAB2_LIB.BASEBOARD_FAB2(SCH_1):GND    I43 @BASEBOARD_FAB2_LIB.BASEBOARD_FAB2(SCH_1):PAGE48
    50    GND @BASEBOARD_FAB2_LIB.BASEBOARD_FAB2(SCH_1):GND    I43 @BASEBOARD_FAB2_LIB.BASEBOARD_FAB2(SCH_1):PAGE48
    53    GND @BASEBOARD_FAB2_LIB.BASEBOARD_FAB2(SCH_1):GND    I43 @BASEBOARD_FAB2_LIB.BASEBOARD_FAB2(SCH_1):PAGE48
    55    GND @BASEBOARD_FAB2_LIB.BASEBOARD_FAB2(SCH_1):GND    I43 @BASEBOARD_FAB2_LIB.BASEBOARD_FAB2(SCH_1):PAGE48
    57    GND @BASEBOARD_FAB2_LIB.BASEBOARD_FAB2(SCH_1):GND    I43 @BASEBOARD_FAB2_LIB.BASEBOARD_FAB2(SCH_1):PAGE48
    94    GND @BASEBOARD_FAB2_LIB.BASEBOARD_FAB2(SCH_1):GND    I43 @BASEBOARD_FAB2_LIB.BASEBOARD_FAB2(SCH_1):PAGE48
    96    GND @BASEBOARD_FAB2_LIB.BASEBOARD_FAB2(SCH_1):GND    I43 @BASEBOARD_FAB2_LIB.BASEBOARD_FAB2(SCH_1):PAGE48
    98    GND @BASEBOARD_FAB2_LIB.BASEBOARD_FAB2(SCH_1):GND    I43 @BASEBOARD_FAB2_LIB.BASEBOARD_FAB2(SCH_1):PAGE48
   101    GND @BASEBOARD_FAB2_LIB.BASEBOARD_FAB2(SCH_1):GND    I43 @BASEBOARD_FAB2_LIB.BASEBOARD_FAB2(SCH_1):PAGE48
   103    GND @BASEBOARD_FAB2_LIB.BASEBOARD_FAB2(SCH_1):GND    I43 @BASEBOARD_FAB2_LIB.BASEBOARD_FAB2(SCH_1):PAGE48
   105    GND @BASEBOARD_FAB2_LIB.BASEBOARD_FAB2(SCH_1):GND    I43 @BASEBOARD_FAB2_LIB.BASEBOARD_FAB2(SCH_1):PAGE48
   107    GND @BASEBOARD_FAB2_LIB.BASEBOARD_FAB2(SCH_1):GND    I43 @BASEBOARD_FAB2_LIB.BASEBOARD_FAB2(SCH_1):PAGE48
   109    GND @BASEBOARD_FAB2_LIB.BASEBOARD_FAB2(SCH_1):GND    I43 @BASEBOARD_FAB2_LIB.BASEBOARD_FAB2(SCH_1):PAGE48
   112    GND @BASEBOARD_FAB2_LIB.BASEBOARD_FAB2(SCH_1):GND    I43 @BASEBOARD_FAB2_LIB.BASEBOARD_FAB2(SCH_1):PAGE48
   114    GND @BASEBOARD_FAB2_LIB.BASEBOARD_FAB2(SCH_1):GND    I43 @BASEBOARD_FAB2_LIB.BASEBOARD_FAB2(SCH_1):PAGE48
   116    GND @BASEBOARD_FAB2_LIB.BASEBOARD_FAB2(SCH_1):GND    I43 @BASEBOARD_FAB2_LIB.BASEBOARD_FAB2(SCH_1):PAGE48
   118    GND @BASEBOARD_FAB2_LIB.BASEBOARD_FAB2(SCH_1):GND    I43 @BASEBOARD_FAB2_LIB.BASEBOARD_FAB2(SCH_1):PAGE48
   120    GND @BASEBOARD_FAB2_LIB.BASEBOARD_FAB2(SCH_1):GND    I43 @BASEBOARD_FAB2_LIB.BASEBOARD_FAB2(SCH_1):PAGE48
   123    GND @BASEBOARD_FAB2_LIB.BASEBOARD_FAB2(SCH_1):GND    I43 @BASEBOARD_FAB2_LIB.BASEBOARD_FAB2(SCH_1):PAGE48
   125    GND @BASEBOARD_FAB2_LIB.BASEBOARD_FAB2(SCH_1):GND    I43 @BASEBOARD_FAB2_LIB.BASEBOARD_FAB2(SCH_1):PAGE48
   127    GND @BASEBOARD_FAB2_LIB.BASEBOARD_FAB2(SCH_1):GND    I43 @BASEBOARD_FAB2_LIB.BASEBOARD_FAB2(SCH_1):PAGE48
   129    GND @BASEBOARD_FAB2_LIB.BASEBOARD_FAB2(SCH_1):GND    I43 @BASEBOARD_FAB2_LIB.BASEBOARD_FAB2(SCH_1):PAGE48
   131    GND @BASEBOARD_FAB2_LIB.BASEBOARD_FAB2(SCH_1):GND    I43 @BASEBOARD_FAB2_LIB.BASEBOARD_FAB2(SCH_1):PAGE48
   134    GND @BASEBOARD_FAB2_LIB.BASEBOARD_FAB2(SCH_1):GND    I43 @BASEBOARD_FAB2_LIB.BASEBOARD_FAB2(SCH_1):PAGE48
   136    GND @BASEBOARD_FAB2_LIB.BASEBOARD_FAB2(SCH_1):GND    I43 @BASEBOARD_FAB2_LIB.BASEBOARD_FAB2(SCH_1):PAGE48
   138    GND @BASEBOARD_FAB2_LIB.BASEBOARD_FAB2(SCH_1):GND    I43 @BASEBOARD_FAB2_LIB.BASEBOARD_FAB2(SCH_1):PAGE48
   147    GND @BASEBOARD_FAB2_LIB.BASEBOARD_FAB2(SCH_1):GND    I43 @BASEBOARD_FAB2_LIB.BASEBOARD_FAB2(SCH_1):PAGE48
   149    GND @BASEBOARD_FAB2_LIB.BASEBOARD_FAB2(SCH_1):GND    I43 @BASEBOARD_FAB2_LIB.BASEBOARD_FAB2(SCH_1):PAGE48
   151    GND @BASEBOARD_FAB2_LIB.BASEBOARD_FAB2(SCH_1):GND    I43 @BASEBOARD_FAB2_LIB.BASEBOARD_FAB2(SCH_1):PAGE48
   154    GND @BASEBOARD_FAB2_LIB.BASEBOARD_FAB2(SCH_1):GND    I43 @BASEBOARD_FAB2_LIB.BASEBOARD_FAB2(SCH_1):PAGE48
   156    GND @BASEBOARD_FAB2_LIB.BASEBOARD_FAB2(SCH_1):GND    I43 @BASEBOARD_FAB2_LIB.BASEBOARD_FAB2(SCH_1):PAGE48
   158    GND @BASEBOARD_FAB2_LIB.BASEBOARD_FAB2(SCH_1):GND    I43 @BASEBOARD_FAB2_LIB.BASEBOARD_FAB2(SCH_1):PAGE48
   160    GND @BASEBOARD_FAB2_LIB.BASEBOARD_FAB2(SCH_1):GND    I43 @BASEBOARD_FAB2_LIB.BASEBOARD_FAB2(SCH_1):PAGE48
   162    GND @BASEBOARD_FAB2_LIB.BASEBOARD_FAB2(SCH_1):GND    I43 @BASEBOARD_FAB2_LIB.BASEBOARD_FAB2(SCH_1):PAGE48
   165    GND @BASEBOARD_FAB2_LIB.BASEBOARD_FAB2(SCH_1):GND    I43 @BASEBOARD_FAB2_LIB.BASEBOARD_FAB2(SCH_1):PAGE48
   167    GND @BASEBOARD_FAB2_LIB.BASEBOARD_FAB2(SCH_1):GND    I43 @BASEBOARD_FAB2_LIB.BASEBOARD_FAB2(SCH_1):PAGE48
   169    GND @BASEBOARD_FAB2_LIB.BASEBOARD_FAB2(SCH_1):GND    I43 @BASEBOARD_FAB2_LIB.BASEBOARD_FAB2(SCH_1):PAGE48
   171    GND @BASEBOARD_FAB2_LIB.BASEBOARD_FAB2(SCH_1):GND    I43 @BASEBOARD_FAB2_LIB.BASEBOARD_FAB2(SCH_1):PAGE48
   173    GND @BASEBOARD_FAB2_LIB.BASEBOARD_FAB2(SCH_1):GND    I43 @BASEBOARD_FAB2_LIB.BASEBOARD_FAB2(SCH_1):PAGE48
   176    GND @BASEBOARD_FAB2_LIB.BASEBOARD_FAB2(SCH_1):GND    I43 @BASEBOARD_FAB2_LIB.BASEBOARD_FAB2(SCH_1):PAGE48
   178    GND @BASEBOARD_FAB2_LIB.BASEBOARD_FAB2(SCH_1):GND    I43 @BASEBOARD_FAB2_LIB.BASEBOARD_FAB2(SCH_1):PAGE48
   180    GND @BASEBOARD_FAB2_LIB.BASEBOARD_FAB2(SCH_1):GND    I43 @BASEBOARD_FAB2_LIB.BASEBOARD_FAB2(SCH_1):PAGE48
   182    GND @BASEBOARD_FAB2_LIB.BASEBOARD_FAB2(SCH_1):GND    I43 @BASEBOARD_FAB2_LIB.BASEBOARD_FAB2(SCH_1):PAGE48
   184    GND @BASEBOARD_FAB2_LIB.BASEBOARD_FAB2(SCH_1):GND    I43 @BASEBOARD_FAB2_LIB.BASEBOARD_FAB2(SCH_1):PAGE48
   187    GND @BASEBOARD_FAB2_LIB.BASEBOARD_FAB2(SCH_1):GND    I43 @BASEBOARD_FAB2_LIB.BASEBOARD_FAB2(SCH_1):PAGE48
   189    GND @BASEBOARD_FAB2_LIB.BASEBOARD_FAB2(SCH_1):GND    I43 @BASEBOARD_FAB2_LIB.BASEBOARD_FAB2(SCH_1):PAGE48
   191    GND @BASEBOARD_FAB2_LIB.BASEBOARD_FAB2(SCH_1):GND    I43 @BASEBOARD_FAB2_LIB.BASEBOARD_FAB2(SCH_1):PAGE48
   193    GND @BASEBOARD_FAB2_LIB.BASEBOARD_FAB2(SCH_1):GND    I43 @BASEBOARD_FAB2_LIB.BASEBOARD_FAB2(SCH_1):PAGE48
   195    GND @BASEBOARD_FAB2_LIB.BASEBOARD_FAB2(SCH_1):GND    I43 @BASEBOARD_FAB2_LIB.BASEBOARD_FAB2(SCH_1):PAGE48
   198    GND @BASEBOARD_FAB2_LIB.BASEBOARD_FAB2(SCH_1):GND    I43 @BASEBOARD_FAB2_LIB.BASEBOARD_FAB2(SCH_1):PAGE48
   200    GND @BASEBOARD_FAB2_LIB.BASEBOARD_FAB2(SCH_1):GND    I43 @BASEBOARD_FAB2_LIB.BASEBOARD_FAB2(SCH_1):PAGE48
   202    GND @BASEBOARD_FAB2_LIB.BASEBOARD_FAB2(SCH_1):GND    I43 @BASEBOARD_FAB2_LIB.BASEBOARD_FAB2(SCH_1):PAGE48
   239    GND @BASEBOARD_FAB2_LIB.BASEBOARD_FAB2(SCH_1):GND    I43 @BASEBOARD_FAB2_LIB.BASEBOARD_FAB2(SCH_1):PAGE48
   241    GND @BASEBOARD_FAB2_LIB.BASEBOARD_FAB2(SCH_1):GND    I43 @BASEBOARD_FAB2_LIB.BASEBOARD_FAB2(SCH_1):PAGE48
   243    GND @BASEBOARD_FAB2_LIB.BASEBOARD_FAB2(SCH_1):GND    I43 @BASEBOARD_FAB2_LIB.BASEBOARD_FAB2(SCH_1):PAGE48
   246    GND @BASEBOARD_FAB2_LIB.BASEBOARD_FAB2(SCH_1):GND    I43 @BASEBOARD_FAB2_LIB.BASEBOARD_FAB2(SCH_1):PAGE48
   248    GND @BASEBOARD_FAB2_LIB.BASEBOARD_FAB2(SCH_1):GND    I43 @BASEBOARD_FAB2_LIB.BASEBOARD_FAB2(SCH_1):PAGE48
   250    GND @BASEBOARD_FAB2_LIB.BASEBOARD_FAB2(SCH_1):GND    I43 @BASEBOARD_FAB2_LIB.BASEBOARD_FAB2(SCH_1):PAGE48
   252    GND @BASEBOARD_FAB2_LIB.BASEBOARD_FAB2(SCH_1):GND    I43 @BASEBOARD_FAB2_LIB.BASEBOARD_FAB2(SCH_1):PAGE48
   254    GND @BASEBOARD_FAB2_LIB.BASEBOARD_FAB2(SCH_1):GND    I43 @BASEBOARD_FAB2_LIB.BASEBOARD_FAB2(SCH_1):PAGE48
   257    GND @BASEBOARD_FAB2_LIB.BASEBOARD_FAB2(SCH_1):GND    I43 @BASEBOARD_FAB2_LIB.BASEBOARD_FAB2(SCH_1):PAGE48
   259    GND @BASEBOARD_FAB2_LIB.BASEBOARD_FAB2(SCH_1):GND    I43 @BASEBOARD_FAB2_LIB.BASEBOARD_FAB2(SCH_1):PAGE48
   261    GND @BASEBOARD_FAB2_LIB.BASEBOARD_FAB2(SCH_1):GND    I43 @BASEBOARD_FAB2_LIB.BASEBOARD_FAB2(SCH_1):PAGE48
   263    GND @BASEBOARD_FAB2_LIB.BASEBOARD_FAB2(SCH_1):GND    I43 @BASEBOARD_FAB2_LIB.BASEBOARD_FAB2(SCH_1):PAGE48
   265    GND @BASEBOARD_FAB2_LIB.BASEBOARD_FAB2(SCH_1):GND    I43 @BASEBOARD_FAB2_LIB.BASEBOARD_FAB2(SCH_1):PAGE48
   268    GND @BASEBOARD_FAB2_LIB.BASEBOARD_FAB2(SCH_1):GND    I43 @BASEBOARD_FAB2_LIB.BASEBOARD_FAB2(SCH_1):PAGE48
   270    GND @BASEBOARD_FAB2_LIB.BASEBOARD_FAB2(SCH_1):GND    I43 @BASEBOARD_FAB2_LIB.BASEBOARD_FAB2(SCH_1):PAGE48
   272    GND @BASEBOARD_FAB2_LIB.BASEBOARD_FAB2(SCH_1):GND    I43 @BASEBOARD_FAB2_LIB.BASEBOARD_FAB2(SCH_1):PAGE48
   274    GND @BASEBOARD_FAB2_LIB.BASEBOARD_FAB2(SCH_1):GND    I43 @BASEBOARD_FAB2_LIB.BASEBOARD_FAB2(SCH_1):PAGE48
   276    GND @BASEBOARD_FAB2_LIB.BASEBOARD_FAB2(SCH_1):GND    I43 @BASEBOARD_FAB2_LIB.BASEBOARD_FAB2(SCH_1):PAGE48
   279    GND @BASEBOARD_FAB2_LIB.BASEBOARD_FAB2(SCH_1):GND    I43 @BASEBOARD_FAB2_LIB.BASEBOARD_FAB2(SCH_1):PAGE48
   281    GND @BASEBOARD_FAB2_LIB.BASEBOARD_FAB2(SCH_1):GND    I43 @BASEBOARD_FAB2_LIB.BASEBOARD_FAB2(SCH_1):PAGE48
   283    GND @BASEBOARD_FAB2_LIB.BASEBOARD_FAB2(SCH_1):GND    I43 @BASEBOARD_FAB2_LIB.BASEBOARD_FAB2(SCH_1):PAGE48
     1 P12V_NVDIMM_ABC @BASEBOARD_FAB2_LIB.BASEBOARD_FAB2(SCH_1):P12V_NVDIMM_ABC   I171 @BASEBOARD_FAB2_LIB.BASEBOARD_FAB2(SCH_1):PAGE48
   145 P12V_NVDIMM_ABC @BASEBOARD_FAB2_LIB.BASEBOARD_FAB2(SCH_1):P12V_NVDIMM_ABC   I171 @BASEBOARD_FAB2_LIB.BASEBOARD_FAB2(SCH_1):PAGE48
    59 PVDDQ_ABC @BASEBOARD_FAB2_LIB.BASEBOARD_FAB2(SCH_1):PVDDQ_ABC   I171 @BASEBOARD_FAB2_LIB.BASEBOARD_FAB2(SCH_1):PAGE48
    61 PVDDQ_ABC @BASEBOARD_FAB2_LIB.BASEBOARD_FAB2(SCH_1):PVDDQ_ABC   I171 @BASEBOARD_FAB2_LIB.BASEBOARD_FAB2(SCH_1):PAGE48
    64 PVDDQ_ABC @BASEBOARD_FAB2_LIB.BASEBOARD_FAB2(SCH_1):PVDDQ_ABC   I171 @BASEBOARD_FAB2_LIB.BASEBOARD_FAB2(SCH_1):PAGE48
    67 PVDDQ_ABC @BASEBOARD_FAB2_LIB.BASEBOARD_FAB2(SCH_1):PVDDQ_ABC   I171 @BASEBOARD_FAB2_LIB.BASEBOARD_FAB2(SCH_1):PAGE48
    70 PVDDQ_ABC @BASEBOARD_FAB2_LIB.BASEBOARD_FAB2(SCH_1):PVDDQ_ABC   I171 @BASEBOARD_FAB2_LIB.BASEBOARD_FAB2(SCH_1):PAGE48
    73 PVDDQ_ABC @BASEBOARD_FAB2_LIB.BASEBOARD_FAB2(SCH_1):PVDDQ_ABC   I171 @BASEBOARD_FAB2_LIB.BASEBOARD_FAB2(SCH_1):PAGE48
    76 PVDDQ_ABC @BASEBOARD_FAB2_LIB.BASEBOARD_FAB2(SCH_1):PVDDQ_ABC   I171 @BASEBOARD_FAB2_LIB.BASEBOARD_FAB2(SCH_1):PAGE48
    80 PVDDQ_ABC @BASEBOARD_FAB2_LIB.BASEBOARD_FAB2(SCH_1):PVDDQ_ABC   I171 @BASEBOARD_FAB2_LIB.BASEBOARD_FAB2(SCH_1):PAGE48
    83 PVDDQ_ABC @BASEBOARD_FAB2_LIB.BASEBOARD_FAB2(SCH_1):PVDDQ_ABC   I171 @BASEBOARD_FAB2_LIB.BASEBOARD_FAB2(SCH_1):PAGE48
    85 PVDDQ_ABC @BASEBOARD_FAB2_LIB.BASEBOARD_FAB2(SCH_1):PVDDQ_ABC   I171 @BASEBOARD_FAB2_LIB.BASEBOARD_FAB2(SCH_1):PAGE48
    88 PVDDQ_ABC @BASEBOARD_FAB2_LIB.BASEBOARD_FAB2(SCH_1):PVDDQ_ABC   I171 @BASEBOARD_FAB2_LIB.BASEBOARD_FAB2(SCH_1):PAGE48
    90 PVDDQ_ABC @BASEBOARD_FAB2_LIB.BASEBOARD_FAB2(SCH_1):PVDDQ_ABC   I171 @BASEBOARD_FAB2_LIB.BASEBOARD_FAB2(SCH_1):PAGE48
    92 PVDDQ_ABC @BASEBOARD_FAB2_LIB.BASEBOARD_FAB2(SCH_1):PVDDQ_ABC   I171 @BASEBOARD_FAB2_LIB.BASEBOARD_FAB2(SCH_1):PAGE48
   204 PVDDQ_ABC @BASEBOARD_FAB2_LIB.BASEBOARD_FAB2(SCH_1):PVDDQ_ABC   I171 @BASEBOARD_FAB2_LIB.BASEBOARD_FAB2(SCH_1):PAGE48
   206 PVDDQ_ABC @BASEBOARD_FAB2_LIB.BASEBOARD_FAB2(SCH_1):PVDDQ_ABC   I171 @BASEBOARD_FAB2_LIB.BASEBOARD_FAB2(SCH_1):PAGE48
   209 PVDDQ_ABC @BASEBOARD_FAB2_LIB.BASEBOARD_FAB2(SCH_1):PVDDQ_ABC   I171 @BASEBOARD_FAB2_LIB.BASEBOARD_FAB2(SCH_1):PAGE48
   212 PVDDQ_ABC @BASEBOARD_FAB2_LIB.BASEBOARD_FAB2(SCH_1):PVDDQ_ABC   I171 @BASEBOARD_FAB2_LIB.BASEBOARD_FAB2(SCH_1):PAGE48
   215 PVDDQ_ABC @BASEBOARD_FAB2_LIB.BASEBOARD_FAB2(SCH_1):PVDDQ_ABC   I171 @BASEBOARD_FAB2_LIB.BASEBOARD_FAB2(SCH_1):PAGE48
   217 PVDDQ_ABC @BASEBOARD_FAB2_LIB.BASEBOARD_FAB2(SCH_1):PVDDQ_ABC   I171 @BASEBOARD_FAB2_LIB.BASEBOARD_FAB2(SCH_1):PAGE48
   220 PVDDQ_ABC @BASEBOARD_FAB2_LIB.BASEBOARD_FAB2(SCH_1):PVDDQ_ABC   I171 @BASEBOARD_FAB2_LIB.BASEBOARD_FAB2(SCH_1):PAGE48
   223 PVDDQ_ABC @BASEBOARD_FAB2_LIB.BASEBOARD_FAB2(SCH_1):PVDDQ_ABC   I171 @BASEBOARD_FAB2_LIB.BASEBOARD_FAB2(SCH_1):PAGE48
   226 PVDDQ_ABC @BASEBOARD_FAB2_LIB.BASEBOARD_FAB2(SCH_1):PVDDQ_ABC   I171 @BASEBOARD_FAB2_LIB.BASEBOARD_FAB2(SCH_1):PAGE48
   229 PVDDQ_ABC @BASEBOARD_FAB2_LIB.BASEBOARD_FAB2(SCH_1):PVDDQ_ABC   I171 @BASEBOARD_FAB2_LIB.BASEBOARD_FAB2(SCH_1):PAGE48
   231 PVDDQ_ABC @BASEBOARD_FAB2_LIB.BASEBOARD_FAB2(SCH_1):PVDDQ_ABC   I171 @BASEBOARD_FAB2_LIB.BASEBOARD_FAB2(SCH_1):PAGE48
   233 PVDDQ_ABC @BASEBOARD_FAB2_LIB.BASEBOARD_FAB2(SCH_1):PVDDQ_ABC   I171 @BASEBOARD_FAB2_LIB.BASEBOARD_FAB2(SCH_1):PAGE48
   236 PVDDQ_ABC @BASEBOARD_FAB2_LIB.BASEBOARD_FAB2(SCH_1):PVDDQ_ABC   I171 @BASEBOARD_FAB2_LIB.BASEBOARD_FAB2(SCH_1):PAGE48
   142 PVPP_ABC @BASEBOARD_FAB2_LIB.BASEBOARD_FAB2(SCH_1):PVPP_ABC   I171 @BASEBOARD_FAB2_LIB.BASEBOARD_FAB2(SCH_1):PAGE48
   143 PVPP_ABC @BASEBOARD_FAB2_LIB.BASEBOARD_FAB2(SCH_1):PVPP_ABC   I171 @BASEBOARD_FAB2_LIB.BASEBOARD_FAB2(SCH_1):PAGE48
   288 PVPP_ABC @BASEBOARD_FAB2_LIB.BASEBOARD_FAB2(SCH_1):PVPP_ABC   I171 @BASEBOARD_FAB2_LIB.BASEBOARD_FAB2(SCH_1):PAGE48
   286 PVPP_ABC @BASEBOARD_FAB2_LIB.BASEBOARD_FAB2(SCH_1):PVPP_ABC   I171 @BASEBOARD_FAB2_LIB.BASEBOARD_FAB2(SCH_1):PAGE48
   287 PVPP_ABC @BASEBOARD_FAB2_LIB.BASEBOARD_FAB2(SCH_1):PVPP_ABC   I171 @BASEBOARD_FAB2_LIB.BASEBOARD_FAB2(SCH_1):PAGE48
    77 PVTT_ABC @BASEBOARD_FAB2_LIB.BASEBOARD_FAB2(SCH_1):PVTT_ABC   I171 @BASEBOARD_FAB2_LIB.BASEBOARD_FAB2(SCH_1):PAGE48
   221 PVTT_ABC @BASEBOARD_FAB2_LIB.BASEBOARD_FAB2(SCH_1):PVTT_ABC   I171 @BASEBOARD_FAB2_LIB.BASEBOARD_FAB2(SCH_1):PAGE48

J7G2 CONN8_C77962004_PIP-CONN,C7796A
     1 P3V3_STBY_PLD_D @BASEBOARD_FAB2_LIB.BASEBOARD_FAB2(SCH_1):P3V3_STBY_PLD_D    I47 @BASEBOARD_FAB2_LIB.BASEBOARD_FAB2(SCH_1):PAGE189
     2 JTAG_TDO_R @BASEBOARD_FAB2_LIB.BASEBOARD_FAB2(SCH_1):JTAG_TDO_R    I47 @BASEBOARD_FAB2_LIB.BASEBOARD_FAB2(SCH_1):PAGE189
     3 JTAG_TDI_R @BASEBOARD_FAB2_LIB.BASEBOARD_FAB2(SCH_1):JTAG_TDI_R    I47 @BASEBOARD_FAB2_LIB.BASEBOARD_FAB2(SCH_1):PAGE189
     4 JTAG_TRST_N @BASEBOARD_FAB2_LIB.BASEBOARD_FAB2(SCH_1):JTAG_TRST_N    I47 @BASEBOARD_FAB2_LIB.BASEBOARD_FAB2(SCH_1):PAGE189
     5 PWRGD_P3V3_STBY @BASEBOARD_FAB2_LIB.BASEBOARD_FAB2(SCH_1):PWRGD_P3V3_STBY    I47 @BASEBOARD_FAB2_LIB.BASEBOARD_FAB2(SCH_1):PAGE189
     6 JTAG_TMS_R @BASEBOARD_FAB2_LIB.BASEBOARD_FAB2(SCH_1):JTAG_TMS_R    I47 @BASEBOARD_FAB2_LIB.BASEBOARD_FAB2(SCH_1):PAGE189
     7    GND @BASEBOARD_FAB2_LIB.BASEBOARD_FAB2(SCH_1):GND    I47 @BASEBOARD_FAB2_LIB.BASEBOARD_FAB2(SCH_1):PAGE189
     8 JTAG_TCK_R @BASEBOARD_FAB2_LIB.BASEBOARD_FAB2(SCH_1):JTAG_TCK_R    I47 @BASEBOARD_FAB2_LIB.BASEBOARD_FAB2(SCH_1):PAGE189

J7G3 CONN12_C73564003_PIP-CONN,C735A
     1 TP_ME_RCVR_BOOT @BASEBOARD_FAB2_LIB.BASEBOARD_FAB2(SCH_1):TP_ME_RCVR_BOOT   I174 @BASEBOARD_FAB2_LIB.BASEBOARD_FAB2(SCH_1):PAGE136
    10 FM_BIOS_TOP_SWAP @BASEBOARD_FAB2_LIB.BASEBOARD_FAB2(SCH_1):FM_BIOS_TOP_SWAP   I174 @BASEBOARD_FAB2_LIB.BASEBOARD_FAB2(SCH_1):PAGE136
    11 PD_PASSWORD_CLEAR @BASEBOARD_FAB2_LIB.BASEBOARD_FAB2(SCH_1):PD_PASSWORD_CLEAR   I174 @BASEBOARD_FAB2_LIB.BASEBOARD_FAB2(SCH_1):PAGE136
    12 PU_BIOS_RECOVER_BOOT @BASEBOARD_FAB2_LIB.BASEBOARD_FAB2(SCH_1):PU_BIOS_RECOVER_BOOT   I174 @BASEBOARD_FAB2_LIB.BASEBOARD_FAB2(SCH_1):PAGE136
     2 TP_BIOS_USB_RECOVERY @BASEBOARD_FAB2_LIB.BASEBOARD_FAB2(SCH_1):TP_BIOS_USB_RECOVERY   I174 @BASEBOARD_FAB2_LIB.BASEBOARD_FAB2(SCH_1):PAGE136
     3 FM_ME_RECOVER_N @BASEBOARD_FAB2_LIB.BASEBOARD_FAB2(SCH_1):FM_ME_RECOVER_N   I174 @BASEBOARD_FAB2_LIB.BASEBOARD_FAB2(SCH_1):PAGE136
     4 FM_BIOS_USB_RECOVERY @BASEBOARD_FAB2_LIB.BASEBOARD_FAB2(SCH_1):FM_BIOS_USB_RECOVERY   I174 @BASEBOARD_FAB2_LIB.BASEBOARD_FAB2(SCH_1):PAGE136
     5 PD_ME_RCVR_N @BASEBOARD_FAB2_LIB.BASEBOARD_FAB2(SCH_1):PD_ME_RCVR_N   I174 @BASEBOARD_FAB2_LIB.BASEBOARD_FAB2(SCH_1):PAGE136
     6 PU_BIOS_USB_RECOVERY @BASEBOARD_FAB2_LIB.BASEBOARD_FAB2(SCH_1):PU_BIOS_USB_RECOVERY   I174 @BASEBOARD_FAB2_LIB.BASEBOARD_FAB2(SCH_1):PAGE136
     7 TP_PASSWORD_CLEAR @BASEBOARD_FAB2_LIB.BASEBOARD_FAB2(SCH_1):TP_PASSWORD_CLEAR   I174 @BASEBOARD_FAB2_LIB.BASEBOARD_FAB2(SCH_1):PAGE136
     8 TP_BIOS_RECOVER_BOOT @BASEBOARD_FAB2_LIB.BASEBOARD_FAB2(SCH_1):TP_BIOS_RECOVER_BOOT   I174 @BASEBOARD_FAB2_LIB.BASEBOARD_FAB2(SCH_1):PAGE136
     9 FM_PASSWORD_CLEAR_N @BASEBOARD_FAB2_LIB.BASEBOARD_FAB2(SCH_1):FM_PASSWORD_CLEAR_N   I174 @BASEBOARD_FAB2_LIB.BASEBOARD_FAB2(SCH_1):PAGE136

J8A1 CONN72_G97614002_A_CP-CONN,G97A
   1A3    GND @BASEBOARD_FAB2_LIB.BASEBOARD_FAB2(SCH_1):GND   I163 @BASEBOARD_FAB2_LIB.BASEBOARD_FAB2(SCH_1):PAGE173
   1A6    GND @BASEBOARD_FAB2_LIB.BASEBOARD_FAB2(SCH_1):GND   I163 @BASEBOARD_FAB2_LIB.BASEBOARD_FAB2(SCH_1):PAGE173
   1A9    GND @BASEBOARD_FAB2_LIB.BASEBOARD_FAB2(SCH_1):GND   I163 @BASEBOARD_FAB2_LIB.BASEBOARD_FAB2(SCH_1):PAGE173
   1B3    GND @BASEBOARD_FAB2_LIB.BASEBOARD_FAB2(SCH_1):GND   I163 @BASEBOARD_FAB2_LIB.BASEBOARD_FAB2(SCH_1):PAGE173
   1B6    GND @BASEBOARD_FAB2_LIB.BASEBOARD_FAB2(SCH_1):GND   I163 @BASEBOARD_FAB2_LIB.BASEBOARD_FAB2(SCH_1):PAGE173
   1B9    GND @BASEBOARD_FAB2_LIB.BASEBOARD_FAB2(SCH_1):GND   I163 @BASEBOARD_FAB2_LIB.BASEBOARD_FAB2(SCH_1):PAGE173
   1C3    GND @BASEBOARD_FAB2_LIB.BASEBOARD_FAB2(SCH_1):GND   I163 @BASEBOARD_FAB2_LIB.BASEBOARD_FAB2(SCH_1):PAGE173
   1C6    GND @BASEBOARD_FAB2_LIB.BASEBOARD_FAB2(SCH_1):GND   I163 @BASEBOARD_FAB2_LIB.BASEBOARD_FAB2(SCH_1):PAGE173
   1C9    GND @BASEBOARD_FAB2_LIB.BASEBOARD_FAB2(SCH_1):GND   I163 @BASEBOARD_FAB2_LIB.BASEBOARD_FAB2(SCH_1):PAGE173
   1D3    GND @BASEBOARD_FAB2_LIB.BASEBOARD_FAB2(SCH_1):GND   I163 @BASEBOARD_FAB2_LIB.BASEBOARD_FAB2(SCH_1):PAGE173
   1D6    GND @BASEBOARD_FAB2_LIB.BASEBOARD_FAB2(SCH_1):GND   I163 @BASEBOARD_FAB2_LIB.BASEBOARD_FAB2(SCH_1):PAGE173
   1D9    GND @BASEBOARD_FAB2_LIB.BASEBOARD_FAB2(SCH_1):GND   I163 @BASEBOARD_FAB2_LIB.BASEBOARD_FAB2(SCH_1):PAGE173
   2A3    GND @BASEBOARD_FAB2_LIB.BASEBOARD_FAB2(SCH_1):GND   I163 @BASEBOARD_FAB2_LIB.BASEBOARD_FAB2(SCH_1):PAGE173
   2A6    GND @BASEBOARD_FAB2_LIB.BASEBOARD_FAB2(SCH_1):GND   I163 @BASEBOARD_FAB2_LIB.BASEBOARD_FAB2(SCH_1):PAGE173
   2A9    GND @BASEBOARD_FAB2_LIB.BASEBOARD_FAB2(SCH_1):GND   I163 @BASEBOARD_FAB2_LIB.BASEBOARD_FAB2(SCH_1):PAGE173
   2B3    GND @BASEBOARD_FAB2_LIB.BASEBOARD_FAB2(SCH_1):GND   I163 @BASEBOARD_FAB2_LIB.BASEBOARD_FAB2(SCH_1):PAGE173
   2B6    GND @BASEBOARD_FAB2_LIB.BASEBOARD_FAB2(SCH_1):GND   I163 @BASEBOARD_FAB2_LIB.BASEBOARD_FAB2(SCH_1):PAGE173
   2B9    GND @BASEBOARD_FAB2_LIB.BASEBOARD_FAB2(SCH_1):GND   I163 @BASEBOARD_FAB2_LIB.BASEBOARD_FAB2(SCH_1):PAGE173
   2C3    GND @BASEBOARD_FAB2_LIB.BASEBOARD_FAB2(SCH_1):GND   I163 @BASEBOARD_FAB2_LIB.BASEBOARD_FAB2(SCH_1):PAGE173
   2C6    GND @BASEBOARD_FAB2_LIB.BASEBOARD_FAB2(SCH_1):GND   I163 @BASEBOARD_FAB2_LIB.BASEBOARD_FAB2(SCH_1):PAGE173
   2C9    GND @BASEBOARD_FAB2_LIB.BASEBOARD_FAB2(SCH_1):GND   I163 @BASEBOARD_FAB2_LIB.BASEBOARD_FAB2(SCH_1):PAGE173
   2D3    GND @BASEBOARD_FAB2_LIB.BASEBOARD_FAB2(SCH_1):GND   I163 @BASEBOARD_FAB2_LIB.BASEBOARD_FAB2(SCH_1):PAGE173
   2D6    GND @BASEBOARD_FAB2_LIB.BASEBOARD_FAB2(SCH_1):GND   I163 @BASEBOARD_FAB2_LIB.BASEBOARD_FAB2(SCH_1):PAGE173
   2D9    GND @BASEBOARD_FAB2_LIB.BASEBOARD_FAB2(SCH_1):GND   I163 @BASEBOARD_FAB2_LIB.BASEBOARD_FAB2(SCH_1):PAGE173
   1B5 SATA6G_P0_RX_C_DN @BASEBOARD_FAB2_LIB.BASEBOARD_FAB2(SCH_1):SATA6G_P0_RX_C_DN   I163 @BASEBOARD_FAB2_LIB.BASEBOARD_FAB2(SCH_1):PAGE173
   1B4 SATA6G_P0_RX_C_DP @BASEBOARD_FAB2_LIB.BASEBOARD_FAB2(SCH_1):SATA6G_P0_RX_C_DP   I163 @BASEBOARD_FAB2_LIB.BASEBOARD_FAB2(SCH_1):PAGE173
   1A5 SATA6G_P1_RX_C_DN @BASEBOARD_FAB2_LIB.BASEBOARD_FAB2(SCH_1):SATA6G_P1_RX_C_DN   I163 @BASEBOARD_FAB2_LIB.BASEBOARD_FAB2(SCH_1):PAGE173
   1A4 SATA6G_P1_RX_C_DP @BASEBOARD_FAB2_LIB.BASEBOARD_FAB2(SCH_1):SATA6G_P1_RX_C_DP   I163 @BASEBOARD_FAB2_LIB.BASEBOARD_FAB2(SCH_1):PAGE173
   1B8 SATA6G_P2_RX_C_DN @BASEBOARD_FAB2_LIB.BASEBOARD_FAB2(SCH_1):SATA6G_P2_RX_C_DN   I163 @BASEBOARD_FAB2_LIB.BASEBOARD_FAB2(SCH_1):PAGE173
   1B7 SATA6G_P2_RX_C_DP @BASEBOARD_FAB2_LIB.BASEBOARD_FAB2(SCH_1):SATA6G_P2_RX_C_DP   I163 @BASEBOARD_FAB2_LIB.BASEBOARD_FAB2(SCH_1):PAGE173
   1A8 SATA6G_P3_RX_C_DN @BASEBOARD_FAB2_LIB.BASEBOARD_FAB2(SCH_1):SATA6G_P3_RX_C_DN   I163 @BASEBOARD_FAB2_LIB.BASEBOARD_FAB2(SCH_1):PAGE173
   1A7 SATA6G_P3_RX_C_DP @BASEBOARD_FAB2_LIB.BASEBOARD_FAB2(SCH_1):SATA6G_P3_RX_C_DP   I163 @BASEBOARD_FAB2_LIB.BASEBOARD_FAB2(SCH_1):PAGE173
   2B5 SATA6G_P4_RX_C_DN @BASEBOARD_FAB2_LIB.BASEBOARD_FAB2(SCH_1):SATA6G_P4_RX_C_DN   I163 @BASEBOARD_FAB2_LIB.BASEBOARD_FAB2(SCH_1):PAGE173
   2B4 SATA6G_P4_RX_C_DP @BASEBOARD_FAB2_LIB.BASEBOARD_FAB2(SCH_1):SATA6G_P4_RX_C_DP   I163 @BASEBOARD_FAB2_LIB.BASEBOARD_FAB2(SCH_1):PAGE173
   2A5 SATA6G_P5_RX_C_DN @BASEBOARD_FAB2_LIB.BASEBOARD_FAB2(SCH_1):SATA6G_P5_RX_C_DN   I163 @BASEBOARD_FAB2_LIB.BASEBOARD_FAB2(SCH_1):PAGE173
   2A4 SATA6G_P5_RX_C_DP @BASEBOARD_FAB2_LIB.BASEBOARD_FAB2(SCH_1):SATA6G_P5_RX_C_DP   I163 @BASEBOARD_FAB2_LIB.BASEBOARD_FAB2(SCH_1):PAGE173
   2B8 SATA6G_P6_RX_C_DN @BASEBOARD_FAB2_LIB.BASEBOARD_FAB2(SCH_1):SATA6G_P6_RX_C_DN   I163 @BASEBOARD_FAB2_LIB.BASEBOARD_FAB2(SCH_1):PAGE173
   2B7 SATA6G_P6_RX_C_DP @BASEBOARD_FAB2_LIB.BASEBOARD_FAB2(SCH_1):SATA6G_P6_RX_C_DP   I163 @BASEBOARD_FAB2_LIB.BASEBOARD_FAB2(SCH_1):PAGE173
   2A8 SATA6G_P7_RX_C_DN @BASEBOARD_FAB2_LIB.BASEBOARD_FAB2(SCH_1):SATA6G_P7_RX_C_DN   I163 @BASEBOARD_FAB2_LIB.BASEBOARD_FAB2(SCH_1):PAGE173
   2A7 SATA6G_P7_RX_C_DP @BASEBOARD_FAB2_LIB.BASEBOARD_FAB2(SCH_1):SATA6G_P7_RX_C_DP   I163 @BASEBOARD_FAB2_LIB.BASEBOARD_FAB2(SCH_1):PAGE173
   1A2 SGPIO_PCH_SATA_CLOCK_R @BASEBOARD_FAB2_LIB.BASEBOARD_FAB2(SCH_1):SGPIO_PCH_SATA_CLOCK_R   I163 @BASEBOARD_FAB2_LIB.BASEBOARD_FAB2(SCH_1):PAGE173
   1B2 SGPIO_PCH_SATA_LOAD_R @BASEBOARD_FAB2_LIB.BASEBOARD_FAB2(SCH_1):SGPIO_PCH_SATA_LOAD_R   I163 @BASEBOARD_FAB2_LIB.BASEBOARD_FAB2(SCH_1):PAGE173
   1C2    GND @BASEBOARD_FAB2_LIB.BASEBOARD_FAB2(SCH_1):GND   I163 @BASEBOARD_FAB2_LIB.BASEBOARD_FAB2(SCH_1):PAGE173
   1B1    GND @BASEBOARD_FAB2_LIB.BASEBOARD_FAB2(SCH_1):GND   I163 @BASEBOARD_FAB2_LIB.BASEBOARD_FAB2(SCH_1):PAGE173
   1C1 SGPIO_PCH_SATA_DOUT0_R @BASEBOARD_FAB2_LIB.BASEBOARD_FAB2(SCH_1):SGPIO_PCH_SATA_DOUT0_R   I163 @BASEBOARD_FAB2_LIB.BASEBOARD_FAB2(SCH_1):PAGE173
   1D1 PU_DATAIN1_SATA_0_R @BASEBOARD_FAB2_LIB.BASEBOARD_FAB2(SCH_1):PU_DATAIN1_SATA_0_R   I163 @BASEBOARD_FAB2_LIB.BASEBOARD_FAB2(SCH_1):PAGE173
   1D2 PD_SATA0_CONTROLLER_TYPE_R @BASEBOARD_FAB2_LIB.BASEBOARD_FAB2(SCH_1):PD_SATA0_CONTROLLER_TYPE_R   I163 @BASEBOARD_FAB2_LIB.BASEBOARD_FAB2(SCH_1):PAGE173
   1A1 TP_FM_QAT_CBL_PRSNT0_R_N @BASEBOARD_FAB2_LIB.BASEBOARD_FAB2(SCH_1):TP_FM_QAT_CBL_PRSNT0_R_N   I163 @BASEBOARD_FAB2_LIB.BASEBOARD_FAB2(SCH_1):PAGE173
   2A2 TP_SGPIO_SATA_CLOCK1_R @BASEBOARD_FAB2_LIB.BASEBOARD_FAB2(SCH_1):TP_SGPIO_SATA_CLOCK1_R   I163 @BASEBOARD_FAB2_LIB.BASEBOARD_FAB2(SCH_1):PAGE173
   2B2 TP_SGPIO_SATA_LOAD1_R @BASEBOARD_FAB2_LIB.BASEBOARD_FAB2(SCH_1):TP_SGPIO_SATA_LOAD1_R   I163 @BASEBOARD_FAB2_LIB.BASEBOARD_FAB2(SCH_1):PAGE173
   2C2    GND @BASEBOARD_FAB2_LIB.BASEBOARD_FAB2(SCH_1):GND   I163 @BASEBOARD_FAB2_LIB.BASEBOARD_FAB2(SCH_1):PAGE173
   2B1    GND @BASEBOARD_FAB2_LIB.BASEBOARD_FAB2(SCH_1):GND   I163 @BASEBOARD_FAB2_LIB.BASEBOARD_FAB2(SCH_1):PAGE173
   2C1 TP_SGPIO_SATA_DATA1_R @BASEBOARD_FAB2_LIB.BASEBOARD_FAB2(SCH_1):TP_SGPIO_SATA_DATA1_R   I163 @BASEBOARD_FAB2_LIB.BASEBOARD_FAB2(SCH_1):PAGE173
   2D1 PU_DATAIN1_SATA_1_R @BASEBOARD_FAB2_LIB.BASEBOARD_FAB2(SCH_1):PU_DATAIN1_SATA_1_R   I163 @BASEBOARD_FAB2_LIB.BASEBOARD_FAB2(SCH_1):PAGE173
   2D2 PD_SATA1_CONTROLLER_TYPE_R @BASEBOARD_FAB2_LIB.BASEBOARD_FAB2(SCH_1):PD_SATA1_CONTROLLER_TYPE_R   I163 @BASEBOARD_FAB2_LIB.BASEBOARD_FAB2(SCH_1):PAGE173
   2A1 TP_FM_QAT_CBL_PRSNT1_N_R @BASEBOARD_FAB2_LIB.BASEBOARD_FAB2(SCH_1):TP_FM_QAT_CBL_PRSNT1_N_R   I163 @BASEBOARD_FAB2_LIB.BASEBOARD_FAB2(SCH_1):PAGE173
   1D5 SATA6G_P0_TX_C_DN @BASEBOARD_FAB2_LIB.BASEBOARD_FAB2(SCH_1):SATA6G_P0_TX_C_DN   I163 @BASEBOARD_FAB2_LIB.BASEBOARD_FAB2(SCH_1):PAGE173
   1D4 SATA6G_P0_TX_C_DP @BASEBOARD_FAB2_LIB.BASEBOARD_FAB2(SCH_1):SATA6G_P0_TX_C_DP   I163 @BASEBOARD_FAB2_LIB.BASEBOARD_FAB2(SCH_1):PAGE173
   1C5 SATA6G_P1_TX_C_DN @BASEBOARD_FAB2_LIB.BASEBOARD_FAB2(SCH_1):SATA6G_P1_TX_C_DN   I163 @BASEBOARD_FAB2_LIB.BASEBOARD_FAB2(SCH_1):PAGE173
   1C4 SATA6G_P1_TX_C_DP @BASEBOARD_FAB2_LIB.BASEBOARD_FAB2(SCH_1):SATA6G_P1_TX_C_DP   I163 @BASEBOARD_FAB2_LIB.BASEBOARD_FAB2(SCH_1):PAGE173
   1D8 SATA6G_P2_TX_C_DN @BASEBOARD_FAB2_LIB.BASEBOARD_FAB2(SCH_1):SATA6G_P2_TX_C_DN   I163 @BASEBOARD_FAB2_LIB.BASEBOARD_FAB2(SCH_1):PAGE173
   1D7 SATA6G_P2_TX_C_DP @BASEBOARD_FAB2_LIB.BASEBOARD_FAB2(SCH_1):SATA6G_P2_TX_C_DP   I163 @BASEBOARD_FAB2_LIB.BASEBOARD_FAB2(SCH_1):PAGE173
   1C8 SATA6G_P3_TX_C_DN @BASEBOARD_FAB2_LIB.BASEBOARD_FAB2(SCH_1):SATA6G_P3_TX_C_DN   I163 @BASEBOARD_FAB2_LIB.BASEBOARD_FAB2(SCH_1):PAGE173
   1C7 SATA6G_P3_TX_C_DP @BASEBOARD_FAB2_LIB.BASEBOARD_FAB2(SCH_1):SATA6G_P3_TX_C_DP   I163 @BASEBOARD_FAB2_LIB.BASEBOARD_FAB2(SCH_1):PAGE173
   2D5 SATA6G_P4_TX_C_DN @BASEBOARD_FAB2_LIB.BASEBOARD_FAB2(SCH_1):SATA6G_P4_TX_C_DN   I163 @BASEBOARD_FAB2_LIB.BASEBOARD_FAB2(SCH_1):PAGE173
   2D4 SATA6G_P4_TX_C_DP @BASEBOARD_FAB2_LIB.BASEBOARD_FAB2(SCH_1):SATA6G_P4_TX_C_DP   I163 @BASEBOARD_FAB2_LIB.BASEBOARD_FAB2(SCH_1):PAGE173
   2C5 SATA6G_P5_TX_C_DN @BASEBOARD_FAB2_LIB.BASEBOARD_FAB2(SCH_1):SATA6G_P5_TX_C_DN   I163 @BASEBOARD_FAB2_LIB.BASEBOARD_FAB2(SCH_1):PAGE173
   2C4 SATA6G_P5_TX_C_DP @BASEBOARD_FAB2_LIB.BASEBOARD_FAB2(SCH_1):SATA6G_P5_TX_C_DP   I163 @BASEBOARD_FAB2_LIB.BASEBOARD_FAB2(SCH_1):PAGE173
   2D8 SATA6G_P6_TX_C_DN @BASEBOARD_FAB2_LIB.BASEBOARD_FAB2(SCH_1):SATA6G_P6_TX_C_DN   I163 @BASEBOARD_FAB2_LIB.BASEBOARD_FAB2(SCH_1):PAGE173
   2D7 SATA6G_P6_TX_C_DP @BASEBOARD_FAB2_LIB.BASEBOARD_FAB2(SCH_1):SATA6G_P6_TX_C_DP   I163 @BASEBOARD_FAB2_LIB.BASEBOARD_FAB2(SCH_1):PAGE173
   2C8 SATA6G_P7_TX_C_DN @BASEBOARD_FAB2_LIB.BASEBOARD_FAB2(SCH_1):SATA6G_P7_TX_C_DN   I163 @BASEBOARD_FAB2_LIB.BASEBOARD_FAB2(SCH_1):PAGE173
   2C7 SATA6G_P7_TX_C_DP @BASEBOARD_FAB2_LIB.BASEBOARD_FAB2(SCH_1):SATA6G_P7_TX_C_DP   I163 @BASEBOARD_FAB2_LIB.BASEBOARD_FAB2(SCH_1):PAGE173

J8A2 CONN36_G97614001_CP-CONN,G9761A
    A3    GND @BASEBOARD_FAB2_LIB.BASEBOARD_FAB2(SCH_1):GND    I26 @BASEBOARD_FAB2_LIB.BASEBOARD_FAB2(SCH_1):PAGE174
    D3    GND @BASEBOARD_FAB2_LIB.BASEBOARD_FAB2(SCH_1):GND    I26 @BASEBOARD_FAB2_LIB.BASEBOARD_FAB2(SCH_1):PAGE174
    D6    GND @BASEBOARD_FAB2_LIB.BASEBOARD_FAB2(SCH_1):GND    I26 @BASEBOARD_FAB2_LIB.BASEBOARD_FAB2(SCH_1):PAGE174
    D9    GND @BASEBOARD_FAB2_LIB.BASEBOARD_FAB2(SCH_1):GND    I26 @BASEBOARD_FAB2_LIB.BASEBOARD_FAB2(SCH_1):PAGE174
    A6    GND @BASEBOARD_FAB2_LIB.BASEBOARD_FAB2(SCH_1):GND    I26 @BASEBOARD_FAB2_LIB.BASEBOARD_FAB2(SCH_1):PAGE174
    A9    GND @BASEBOARD_FAB2_LIB.BASEBOARD_FAB2(SCH_1):GND    I26 @BASEBOARD_FAB2_LIB.BASEBOARD_FAB2(SCH_1):PAGE174
    B3    GND @BASEBOARD_FAB2_LIB.BASEBOARD_FAB2(SCH_1):GND    I26 @BASEBOARD_FAB2_LIB.BASEBOARD_FAB2(SCH_1):PAGE174
    B6    GND @BASEBOARD_FAB2_LIB.BASEBOARD_FAB2(SCH_1):GND    I26 @BASEBOARD_FAB2_LIB.BASEBOARD_FAB2(SCH_1):PAGE174
    B9    GND @BASEBOARD_FAB2_LIB.BASEBOARD_FAB2(SCH_1):GND    I26 @BASEBOARD_FAB2_LIB.BASEBOARD_FAB2(SCH_1):PAGE174
    C3    GND @BASEBOARD_FAB2_LIB.BASEBOARD_FAB2(SCH_1):GND    I26 @BASEBOARD_FAB2_LIB.BASEBOARD_FAB2(SCH_1):PAGE174
    C6    GND @BASEBOARD_FAB2_LIB.BASEBOARD_FAB2(SCH_1):GND    I26 @BASEBOARD_FAB2_LIB.BASEBOARD_FAB2(SCH_1):PAGE174
    C9    GND @BASEBOARD_FAB2_LIB.BASEBOARD_FAB2(SCH_1):GND    I26 @BASEBOARD_FAB2_LIB.BASEBOARD_FAB2(SCH_1):PAGE174
    B5 SATA6G_P8_RX_C_DN @BASEBOARD_FAB2_LIB.BASEBOARD_FAB2(SCH_1):SATA6G_P8_RX_C_DN    I26 @BASEBOARD_FAB2_LIB.BASEBOARD_FAB2(SCH_1):PAGE174
    B4 SATA6G_P8_RX_C_DP @BASEBOARD_FAB2_LIB.BASEBOARD_FAB2(SCH_1):SATA6G_P8_RX_C_DP    I26 @BASEBOARD_FAB2_LIB.BASEBOARD_FAB2(SCH_1):PAGE174
    A5 SATA6G_P9_RX_C_DN @BASEBOARD_FAB2_LIB.BASEBOARD_FAB2(SCH_1):SATA6G_P9_RX_C_DN    I26 @BASEBOARD_FAB2_LIB.BASEBOARD_FAB2(SCH_1):PAGE174
    A4 SATA6G_P9_RX_C_DP @BASEBOARD_FAB2_LIB.BASEBOARD_FAB2(SCH_1):SATA6G_P9_RX_C_DP    I26 @BASEBOARD_FAB2_LIB.BASEBOARD_FAB2(SCH_1):PAGE174
    B8 SATA6G_P10_RX_C_DN @BASEBOARD_FAB2_LIB.BASEBOARD_FAB2(SCH_1):SATA6G_P10_RX_C_DN    I26 @BASEBOARD_FAB2_LIB.BASEBOARD_FAB2(SCH_1):PAGE174
    B7 SATA6G_P10_RX_C_DP @BASEBOARD_FAB2_LIB.BASEBOARD_FAB2(SCH_1):SATA6G_P10_RX_C_DP    I26 @BASEBOARD_FAB2_LIB.BASEBOARD_FAB2(SCH_1):PAGE174
    A8 SATA6G_P11_RX_C_DN @BASEBOARD_FAB2_LIB.BASEBOARD_FAB2(SCH_1):SATA6G_P11_RX_C_DN    I26 @BASEBOARD_FAB2_LIB.BASEBOARD_FAB2(SCH_1):PAGE174
    A7 SATA6G_P11_RX_C_DP @BASEBOARD_FAB2_LIB.BASEBOARD_FAB2(SCH_1):SATA6G_P11_RX_C_DP    I26 @BASEBOARD_FAB2_LIB.BASEBOARD_FAB2(SCH_1):PAGE174
    A2 SGPIO_PCH_SSATA_CLOCK_R @BASEBOARD_FAB2_LIB.BASEBOARD_FAB2(SCH_1):SGPIO_PCH_SSATA_CLOCK_R    I26 @BASEBOARD_FAB2_LIB.BASEBOARD_FAB2(SCH_1):PAGE174
    B2 SGPIO_PCH_SSATA_LOAD_R @BASEBOARD_FAB2_LIB.BASEBOARD_FAB2(SCH_1):SGPIO_PCH_SSATA_LOAD_R    I26 @BASEBOARD_FAB2_LIB.BASEBOARD_FAB2(SCH_1):PAGE174
    C2    GND @BASEBOARD_FAB2_LIB.BASEBOARD_FAB2(SCH_1):GND    I26 @BASEBOARD_FAB2_LIB.BASEBOARD_FAB2(SCH_1):PAGE174
    B1    GND @BASEBOARD_FAB2_LIB.BASEBOARD_FAB2(SCH_1):GND    I26 @BASEBOARD_FAB2_LIB.BASEBOARD_FAB2(SCH_1):PAGE174
    C1 SGPIO_PCH_SSATA_DOUT0_R @BASEBOARD_FAB2_LIB.BASEBOARD_FAB2(SCH_1):SGPIO_PCH_SSATA_DOUT0_R    I26 @BASEBOARD_FAB2_LIB.BASEBOARD_FAB2(SCH_1):PAGE174
    D1 PU_DATAIN1_SATA_2 @BASEBOARD_FAB2_LIB.BASEBOARD_FAB2(SCH_1):PU_DATAIN1_SATA_2    I26 @BASEBOARD_FAB2_LIB.BASEBOARD_FAB2(SCH_1):PAGE174
    D2 PD_SATA2_CONTROLLER_TYPE @BASEBOARD_FAB2_LIB.BASEBOARD_FAB2(SCH_1):PD_SATA2_CONTROLLER_TYPE    I26 @BASEBOARD_FAB2_LIB.BASEBOARD_FAB2(SCH_1):PAGE174
    A1 TP_FM_QAT_CBL_PRSNT2_N @BASEBOARD_FAB2_LIB.BASEBOARD_FAB2(SCH_1):TP_FM_QAT_CBL_PRSNT2_N    I26 @BASEBOARD_FAB2_LIB.BASEBOARD_FAB2(SCH_1):PAGE174
    D5 SATA6G_P8_TX_C_DN @BASEBOARD_FAB2_LIB.BASEBOARD_FAB2(SCH_1):SATA6G_P8_TX_C_DN    I26 @BASEBOARD_FAB2_LIB.BASEBOARD_FAB2(SCH_1):PAGE174
    D4 SATA6G_P8_TX_C_DP @BASEBOARD_FAB2_LIB.BASEBOARD_FAB2(SCH_1):SATA6G_P8_TX_C_DP    I26 @BASEBOARD_FAB2_LIB.BASEBOARD_FAB2(SCH_1):PAGE174
    C5 SATA6G_P9_TX_C_DN @BASEBOARD_FAB2_LIB.BASEBOARD_FAB2(SCH_1):SATA6G_P9_TX_C_DN    I26 @BASEBOARD_FAB2_LIB.BASEBOARD_FAB2(SCH_1):PAGE174
    C4 SATA6G_P9_TX_C_DP @BASEBOARD_FAB2_LIB.BASEBOARD_FAB2(SCH_1):SATA6G_P9_TX_C_DP    I26 @BASEBOARD_FAB2_LIB.BASEBOARD_FAB2(SCH_1):PAGE174
    D8 SATA6G_P10_TX_C_DN @BASEBOARD_FAB2_LIB.BASEBOARD_FAB2(SCH_1):SATA6G_P10_TX_C_DN    I26 @BASEBOARD_FAB2_LIB.BASEBOARD_FAB2(SCH_1):PAGE174
    D7 SATA6G_P10_TX_C_DP @BASEBOARD_FAB2_LIB.BASEBOARD_FAB2(SCH_1):SATA6G_P10_TX_C_DP    I26 @BASEBOARD_FAB2_LIB.BASEBOARD_FAB2(SCH_1):PAGE174
    C8 SATA6G_P11_TX_C_DN @BASEBOARD_FAB2_LIB.BASEBOARD_FAB2(SCH_1):SATA6G_P11_TX_C_DN    I26 @BASEBOARD_FAB2_LIB.BASEBOARD_FAB2(SCH_1):PAGE174
    C7 SATA6G_P11_TX_C_DP @BASEBOARD_FAB2_LIB.BASEBOARD_FAB2(SCH_1):SATA6G_P11_TX_C_DP    I26 @BASEBOARD_FAB2_LIB.BASEBOARD_FAB2(SCH_1):PAGE174

J8A3 CONN7_E82125014_PIP_TH-EMPTY,EA
     1    GND @BASEBOARD_FAB2_LIB.BASEBOARD_FAB2(SCH_1):GND    I17 @BASEBOARD_FAB2_LIB.BASEBOARD_FAB2(SCH_1):PAGE172
     4    GND @BASEBOARD_FAB2_LIB.BASEBOARD_FAB2(SCH_1):GND    I17 @BASEBOARD_FAB2_LIB.BASEBOARD_FAB2(SCH_1):PAGE172
     7    GND @BASEBOARD_FAB2_LIB.BASEBOARD_FAB2(SCH_1):GND    I17 @BASEBOARD_FAB2_LIB.BASEBOARD_FAB2(SCH_1):PAGE172
   MH1    GND @BASEBOARD_FAB2_LIB.BASEBOARD_FAB2(SCH_1):GND    I17 @BASEBOARD_FAB2_LIB.BASEBOARD_FAB2(SCH_1):PAGE172
   MH2    GND @BASEBOARD_FAB2_LIB.BASEBOARD_FAB2(SCH_1):GND    I17 @BASEBOARD_FAB2_LIB.BASEBOARD_FAB2(SCH_1):PAGE172
     5 SATA6G_S1_RX_C_DN @BASEBOARD_FAB2_LIB.BASEBOARD_FAB2(SCH_1):SATA6G_S1_RX_C_DN    I17 @BASEBOARD_FAB2_LIB.BASEBOARD_FAB2(SCH_1):PAGE172
     6 SATA6G_S1_RX_C_DP @BASEBOARD_FAB2_LIB.BASEBOARD_FAB2(SCH_1):SATA6G_S1_RX_C_DP    I17 @BASEBOARD_FAB2_LIB.BASEBOARD_FAB2(SCH_1):PAGE172
     3 SATA6G_S1_TX_C_DN @BASEBOARD_FAB2_LIB.BASEBOARD_FAB2(SCH_1):SATA6G_S1_TX_C_DN    I17 @BASEBOARD_FAB2_LIB.BASEBOARD_FAB2(SCH_1):PAGE172
     2 SATA6G_S1_TX_C_DP @BASEBOARD_FAB2_LIB.BASEBOARD_FAB2(SCH_1):SATA6G_S1_TX_C_DP    I17 @BASEBOARD_FAB2_LIB.BASEBOARD_FAB2(SCH_1):PAGE172

J8A4 CONN4_H73295001_PIP-EMPTY,H732A
     1 P5V_HDD_SATA @BASEBOARD_FAB2_LIB.BASEBOARD_FAB2(SCH_1):P5V_HDD_SATA    I25 @BASEBOARD_FAB2_LIB.BASEBOARD_FAB2(SCH_1):PAGE172
     2    GND @BASEBOARD_FAB2_LIB.BASEBOARD_FAB2(SCH_1):GND    I25 @BASEBOARD_FAB2_LIB.BASEBOARD_FAB2(SCH_1):PAGE172
     3    GND @BASEBOARD_FAB2_LIB.BASEBOARD_FAB2(SCH_1):GND    I25 @BASEBOARD_FAB2_LIB.BASEBOARD_FAB2(SCH_1):PAGE172
     4 P12V_HDD_SATA @BASEBOARD_FAB2_LIB.BASEBOARD_FAB2(SCH_1):P12V_HDD_SATA    I25 @BASEBOARD_FAB2_LIB.BASEBOARD_FAB2(SCH_1):PAGE172

J8B1 SCONN24_H46321001_SM-SCONN,H46A
     1    GND @BASEBOARD_FAB2_LIB.BASEBOARD_FAB2(SCH_1):GND     I1 @BASEBOARD_FAB2_LIB.BASEBOARD_FAB2(SCH_1):PAGE91
    10 SMB_HFI1_CPU0_LVC2_SCL @BASEBOARD_FAB2_LIB.BASEBOARD_FAB2(SCH_1):SMB_HFI1_CPU0_LVC2_SCL     I1 @BASEBOARD_FAB2_LIB.BASEBOARD_FAB2(SCH_1):PAGE91
    11 FM_MODPRST_HFI1_CPU0_LVT2_N @BASEBOARD_FAB2_LIB.BASEBOARD_FAB2(SCH_1):FM_MODPRST_HFI1_CPU0_LVT2_N     I1 @BASEBOARD_FAB2_LIB.BASEBOARD_FAB2(SCH_1):PAGE91
    12 SMB_HFI1_CPU0_LVC2_SDA @BASEBOARD_FAB2_LIB.BASEBOARD_FAB2(SCH_1):SMB_HFI1_CPU0_LVC2_SDA     I1 @BASEBOARD_FAB2_LIB.BASEBOARD_FAB2(SCH_1):PAGE91
    13 LED_HFI1_CPU0_N @BASEBOARD_FAB2_LIB.BASEBOARD_FAB2(SCH_1):LED_HFI1_CPU0_N     I1 @BASEBOARD_FAB2_LIB.BASEBOARD_FAB2(SCH_1):PAGE91
    14 RST_HFI1_CPU0_LVT2_N @BASEBOARD_FAB2_LIB.BASEBOARD_FAB2(SCH_1):RST_HFI1_CPU0_LVT2_N     I1 @BASEBOARD_FAB2_LIB.BASEBOARD_FAB2(SCH_1):PAGE91
    15    GND @BASEBOARD_FAB2_LIB.BASEBOARD_FAB2(SCH_1):GND     I1 @BASEBOARD_FAB2_LIB.BASEBOARD_FAB2(SCH_1):PAGE91
    16 IRQ_HFI1_CPU0_LVT2_N @BASEBOARD_FAB2_LIB.BASEBOARD_FAB2(SCH_1):IRQ_HFI1_CPU0_LVT2_N     I1 @BASEBOARD_FAB2_LIB.BASEBOARD_FAB2(SCH_1):PAGE91
    17 TP_HFI_IO_CONN0_RSVD_17 @BASEBOARD_FAB2_LIB.BASEBOARD_FAB2(SCH_1):TP_HFI_IO_CONN0_RSVD_17     I1 @BASEBOARD_FAB2_LIB.BASEBOARD_FAB2(SCH_1):PAGE91
    18   P3V3 @BASEBOARD_FAB2_LIB.BASEBOARD_FAB2(SCH_1):P3V3     I1 @BASEBOARD_FAB2_LIB.BASEBOARD_FAB2(SCH_1):PAGE91
    19 PWRGD_PVPP_ABC @BASEBOARD_FAB2_LIB.BASEBOARD_FAB2(SCH_1):PWRGD_PVPP_ABC     I1 @BASEBOARD_FAB2_LIB.BASEBOARD_FAB2(SCH_1):PAGE91
     2 SMB_HFI0_CPU0_LVC2_SCL @BASEBOARD_FAB2_LIB.BASEBOARD_FAB2(SCH_1):SMB_HFI0_CPU0_LVC2_SCL     I1 @BASEBOARD_FAB2_LIB.BASEBOARD_FAB2(SCH_1):PAGE91
    20   P3V3 @BASEBOARD_FAB2_LIB.BASEBOARD_FAB2(SCH_1):P3V3     I1 @BASEBOARD_FAB2_LIB.BASEBOARD_FAB2(SCH_1):PAGE91
    21 PVPP_ABC @BASEBOARD_FAB2_LIB.BASEBOARD_FAB2(SCH_1):PVPP_ABC     I1 @BASEBOARD_FAB2_LIB.BASEBOARD_FAB2(SCH_1):PAGE91
    22 SMB_OCP_FRU_STBY_LVC3_SCL @BASEBOARD_FAB2_LIB.BASEBOARD_FAB2(SCH_1):SMB_OCP_FRU_STBY_LVC3_SCL     I1 @BASEBOARD_FAB2_LIB.BASEBOARD_FAB2(SCH_1):PAGE91
    23    GND @BASEBOARD_FAB2_LIB.BASEBOARD_FAB2(SCH_1):GND     I1 @BASEBOARD_FAB2_LIB.BASEBOARD_FAB2(SCH_1):PAGE91
    24 SMB_OCP_FRU_STBY_LVC3_SDA @BASEBOARD_FAB2_LIB.BASEBOARD_FAB2(SCH_1):SMB_OCP_FRU_STBY_LVC3_SDA     I1 @BASEBOARD_FAB2_LIB.BASEBOARD_FAB2(SCH_1):PAGE91
     3 FM_MODPRST_HFI0_CPU0_LVT2_N @BASEBOARD_FAB2_LIB.BASEBOARD_FAB2(SCH_1):FM_MODPRST_HFI0_CPU0_LVT2_N     I1 @BASEBOARD_FAB2_LIB.BASEBOARD_FAB2(SCH_1):PAGE91
     4 SMB_HFI0_CPU0_LVC2_SDA @BASEBOARD_FAB2_LIB.BASEBOARD_FAB2(SCH_1):SMB_HFI0_CPU0_LVC2_SDA     I1 @BASEBOARD_FAB2_LIB.BASEBOARD_FAB2(SCH_1):PAGE91
     5 LED_HFI0_CPU0_N @BASEBOARD_FAB2_LIB.BASEBOARD_FAB2(SCH_1):LED_HFI0_CPU0_N     I1 @BASEBOARD_FAB2_LIB.BASEBOARD_FAB2(SCH_1):PAGE91
     6 RST_HFI0_CPU0_LVT2_N @BASEBOARD_FAB2_LIB.BASEBOARD_FAB2(SCH_1):RST_HFI0_CPU0_LVT2_N     I1 @BASEBOARD_FAB2_LIB.BASEBOARD_FAB2(SCH_1):PAGE91
     7    GND @BASEBOARD_FAB2_LIB.BASEBOARD_FAB2(SCH_1):GND     I1 @BASEBOARD_FAB2_LIB.BASEBOARD_FAB2(SCH_1):PAGE91
     8 IRQ_HFI0_CPU0_LVT2_N @BASEBOARD_FAB2_LIB.BASEBOARD_FAB2(SCH_1):IRQ_HFI0_CPU0_LVT2_N     I1 @BASEBOARD_FAB2_LIB.BASEBOARD_FAB2(SCH_1):PAGE91
     9    GND @BASEBOARD_FAB2_LIB.BASEBOARD_FAB2(SCH_1):GND     I1 @BASEBOARD_FAB2_LIB.BASEBOARD_FAB2(SCH_1):PAGE91
   MP1    GND @BASEBOARD_FAB2_LIB.BASEBOARD_FAB2(SCH_1):GND     I1 @BASEBOARD_FAB2_LIB.BASEBOARD_FAB2(SCH_1):PAGE91
   MP2    GND @BASEBOARD_FAB2_LIB.BASEBOARD_FAB2(SCH_1):GND     I1 @BASEBOARD_FAB2_LIB.BASEBOARD_FAB2(SCH_1):PAGE91

J8C1 CONN3_C95678002_PIP-CONN,C9567A
     1 SMB_HOST_STBY_LVC3_SDA @BASEBOARD_FAB2_LIB.BASEBOARD_FAB2(SCH_1):SMB_HOST_STBY_LVC3_SDA   I285 @BASEBOARD_FAB2_LIB.BASEBOARD_FAB2(SCH_1):PAGE156
     2    GND @BASEBOARD_FAB2_LIB.BASEBOARD_FAB2(SCH_1):GND   I285 @BASEBOARD_FAB2_LIB.BASEBOARD_FAB2(SCH_1):PAGE156
     3 SMB_HOST_STBY_LVC3_SCL @BASEBOARD_FAB2_LIB.BASEBOARD_FAB2(SCH_1):SMB_HOST_STBY_LVC3_SCL   I285 @BASEBOARD_FAB2_LIB.BASEBOARD_FAB2(SCH_1):PAGE156

J8D4 CONN3_C95678002_PIP-CONN,C9567A
     1 SMB_VR_STBY_LVC3_SDA @BASEBOARD_FAB2_LIB.BASEBOARD_FAB2(SCH_1):SMB_VR_STBY_LVC3_SDA   I122 @BASEBOARD_FAB2_LIB.BASEBOARD_FAB2(SCH_1):PAGE201
     2    GND @BASEBOARD_FAB2_LIB.BASEBOARD_FAB2(SCH_1):GND   I122 @BASEBOARD_FAB2_LIB.BASEBOARD_FAB2(SCH_1):PAGE201
     3 SMB_VR_STBY_LVC3_SCL @BASEBOARD_FAB2_LIB.BASEBOARD_FAB2(SCH_1):SMB_VR_STBY_LVC3_SCL   I122 @BASEBOARD_FAB2_LIB.BASEBOARD_FAB2(SCH_1):PAGE201

J8E1 SCONN11_H67026001_SM-CONN,H670A
     1 SPI_PCH_TPM_CLK_R @BASEBOARD_FAB2_LIB.BASEBOARD_FAB2(SCH_1):SPI_PCH_TPM_CLK_R    I87 @BASEBOARD_FAB2_LIB.BASEBOARD_FAB2(SCH_1):PAGE184
     2 RST_PLTRST_BUF_N @BASEBOARD_FAB2_LIB.BASEBOARD_FAB2(SCH_1):RST_PLTRST_BUF_N    I87 @BASEBOARD_FAB2_LIB.BASEBOARD_FAB2(SCH_1):PAGE184
     3 SPI_PCH_TPM_MOSI_R @BASEBOARD_FAB2_LIB.BASEBOARD_FAB2(SCH_1):SPI_PCH_TPM_MOSI_R    I87 @BASEBOARD_FAB2_LIB.BASEBOARD_FAB2(SCH_1):PAGE184
     4 SPI_PCH_TPM_MISO_R @BASEBOARD_FAB2_LIB.BASEBOARD_FAB2(SCH_1):SPI_PCH_TPM_MISO_R    I87 @BASEBOARD_FAB2_LIB.BASEBOARD_FAB2(SCH_1):PAGE184
     5 SPI_PCH_TPM_CS_R_N @BASEBOARD_FAB2_LIB.BASEBOARD_FAB2(SCH_1):SPI_PCH_TPM_CS_R_N    I87 @BASEBOARD_FAB2_LIB.BASEBOARD_FAB2(SCH_1):PAGE184
     6 SMB_SENSOR_STBY_LVC3_SDA @BASEBOARD_FAB2_LIB.BASEBOARD_FAB2(SCH_1):SMB_SENSOR_STBY_LVC3_SDA    I87 @BASEBOARD_FAB2_LIB.BASEBOARD_FAB2(SCH_1):PAGE184
     7 P3V3_STBY @BASEBOARD_FAB2_LIB.BASEBOARD_FAB2(SCH_1):P3V3_STBY    I87 @BASEBOARD_FAB2_LIB.BASEBOARD_FAB2(SCH_1):PAGE184
     8 FM_TPM_PRES_RST_N @BASEBOARD_FAB2_LIB.BASEBOARD_FAB2(SCH_1):FM_TPM_PRES_RST_N    I87 @BASEBOARD_FAB2_LIB.BASEBOARD_FAB2(SCH_1):PAGE184
     9 IRQ_SPI_TPM_N_R @BASEBOARD_FAB2_LIB.BASEBOARD_FAB2(SCH_1):IRQ_SPI_TPM_N_R    I87 @BASEBOARD_FAB2_LIB.BASEBOARD_FAB2(SCH_1):PAGE184
    10 SMB_SENSOR_STBY_LVC3_SCL @BASEBOARD_FAB2_LIB.BASEBOARD_FAB2(SCH_1):SMB_SENSOR_STBY_LVC3_SCL    I87 @BASEBOARD_FAB2_LIB.BASEBOARD_FAB2(SCH_1):PAGE184
    11    GND @BASEBOARD_FAB2_LIB.BASEBOARD_FAB2(SCH_1):GND    I87 @BASEBOARD_FAB2_LIB.BASEBOARD_FAB2(SCH_1):PAGE184
   MP1    GND @BASEBOARD_FAB2_LIB.BASEBOARD_FAB2(SCH_1):GND    I87 @BASEBOARD_FAB2_LIB.BASEBOARD_FAB2(SCH_1):PAGE184
   MP2    GND @BASEBOARD_FAB2_LIB.BASEBOARD_FAB2(SCH_1):GND    I87 @BASEBOARD_FAB2_LIB.BASEBOARD_FAB2(SCH_1):PAGE184

J8E3 SCONN80_E67482007_SM-CONN,E674A
     1 FM_MEZZ_PRSNTB1_N @BASEBOARD_FAB2_LIB.BASEBOARD_FAB2(SCH_1):FM_MEZZ_PRSNTB1_N   I119 @BASEBOARD_FAB2_LIB.BASEBOARD_FAB2(SCH_1):PAGE187
    10 P3E_OCP_CPU0_PE3_C_TXP<7> @BASEBOARD_FAB2_LIB.BASEBOARD_FAB2(SCH_1):P3E_OCP_CPU0_PE3_C_TXP(7)   I119 @BASEBOARD_FAB2_LIB.BASEBOARD_FAB2(SCH_1):PAGE187
    11    GND @BASEBOARD_FAB2_LIB.BASEBOARD_FAB2(SCH_1):GND   I119 @BASEBOARD_FAB2_LIB.BASEBOARD_FAB2(SCH_1):PAGE187
    12 P3E_OCP_CPU0_PE3_C_TXN<7> @BASEBOARD_FAB2_LIB.BASEBOARD_FAB2(SCH_1):P3E_OCP_CPU0_PE3_C_TXN(7)   I119 @BASEBOARD_FAB2_LIB.BASEBOARD_FAB2(SCH_1):PAGE187
    13 P3E_CPU0_PE3_OCP_RXN<6> @BASEBOARD_FAB2_LIB.BASEBOARD_FAB2(SCH_1):P3E_CPU0_PE3_OCP_RXN(6)   I119 @BASEBOARD_FAB2_LIB.BASEBOARD_FAB2(SCH_1):PAGE187
    14    GND @BASEBOARD_FAB2_LIB.BASEBOARD_FAB2(SCH_1):GND   I119 @BASEBOARD_FAB2_LIB.BASEBOARD_FAB2(SCH_1):PAGE187
    15 P3E_CPU0_PE3_OCP_RXP<6> @BASEBOARD_FAB2_LIB.BASEBOARD_FAB2(SCH_1):P3E_CPU0_PE3_OCP_RXP(6)   I119 @BASEBOARD_FAB2_LIB.BASEBOARD_FAB2(SCH_1):PAGE187
    16    GND @BASEBOARD_FAB2_LIB.BASEBOARD_FAB2(SCH_1):GND   I119 @BASEBOARD_FAB2_LIB.BASEBOARD_FAB2(SCH_1):PAGE187
    17    GND @BASEBOARD_FAB2_LIB.BASEBOARD_FAB2(SCH_1):GND   I119 @BASEBOARD_FAB2_LIB.BASEBOARD_FAB2(SCH_1):PAGE187
    18 P3E_OCP_CPU0_PE3_C_TXP<6> @BASEBOARD_FAB2_LIB.BASEBOARD_FAB2(SCH_1):P3E_OCP_CPU0_PE3_C_TXP(6)   I119 @BASEBOARD_FAB2_LIB.BASEBOARD_FAB2(SCH_1):PAGE187
    19    GND @BASEBOARD_FAB2_LIB.BASEBOARD_FAB2(SCH_1):GND   I119 @BASEBOARD_FAB2_LIB.BASEBOARD_FAB2(SCH_1):PAGE187
     2 P12V_STBY @BASEBOARD_FAB2_LIB.BASEBOARD_FAB2(SCH_1):P12V_STBY   I119 @BASEBOARD_FAB2_LIB.BASEBOARD_FAB2(SCH_1):PAGE187
    20 P3E_OCP_CPU0_PE3_C_TXN<6> @BASEBOARD_FAB2_LIB.BASEBOARD_FAB2(SCH_1):P3E_OCP_CPU0_PE3_C_TXN(6)   I119 @BASEBOARD_FAB2_LIB.BASEBOARD_FAB2(SCH_1):PAGE187
    21 P3E_CPU0_PE3_OCP_RXN<5> @BASEBOARD_FAB2_LIB.BASEBOARD_FAB2(SCH_1):P3E_CPU0_PE3_OCP_RXN(5)   I119 @BASEBOARD_FAB2_LIB.BASEBOARD_FAB2(SCH_1):PAGE187
    22    GND @BASEBOARD_FAB2_LIB.BASEBOARD_FAB2(SCH_1):GND   I119 @BASEBOARD_FAB2_LIB.BASEBOARD_FAB2(SCH_1):PAGE187
    23 P3E_CPU0_PE3_OCP_RXP<5> @BASEBOARD_FAB2_LIB.BASEBOARD_FAB2(SCH_1):P3E_CPU0_PE3_OCP_RXP(5)   I119 @BASEBOARD_FAB2_LIB.BASEBOARD_FAB2(SCH_1):PAGE187
    24    GND @BASEBOARD_FAB2_LIB.BASEBOARD_FAB2(SCH_1):GND   I119 @BASEBOARD_FAB2_LIB.BASEBOARD_FAB2(SCH_1):PAGE187
    25    GND @BASEBOARD_FAB2_LIB.BASEBOARD_FAB2(SCH_1):GND   I119 @BASEBOARD_FAB2_LIB.BASEBOARD_FAB2(SCH_1):PAGE187
    26 P3E_OCP_CPU0_PE3_C_TXP<5> @BASEBOARD_FAB2_LIB.BASEBOARD_FAB2(SCH_1):P3E_OCP_CPU0_PE3_C_TXP(5)   I119 @BASEBOARD_FAB2_LIB.BASEBOARD_FAB2(SCH_1):PAGE187
    27    GND @BASEBOARD_FAB2_LIB.BASEBOARD_FAB2(SCH_1):GND   I119 @BASEBOARD_FAB2_LIB.BASEBOARD_FAB2(SCH_1):PAGE187
    28 P3E_OCP_CPU0_PE3_C_TXN<5> @BASEBOARD_FAB2_LIB.BASEBOARD_FAB2(SCH_1):P3E_OCP_CPU0_PE3_C_TXN(5)   I119 @BASEBOARD_FAB2_LIB.BASEBOARD_FAB2(SCH_1):PAGE187
    29 P3E_CPU0_PE3_OCP_RXN<4> @BASEBOARD_FAB2_LIB.BASEBOARD_FAB2(SCH_1):P3E_CPU0_PE3_OCP_RXN(4)   I119 @BASEBOARD_FAB2_LIB.BASEBOARD_FAB2(SCH_1):PAGE187
     3    GND @BASEBOARD_FAB2_LIB.BASEBOARD_FAB2(SCH_1):GND   I119 @BASEBOARD_FAB2_LIB.BASEBOARD_FAB2(SCH_1):PAGE187
    30    GND @BASEBOARD_FAB2_LIB.BASEBOARD_FAB2(SCH_1):GND   I119 @BASEBOARD_FAB2_LIB.BASEBOARD_FAB2(SCH_1):PAGE187
    31 P3E_CPU0_PE3_OCP_RXP<4> @BASEBOARD_FAB2_LIB.BASEBOARD_FAB2(SCH_1):P3E_CPU0_PE3_OCP_RXP(4)   I119 @BASEBOARD_FAB2_LIB.BASEBOARD_FAB2(SCH_1):PAGE187
    32    GND @BASEBOARD_FAB2_LIB.BASEBOARD_FAB2(SCH_1):GND   I119 @BASEBOARD_FAB2_LIB.BASEBOARD_FAB2(SCH_1):PAGE187
    33    GND @BASEBOARD_FAB2_LIB.BASEBOARD_FAB2(SCH_1):GND   I119 @BASEBOARD_FAB2_LIB.BASEBOARD_FAB2(SCH_1):PAGE187
    34 P3E_OCP_CPU0_PE3_C_TXP<4> @BASEBOARD_FAB2_LIB.BASEBOARD_FAB2(SCH_1):P3E_OCP_CPU0_PE3_C_TXP(4)   I119 @BASEBOARD_FAB2_LIB.BASEBOARD_FAB2(SCH_1):PAGE187
    35    GND @BASEBOARD_FAB2_LIB.BASEBOARD_FAB2(SCH_1):GND   I119 @BASEBOARD_FAB2_LIB.BASEBOARD_FAB2(SCH_1):PAGE187
    36 P3E_OCP_CPU0_PE3_C_TXN<4> @BASEBOARD_FAB2_LIB.BASEBOARD_FAB2(SCH_1):P3E_OCP_CPU0_PE3_C_TXN(4)   I119 @BASEBOARD_FAB2_LIB.BASEBOARD_FAB2(SCH_1):PAGE187
    37 P3E_CPU0_PE3_OCP_RXP<3> @BASEBOARD_FAB2_LIB.BASEBOARD_FAB2(SCH_1):P3E_CPU0_PE3_OCP_RXP(3)   I119 @BASEBOARD_FAB2_LIB.BASEBOARD_FAB2(SCH_1):PAGE187
    38    GND @BASEBOARD_FAB2_LIB.BASEBOARD_FAB2(SCH_1):GND   I119 @BASEBOARD_FAB2_LIB.BASEBOARD_FAB2(SCH_1):PAGE187
    39 P3E_CPU0_PE3_OCP_RXN<3> @BASEBOARD_FAB2_LIB.BASEBOARD_FAB2(SCH_1):P3E_CPU0_PE3_OCP_RXN(3)   I119 @BASEBOARD_FAB2_LIB.BASEBOARD_FAB2(SCH_1):PAGE187
     4 P12V_STBY @BASEBOARD_FAB2_LIB.BASEBOARD_FAB2(SCH_1):P12V_STBY   I119 @BASEBOARD_FAB2_LIB.BASEBOARD_FAB2(SCH_1):PAGE187
    40    GND @BASEBOARD_FAB2_LIB.BASEBOARD_FAB2(SCH_1):GND   I119 @BASEBOARD_FAB2_LIB.BASEBOARD_FAB2(SCH_1):PAGE187
    41    GND @BASEBOARD_FAB2_LIB.BASEBOARD_FAB2(SCH_1):GND   I119 @BASEBOARD_FAB2_LIB.BASEBOARD_FAB2(SCH_1):PAGE187
    42 P3E_OCP_CPU0_PE3_C_TXP<3> @BASEBOARD_FAB2_LIB.BASEBOARD_FAB2(SCH_1):P3E_OCP_CPU0_PE3_C_TXP(3)   I119 @BASEBOARD_FAB2_LIB.BASEBOARD_FAB2(SCH_1):PAGE187
    43    GND @BASEBOARD_FAB2_LIB.BASEBOARD_FAB2(SCH_1):GND   I119 @BASEBOARD_FAB2_LIB.BASEBOARD_FAB2(SCH_1):PAGE187
    44 P3E_OCP_CPU0_PE3_C_TXN<3> @BASEBOARD_FAB2_LIB.BASEBOARD_FAB2(SCH_1):P3E_OCP_CPU0_PE3_C_TXN(3)   I119 @BASEBOARD_FAB2_LIB.BASEBOARD_FAB2(SCH_1):PAGE187
    45 P3E_CPU0_PE3_OCP_RXP<2> @BASEBOARD_FAB2_LIB.BASEBOARD_FAB2(SCH_1):P3E_CPU0_PE3_OCP_RXP(2)   I119 @BASEBOARD_FAB2_LIB.BASEBOARD_FAB2(SCH_1):PAGE187
    46    GND @BASEBOARD_FAB2_LIB.BASEBOARD_FAB2(SCH_1):GND   I119 @BASEBOARD_FAB2_LIB.BASEBOARD_FAB2(SCH_1):PAGE187
    47 P3E_CPU0_PE3_OCP_RXN<2> @BASEBOARD_FAB2_LIB.BASEBOARD_FAB2(SCH_1):P3E_CPU0_PE3_OCP_RXN(2)   I119 @BASEBOARD_FAB2_LIB.BASEBOARD_FAB2(SCH_1):PAGE187
    48    GND @BASEBOARD_FAB2_LIB.BASEBOARD_FAB2(SCH_1):GND   I119 @BASEBOARD_FAB2_LIB.BASEBOARD_FAB2(SCH_1):PAGE187
    49    GND @BASEBOARD_FAB2_LIB.BASEBOARD_FAB2(SCH_1):GND   I119 @BASEBOARD_FAB2_LIB.BASEBOARD_FAB2(SCH_1):PAGE187
     5 P3E_CPU0_PE3_OCP_RXP<7> @BASEBOARD_FAB2_LIB.BASEBOARD_FAB2(SCH_1):P3E_CPU0_PE3_OCP_RXP(7)   I119 @BASEBOARD_FAB2_LIB.BASEBOARD_FAB2(SCH_1):PAGE187
    50 P3E_OCP_CPU0_PE3_C_TXP<2> @BASEBOARD_FAB2_LIB.BASEBOARD_FAB2(SCH_1):P3E_OCP_CPU0_PE3_C_TXP(2)   I119 @BASEBOARD_FAB2_LIB.BASEBOARD_FAB2(SCH_1):PAGE187
    51    GND @BASEBOARD_FAB2_LIB.BASEBOARD_FAB2(SCH_1):GND   I119 @BASEBOARD_FAB2_LIB.BASEBOARD_FAB2(SCH_1):PAGE187
    52 P3E_OCP_CPU0_PE3_C_TXN<2> @BASEBOARD_FAB2_LIB.BASEBOARD_FAB2(SCH_1):P3E_OCP_CPU0_PE3_C_TXN(2)   I119 @BASEBOARD_FAB2_LIB.BASEBOARD_FAB2(SCH_1):PAGE187
    53 P3E_CPU0_PE3_OCP_RXP<1> @BASEBOARD_FAB2_LIB.BASEBOARD_FAB2(SCH_1):P3E_CPU0_PE3_OCP_RXP(1)   I119 @BASEBOARD_FAB2_LIB.BASEBOARD_FAB2(SCH_1):PAGE187
    54    GND @BASEBOARD_FAB2_LIB.BASEBOARD_FAB2(SCH_1):GND   I119 @BASEBOARD_FAB2_LIB.BASEBOARD_FAB2(SCH_1):PAGE187
    55 P3E_CPU0_PE3_OCP_RXN<1> @BASEBOARD_FAB2_LIB.BASEBOARD_FAB2(SCH_1):P3E_CPU0_PE3_OCP_RXN(1)   I119 @BASEBOARD_FAB2_LIB.BASEBOARD_FAB2(SCH_1):PAGE187
    56    GND @BASEBOARD_FAB2_LIB.BASEBOARD_FAB2(SCH_1):GND   I119 @BASEBOARD_FAB2_LIB.BASEBOARD_FAB2(SCH_1):PAGE187
    57    GND @BASEBOARD_FAB2_LIB.BASEBOARD_FAB2(SCH_1):GND   I119 @BASEBOARD_FAB2_LIB.BASEBOARD_FAB2(SCH_1):PAGE187
    58 P3E_OCP_CPU0_PE3_C_TXP<1> @BASEBOARD_FAB2_LIB.BASEBOARD_FAB2(SCH_1):P3E_OCP_CPU0_PE3_C_TXP(1)   I119 @BASEBOARD_FAB2_LIB.BASEBOARD_FAB2(SCH_1):PAGE187
    59    GND @BASEBOARD_FAB2_LIB.BASEBOARD_FAB2(SCH_1):GND   I119 @BASEBOARD_FAB2_LIB.BASEBOARD_FAB2(SCH_1):PAGE187
     6 TP_RSVD_B1 @BASEBOARD_FAB2_LIB.BASEBOARD_FAB2(SCH_1):TP_RSVD_B1   I119 @BASEBOARD_FAB2_LIB.BASEBOARD_FAB2(SCH_1):PAGE187
    60 P3E_OCP_CPU0_PE3_C_TXN<1> @BASEBOARD_FAB2_LIB.BASEBOARD_FAB2(SCH_1):P3E_OCP_CPU0_PE3_C_TXN(1)   I119 @BASEBOARD_FAB2_LIB.BASEBOARD_FAB2(SCH_1):PAGE187
    61 P3E_CPU0_PE3_OCP_RXP<0> @BASEBOARD_FAB2_LIB.BASEBOARD_FAB2(SCH_1):P3E_CPU0_PE3_OCP_RXP(0)   I119 @BASEBOARD_FAB2_LIB.BASEBOARD_FAB2(SCH_1):PAGE187
    62    GND @BASEBOARD_FAB2_LIB.BASEBOARD_FAB2(SCH_1):GND   I119 @BASEBOARD_FAB2_LIB.BASEBOARD_FAB2(SCH_1):PAGE187
    63 P3E_CPU0_PE3_OCP_RXN<0> @BASEBOARD_FAB2_LIB.BASEBOARD_FAB2(SCH_1):P3E_CPU0_PE3_OCP_RXN(0)   I119 @BASEBOARD_FAB2_LIB.BASEBOARD_FAB2(SCH_1):PAGE187
    64    GND @BASEBOARD_FAB2_LIB.BASEBOARD_FAB2(SCH_1):GND   I119 @BASEBOARD_FAB2_LIB.BASEBOARD_FAB2(SCH_1):PAGE187
    65    GND @BASEBOARD_FAB2_LIB.BASEBOARD_FAB2(SCH_1):GND   I119 @BASEBOARD_FAB2_LIB.BASEBOARD_FAB2(SCH_1):PAGE187
    66 P3E_OCP_CPU0_PE3_C_TXP<0> @BASEBOARD_FAB2_LIB.BASEBOARD_FAB2(SCH_1):P3E_OCP_CPU0_PE3_C_TXP(0)   I119 @BASEBOARD_FAB2_LIB.BASEBOARD_FAB2(SCH_1):PAGE187
    67    GND @BASEBOARD_FAB2_LIB.BASEBOARD_FAB2(SCH_1):GND   I119 @BASEBOARD_FAB2_LIB.BASEBOARD_FAB2(SCH_1):PAGE187
    68 P3E_OCP_CPU0_PE3_C_TXN<0> @BASEBOARD_FAB2_LIB.BASEBOARD_FAB2(SCH_1):P3E_OCP_CPU0_PE3_C_TXN(0)   I119 @BASEBOARD_FAB2_LIB.BASEBOARD_FAB2(SCH_1):PAGE187
    69 CLK_100M_MEZZ3_DP @BASEBOARD_FAB2_LIB.BASEBOARD_FAB2(SCH_1):CLK_100M_MEZZ3_DP   I119 @BASEBOARD_FAB2_LIB.BASEBOARD_FAB2(SCH_1):PAGE187
     7 P3E_CPU0_PE3_OCP_RXN<7> @BASEBOARD_FAB2_LIB.BASEBOARD_FAB2(SCH_1):P3E_CPU0_PE3_OCP_RXN(7)   I119 @BASEBOARD_FAB2_LIB.BASEBOARD_FAB2(SCH_1):PAGE187
    70    GND @BASEBOARD_FAB2_LIB.BASEBOARD_FAB2(SCH_1):GND   I119 @BASEBOARD_FAB2_LIB.BASEBOARD_FAB2(SCH_1):PAGE187
    71 CLK_100M_MEZZ3_DN @BASEBOARD_FAB2_LIB.BASEBOARD_FAB2(SCH_1):CLK_100M_MEZZ3_DN   I119 @BASEBOARD_FAB2_LIB.BASEBOARD_FAB2(SCH_1):PAGE187
    72    GND @BASEBOARD_FAB2_LIB.BASEBOARD_FAB2(SCH_1):GND   I119 @BASEBOARD_FAB2_LIB.BASEBOARD_FAB2(SCH_1):PAGE187
    73    GND @BASEBOARD_FAB2_LIB.BASEBOARD_FAB2(SCH_1):GND   I119 @BASEBOARD_FAB2_LIB.BASEBOARD_FAB2(SCH_1):PAGE187
    74 CLK_100M_MEZZ4_DP @BASEBOARD_FAB2_LIB.BASEBOARD_FAB2(SCH_1):CLK_100M_MEZZ4_DP   I119 @BASEBOARD_FAB2_LIB.BASEBOARD_FAB2(SCH_1):PAGE187
    75 RST_PCIE_CPU_DEV1_R_N @BASEBOARD_FAB2_LIB.BASEBOARD_FAB2(SCH_1):RST_PCIE_CPU_DEV1_R_N   I119 @BASEBOARD_FAB2_LIB.BASEBOARD_FAB2(SCH_1):PAGE187
    76 CLK_100M_MEZZ4_DN @BASEBOARD_FAB2_LIB.BASEBOARD_FAB2(SCH_1):CLK_100M_MEZZ4_DN   I119 @BASEBOARD_FAB2_LIB.BASEBOARD_FAB2(SCH_1):PAGE187
    77 RST_PCIE_CPU_DEV2_R_N @BASEBOARD_FAB2_LIB.BASEBOARD_FAB2(SCH_1):RST_PCIE_CPU_DEV2_R_N   I119 @BASEBOARD_FAB2_LIB.BASEBOARD_FAB2(SCH_1):PAGE187
    78    GND @BASEBOARD_FAB2_LIB.BASEBOARD_FAB2(SCH_1):GND   I119 @BASEBOARD_FAB2_LIB.BASEBOARD_FAB2(SCH_1):PAGE187
    79 RST_PCIE_CPU_DEV3_R_N @BASEBOARD_FAB2_LIB.BASEBOARD_FAB2(SCH_1):RST_PCIE_CPU_DEV3_R_N   I119 @BASEBOARD_FAB2_LIB.BASEBOARD_FAB2(SCH_1):PAGE187
     8    GND @BASEBOARD_FAB2_LIB.BASEBOARD_FAB2(SCH_1):GND   I119 @BASEBOARD_FAB2_LIB.BASEBOARD_FAB2(SCH_1):PAGE187
    80 FM_OCP_MEZZB_PRES_N @BASEBOARD_FAB2_LIB.BASEBOARD_FAB2(SCH_1):FM_OCP_MEZZB_PRES_N   I119 @BASEBOARD_FAB2_LIB.BASEBOARD_FAB2(SCH_1):PAGE187
     9    GND @BASEBOARD_FAB2_LIB.BASEBOARD_FAB2(SCH_1):GND   I119 @BASEBOARD_FAB2_LIB.BASEBOARD_FAB2(SCH_1):PAGE187

J8E4 SCONN64_H87568002_A_SMT-CONN,HA
     1 SMB_OCP_FRU_STBY_LVC3_SCL @BASEBOARD_FAB2_LIB.BASEBOARD_FAB2(SCH_1):SMB_OCP_FRU_STBY_LVC3_SCL    I27 @BASEBOARD_FAB2_LIB.BASEBOARD_FAB2(SCH_1):PAGE188
    10    GND @BASEBOARD_FAB2_LIB.BASEBOARD_FAB2(SCH_1):GND    I27 @BASEBOARD_FAB2_LIB.BASEBOARD_FAB2(SCH_1):PAGE188
    11 KR_P3_OCP_TX_DP @BASEBOARD_FAB2_LIB.BASEBOARD_FAB2(SCH_1):KR_P3_OCP_TX_DP    I27 @BASEBOARD_FAB2_LIB.BASEBOARD_FAB2(SCH_1):PAGE188
    12 KR_P3_OCP_TX_DN @BASEBOARD_FAB2_LIB.BASEBOARD_FAB2(SCH_1):KR_P3_OCP_TX_DN    I27 @BASEBOARD_FAB2_LIB.BASEBOARD_FAB2(SCH_1):PAGE188
    13    GND @BASEBOARD_FAB2_LIB.BASEBOARD_FAB2(SCH_1):GND    I27 @BASEBOARD_FAB2_LIB.BASEBOARD_FAB2(SCH_1):PAGE188
    14 LED_GBE_P2_0 @BASEBOARD_FAB2_LIB.BASEBOARD_FAB2(SCH_1):LED_GBE_P2_0    I27 @BASEBOARD_FAB2_LIB.BASEBOARD_FAB2(SCH_1):PAGE188
    15 LED_GBE_P2_1 @BASEBOARD_FAB2_LIB.BASEBOARD_FAB2(SCH_1):LED_GBE_P2_1    I27 @BASEBOARD_FAB2_LIB.BASEBOARD_FAB2(SCH_1):PAGE188
    16    GND @BASEBOARD_FAB2_LIB.BASEBOARD_FAB2(SCH_1):GND    I27 @BASEBOARD_FAB2_LIB.BASEBOARD_FAB2(SCH_1):PAGE188
    17 KR_P2_OCP_RX_DP @BASEBOARD_FAB2_LIB.BASEBOARD_FAB2(SCH_1):KR_P2_OCP_RX_DP    I27 @BASEBOARD_FAB2_LIB.BASEBOARD_FAB2(SCH_1):PAGE188
    18 KR_P2_OCP_RX_DN @BASEBOARD_FAB2_LIB.BASEBOARD_FAB2(SCH_1):KR_P2_OCP_RX_DN    I27 @BASEBOARD_FAB2_LIB.BASEBOARD_FAB2(SCH_1):PAGE188
    19    GND @BASEBOARD_FAB2_LIB.BASEBOARD_FAB2(SCH_1):GND    I27 @BASEBOARD_FAB2_LIB.BASEBOARD_FAB2(SCH_1):PAGE188
     2 SMB_OCP_FRU_STBY_LVC3_SDA @BASEBOARD_FAB2_LIB.BASEBOARD_FAB2(SCH_1):SMB_OCP_FRU_STBY_LVC3_SDA    I27 @BASEBOARD_FAB2_LIB.BASEBOARD_FAB2(SCH_1):PAGE188
    20 SMB_PCH_MEZZ_LOM0_SCL @BASEBOARD_FAB2_LIB.BASEBOARD_FAB2(SCH_1):SMB_PCH_MEZZ_LOM0_SCL    I27 @BASEBOARD_FAB2_LIB.BASEBOARD_FAB2(SCH_1):PAGE188
    21 SMB_PCH_MEZZ_LOM0_SDA @BASEBOARD_FAB2_LIB.BASEBOARD_FAB2(SCH_1):SMB_PCH_MEZZ_LOM0_SDA    I27 @BASEBOARD_FAB2_LIB.BASEBOARD_FAB2(SCH_1):PAGE188
    22    GND @BASEBOARD_FAB2_LIB.BASEBOARD_FAB2(SCH_1):GND    I27 @BASEBOARD_FAB2_LIB.BASEBOARD_FAB2(SCH_1):PAGE188
    23 KR_P3_OCP_RX_DP @BASEBOARD_FAB2_LIB.BASEBOARD_FAB2(SCH_1):KR_P3_OCP_RX_DP    I27 @BASEBOARD_FAB2_LIB.BASEBOARD_FAB2(SCH_1):PAGE188
    24 KR_P3_OCP_RX_DN @BASEBOARD_FAB2_LIB.BASEBOARD_FAB2(SCH_1):KR_P3_OCP_RX_DN    I27 @BASEBOARD_FAB2_LIB.BASEBOARD_FAB2(SCH_1):PAGE188
    25    GND @BASEBOARD_FAB2_LIB.BASEBOARD_FAB2(SCH_1):GND    I27 @BASEBOARD_FAB2_LIB.BASEBOARD_FAB2(SCH_1):PAGE188
    26 SMB_PCH_MEZZ_LOM1_SCL @BASEBOARD_FAB2_LIB.BASEBOARD_FAB2(SCH_1):SMB_PCH_MEZZ_LOM1_SCL    I27 @BASEBOARD_FAB2_LIB.BASEBOARD_FAB2(SCH_1):PAGE188
    27 SMB_PCH_MEZZ_LOM1_SDA @BASEBOARD_FAB2_LIB.BASEBOARD_FAB2(SCH_1):SMB_PCH_MEZZ_LOM1_SDA    I27 @BASEBOARD_FAB2_LIB.BASEBOARD_FAB2(SCH_1):PAGE188
    28    GND @BASEBOARD_FAB2_LIB.BASEBOARD_FAB2(SCH_1):GND    I27 @BASEBOARD_FAB2_LIB.BASEBOARD_FAB2(SCH_1):PAGE188
    29 SMB_PCH_MEZZ_LOM3_SCL @BASEBOARD_FAB2_LIB.BASEBOARD_FAB2(SCH_1):SMB_PCH_MEZZ_LOM3_SCL    I27 @BASEBOARD_FAB2_LIB.BASEBOARD_FAB2(SCH_1):PAGE188
     3 TP_EXT_MDIO_I2C_SEL @BASEBOARD_FAB2_LIB.BASEBOARD_FAB2(SCH_1):TP_EXT_MDIO_I2C_SEL    I27 @BASEBOARD_FAB2_LIB.BASEBOARD_FAB2(SCH_1):PAGE188
    30 SMB_PCH_MEZZ_LOM3_SDA @BASEBOARD_FAB2_LIB.BASEBOARD_FAB2(SCH_1):SMB_PCH_MEZZ_LOM3_SDA    I27 @BASEBOARD_FAB2_LIB.BASEBOARD_FAB2(SCH_1):PAGE188
    31 FM_GBE2_LVC3_MOD_ABS @BASEBOARD_FAB2_LIB.BASEBOARD_FAB2(SCH_1):FM_GBE2_LVC3_MOD_ABS    I27 @BASEBOARD_FAB2_LIB.BASEBOARD_FAB2(SCH_1):PAGE188
    32 FM_GBE3_LVC3_MOD_ABS @BASEBOARD_FAB2_LIB.BASEBOARD_FAB2(SCH_1):FM_GBE3_LVC3_MOD_ABS    I27 @BASEBOARD_FAB2_LIB.BASEBOARD_FAB2(SCH_1):PAGE188
    33 P12V_STBY @BASEBOARD_FAB2_LIB.BASEBOARD_FAB2(SCH_1):P12V_STBY    I27 @BASEBOARD_FAB2_LIB.BASEBOARD_FAB2(SCH_1):PAGE188
    34 P12V_STBY @BASEBOARD_FAB2_LIB.BASEBOARD_FAB2(SCH_1):P12V_STBY    I27 @BASEBOARD_FAB2_LIB.BASEBOARD_FAB2(SCH_1):PAGE188
    35 P12V_STBY @BASEBOARD_FAB2_LIB.BASEBOARD_FAB2(SCH_1):P12V_STBY    I27 @BASEBOARD_FAB2_LIB.BASEBOARD_FAB2(SCH_1):PAGE188
    36 TP_RSVD<0> @BASEBOARD_FAB2_LIB.BASEBOARD_FAB2(SCH_1):TP_RSVD(0)    I27 @BASEBOARD_FAB2_LIB.BASEBOARD_FAB2(SCH_1):PAGE188
    37 FM_GBE0_LVC3_MOD_ABS @BASEBOARD_FAB2_LIB.BASEBOARD_FAB2(SCH_1):FM_GBE0_LVC3_MOD_ABS    I27 @BASEBOARD_FAB2_LIB.BASEBOARD_FAB2(SCH_1):PAGE188
    38 FM_GBE1_LVC3_MOD_ABS @BASEBOARD_FAB2_LIB.BASEBOARD_FAB2(SCH_1):FM_GBE1_LVC3_MOD_ABS    I27 @BASEBOARD_FAB2_LIB.BASEBOARD_FAB2(SCH_1):PAGE188
    39    GND @BASEBOARD_FAB2_LIB.BASEBOARD_FAB2(SCH_1):GND    I27 @BASEBOARD_FAB2_LIB.BASEBOARD_FAB2(SCH_1):PAGE188
     4    GND @BASEBOARD_FAB2_LIB.BASEBOARD_FAB2(SCH_1):GND    I27 @BASEBOARD_FAB2_LIB.BASEBOARD_FAB2(SCH_1):PAGE188
    40 KR_P0_OCP_TX_DP @BASEBOARD_FAB2_LIB.BASEBOARD_FAB2(SCH_1):KR_P0_OCP_TX_DP    I27 @BASEBOARD_FAB2_LIB.BASEBOARD_FAB2(SCH_1):PAGE188
    41 KR_P0_OCP_TX_DN @BASEBOARD_FAB2_LIB.BASEBOARD_FAB2(SCH_1):KR_P0_OCP_TX_DN    I27 @BASEBOARD_FAB2_LIB.BASEBOARD_FAB2(SCH_1):PAGE188
    42    GND @BASEBOARD_FAB2_LIB.BASEBOARD_FAB2(SCH_1):GND    I27 @BASEBOARD_FAB2_LIB.BASEBOARD_FAB2(SCH_1):PAGE188
    43 LED_GBE_P0_0 @BASEBOARD_FAB2_LIB.BASEBOARD_FAB2(SCH_1):LED_GBE_P0_0    I27 @BASEBOARD_FAB2_LIB.BASEBOARD_FAB2(SCH_1):PAGE188
    44 LED_GBE_P0_1 @BASEBOARD_FAB2_LIB.BASEBOARD_FAB2(SCH_1):LED_GBE_P0_1    I27 @BASEBOARD_FAB2_LIB.BASEBOARD_FAB2(SCH_1):PAGE188
    45    GND @BASEBOARD_FAB2_LIB.BASEBOARD_FAB2(SCH_1):GND    I27 @BASEBOARD_FAB2_LIB.BASEBOARD_FAB2(SCH_1):PAGE188
    46 KR_P1_OCP_TX_DP @BASEBOARD_FAB2_LIB.BASEBOARD_FAB2(SCH_1):KR_P1_OCP_TX_DP    I27 @BASEBOARD_FAB2_LIB.BASEBOARD_FAB2(SCH_1):PAGE188
    47 KR_P1_OCP_TX_DN @BASEBOARD_FAB2_LIB.BASEBOARD_FAB2(SCH_1):KR_P1_OCP_TX_DN    I27 @BASEBOARD_FAB2_LIB.BASEBOARD_FAB2(SCH_1):PAGE188
    48    GND @BASEBOARD_FAB2_LIB.BASEBOARD_FAB2(SCH_1):GND    I27 @BASEBOARD_FAB2_LIB.BASEBOARD_FAB2(SCH_1):PAGE188
    49 TP_SHARED_KR_MDC_0 @BASEBOARD_FAB2_LIB.BASEBOARD_FAB2(SCH_1):TP_SHARED_KR_MDC_0    I27 @BASEBOARD_FAB2_LIB.BASEBOARD_FAB2(SCH_1):PAGE188
     5 KR_P2_OCP_TX_DP @BASEBOARD_FAB2_LIB.BASEBOARD_FAB2(SCH_1):KR_P2_OCP_TX_DP    I27 @BASEBOARD_FAB2_LIB.BASEBOARD_FAB2(SCH_1):PAGE188
    50 TP_SHARED_KR_MDIO_0 @BASEBOARD_FAB2_LIB.BASEBOARD_FAB2(SCH_1):TP_SHARED_KR_MDIO_0    I27 @BASEBOARD_FAB2_LIB.BASEBOARD_FAB2(SCH_1):PAGE188
    51    GND @BASEBOARD_FAB2_LIB.BASEBOARD_FAB2(SCH_1):GND    I27 @BASEBOARD_FAB2_LIB.BASEBOARD_FAB2(SCH_1):PAGE188
    52 KR_P0_OCP_RX_DP @BASEBOARD_FAB2_LIB.BASEBOARD_FAB2(SCH_1):KR_P0_OCP_RX_DP    I27 @BASEBOARD_FAB2_LIB.BASEBOARD_FAB2(SCH_1):PAGE188
    53 KR_P0_OCP_RX_DN @BASEBOARD_FAB2_LIB.BASEBOARD_FAB2(SCH_1):KR_P0_OCP_RX_DN    I27 @BASEBOARD_FAB2_LIB.BASEBOARD_FAB2(SCH_1):PAGE188
    54    GND @BASEBOARD_FAB2_LIB.BASEBOARD_FAB2(SCH_1):GND    I27 @BASEBOARD_FAB2_LIB.BASEBOARD_FAB2(SCH_1):PAGE188
    55 LED_GBE_P3_0 @BASEBOARD_FAB2_LIB.BASEBOARD_FAB2(SCH_1):LED_GBE_P3_0    I27 @BASEBOARD_FAB2_LIB.BASEBOARD_FAB2(SCH_1):PAGE188
    56 LED_GBE_P3_1 @BASEBOARD_FAB2_LIB.BASEBOARD_FAB2(SCH_1):LED_GBE_P3_1    I27 @BASEBOARD_FAB2_LIB.BASEBOARD_FAB2(SCH_1):PAGE188
    57    GND @BASEBOARD_FAB2_LIB.BASEBOARD_FAB2(SCH_1):GND    I27 @BASEBOARD_FAB2_LIB.BASEBOARD_FAB2(SCH_1):PAGE188
    58 KR_P1_OCP_RX_DP @BASEBOARD_FAB2_LIB.BASEBOARD_FAB2(SCH_1):KR_P1_OCP_RX_DP    I27 @BASEBOARD_FAB2_LIB.BASEBOARD_FAB2(SCH_1):PAGE188
    59 KR_P1_OCP_RX_DN @BASEBOARD_FAB2_LIB.BASEBOARD_FAB2(SCH_1):KR_P1_OCP_RX_DN    I27 @BASEBOARD_FAB2_LIB.BASEBOARD_FAB2(SCH_1):PAGE188
     6 KR_P2_OCP_TX_DN @BASEBOARD_FAB2_LIB.BASEBOARD_FAB2(SCH_1):KR_P2_OCP_TX_DN    I27 @BASEBOARD_FAB2_LIB.BASEBOARD_FAB2(SCH_1):PAGE188
    60    GND @BASEBOARD_FAB2_LIB.BASEBOARD_FAB2(SCH_1):GND    I27 @BASEBOARD_FAB2_LIB.BASEBOARD_FAB2(SCH_1):PAGE188
    61 SMB_PCH_MEZZ_LOM2_SCL @BASEBOARD_FAB2_LIB.BASEBOARD_FAB2(SCH_1):SMB_PCH_MEZZ_LOM2_SCL    I27 @BASEBOARD_FAB2_LIB.BASEBOARD_FAB2(SCH_1):PAGE188
    62 SMB_PCH_MEZZ_LOM2_SDA @BASEBOARD_FAB2_LIB.BASEBOARD_FAB2(SCH_1):SMB_PCH_MEZZ_LOM2_SDA    I27 @BASEBOARD_FAB2_LIB.BASEBOARD_FAB2(SCH_1):PAGE188
    63    GND @BASEBOARD_FAB2_LIB.BASEBOARD_FAB2(SCH_1):GND    I27 @BASEBOARD_FAB2_LIB.BASEBOARD_FAB2(SCH_1):PAGE188
    64 FM_OCP_MEZZC_PRES_N @BASEBOARD_FAB2_LIB.BASEBOARD_FAB2(SCH_1):FM_OCP_MEZZC_PRES_N    I27 @BASEBOARD_FAB2_LIB.BASEBOARD_FAB2(SCH_1):PAGE188
     7    GND @BASEBOARD_FAB2_LIB.BASEBOARD_FAB2(SCH_1):GND    I27 @BASEBOARD_FAB2_LIB.BASEBOARD_FAB2(SCH_1):PAGE188
     8 LED_GBE_P1_0 @BASEBOARD_FAB2_LIB.BASEBOARD_FAB2(SCH_1):LED_GBE_P1_0    I27 @BASEBOARD_FAB2_LIB.BASEBOARD_FAB2(SCH_1):PAGE188
     9 LED_GBE_P1_1 @BASEBOARD_FAB2_LIB.BASEBOARD_FAB2(SCH_1):LED_GBE_P1_1    I27 @BASEBOARD_FAB2_LIB.BASEBOARD_FAB2(SCH_1):PAGE188

J8F1 SCONN75K_H17033002_SMT1-SCONN,A
     1    GND @BASEBOARD_FAB2_LIB.BASEBOARD_FAB2(SCH_1):GND    I53 @BASEBOARD_FAB2_LIB.BASEBOARD_FAB2(SCH_1):PAGE185
     2   P3V3 @BASEBOARD_FAB2_LIB.BASEBOARD_FAB2(SCH_1):P3V3    I53 @BASEBOARD_FAB2_LIB.BASEBOARD_FAB2(SCH_1):PAGE185
     3    GND @BASEBOARD_FAB2_LIB.BASEBOARD_FAB2(SCH_1):GND    I53 @BASEBOARD_FAB2_LIB.BASEBOARD_FAB2(SCH_1):PAGE185
     4   P3V3 @BASEBOARD_FAB2_LIB.BASEBOARD_FAB2(SCH_1):P3V3    I53 @BASEBOARD_FAB2_LIB.BASEBOARD_FAB2(SCH_1):PAGE185
     5 P3E_PCH_M2_RX_DN<3> @BASEBOARD_FAB2_LIB.BASEBOARD_FAB2(SCH_1):P3E_PCH_M2_RX_DN(3)    I53 @BASEBOARD_FAB2_LIB.BASEBOARD_FAB2(SCH_1):PAGE185
     6 NC_M2<0> @BASEBOARD_FAB2_LIB.BASEBOARD_FAB2(SCH_1):NC_M2(0)    I53 @BASEBOARD_FAB2_LIB.BASEBOARD_FAB2(SCH_1):PAGE185
     7 P3E_PCH_M2_RX_DP<3> @BASEBOARD_FAB2_LIB.BASEBOARD_FAB2(SCH_1):P3E_PCH_M2_RX_DP(3)    I53 @BASEBOARD_FAB2_LIB.BASEBOARD_FAB2(SCH_1):PAGE185
     8 NC_M2<1> @BASEBOARD_FAB2_LIB.BASEBOARD_FAB2(SCH_1):NC_M2(1)    I53 @BASEBOARD_FAB2_LIB.BASEBOARD_FAB2(SCH_1):PAGE185
     9    GND @BASEBOARD_FAB2_LIB.BASEBOARD_FAB2(SCH_1):GND    I53 @BASEBOARD_FAB2_LIB.BASEBOARD_FAB2(SCH_1):PAGE185
    10 TP_LED_M2_ACT_N @BASEBOARD_FAB2_LIB.BASEBOARD_FAB2(SCH_1):TP_LED_M2_ACT_N    I53 @BASEBOARD_FAB2_LIB.BASEBOARD_FAB2(SCH_1):PAGE185
    11 P3E_PCH_M2_TX_C_DN<3> @BASEBOARD_FAB2_LIB.BASEBOARD_FAB2(SCH_1):P3E_PCH_M2_TX_C_DN(3)    I53 @BASEBOARD_FAB2_LIB.BASEBOARD_FAB2(SCH_1):PAGE185
    12   P3V3 @BASEBOARD_FAB2_LIB.BASEBOARD_FAB2(SCH_1):P3V3    I53 @BASEBOARD_FAB2_LIB.BASEBOARD_FAB2(SCH_1):PAGE185
    13 P3E_PCH_M2_TX_C_DP<3> @BASEBOARD_FAB2_LIB.BASEBOARD_FAB2(SCH_1):P3E_PCH_M2_TX_C_DP(3)    I53 @BASEBOARD_FAB2_LIB.BASEBOARD_FAB2(SCH_1):PAGE185
    14   P3V3 @BASEBOARD_FAB2_LIB.BASEBOARD_FAB2(SCH_1):P3V3    I53 @BASEBOARD_FAB2_LIB.BASEBOARD_FAB2(SCH_1):PAGE185
    15    GND @BASEBOARD_FAB2_LIB.BASEBOARD_FAB2(SCH_1):GND    I53 @BASEBOARD_FAB2_LIB.BASEBOARD_FAB2(SCH_1):PAGE185
    16   P3V3 @BASEBOARD_FAB2_LIB.BASEBOARD_FAB2(SCH_1):P3V3    I53 @BASEBOARD_FAB2_LIB.BASEBOARD_FAB2(SCH_1):PAGE185
    17 P3E_PCH_M2_RX_DN<2> @BASEBOARD_FAB2_LIB.BASEBOARD_FAB2(SCH_1):P3E_PCH_M2_RX_DN(2)    I53 @BASEBOARD_FAB2_LIB.BASEBOARD_FAB2(SCH_1):PAGE185
    18   P3V3 @BASEBOARD_FAB2_LIB.BASEBOARD_FAB2(SCH_1):P3V3    I53 @BASEBOARD_FAB2_LIB.BASEBOARD_FAB2(SCH_1):PAGE185
    19 P3E_PCH_M2_RX_DP<2> @BASEBOARD_FAB2_LIB.BASEBOARD_FAB2(SCH_1):P3E_PCH_M2_RX_DP(2)    I53 @BASEBOARD_FAB2_LIB.BASEBOARD_FAB2(SCH_1):PAGE185
    20 NC_M2<2> @BASEBOARD_FAB2_LIB.BASEBOARD_FAB2(SCH_1):NC_M2(2)    I53 @BASEBOARD_FAB2_LIB.BASEBOARD_FAB2(SCH_1):PAGE185
    21    GND @BASEBOARD_FAB2_LIB.BASEBOARD_FAB2(SCH_1):GND    I53 @BASEBOARD_FAB2_LIB.BASEBOARD_FAB2(SCH_1):PAGE185
    22 NC_M2<3> @BASEBOARD_FAB2_LIB.BASEBOARD_FAB2(SCH_1):NC_M2(3)    I53 @BASEBOARD_FAB2_LIB.BASEBOARD_FAB2(SCH_1):PAGE185
    23 P3E_PCH_M2_TX_C_DN<2> @BASEBOARD_FAB2_LIB.BASEBOARD_FAB2(SCH_1):P3E_PCH_M2_TX_C_DN(2)    I53 @BASEBOARD_FAB2_LIB.BASEBOARD_FAB2(SCH_1):PAGE185
    24 NC_M2<4> @BASEBOARD_FAB2_LIB.BASEBOARD_FAB2(SCH_1):NC_M2(4)    I53 @BASEBOARD_FAB2_LIB.BASEBOARD_FAB2(SCH_1):PAGE185
    25 P3E_PCH_M2_TX_C_DP<2> @BASEBOARD_FAB2_LIB.BASEBOARD_FAB2(SCH_1):P3E_PCH_M2_TX_C_DP(2)    I53 @BASEBOARD_FAB2_LIB.BASEBOARD_FAB2(SCH_1):PAGE185
    26 NC_M2<5> @BASEBOARD_FAB2_LIB.BASEBOARD_FAB2(SCH_1):NC_M2(5)    I53 @BASEBOARD_FAB2_LIB.BASEBOARD_FAB2(SCH_1):PAGE185
    27    GND @BASEBOARD_FAB2_LIB.BASEBOARD_FAB2(SCH_1):GND    I53 @BASEBOARD_FAB2_LIB.BASEBOARD_FAB2(SCH_1):PAGE185
    28 NC_M2<6> @BASEBOARD_FAB2_LIB.BASEBOARD_FAB2(SCH_1):NC_M2(6)    I53 @BASEBOARD_FAB2_LIB.BASEBOARD_FAB2(SCH_1):PAGE185
    29 P3E_PCH_M2_RX_DN<1> @BASEBOARD_FAB2_LIB.BASEBOARD_FAB2(SCH_1):P3E_PCH_M2_RX_DN(1)    I53 @BASEBOARD_FAB2_LIB.BASEBOARD_FAB2(SCH_1):PAGE185
    30 NC_M2<7> @BASEBOARD_FAB2_LIB.BASEBOARD_FAB2(SCH_1):NC_M2(7)    I53 @BASEBOARD_FAB2_LIB.BASEBOARD_FAB2(SCH_1):PAGE185
    31 P3E_PCH_M2_RX_DP<1> @BASEBOARD_FAB2_LIB.BASEBOARD_FAB2(SCH_1):P3E_PCH_M2_RX_DP(1)    I53 @BASEBOARD_FAB2_LIB.BASEBOARD_FAB2(SCH_1):PAGE185
    32 NC_M2<8> @BASEBOARD_FAB2_LIB.BASEBOARD_FAB2(SCH_1):NC_M2(8)    I53 @BASEBOARD_FAB2_LIB.BASEBOARD_FAB2(SCH_1):PAGE185
    33    GND @BASEBOARD_FAB2_LIB.BASEBOARD_FAB2(SCH_1):GND    I53 @BASEBOARD_FAB2_LIB.BASEBOARD_FAB2(SCH_1):PAGE185
    34 NC_M2<9> @BASEBOARD_FAB2_LIB.BASEBOARD_FAB2(SCH_1):NC_M2(9)    I53 @BASEBOARD_FAB2_LIB.BASEBOARD_FAB2(SCH_1):PAGE185
    35 P3E_PCH_M2_TX_C_DN<1> @BASEBOARD_FAB2_LIB.BASEBOARD_FAB2(SCH_1):P3E_PCH_M2_TX_C_DN(1)    I53 @BASEBOARD_FAB2_LIB.BASEBOARD_FAB2(SCH_1):PAGE185
    36 NC_M2<10> @BASEBOARD_FAB2_LIB.BASEBOARD_FAB2(SCH_1):NC_M2(10)    I53 @BASEBOARD_FAB2_LIB.BASEBOARD_FAB2(SCH_1):PAGE185
    37 P3E_PCH_M2_TX_C_DP<1> @BASEBOARD_FAB2_LIB.BASEBOARD_FAB2(SCH_1):P3E_PCH_M2_TX_C_DP(1)    I53 @BASEBOARD_FAB2_LIB.BASEBOARD_FAB2(SCH_1):PAGE185
    38 TP_M2_DEVSLP @BASEBOARD_FAB2_LIB.BASEBOARD_FAB2(SCH_1):TP_M2_DEVSLP    I53 @BASEBOARD_FAB2_LIB.BASEBOARD_FAB2(SCH_1):PAGE185
    39    GND @BASEBOARD_FAB2_LIB.BASEBOARD_FAB2(SCH_1):GND    I53 @BASEBOARD_FAB2_LIB.BASEBOARD_FAB2(SCH_1):PAGE185
    40 NC_M2<11> @BASEBOARD_FAB2_LIB.BASEBOARD_FAB2(SCH_1):NC_M2(11)    I53 @BASEBOARD_FAB2_LIB.BASEBOARD_FAB2(SCH_1):PAGE185
    41 P3E_PCH_M2_SATA6G_RX_R_DP @BASEBOARD_FAB2_LIB.BASEBOARD_FAB2(SCH_1):P3E_PCH_M2_SATA6G_RX_R_DP    I53 @BASEBOARD_FAB2_LIB.BASEBOARD_FAB2(SCH_1):PAGE185
    42 NC_M2<12> @BASEBOARD_FAB2_LIB.BASEBOARD_FAB2(SCH_1):NC_M2(12)    I53 @BASEBOARD_FAB2_LIB.BASEBOARD_FAB2(SCH_1):PAGE185
    43 P3E_PCH_M2_SATA6G_RX_R_DN @BASEBOARD_FAB2_LIB.BASEBOARD_FAB2(SCH_1):P3E_PCH_M2_SATA6G_RX_R_DN    I53 @BASEBOARD_FAB2_LIB.BASEBOARD_FAB2(SCH_1):PAGE185
    44 NC_M2<13> @BASEBOARD_FAB2_LIB.BASEBOARD_FAB2(SCH_1):NC_M2(13)    I53 @BASEBOARD_FAB2_LIB.BASEBOARD_FAB2(SCH_1):PAGE185
    45    GND @BASEBOARD_FAB2_LIB.BASEBOARD_FAB2(SCH_1):GND    I53 @BASEBOARD_FAB2_LIB.BASEBOARD_FAB2(SCH_1):PAGE185
    46 NC_M2<14> @BASEBOARD_FAB2_LIB.BASEBOARD_FAB2(SCH_1):NC_M2(14)    I53 @BASEBOARD_FAB2_LIB.BASEBOARD_FAB2(SCH_1):PAGE185
    47 P3E_PCH_M2_SATA6G_TX_R_DN @BASEBOARD_FAB2_LIB.BASEBOARD_FAB2(SCH_1):P3E_PCH_M2_SATA6G_TX_R_DN    I53 @BASEBOARD_FAB2_LIB.BASEBOARD_FAB2(SCH_1):PAGE185
    48 NC_M2<15> @BASEBOARD_FAB2_LIB.BASEBOARD_FAB2(SCH_1):NC_M2(15)    I53 @BASEBOARD_FAB2_LIB.BASEBOARD_FAB2(SCH_1):PAGE185
    49 P3E_PCH_M2_SATA6G_TX_R_DP @BASEBOARD_FAB2_LIB.BASEBOARD_FAB2(SCH_1):P3E_PCH_M2_SATA6G_TX_R_DP    I53 @BASEBOARD_FAB2_LIB.BASEBOARD_FAB2(SCH_1):PAGE185
    50 RST_PCIE_M2_DEV_N @BASEBOARD_FAB2_LIB.BASEBOARD_FAB2(SCH_1):RST_PCIE_M2_DEV_N    I53 @BASEBOARD_FAB2_LIB.BASEBOARD_FAB2(SCH_1):PAGE185
    51    GND @BASEBOARD_FAB2_LIB.BASEBOARD_FAB2(SCH_1):GND    I53 @BASEBOARD_FAB2_LIB.BASEBOARD_FAB2(SCH_1):PAGE185
    52 PU_M2_CLK_REQ_N @BASEBOARD_FAB2_LIB.BASEBOARD_FAB2(SCH_1):PU_M2_CLK_REQ_N    I53 @BASEBOARD_FAB2_LIB.BASEBOARD_FAB2(SCH_1):PAGE185
    53 CLK_100M_M2_DN @BASEBOARD_FAB2_LIB.BASEBOARD_FAB2(SCH_1):CLK_100M_M2_DN    I53 @BASEBOARD_FAB2_LIB.BASEBOARD_FAB2(SCH_1):PAGE185
    54 FM_PE_M2_WAKE_N @BASEBOARD_FAB2_LIB.BASEBOARD_FAB2(SCH_1):FM_PE_M2_WAKE_N    I53 @BASEBOARD_FAB2_LIB.BASEBOARD_FAB2(SCH_1):PAGE185
    55 CLK_100M_M2_DP @BASEBOARD_FAB2_LIB.BASEBOARD_FAB2(SCH_1):CLK_100M_M2_DP    I53 @BASEBOARD_FAB2_LIB.BASEBOARD_FAB2(SCH_1):PAGE185
    56 NC_M2<16> @BASEBOARD_FAB2_LIB.BASEBOARD_FAB2(SCH_1):NC_M2(16)    I53 @BASEBOARD_FAB2_LIB.BASEBOARD_FAB2(SCH_1):PAGE185
    57    GND @BASEBOARD_FAB2_LIB.BASEBOARD_FAB2(SCH_1):GND    I53 @BASEBOARD_FAB2_LIB.BASEBOARD_FAB2(SCH_1):PAGE185
    58 NC_M2<17> @BASEBOARD_FAB2_LIB.BASEBOARD_FAB2(SCH_1):NC_M2(17)    I53 @BASEBOARD_FAB2_LIB.BASEBOARD_FAB2(SCH_1):PAGE185
    67 NC_M2<18> @BASEBOARD_FAB2_LIB.BASEBOARD_FAB2(SCH_1):NC_M2(18)    I53 @BASEBOARD_FAB2_LIB.BASEBOARD_FAB2(SCH_1):PAGE185
    68 TP_M2_32M_SUSCLK @BASEBOARD_FAB2_LIB.BASEBOARD_FAB2(SCH_1):TP_M2_32M_SUSCLK    I53 @BASEBOARD_FAB2_LIB.BASEBOARD_FAB2(SCH_1):PAGE185
    69 FM_M2_SSD_PEDET @BASEBOARD_FAB2_LIB.BASEBOARD_FAB2(SCH_1):FM_M2_SSD_PEDET    I53 @BASEBOARD_FAB2_LIB.BASEBOARD_FAB2(SCH_1):PAGE185
    70   P3V3 @BASEBOARD_FAB2_LIB.BASEBOARD_FAB2(SCH_1):P3V3    I53 @BASEBOARD_FAB2_LIB.BASEBOARD_FAB2(SCH_1):PAGE185
    71    GND @BASEBOARD_FAB2_LIB.BASEBOARD_FAB2(SCH_1):GND    I53 @BASEBOARD_FAB2_LIB.BASEBOARD_FAB2(SCH_1):PAGE185
    72   P3V3 @BASEBOARD_FAB2_LIB.BASEBOARD_FAB2(SCH_1):P3V3    I53 @BASEBOARD_FAB2_LIB.BASEBOARD_FAB2(SCH_1):PAGE185
    73    GND @BASEBOARD_FAB2_LIB.BASEBOARD_FAB2(SCH_1):GND    I53 @BASEBOARD_FAB2_LIB.BASEBOARD_FAB2(SCH_1):PAGE185
    74   P3V3 @BASEBOARD_FAB2_LIB.BASEBOARD_FAB2(SCH_1):P3V3    I53 @BASEBOARD_FAB2_LIB.BASEBOARD_FAB2(SCH_1):PAGE185
    75    GND @BASEBOARD_FAB2_LIB.BASEBOARD_FAB2(SCH_1):GND    I53 @BASEBOARD_FAB2_LIB.BASEBOARD_FAB2(SCH_1):PAGE185
   MP1    GND @BASEBOARD_FAB2_LIB.BASEBOARD_FAB2(SCH_1):GND    I53 @BASEBOARD_FAB2_LIB.BASEBOARD_FAB2(SCH_1):PAGE185
   MP2    GND @BASEBOARD_FAB2_LIB.BASEBOARD_FAB2(SCH_1):GND    I53 @BASEBOARD_FAB2_LIB.BASEBOARD_FAB2(SCH_1):PAGE185

J8G1 SCONN200_H68296001_SM-CONN,H68A
     1   P12V @BASEBOARD_FAB2_LIB.BASEBOARD_FAB2(SCH_1):P12V   I258 @BASEBOARD_FAB2_LIB.BASEBOARD_FAB2(SCH_1):PAGE108
     2   P12V @BASEBOARD_FAB2_LIB.BASEBOARD_FAB2(SCH_1):P12V   I258 @BASEBOARD_FAB2_LIB.BASEBOARD_FAB2(SCH_1):PAGE108
     3   P12V @BASEBOARD_FAB2_LIB.BASEBOARD_FAB2(SCH_1):P12V   I258 @BASEBOARD_FAB2_LIB.BASEBOARD_FAB2(SCH_1):PAGE108
     4   P12V @BASEBOARD_FAB2_LIB.BASEBOARD_FAB2(SCH_1):P12V   I258 @BASEBOARD_FAB2_LIB.BASEBOARD_FAB2(SCH_1):PAGE108
     5   P12V @BASEBOARD_FAB2_LIB.BASEBOARD_FAB2(SCH_1):P12V   I258 @BASEBOARD_FAB2_LIB.BASEBOARD_FAB2(SCH_1):PAGE108
     6   P12V @BASEBOARD_FAB2_LIB.BASEBOARD_FAB2(SCH_1):P12V   I258 @BASEBOARD_FAB2_LIB.BASEBOARD_FAB2(SCH_1):PAGE108
     7   P12V @BASEBOARD_FAB2_LIB.BASEBOARD_FAB2(SCH_1):P12V   I258 @BASEBOARD_FAB2_LIB.BASEBOARD_FAB2(SCH_1):PAGE108
     8   P12V @BASEBOARD_FAB2_LIB.BASEBOARD_FAB2(SCH_1):P12V   I258 @BASEBOARD_FAB2_LIB.BASEBOARD_FAB2(SCH_1):PAGE108
     9   P12V @BASEBOARD_FAB2_LIB.BASEBOARD_FAB2(SCH_1):P12V   I258 @BASEBOARD_FAB2_LIB.BASEBOARD_FAB2(SCH_1):PAGE108
    10   P12V @BASEBOARD_FAB2_LIB.BASEBOARD_FAB2(SCH_1):P12V   I258 @BASEBOARD_FAB2_LIB.BASEBOARD_FAB2(SCH_1):PAGE108
    11   P12V @BASEBOARD_FAB2_LIB.BASEBOARD_FAB2(SCH_1):P12V   I258 @BASEBOARD_FAB2_LIB.BASEBOARD_FAB2(SCH_1):PAGE108
    12   P12V @BASEBOARD_FAB2_LIB.BASEBOARD_FAB2(SCH_1):P12V   I258 @BASEBOARD_FAB2_LIB.BASEBOARD_FAB2(SCH_1):PAGE108
    13    GND @BASEBOARD_FAB2_LIB.BASEBOARD_FAB2(SCH_1):GND   I258 @BASEBOARD_FAB2_LIB.BASEBOARD_FAB2(SCH_1):PAGE108
    14    GND @BASEBOARD_FAB2_LIB.BASEBOARD_FAB2(SCH_1):GND   I258 @BASEBOARD_FAB2_LIB.BASEBOARD_FAB2(SCH_1):PAGE108
    15 SMB_SLOTX24_STBY_LVC3_SDA_R2 @BASEBOARD_FAB2_LIB.BASEBOARD_FAB2(SCH_1):SMB_SLOTX24_STBY_LVC3_SDA_R2   I258 @BASEBOARD_FAB2_LIB.BASEBOARD_FAB2(SCH_1):PAGE108
    16 IRQ_OOB_MGMT_RISER_ALERT_N @BASEBOARD_FAB2_LIB.BASEBOARD_FAB2(SCH_1):IRQ_OOB_MGMT_RISER_ALERT_N   I258 @BASEBOARD_FAB2_LIB.BASEBOARD_FAB2(SCH_1):PAGE108
    17 SMB_SLOTX24_STBY_LVC3_SCL_R2 @BASEBOARD_FAB2_LIB.BASEBOARD_FAB2(SCH_1):SMB_SLOTX24_STBY_LVC3_SCL_R2   I258 @BASEBOARD_FAB2_LIB.BASEBOARD_FAB2(SCH_1):PAGE108
    18 FM_SLT_CFG1 @BASEBOARD_FAB2_LIB.BASEBOARD_FAB2(SCH_1):FM_SLT_CFG1   I258 @BASEBOARD_FAB2_LIB.BASEBOARD_FAB2(SCH_1):PAGE108
    19 FM_SLT_CFG0 @BASEBOARD_FAB2_LIB.BASEBOARD_FAB2(SCH_1):FM_SLT_CFG0   I258 @BASEBOARD_FAB2_LIB.BASEBOARD_FAB2(SCH_1):PAGE108
    20 FM_PWRBRK_SLOT_N @BASEBOARD_FAB2_LIB.BASEBOARD_FAB2(SCH_1):FM_PWRBRK_SLOT_N   I258 @BASEBOARD_FAB2_LIB.BASEBOARD_FAB2(SCH_1):PAGE108
    21   P3V3 @BASEBOARD_FAB2_LIB.BASEBOARD_FAB2(SCH_1):P3V3   I258 @BASEBOARD_FAB2_LIB.BASEBOARD_FAB2(SCH_1):PAGE108
    22   P3V3 @BASEBOARD_FAB2_LIB.BASEBOARD_FAB2(SCH_1):P3V3   I258 @BASEBOARD_FAB2_LIB.BASEBOARD_FAB2(SCH_1):PAGE108
    23   P3V3 @BASEBOARD_FAB2_LIB.BASEBOARD_FAB2(SCH_1):P3V3   I258 @BASEBOARD_FAB2_LIB.BASEBOARD_FAB2(SCH_1):PAGE108
    24   P3V3 @BASEBOARD_FAB2_LIB.BASEBOARD_FAB2(SCH_1):P3V3   I258 @BASEBOARD_FAB2_LIB.BASEBOARD_FAB2(SCH_1):PAGE108
    25 P3V3_STBY @BASEBOARD_FAB2_LIB.BASEBOARD_FAB2(SCH_1):P3V3_STBY   I258 @BASEBOARD_FAB2_LIB.BASEBOARD_FAB2(SCH_1):PAGE108
    26    GND @BASEBOARD_FAB2_LIB.BASEBOARD_FAB2(SCH_1):GND   I258 @BASEBOARD_FAB2_LIB.BASEBOARD_FAB2(SCH_1):PAGE108
    27 FM_PRSNT_2_1_N @BASEBOARD_FAB2_LIB.BASEBOARD_FAB2(SCH_1):FM_PRSNT_2_1_N   I258 @BASEBOARD_FAB2_LIB.BASEBOARD_FAB2(SCH_1):PAGE108
    28 FM_PE_SLOTX24_WAKE_N @BASEBOARD_FAB2_LIB.BASEBOARD_FAB2(SCH_1):FM_PE_SLOTX24_WAKE_N   I258 @BASEBOARD_FAB2_LIB.BASEBOARD_FAB2(SCH_1):PAGE108
    29 RST_PCIE_RISER1_PERST_R_N @BASEBOARD_FAB2_LIB.BASEBOARD_FAB2(SCH_1):RST_PCIE_RISER1_PERST_R_N   I258 @BASEBOARD_FAB2_LIB.BASEBOARD_FAB2(SCH_1):PAGE108
    30 FM_PRSNT_2_2_N @BASEBOARD_FAB2_LIB.BASEBOARD_FAB2(SCH_1):FM_PRSNT_2_2_N   I258 @BASEBOARD_FAB2_LIB.BASEBOARD_FAB2(SCH_1):PAGE108
    31    GND @BASEBOARD_FAB2_LIB.BASEBOARD_FAB2(SCH_1):GND   I258 @BASEBOARD_FAB2_LIB.BASEBOARD_FAB2(SCH_1):PAGE108
    32 FM_PRSNT_2_3_N @BASEBOARD_FAB2_LIB.BASEBOARD_FAB2(SCH_1):FM_PRSNT_2_3_N   I258 @BASEBOARD_FAB2_LIB.BASEBOARD_FAB2(SCH_1):PAGE108
    33 CLK_100M_PCH_SLOTX24_S5_DP @BASEBOARD_FAB2_LIB.BASEBOARD_FAB2(SCH_1):CLK_100M_PCH_SLOTX24_S5_DP   I258 @BASEBOARD_FAB2_LIB.BASEBOARD_FAB2(SCH_1):PAGE108
    34    GND @BASEBOARD_FAB2_LIB.BASEBOARD_FAB2(SCH_1):GND   I258 @BASEBOARD_FAB2_LIB.BASEBOARD_FAB2(SCH_1):PAGE108
    35 CLK_100M_PCH_SLOTX24_S5_DN @BASEBOARD_FAB2_LIB.BASEBOARD_FAB2(SCH_1):CLK_100M_PCH_SLOTX24_S5_DN   I258 @BASEBOARD_FAB2_LIB.BASEBOARD_FAB2(SCH_1):PAGE108
    36 CLK_100M_PCH_SLOTX24_S4_DP @BASEBOARD_FAB2_LIB.BASEBOARD_FAB2(SCH_1):CLK_100M_PCH_SLOTX24_S4_DP   I258 @BASEBOARD_FAB2_LIB.BASEBOARD_FAB2(SCH_1):PAGE108
    37    GND @BASEBOARD_FAB2_LIB.BASEBOARD_FAB2(SCH_1):GND   I258 @BASEBOARD_FAB2_LIB.BASEBOARD_FAB2(SCH_1):PAGE108
    38 CLK_100M_PCH_SLOTX24_S4_DN @BASEBOARD_FAB2_LIB.BASEBOARD_FAB2(SCH_1):CLK_100M_PCH_SLOTX24_S4_DN   I258 @BASEBOARD_FAB2_LIB.BASEBOARD_FAB2(SCH_1):PAGE108
    39 CLK_100M_PCH_SLOTX24_S0_DP @BASEBOARD_FAB2_LIB.BASEBOARD_FAB2(SCH_1):CLK_100M_PCH_SLOTX24_S0_DP   I258 @BASEBOARD_FAB2_LIB.BASEBOARD_FAB2(SCH_1):PAGE108
    40    GND @BASEBOARD_FAB2_LIB.BASEBOARD_FAB2(SCH_1):GND   I258 @BASEBOARD_FAB2_LIB.BASEBOARD_FAB2(SCH_1):PAGE108
    41 CLK_100M_PCH_SLOTX24_S0_DN @BASEBOARD_FAB2_LIB.BASEBOARD_FAB2(SCH_1):CLK_100M_PCH_SLOTX24_S0_DN   I258 @BASEBOARD_FAB2_LIB.BASEBOARD_FAB2(SCH_1):PAGE108
    42 CLK_100M_PCH_SLOTX24_S1_DP @BASEBOARD_FAB2_LIB.BASEBOARD_FAB2(SCH_1):CLK_100M_PCH_SLOTX24_S1_DP   I258 @BASEBOARD_FAB2_LIB.BASEBOARD_FAB2(SCH_1):PAGE108
    43    GND @BASEBOARD_FAB2_LIB.BASEBOARD_FAB2(SCH_1):GND   I258 @BASEBOARD_FAB2_LIB.BASEBOARD_FAB2(SCH_1):PAGE108
    44 CLK_100M_PCH_SLOTX24_S1_DN @BASEBOARD_FAB2_LIB.BASEBOARD_FAB2(SCH_1):CLK_100M_PCH_SLOTX24_S1_DN   I258 @BASEBOARD_FAB2_LIB.BASEBOARD_FAB2(SCH_1):PAGE108
    45 CLK_100M_PCH_SLOTX24_S3_DP @BASEBOARD_FAB2_LIB.BASEBOARD_FAB2(SCH_1):CLK_100M_PCH_SLOTX24_S3_DP   I258 @BASEBOARD_FAB2_LIB.BASEBOARD_FAB2(SCH_1):PAGE108
    46    GND @BASEBOARD_FAB2_LIB.BASEBOARD_FAB2(SCH_1):GND   I258 @BASEBOARD_FAB2_LIB.BASEBOARD_FAB2(SCH_1):PAGE108
    47 CLK_100M_PCH_SLOTX24_S3_DN @BASEBOARD_FAB2_LIB.BASEBOARD_FAB2(SCH_1):CLK_100M_PCH_SLOTX24_S3_DN   I258 @BASEBOARD_FAB2_LIB.BASEBOARD_FAB2(SCH_1):PAGE108
    48 CLK_100M_PCH_SLOTX24_S2_DP @BASEBOARD_FAB2_LIB.BASEBOARD_FAB2(SCH_1):CLK_100M_PCH_SLOTX24_S2_DP   I258 @BASEBOARD_FAB2_LIB.BASEBOARD_FAB2(SCH_1):PAGE108
    49    GND @BASEBOARD_FAB2_LIB.BASEBOARD_FAB2(SCH_1):GND   I258 @BASEBOARD_FAB2_LIB.BASEBOARD_FAB2(SCH_1):PAGE108
    50 CLK_100M_PCH_SLOTX24_S2_DN @BASEBOARD_FAB2_LIB.BASEBOARD_FAB2(SCH_1):CLK_100M_PCH_SLOTX24_S2_DN   I258 @BASEBOARD_FAB2_LIB.BASEBOARD_FAB2(SCH_1):PAGE108
    51 P3E_CPU0_PE1_PCH_CON_TXN<15> @BASEBOARD_FAB2_LIB.BASEBOARD_FAB2(SCH_1):P3E_CPU0_PE1_PCH_CON_TXN(15)   I258 @BASEBOARD_FAB2_LIB.BASEBOARD_FAB2(SCH_1):PAGE108
    52    GND @BASEBOARD_FAB2_LIB.BASEBOARD_FAB2(SCH_1):GND   I258 @BASEBOARD_FAB2_LIB.BASEBOARD_FAB2(SCH_1):PAGE108
    53 P3E_CPU0_PE1_PCH_CON_TXP<15> @BASEBOARD_FAB2_LIB.BASEBOARD_FAB2(SCH_1):P3E_CPU0_PE1_PCH_CON_TXP(15)   I258 @BASEBOARD_FAB2_LIB.BASEBOARD_FAB2(SCH_1):PAGE108
    54 P3E_CPU0_PE1_PCH_CON_RXN<15> @BASEBOARD_FAB2_LIB.BASEBOARD_FAB2(SCH_1):P3E_CPU0_PE1_PCH_CON_RXN(15)   I258 @BASEBOARD_FAB2_LIB.BASEBOARD_FAB2(SCH_1):PAGE108
    55    GND @BASEBOARD_FAB2_LIB.BASEBOARD_FAB2(SCH_1):GND   I258 @BASEBOARD_FAB2_LIB.BASEBOARD_FAB2(SCH_1):PAGE108
    56 P3E_CPU0_PE1_PCH_CON_RXP<15> @BASEBOARD_FAB2_LIB.BASEBOARD_FAB2(SCH_1):P3E_CPU0_PE1_PCH_CON_RXP(15)   I258 @BASEBOARD_FAB2_LIB.BASEBOARD_FAB2(SCH_1):PAGE108
    57 P3E_CPU0_PE1_PCH_CON_TXP<14> @BASEBOARD_FAB2_LIB.BASEBOARD_FAB2(SCH_1):P3E_CPU0_PE1_PCH_CON_TXP(14)   I258 @BASEBOARD_FAB2_LIB.BASEBOARD_FAB2(SCH_1):PAGE108
    58    GND @BASEBOARD_FAB2_LIB.BASEBOARD_FAB2(SCH_1):GND   I258 @BASEBOARD_FAB2_LIB.BASEBOARD_FAB2(SCH_1):PAGE108
    59 P3E_CPU0_PE1_PCH_CON_TXN<14> @BASEBOARD_FAB2_LIB.BASEBOARD_FAB2(SCH_1):P3E_CPU0_PE1_PCH_CON_TXN(14)   I258 @BASEBOARD_FAB2_LIB.BASEBOARD_FAB2(SCH_1):PAGE108
    60 P3E_CPU0_PE1_PCH_CON_RXN<14> @BASEBOARD_FAB2_LIB.BASEBOARD_FAB2(SCH_1):P3E_CPU0_PE1_PCH_CON_RXN(14)   I258 @BASEBOARD_FAB2_LIB.BASEBOARD_FAB2(SCH_1):PAGE108
    61    GND @BASEBOARD_FAB2_LIB.BASEBOARD_FAB2(SCH_1):GND   I258 @BASEBOARD_FAB2_LIB.BASEBOARD_FAB2(SCH_1):PAGE108
    62 P3E_CPU0_PE1_PCH_CON_RXP<14> @BASEBOARD_FAB2_LIB.BASEBOARD_FAB2(SCH_1):P3E_CPU0_PE1_PCH_CON_RXP(14)   I258 @BASEBOARD_FAB2_LIB.BASEBOARD_FAB2(SCH_1):PAGE108
    63 FM_PRSNT_2_4_N @BASEBOARD_FAB2_LIB.BASEBOARD_FAB2(SCH_1):FM_PRSNT_2_4_N   I258 @BASEBOARD_FAB2_LIB.BASEBOARD_FAB2(SCH_1):PAGE108
    64    GND @BASEBOARD_FAB2_LIB.BASEBOARD_FAB2(SCH_1):GND   I258 @BASEBOARD_FAB2_LIB.BASEBOARD_FAB2(SCH_1):PAGE108
    65    GND @BASEBOARD_FAB2_LIB.BASEBOARD_FAB2(SCH_1):GND   I258 @BASEBOARD_FAB2_LIB.BASEBOARD_FAB2(SCH_1):PAGE108
    66 FM_PRSNT_2_5_N @BASEBOARD_FAB2_LIB.BASEBOARD_FAB2(SCH_1):FM_PRSNT_2_5_N   I258 @BASEBOARD_FAB2_LIB.BASEBOARD_FAB2(SCH_1):PAGE108
    67 P3E_CPU0_PE1_PCH_CON_TXN<13> @BASEBOARD_FAB2_LIB.BASEBOARD_FAB2(SCH_1):P3E_CPU0_PE1_PCH_CON_TXN(13)   I258 @BASEBOARD_FAB2_LIB.BASEBOARD_FAB2(SCH_1):PAGE108
    68    GND @BASEBOARD_FAB2_LIB.BASEBOARD_FAB2(SCH_1):GND   I258 @BASEBOARD_FAB2_LIB.BASEBOARD_FAB2(SCH_1):PAGE108
    69 P3E_CPU0_PE1_PCH_CON_TXP<13> @BASEBOARD_FAB2_LIB.BASEBOARD_FAB2(SCH_1):P3E_CPU0_PE1_PCH_CON_TXP(13)   I258 @BASEBOARD_FAB2_LIB.BASEBOARD_FAB2(SCH_1):PAGE108
    70 P3E_CPU0_PE1_PCH_CON_RXN<13> @BASEBOARD_FAB2_LIB.BASEBOARD_FAB2(SCH_1):P3E_CPU0_PE1_PCH_CON_RXN(13)   I258 @BASEBOARD_FAB2_LIB.BASEBOARD_FAB2(SCH_1):PAGE108
    71    GND @BASEBOARD_FAB2_LIB.BASEBOARD_FAB2(SCH_1):GND   I258 @BASEBOARD_FAB2_LIB.BASEBOARD_FAB2(SCH_1):PAGE108
    72 P3E_CPU0_PE1_PCH_CON_RXP<13> @BASEBOARD_FAB2_LIB.BASEBOARD_FAB2(SCH_1):P3E_CPU0_PE1_PCH_CON_RXP(13)   I258 @BASEBOARD_FAB2_LIB.BASEBOARD_FAB2(SCH_1):PAGE108
    73 P3E_CPU0_PE1_PCH_CON_TXN<12> @BASEBOARD_FAB2_LIB.BASEBOARD_FAB2(SCH_1):P3E_CPU0_PE1_PCH_CON_TXN(12)   I258 @BASEBOARD_FAB2_LIB.BASEBOARD_FAB2(SCH_1):PAGE108
    74    GND @BASEBOARD_FAB2_LIB.BASEBOARD_FAB2(SCH_1):GND   I258 @BASEBOARD_FAB2_LIB.BASEBOARD_FAB2(SCH_1):PAGE108
    75 P3E_CPU0_PE1_PCH_CON_TXP<12> @BASEBOARD_FAB2_LIB.BASEBOARD_FAB2(SCH_1):P3E_CPU0_PE1_PCH_CON_TXP(12)   I258 @BASEBOARD_FAB2_LIB.BASEBOARD_FAB2(SCH_1):PAGE108
    76 P3E_CPU0_PE1_PCH_CON_RXN<12> @BASEBOARD_FAB2_LIB.BASEBOARD_FAB2(SCH_1):P3E_CPU0_PE1_PCH_CON_RXN(12)   I258 @BASEBOARD_FAB2_LIB.BASEBOARD_FAB2(SCH_1):PAGE108
    77    GND @BASEBOARD_FAB2_LIB.BASEBOARD_FAB2(SCH_1):GND   I258 @BASEBOARD_FAB2_LIB.BASEBOARD_FAB2(SCH_1):PAGE108
    78 P3E_CPU0_PE1_PCH_CON_RXP<12> @BASEBOARD_FAB2_LIB.BASEBOARD_FAB2(SCH_1):P3E_CPU0_PE1_PCH_CON_RXP(12)   I258 @BASEBOARD_FAB2_LIB.BASEBOARD_FAB2(SCH_1):PAGE108
    79 P3E_CPU0_PE1_PCH_CON_TXN<11> @BASEBOARD_FAB2_LIB.BASEBOARD_FAB2(SCH_1):P3E_CPU0_PE1_PCH_CON_TXN(11)   I258 @BASEBOARD_FAB2_LIB.BASEBOARD_FAB2(SCH_1):PAGE108
    80    GND @BASEBOARD_FAB2_LIB.BASEBOARD_FAB2(SCH_1):GND   I258 @BASEBOARD_FAB2_LIB.BASEBOARD_FAB2(SCH_1):PAGE108
    81 P3E_CPU0_PE1_PCH_CON_TXP<11> @BASEBOARD_FAB2_LIB.BASEBOARD_FAB2(SCH_1):P3E_CPU0_PE1_PCH_CON_TXP(11)   I258 @BASEBOARD_FAB2_LIB.BASEBOARD_FAB2(SCH_1):PAGE108
    82 P3E_CPU0_PE1_PCH_CON_RXN<11> @BASEBOARD_FAB2_LIB.BASEBOARD_FAB2(SCH_1):P3E_CPU0_PE1_PCH_CON_RXN(11)   I258 @BASEBOARD_FAB2_LIB.BASEBOARD_FAB2(SCH_1):PAGE108
    83    GND @BASEBOARD_FAB2_LIB.BASEBOARD_FAB2(SCH_1):GND   I258 @BASEBOARD_FAB2_LIB.BASEBOARD_FAB2(SCH_1):PAGE108
    84 P3E_CPU0_PE1_PCH_CON_RXP<11> @BASEBOARD_FAB2_LIB.BASEBOARD_FAB2(SCH_1):P3E_CPU0_PE1_PCH_CON_RXP(11)   I258 @BASEBOARD_FAB2_LIB.BASEBOARD_FAB2(SCH_1):PAGE108
    85 P3E_CPU0_PE1_PCH_CON_TXN<10> @BASEBOARD_FAB2_LIB.BASEBOARD_FAB2(SCH_1):P3E_CPU0_PE1_PCH_CON_TXN(10)   I258 @BASEBOARD_FAB2_LIB.BASEBOARD_FAB2(SCH_1):PAGE108
    86    GND @BASEBOARD_FAB2_LIB.BASEBOARD_FAB2(SCH_1):GND   I258 @BASEBOARD_FAB2_LIB.BASEBOARD_FAB2(SCH_1):PAGE108
    87 P3E_CPU0_PE1_PCH_CON_TXP<10> @BASEBOARD_FAB2_LIB.BASEBOARD_FAB2(SCH_1):P3E_CPU0_PE1_PCH_CON_TXP(10)   I258 @BASEBOARD_FAB2_LIB.BASEBOARD_FAB2(SCH_1):PAGE108
    88 P3E_CPU0_PE1_PCH_CON_RXN<10> @BASEBOARD_FAB2_LIB.BASEBOARD_FAB2(SCH_1):P3E_CPU0_PE1_PCH_CON_RXN(10)   I258 @BASEBOARD_FAB2_LIB.BASEBOARD_FAB2(SCH_1):PAGE108
    89    GND @BASEBOARD_FAB2_LIB.BASEBOARD_FAB2(SCH_1):GND   I258 @BASEBOARD_FAB2_LIB.BASEBOARD_FAB2(SCH_1):PAGE108
    90 P3E_CPU0_PE1_PCH_CON_RXP<10> @BASEBOARD_FAB2_LIB.BASEBOARD_FAB2(SCH_1):P3E_CPU0_PE1_PCH_CON_RXP(10)   I258 @BASEBOARD_FAB2_LIB.BASEBOARD_FAB2(SCH_1):PAGE108
    91 P3E_CPU0_PE1_PCH_CON_TXN<9> @BASEBOARD_FAB2_LIB.BASEBOARD_FAB2(SCH_1):P3E_CPU0_PE1_PCH_CON_TXN(9)   I258 @BASEBOARD_FAB2_LIB.BASEBOARD_FAB2(SCH_1):PAGE108
    92    GND @BASEBOARD_FAB2_LIB.BASEBOARD_FAB2(SCH_1):GND   I258 @BASEBOARD_FAB2_LIB.BASEBOARD_FAB2(SCH_1):PAGE108
    93 P3E_CPU0_PE1_PCH_CON_TXP<9> @BASEBOARD_FAB2_LIB.BASEBOARD_FAB2(SCH_1):P3E_CPU0_PE1_PCH_CON_TXP(9)   I258 @BASEBOARD_FAB2_LIB.BASEBOARD_FAB2(SCH_1):PAGE108
    94 P3E_CPU0_PE1_PCH_CON_RXP<9> @BASEBOARD_FAB2_LIB.BASEBOARD_FAB2(SCH_1):P3E_CPU0_PE1_PCH_CON_RXP(9)   I258 @BASEBOARD_FAB2_LIB.BASEBOARD_FAB2(SCH_1):PAGE108
    95    GND @BASEBOARD_FAB2_LIB.BASEBOARD_FAB2(SCH_1):GND   I258 @BASEBOARD_FAB2_LIB.BASEBOARD_FAB2(SCH_1):PAGE108
    96 P3E_CPU0_PE1_PCH_CON_RXN<9> @BASEBOARD_FAB2_LIB.BASEBOARD_FAB2(SCH_1):P3E_CPU0_PE1_PCH_CON_RXN(9)   I258 @BASEBOARD_FAB2_LIB.BASEBOARD_FAB2(SCH_1):PAGE108
    97 P3E_CPU0_PE1_PCH_CON_TXN<8> @BASEBOARD_FAB2_LIB.BASEBOARD_FAB2(SCH_1):P3E_CPU0_PE1_PCH_CON_TXN(8)   I258 @BASEBOARD_FAB2_LIB.BASEBOARD_FAB2(SCH_1):PAGE108
    98    GND @BASEBOARD_FAB2_LIB.BASEBOARD_FAB2(SCH_1):GND   I258 @BASEBOARD_FAB2_LIB.BASEBOARD_FAB2(SCH_1):PAGE108
    99 P3E_CPU0_PE1_PCH_CON_TXP<8> @BASEBOARD_FAB2_LIB.BASEBOARD_FAB2(SCH_1):P3E_CPU0_PE1_PCH_CON_TXP(8)   I258 @BASEBOARD_FAB2_LIB.BASEBOARD_FAB2(SCH_1):PAGE108
   100 P3E_CPU0_PE1_PCH_CON_RXN<8> @BASEBOARD_FAB2_LIB.BASEBOARD_FAB2(SCH_1):P3E_CPU0_PE1_PCH_CON_RXN(8)   I258 @BASEBOARD_FAB2_LIB.BASEBOARD_FAB2(SCH_1):PAGE108
   MH1    GND @BASEBOARD_FAB2_LIB.BASEBOARD_FAB2(SCH_1):GND   I258 @BASEBOARD_FAB2_LIB.BASEBOARD_FAB2(SCH_1):PAGE108
   MH2    GND @BASEBOARD_FAB2_LIB.BASEBOARD_FAB2(SCH_1):GND   I258 @BASEBOARD_FAB2_LIB.BASEBOARD_FAB2(SCH_1):PAGE108
   101    GND @BASEBOARD_FAB2_LIB.BASEBOARD_FAB2(SCH_1):GND    I78 @BASEBOARD_FAB2_LIB.BASEBOARD_FAB2(SCH_1):PAGE109
   102 P3E_CPU0_PE1_PCH_CON_RXP<8> @BASEBOARD_FAB2_LIB.BASEBOARD_FAB2(SCH_1):P3E_CPU0_PE1_PCH_CON_RXP(8)    I78 @BASEBOARD_FAB2_LIB.BASEBOARD_FAB2(SCH_1):PAGE109
   103 P3E_CPU0_PE1_SS_C_TXN<7> @BASEBOARD_FAB2_LIB.BASEBOARD_FAB2(SCH_1):P3E_CPU0_PE1_SS_C_TXN(7)    I78 @BASEBOARD_FAB2_LIB.BASEBOARD_FAB2(SCH_1):PAGE109
   104    GND @BASEBOARD_FAB2_LIB.BASEBOARD_FAB2(SCH_1):GND    I78 @BASEBOARD_FAB2_LIB.BASEBOARD_FAB2(SCH_1):PAGE109
   105 P3E_CPU0_PE1_SS_C_TXP<7> @BASEBOARD_FAB2_LIB.BASEBOARD_FAB2(SCH_1):P3E_CPU0_PE1_SS_C_TXP(7)    I78 @BASEBOARD_FAB2_LIB.BASEBOARD_FAB2(SCH_1):PAGE109
   106 P3E_CPU0_PE1_SS_R_RXN<7> @BASEBOARD_FAB2_LIB.BASEBOARD_FAB2(SCH_1):P3E_CPU0_PE1_SS_R_RXN(7)    I78 @BASEBOARD_FAB2_LIB.BASEBOARD_FAB2(SCH_1):PAGE109
   107    GND @BASEBOARD_FAB2_LIB.BASEBOARD_FAB2(SCH_1):GND    I78 @BASEBOARD_FAB2_LIB.BASEBOARD_FAB2(SCH_1):PAGE109
   108 P3E_CPU0_PE1_SS_R_RXP<7> @BASEBOARD_FAB2_LIB.BASEBOARD_FAB2(SCH_1):P3E_CPU0_PE1_SS_R_RXP(7)    I78 @BASEBOARD_FAB2_LIB.BASEBOARD_FAB2(SCH_1):PAGE109
   109 P3E_CPU0_PE1_SS_C_TXN<6> @BASEBOARD_FAB2_LIB.BASEBOARD_FAB2(SCH_1):P3E_CPU0_PE1_SS_C_TXN(6)    I78 @BASEBOARD_FAB2_LIB.BASEBOARD_FAB2(SCH_1):PAGE109
   110    GND @BASEBOARD_FAB2_LIB.BASEBOARD_FAB2(SCH_1):GND    I78 @BASEBOARD_FAB2_LIB.BASEBOARD_FAB2(SCH_1):PAGE109
   111 P3E_CPU0_PE1_SS_C_TXP<6> @BASEBOARD_FAB2_LIB.BASEBOARD_FAB2(SCH_1):P3E_CPU0_PE1_SS_C_TXP(6)    I78 @BASEBOARD_FAB2_LIB.BASEBOARD_FAB2(SCH_1):PAGE109
   112 P3E_CPU0_PE1_SS_R_RXN<6> @BASEBOARD_FAB2_LIB.BASEBOARD_FAB2(SCH_1):P3E_CPU0_PE1_SS_R_RXN(6)    I78 @BASEBOARD_FAB2_LIB.BASEBOARD_FAB2(SCH_1):PAGE109
   113    GND @BASEBOARD_FAB2_LIB.BASEBOARD_FAB2(SCH_1):GND    I78 @BASEBOARD_FAB2_LIB.BASEBOARD_FAB2(SCH_1):PAGE109
   114 P3E_CPU0_PE1_SS_R_RXP<6> @BASEBOARD_FAB2_LIB.BASEBOARD_FAB2(SCH_1):P3E_CPU0_PE1_SS_R_RXP(6)    I78 @BASEBOARD_FAB2_LIB.BASEBOARD_FAB2(SCH_1):PAGE109
   115 P3E_CPU0_PE1_SS_C_TXN<5> @BASEBOARD_FAB2_LIB.BASEBOARD_FAB2(SCH_1):P3E_CPU0_PE1_SS_C_TXN(5)    I78 @BASEBOARD_FAB2_LIB.BASEBOARD_FAB2(SCH_1):PAGE109
   116    GND @BASEBOARD_FAB2_LIB.BASEBOARD_FAB2(SCH_1):GND    I78 @BASEBOARD_FAB2_LIB.BASEBOARD_FAB2(SCH_1):PAGE109
   117 P3E_CPU0_PE1_SS_C_TXP<5> @BASEBOARD_FAB2_LIB.BASEBOARD_FAB2(SCH_1):P3E_CPU0_PE1_SS_C_TXP(5)    I78 @BASEBOARD_FAB2_LIB.BASEBOARD_FAB2(SCH_1):PAGE109
   118 P3E_CPU0_PE1_SS_R_RXN<5> @BASEBOARD_FAB2_LIB.BASEBOARD_FAB2(SCH_1):P3E_CPU0_PE1_SS_R_RXN(5)    I78 @BASEBOARD_FAB2_LIB.BASEBOARD_FAB2(SCH_1):PAGE109
   119    GND @BASEBOARD_FAB2_LIB.BASEBOARD_FAB2(SCH_1):GND    I78 @BASEBOARD_FAB2_LIB.BASEBOARD_FAB2(SCH_1):PAGE109
   120 P3E_CPU0_PE1_SS_R_RXP<5> @BASEBOARD_FAB2_LIB.BASEBOARD_FAB2(SCH_1):P3E_CPU0_PE1_SS_R_RXP(5)    I78 @BASEBOARD_FAB2_LIB.BASEBOARD_FAB2(SCH_1):PAGE109
   121 P3E_CPU0_PE1_SS_C_TXP<4> @BASEBOARD_FAB2_LIB.BASEBOARD_FAB2(SCH_1):P3E_CPU0_PE1_SS_C_TXP(4)    I78 @BASEBOARD_FAB2_LIB.BASEBOARD_FAB2(SCH_1):PAGE109
   122    GND @BASEBOARD_FAB2_LIB.BASEBOARD_FAB2(SCH_1):GND    I78 @BASEBOARD_FAB2_LIB.BASEBOARD_FAB2(SCH_1):PAGE109
   123 P3E_CPU0_PE1_SS_C_TXN<4> @BASEBOARD_FAB2_LIB.BASEBOARD_FAB2(SCH_1):P3E_CPU0_PE1_SS_C_TXN(4)    I78 @BASEBOARD_FAB2_LIB.BASEBOARD_FAB2(SCH_1):PAGE109
   124 P3E_CPU0_PE1_SS_R_RXN<4> @BASEBOARD_FAB2_LIB.BASEBOARD_FAB2(SCH_1):P3E_CPU0_PE1_SS_R_RXN(4)    I78 @BASEBOARD_FAB2_LIB.BASEBOARD_FAB2(SCH_1):PAGE109
   125    GND @BASEBOARD_FAB2_LIB.BASEBOARD_FAB2(SCH_1):GND    I78 @BASEBOARD_FAB2_LIB.BASEBOARD_FAB2(SCH_1):PAGE109
   126 P3E_CPU0_PE1_SS_R_RXP<4> @BASEBOARD_FAB2_LIB.BASEBOARD_FAB2(SCH_1):P3E_CPU0_PE1_SS_R_RXP(4)    I78 @BASEBOARD_FAB2_LIB.BASEBOARD_FAB2(SCH_1):PAGE109
   127 P3E_CPU0_PE1_SS_C_TXN<3> @BASEBOARD_FAB2_LIB.BASEBOARD_FAB2(SCH_1):P3E_CPU0_PE1_SS_C_TXN(3)    I78 @BASEBOARD_FAB2_LIB.BASEBOARD_FAB2(SCH_1):PAGE109
   128    GND @BASEBOARD_FAB2_LIB.BASEBOARD_FAB2(SCH_1):GND    I78 @BASEBOARD_FAB2_LIB.BASEBOARD_FAB2(SCH_1):PAGE109
   129 P3E_CPU0_PE1_SS_C_TXP<3> @BASEBOARD_FAB2_LIB.BASEBOARD_FAB2(SCH_1):P3E_CPU0_PE1_SS_C_TXP(3)    I78 @BASEBOARD_FAB2_LIB.BASEBOARD_FAB2(SCH_1):PAGE109
   130 P3E_CPU0_PE1_SS_R_RXN<3> @BASEBOARD_FAB2_LIB.BASEBOARD_FAB2(SCH_1):P3E_CPU0_PE1_SS_R_RXN(3)    I78 @BASEBOARD_FAB2_LIB.BASEBOARD_FAB2(SCH_1):PAGE109
   131    GND @BASEBOARD_FAB2_LIB.BASEBOARD_FAB2(SCH_1):GND    I78 @BASEBOARD_FAB2_LIB.BASEBOARD_FAB2(SCH_1):PAGE109
   132 P3E_CPU0_PE1_SS_R_RXP<3> @BASEBOARD_FAB2_LIB.BASEBOARD_FAB2(SCH_1):P3E_CPU0_PE1_SS_R_RXP(3)    I78 @BASEBOARD_FAB2_LIB.BASEBOARD_FAB2(SCH_1):PAGE109
   133 P3E_CPU0_PE1_SS_C_TXN<2> @BASEBOARD_FAB2_LIB.BASEBOARD_FAB2(SCH_1):P3E_CPU0_PE1_SS_C_TXN(2)    I78 @BASEBOARD_FAB2_LIB.BASEBOARD_FAB2(SCH_1):PAGE109
   134    GND @BASEBOARD_FAB2_LIB.BASEBOARD_FAB2(SCH_1):GND    I78 @BASEBOARD_FAB2_LIB.BASEBOARD_FAB2(SCH_1):PAGE109
   135 P3E_CPU0_PE1_SS_C_TXP<2> @BASEBOARD_FAB2_LIB.BASEBOARD_FAB2(SCH_1):P3E_CPU0_PE1_SS_C_TXP(2)    I78 @BASEBOARD_FAB2_LIB.BASEBOARD_FAB2(SCH_1):PAGE109
   136 P3E_CPU0_PE1_SS_R_RXP<2> @BASEBOARD_FAB2_LIB.BASEBOARD_FAB2(SCH_1):P3E_CPU0_PE1_SS_R_RXP(2)    I78 @BASEBOARD_FAB2_LIB.BASEBOARD_FAB2(SCH_1):PAGE109
   137    GND @BASEBOARD_FAB2_LIB.BASEBOARD_FAB2(SCH_1):GND    I78 @BASEBOARD_FAB2_LIB.BASEBOARD_FAB2(SCH_1):PAGE109
   138 P3E_CPU0_PE1_SS_R_RXN<2> @BASEBOARD_FAB2_LIB.BASEBOARD_FAB2(SCH_1):P3E_CPU0_PE1_SS_R_RXN(2)    I78 @BASEBOARD_FAB2_LIB.BASEBOARD_FAB2(SCH_1):PAGE109
   139 P3E_CPU0_PE1_SS_C_TXP<1> @BASEBOARD_FAB2_LIB.BASEBOARD_FAB2(SCH_1):P3E_CPU0_PE1_SS_C_TXP(1)    I78 @BASEBOARD_FAB2_LIB.BASEBOARD_FAB2(SCH_1):PAGE109
   140    GND @BASEBOARD_FAB2_LIB.BASEBOARD_FAB2(SCH_1):GND    I78 @BASEBOARD_FAB2_LIB.BASEBOARD_FAB2(SCH_1):PAGE109
   141 P3E_CPU0_PE1_SS_C_TXN<1> @BASEBOARD_FAB2_LIB.BASEBOARD_FAB2(SCH_1):P3E_CPU0_PE1_SS_C_TXN(1)    I78 @BASEBOARD_FAB2_LIB.BASEBOARD_FAB2(SCH_1):PAGE109
   142 P3E_CPU0_PE1_SS_R_RXN<1> @BASEBOARD_FAB2_LIB.BASEBOARD_FAB2(SCH_1):P3E_CPU0_PE1_SS_R_RXN(1)    I78 @BASEBOARD_FAB2_LIB.BASEBOARD_FAB2(SCH_1):PAGE109
   143    GND @BASEBOARD_FAB2_LIB.BASEBOARD_FAB2(SCH_1):GND    I78 @BASEBOARD_FAB2_LIB.BASEBOARD_FAB2(SCH_1):PAGE109
   144 P3E_CPU0_PE1_SS_R_RXP<1> @BASEBOARD_FAB2_LIB.BASEBOARD_FAB2(SCH_1):P3E_CPU0_PE1_SS_R_RXP(1)    I78 @BASEBOARD_FAB2_LIB.BASEBOARD_FAB2(SCH_1):PAGE109
   145 P3E_CPU0_PE1_SS_C_TXN<0> @BASEBOARD_FAB2_LIB.BASEBOARD_FAB2(SCH_1):P3E_CPU0_PE1_SS_C_TXN(0)    I78 @BASEBOARD_FAB2_LIB.BASEBOARD_FAB2(SCH_1):PAGE109
   146    GND @BASEBOARD_FAB2_LIB.BASEBOARD_FAB2(SCH_1):GND    I78 @BASEBOARD_FAB2_LIB.BASEBOARD_FAB2(SCH_1):PAGE109
   147 P3E_CPU0_PE1_SS_C_TXP<0> @BASEBOARD_FAB2_LIB.BASEBOARD_FAB2(SCH_1):P3E_CPU0_PE1_SS_C_TXP(0)    I78 @BASEBOARD_FAB2_LIB.BASEBOARD_FAB2(SCH_1):PAGE109
   148 P3E_CPU0_PE1_SS_R_RXN<0> @BASEBOARD_FAB2_LIB.BASEBOARD_FAB2(SCH_1):P3E_CPU0_PE1_SS_R_RXN(0)    I78 @BASEBOARD_FAB2_LIB.BASEBOARD_FAB2(SCH_1):PAGE109
   149    GND @BASEBOARD_FAB2_LIB.BASEBOARD_FAB2(SCH_1):GND    I78 @BASEBOARD_FAB2_LIB.BASEBOARD_FAB2(SCH_1):PAGE109
   150 P3E_CPU0_PE1_SS_R_RXP<0> @BASEBOARD_FAB2_LIB.BASEBOARD_FAB2(SCH_1):P3E_CPU0_PE1_SS_R_RXP(0)    I78 @BASEBOARD_FAB2_LIB.BASEBOARD_FAB2(SCH_1):PAGE109
   151 P3E_CPU0_PE2_SS_C_TXN<0> @BASEBOARD_FAB2_LIB.BASEBOARD_FAB2(SCH_1):P3E_CPU0_PE2_SS_C_TXN(0)    I78 @BASEBOARD_FAB2_LIB.BASEBOARD_FAB2(SCH_1):PAGE109
   152    GND @BASEBOARD_FAB2_LIB.BASEBOARD_FAB2(SCH_1):GND    I78 @BASEBOARD_FAB2_LIB.BASEBOARD_FAB2(SCH_1):PAGE109
   153 P3E_CPU0_PE2_SS_C_TXP<0> @BASEBOARD_FAB2_LIB.BASEBOARD_FAB2(SCH_1):P3E_CPU0_PE2_SS_C_TXP(0)    I78 @BASEBOARD_FAB2_LIB.BASEBOARD_FAB2(SCH_1):PAGE109
   154 P3E_CPU0_PE2_SS_RXN<0> @BASEBOARD_FAB2_LIB.BASEBOARD_FAB2(SCH_1):P3E_CPU0_PE2_SS_RXN(0)    I78 @BASEBOARD_FAB2_LIB.BASEBOARD_FAB2(SCH_1):PAGE109
   155    GND @BASEBOARD_FAB2_LIB.BASEBOARD_FAB2(SCH_1):GND    I78 @BASEBOARD_FAB2_LIB.BASEBOARD_FAB2(SCH_1):PAGE109
   156 P3E_CPU0_PE2_SS_RXP<0> @BASEBOARD_FAB2_LIB.BASEBOARD_FAB2(SCH_1):P3E_CPU0_PE2_SS_RXP(0)    I78 @BASEBOARD_FAB2_LIB.BASEBOARD_FAB2(SCH_1):PAGE109
   157 P3E_CPU0_PE2_SS_C_TXP<1> @BASEBOARD_FAB2_LIB.BASEBOARD_FAB2(SCH_1):P3E_CPU0_PE2_SS_C_TXP(1)    I78 @BASEBOARD_FAB2_LIB.BASEBOARD_FAB2(SCH_1):PAGE109
   158    GND @BASEBOARD_FAB2_LIB.BASEBOARD_FAB2(SCH_1):GND    I78 @BASEBOARD_FAB2_LIB.BASEBOARD_FAB2(SCH_1):PAGE109
   159 P3E_CPU0_PE2_SS_C_TXN<1> @BASEBOARD_FAB2_LIB.BASEBOARD_FAB2(SCH_1):P3E_CPU0_PE2_SS_C_TXN(1)    I78 @BASEBOARD_FAB2_LIB.BASEBOARD_FAB2(SCH_1):PAGE109
   160 P3E_CPU0_PE2_SS_RXN<1> @BASEBOARD_FAB2_LIB.BASEBOARD_FAB2(SCH_1):P3E_CPU0_PE2_SS_RXN(1)    I78 @BASEBOARD_FAB2_LIB.BASEBOARD_FAB2(SCH_1):PAGE109
   161    GND @BASEBOARD_FAB2_LIB.BASEBOARD_FAB2(SCH_1):GND    I78 @BASEBOARD_FAB2_LIB.BASEBOARD_FAB2(SCH_1):PAGE109
   162 P3E_CPU0_PE2_SS_RXP<1> @BASEBOARD_FAB2_LIB.BASEBOARD_FAB2(SCH_1):P3E_CPU0_PE2_SS_RXP(1)    I78 @BASEBOARD_FAB2_LIB.BASEBOARD_FAB2(SCH_1):PAGE109
   163 P3E_CPU0_PE2_SS_C_TXN<2> @BASEBOARD_FAB2_LIB.BASEBOARD_FAB2(SCH_1):P3E_CPU0_PE2_SS_C_TXN(2)    I78 @BASEBOARD_FAB2_LIB.BASEBOARD_FAB2(SCH_1):PAGE109
   164    GND @BASEBOARD_FAB2_LIB.BASEBOARD_FAB2(SCH_1):GND    I78 @BASEBOARD_FAB2_LIB.BASEBOARD_FAB2(SCH_1):PAGE109
   165 P3E_CPU0_PE2_SS_C_TXP<2> @BASEBOARD_FAB2_LIB.BASEBOARD_FAB2(SCH_1):P3E_CPU0_PE2_SS_C_TXP(2)    I78 @BASEBOARD_FAB2_LIB.BASEBOARD_FAB2(SCH_1):PAGE109
   166 P3E_CPU0_PE2_SS_RXP<2> @BASEBOARD_FAB2_LIB.BASEBOARD_FAB2(SCH_1):P3E_CPU0_PE2_SS_RXP(2)    I78 @BASEBOARD_FAB2_LIB.BASEBOARD_FAB2(SCH_1):PAGE109
   167    GND @BASEBOARD_FAB2_LIB.BASEBOARD_FAB2(SCH_1):GND    I78 @BASEBOARD_FAB2_LIB.BASEBOARD_FAB2(SCH_1):PAGE109
   168 P3E_CPU0_PE2_SS_RXN<2> @BASEBOARD_FAB2_LIB.BASEBOARD_FAB2(SCH_1):P3E_CPU0_PE2_SS_RXN(2)    I78 @BASEBOARD_FAB2_LIB.BASEBOARD_FAB2(SCH_1):PAGE109
   169 P3E_CPU0_PE2_SS_C_TXN<3> @BASEBOARD_FAB2_LIB.BASEBOARD_FAB2(SCH_1):P3E_CPU0_PE2_SS_C_TXN(3)    I78 @BASEBOARD_FAB2_LIB.BASEBOARD_FAB2(SCH_1):PAGE109
   170    GND @BASEBOARD_FAB2_LIB.BASEBOARD_FAB2(SCH_1):GND    I78 @BASEBOARD_FAB2_LIB.BASEBOARD_FAB2(SCH_1):PAGE109
   171 P3E_CPU0_PE2_SS_C_TXP<3> @BASEBOARD_FAB2_LIB.BASEBOARD_FAB2(SCH_1):P3E_CPU0_PE2_SS_C_TXP(3)    I78 @BASEBOARD_FAB2_LIB.BASEBOARD_FAB2(SCH_1):PAGE109
   172 P3E_CPU0_PE2_SS_RXN<3> @BASEBOARD_FAB2_LIB.BASEBOARD_FAB2(SCH_1):P3E_CPU0_PE2_SS_RXN(3)    I78 @BASEBOARD_FAB2_LIB.BASEBOARD_FAB2(SCH_1):PAGE109
   173    GND @BASEBOARD_FAB2_LIB.BASEBOARD_FAB2(SCH_1):GND    I78 @BASEBOARD_FAB2_LIB.BASEBOARD_FAB2(SCH_1):PAGE109
   174 P3E_CPU0_PE2_SS_RXP<3> @BASEBOARD_FAB2_LIB.BASEBOARD_FAB2(SCH_1):P3E_CPU0_PE2_SS_RXP(3)    I78 @BASEBOARD_FAB2_LIB.BASEBOARD_FAB2(SCH_1):PAGE109
   175 P3E_CPU0_PE2_SS_C_TXN<4> @BASEBOARD_FAB2_LIB.BASEBOARD_FAB2(SCH_1):P3E_CPU0_PE2_SS_C_TXN(4)    I78 @BASEBOARD_FAB2_LIB.BASEBOARD_FAB2(SCH_1):PAGE109
   176    GND @BASEBOARD_FAB2_LIB.BASEBOARD_FAB2(SCH_1):GND    I78 @BASEBOARD_FAB2_LIB.BASEBOARD_FAB2(SCH_1):PAGE109
   177 P3E_CPU0_PE2_SS_C_TXP<4> @BASEBOARD_FAB2_LIB.BASEBOARD_FAB2(SCH_1):P3E_CPU0_PE2_SS_C_TXP(4)    I78 @BASEBOARD_FAB2_LIB.BASEBOARD_FAB2(SCH_1):PAGE109
   178 P3E_CPU0_PE2_SS_RXN<4> @BASEBOARD_FAB2_LIB.BASEBOARD_FAB2(SCH_1):P3E_CPU0_PE2_SS_RXN(4)    I78 @BASEBOARD_FAB2_LIB.BASEBOARD_FAB2(SCH_1):PAGE109
   179    GND @BASEBOARD_FAB2_LIB.BASEBOARD_FAB2(SCH_1):GND    I78 @BASEBOARD_FAB2_LIB.BASEBOARD_FAB2(SCH_1):PAGE109
   180 P3E_CPU0_PE2_SS_RXP<4> @BASEBOARD_FAB2_LIB.BASEBOARD_FAB2(SCH_1):P3E_CPU0_PE2_SS_RXP(4)    I78 @BASEBOARD_FAB2_LIB.BASEBOARD_FAB2(SCH_1):PAGE109
   181 P3E_CPU0_PE2_SS_C_TXN<5> @BASEBOARD_FAB2_LIB.BASEBOARD_FAB2(SCH_1):P3E_CPU0_PE2_SS_C_TXN(5)    I78 @BASEBOARD_FAB2_LIB.BASEBOARD_FAB2(SCH_1):PAGE109
   182    GND @BASEBOARD_FAB2_LIB.BASEBOARD_FAB2(SCH_1):GND    I78 @BASEBOARD_FAB2_LIB.BASEBOARD_FAB2(SCH_1):PAGE109
   183 P3E_CPU0_PE2_SS_C_TXP<5> @BASEBOARD_FAB2_LIB.BASEBOARD_FAB2(SCH_1):P3E_CPU0_PE2_SS_C_TXP(5)    I78 @BASEBOARD_FAB2_LIB.BASEBOARD_FAB2(SCH_1):PAGE109
   184 P3E_CPU0_PE2_SS_RXN<5> @BASEBOARD_FAB2_LIB.BASEBOARD_FAB2(SCH_1):P3E_CPU0_PE2_SS_RXN(5)    I78 @BASEBOARD_FAB2_LIB.BASEBOARD_FAB2(SCH_1):PAGE109
   185    GND @BASEBOARD_FAB2_LIB.BASEBOARD_FAB2(SCH_1):GND    I78 @BASEBOARD_FAB2_LIB.BASEBOARD_FAB2(SCH_1):PAGE109
   186 P3E_CPU0_PE2_SS_RXP<5> @BASEBOARD_FAB2_LIB.BASEBOARD_FAB2(SCH_1):P3E_CPU0_PE2_SS_RXP(5)    I78 @BASEBOARD_FAB2_LIB.BASEBOARD_FAB2(SCH_1):PAGE109
   187 P3E_CPU0_PE2_SS_C_TXN<6> @BASEBOARD_FAB2_LIB.BASEBOARD_FAB2(SCH_1):P3E_CPU0_PE2_SS_C_TXN(6)    I78 @BASEBOARD_FAB2_LIB.BASEBOARD_FAB2(SCH_1):PAGE109
   188    GND @BASEBOARD_FAB2_LIB.BASEBOARD_FAB2(SCH_1):GND    I78 @BASEBOARD_FAB2_LIB.BASEBOARD_FAB2(SCH_1):PAGE109
   189 P3E_CPU0_PE2_SS_C_TXP<6> @BASEBOARD_FAB2_LIB.BASEBOARD_FAB2(SCH_1):P3E_CPU0_PE2_SS_C_TXP(6)    I78 @BASEBOARD_FAB2_LIB.BASEBOARD_FAB2(SCH_1):PAGE109
   190 P3E_CPU0_PE2_SS_RXP<6> @BASEBOARD_FAB2_LIB.BASEBOARD_FAB2(SCH_1):P3E_CPU0_PE2_SS_RXP(6)    I78 @BASEBOARD_FAB2_LIB.BASEBOARD_FAB2(SCH_1):PAGE109
   191    GND @BASEBOARD_FAB2_LIB.BASEBOARD_FAB2(SCH_1):GND    I78 @BASEBOARD_FAB2_LIB.BASEBOARD_FAB2(SCH_1):PAGE109
   192 P3E_CPU0_PE2_SS_RXN<6> @BASEBOARD_FAB2_LIB.BASEBOARD_FAB2(SCH_1):P3E_CPU0_PE2_SS_RXN(6)    I78 @BASEBOARD_FAB2_LIB.BASEBOARD_FAB2(SCH_1):PAGE109
   193 P3E_CPU0_PE2_SS_C_TXN<7> @BASEBOARD_FAB2_LIB.BASEBOARD_FAB2(SCH_1):P3E_CPU0_PE2_SS_C_TXN(7)    I78 @BASEBOARD_FAB2_LIB.BASEBOARD_FAB2(SCH_1):PAGE109
   194    GND @BASEBOARD_FAB2_LIB.BASEBOARD_FAB2(SCH_1):GND    I78 @BASEBOARD_FAB2_LIB.BASEBOARD_FAB2(SCH_1):PAGE109
   195 P3E_CPU0_PE2_SS_C_TXP<7> @BASEBOARD_FAB2_LIB.BASEBOARD_FAB2(SCH_1):P3E_CPU0_PE2_SS_C_TXP(7)    I78 @BASEBOARD_FAB2_LIB.BASEBOARD_FAB2(SCH_1):PAGE109
   196 P3E_CPU0_PE2_SS_RXN<7> @BASEBOARD_FAB2_LIB.BASEBOARD_FAB2(SCH_1):P3E_CPU0_PE2_SS_RXN(7)    I78 @BASEBOARD_FAB2_LIB.BASEBOARD_FAB2(SCH_1):PAGE109
   197    GND @BASEBOARD_FAB2_LIB.BASEBOARD_FAB2(SCH_1):GND    I78 @BASEBOARD_FAB2_LIB.BASEBOARD_FAB2(SCH_1):PAGE109
   198 P3E_CPU0_PE2_SS_RXP<7> @BASEBOARD_FAB2_LIB.BASEBOARD_FAB2(SCH_1):P3E_CPU0_PE2_SS_RXP(7)    I78 @BASEBOARD_FAB2_LIB.BASEBOARD_FAB2(SCH_1):PAGE109
   199 FM_PRSNT_2_6_N @BASEBOARD_FAB2_LIB.BASEBOARD_FAB2(SCH_1):FM_PRSNT_2_6_N    I78 @BASEBOARD_FAB2_LIB.BASEBOARD_FAB2(SCH_1):PAGE109
   200    GND @BASEBOARD_FAB2_LIB.BASEBOARD_FAB2(SCH_1):GND    I78 @BASEBOARD_FAB2_LIB.BASEBOARD_FAB2(SCH_1):PAGE109

J8G2 CONN12_C73564003_PIP-CONN,C735A
     1 TP_JUMPER_BLOCK_1_1 @BASEBOARD_FAB2_LIB.BASEBOARD_FAB2(SCH_1):TP_JUMPER_BLOCK_1_1   I124 @BASEBOARD_FAB2_LIB.BASEBOARD_FAB2(SCH_1):PAGE135
    10 FM_DIS_ADR_DLY @BASEBOARD_FAB2_LIB.BASEBOARD_FAB2(SCH_1):FM_DIS_ADR_DLY   I124 @BASEBOARD_FAB2_LIB.BASEBOARD_FAB2(SCH_1):PAGE135
    11    GND @BASEBOARD_FAB2_LIB.BASEBOARD_FAB2(SCH_1):GND   I124 @BASEBOARD_FAB2_LIB.BASEBOARD_FAB2(SCH_1):PAGE135
    12    GND @BASEBOARD_FAB2_LIB.BASEBOARD_FAB2(SCH_1):GND   I124 @BASEBOARD_FAB2_LIB.BASEBOARD_FAB2(SCH_1):PAGE135
     2 TP_JUMPER_BLOCK_1_2 @BASEBOARD_FAB2_LIB.BASEBOARD_FAB2(SCH_1):TP_JUMPER_BLOCK_1_2   I124 @BASEBOARD_FAB2_LIB.BASEBOARD_FAB2(SCH_1):PAGE135
     3 RST_BMC_SRST_N @BASEBOARD_FAB2_LIB.BASEBOARD_FAB2(SCH_1):RST_BMC_SRST_N   I124 @BASEBOARD_FAB2_LIB.BASEBOARD_FAB2(SCH_1):PAGE135
     4 FM_IE_DISABLE_N @BASEBOARD_FAB2_LIB.BASEBOARD_FAB2(SCH_1):FM_IE_DISABLE_N   I124 @BASEBOARD_FAB2_LIB.BASEBOARD_FAB2(SCH_1):PAGE135
     5    GND @BASEBOARD_FAB2_LIB.BASEBOARD_FAB2(SCH_1):GND   I124 @BASEBOARD_FAB2_LIB.BASEBOARD_FAB2(SCH_1):PAGE135
     6    GND @BASEBOARD_FAB2_LIB.BASEBOARD_FAB2(SCH_1):GND   I124 @BASEBOARD_FAB2_LIB.BASEBOARD_FAB2(SCH_1):PAGE135
     7 TP_JUMPER_BLOCK_1_7 @BASEBOARD_FAB2_LIB.BASEBOARD_FAB2(SCH_1):TP_JUMPER_BLOCK_ 1_7   I124 @BASEBOARD_FAB2_LIB.BASEBOARD_FAB2(SCH_1):PAGE135
     8 TP_JUMPER_BLOCK_1_8 @BASEBOARD_FAB2_LIB.BASEBOARD_FAB2(SCH_1):TP_JUMPER_BLOCK_1_8   I124 @BASEBOARD_FAB2_LIB.BASEBOARD_FAB2(SCH_1):PAGE135
     9 FM_CPLD_UART_CH_LOCK_N @BASEBOARD_FAB2_LIB.BASEBOARD_FAB2(SCH_1):FM_CPLD_UART_CH_LOCK_N   I124 @BASEBOARD_FAB2_LIB.BASEBOARD_FAB2(SCH_1):PAGE135

J9A1 CONN4_D42317002_PIP-CONN,D4231A
     1    GND @BASEBOARD_FAB2_LIB.BASEBOARD_FAB2(SCH_1):GND   I131 @BASEBOARD_FAB2_LIB.BASEBOARD_FAB2(SCH_1):PAGE135
     2 PU_KEY_CONN_PIN2_R @BASEBOARD_FAB2_LIB.BASEBOARD_FAB2(SCH_1):PU_KEY_CONN_PIN2_R   I131 @BASEBOARD_FAB2_LIB.BASEBOARD_FAB2(SCH_1):PAGE135
     3    GND @BASEBOARD_FAB2_LIB.BASEBOARD_FAB2(SCH_1):GND   I131 @BASEBOARD_FAB2_LIB.BASEBOARD_FAB2(SCH_1):PAGE135
     4 FM_PCH_SATA_RAID_KEY_R @BASEBOARD_FAB2_LIB.BASEBOARD_FAB2(SCH_1):FM_PCH_SATA_RAID_KEY_R   I131 @BASEBOARD_FAB2_LIB.BASEBOARD_FAB2(SCH_1):PAGE135

J9A2 CONN14_H54902001_PIP-CONN,H549A
     1 LED_POSTCODE_0_R @BASEBOARD_FAB2_LIB.BASEBOARD_FAB2(SCH_1):LED_POSTCODE_0_R   I171 @BASEBOARD_FAB2_LIB.BASEBOARD_FAB2(SCH_1):PAGE155
    10 SPA_5V_SIN_SW @BASEBOARD_FAB2_LIB.BASEBOARD_FAB2(SCH_1):SPA_5V_SIN_SW   I171 @BASEBOARD_FAB2_LIB.BASEBOARD_FAB2(SCH_1):PAGE155
    11 FM_DEBUG_RST_BTN_N @BASEBOARD_FAB2_LIB.BASEBOARD_FAB2(SCH_1):FM_DEBUG_RST_BTN_N   I171 @BASEBOARD_FAB2_LIB.BASEBOARD_FAB2(SCH_1):PAGE155
    12 FM_UART_SWITCH_N @BASEBOARD_FAB2_LIB.BASEBOARD_FAB2(SCH_1):FM_UART_SWITCH_N   I171 @BASEBOARD_FAB2_LIB.BASEBOARD_FAB2(SCH_1):PAGE155
    13    GND @BASEBOARD_FAB2_LIB.BASEBOARD_FAB2(SCH_1):GND   I171 @BASEBOARD_FAB2_LIB.BASEBOARD_FAB2(SCH_1):PAGE155
    14 P5V_STBY_DGB_FS @BASEBOARD_FAB2_LIB.BASEBOARD_FAB2(SCH_1):P5V_STBY_DGB_FS   I171 @BASEBOARD_FAB2_LIB.BASEBOARD_FAB2(SCH_1):PAGE155
     2 LED_POSTCODE_1_R @BASEBOARD_FAB2_LIB.BASEBOARD_FAB2(SCH_1):LED_POSTCODE_1_R   I171 @BASEBOARD_FAB2_LIB.BASEBOARD_FAB2(SCH_1):PAGE155
     3 LED_POSTCODE_2_R @BASEBOARD_FAB2_LIB.BASEBOARD_FAB2(SCH_1):LED_POSTCODE_2_R   I171 @BASEBOARD_FAB2_LIB.BASEBOARD_FAB2(SCH_1):PAGE155
     4 LED_POSTCODE_3_R @BASEBOARD_FAB2_LIB.BASEBOARD_FAB2(SCH_1):LED_POSTCODE_3_R   I171 @BASEBOARD_FAB2_LIB.BASEBOARD_FAB2(SCH_1):PAGE155
     5 LED_POSTCODE_4_R @BASEBOARD_FAB2_LIB.BASEBOARD_FAB2(SCH_1):LED_POSTCODE_4_R   I171 @BASEBOARD_FAB2_LIB.BASEBOARD_FAB2(SCH_1):PAGE155
     6 LED_POSTCODE_5_R @BASEBOARD_FAB2_LIB.BASEBOARD_FAB2(SCH_1):LED_POSTCODE_5_R   I171 @BASEBOARD_FAB2_LIB.BASEBOARD_FAB2(SCH_1):PAGE155
     7 LED_POSTCODE_6_R @BASEBOARD_FAB2_LIB.BASEBOARD_FAB2(SCH_1):LED_POSTCODE_6_R   I171 @BASEBOARD_FAB2_LIB.BASEBOARD_FAB2(SCH_1):PAGE155
     8 LED_POSTCODE_7_R @BASEBOARD_FAB2_LIB.BASEBOARD_FAB2(SCH_1):LED_POSTCODE_7_R   I171 @BASEBOARD_FAB2_LIB.BASEBOARD_FAB2(SCH_1):PAGE155
     9 SPA_MID_DBG_TX @BASEBOARD_FAB2_LIB.BASEBOARD_FAB2(SCH_1):SPA_MID_DBG_TX   I171 @BASEBOARD_FAB2_LIB.BASEBOARD_FAB2(SCH_1):PAGE155

J9A3 SCONN60_C21100002_SMLF-CONN,C2A
     1 XDP_DEBUG_CONSENT_N @BASEBOARD_FAB2_LIB.BASEBOARD_FAB2(SCH_1):XDP_DEBUG_CONSENT_N    I26 @BASEBOARD_FAB2_LIB.BASEBOARD_FAB2(SCH_1):PAGE111
     3 XDP_PREQ_N @BASEBOARD_FAB2_LIB.BASEBOARD_FAB2(SCH_1):XDP_PREQ_N    I26 @BASEBOARD_FAB2_LIB.BASEBOARD_FAB2(SCH_1):PAGE111
     5 XDP_PRDY_N @BASEBOARD_FAB2_LIB.BASEBOARD_FAB2(SCH_1):XDP_PRDY_N    I26 @BASEBOARD_FAB2_LIB.BASEBOARD_FAB2(SCH_1):PAGE111
     7    GND @BASEBOARD_FAB2_LIB.BASEBOARD_FAB2(SCH_1):GND    I26 @BASEBOARD_FAB2_LIB.BASEBOARD_FAB2(SCH_1):PAGE111
     9 TP_XDP_OBSDATA_A0 @BASEBOARD_FAB2_LIB.BASEBOARD_FAB2(SCH_1):TP_XDP_OBSDATA_A0    I26 @BASEBOARD_FAB2_LIB.BASEBOARD_FAB2(SCH_1):PAGE111
    11 TP_XDP_OBSDATA_A1 @BASEBOARD_FAB2_LIB.BASEBOARD_FAB2(SCH_1):TP_XDP_OBSDATA_A1    I26 @BASEBOARD_FAB2_LIB.BASEBOARD_FAB2(SCH_1):PAGE111
    13    GND @BASEBOARD_FAB2_LIB.BASEBOARD_FAB2(SCH_1):GND    I26 @BASEBOARD_FAB2_LIB.BASEBOARD_FAB2(SCH_1):PAGE111
    15 TP_XDP_OBSDATA_A2 @BASEBOARD_FAB2_LIB.BASEBOARD_FAB2(SCH_1):TP_XDP_OBSDATA_A2    I26 @BASEBOARD_FAB2_LIB.BASEBOARD_FAB2(SCH_1):PAGE111
    17 TP_XDP_OBSDATA_A3 @BASEBOARD_FAB2_LIB.BASEBOARD_FAB2(SCH_1):TP_XDP_OBSDATA_A3    I26 @BASEBOARD_FAB2_LIB.BASEBOARD_FAB2(SCH_1):PAGE111
    19    GND @BASEBOARD_FAB2_LIB.BASEBOARD_FAB2(SCH_1):GND    I26 @BASEBOARD_FAB2_LIB.BASEBOARD_FAB2(SCH_1):PAGE111
    21 TP_XDP_OBSFN_B0 @BASEBOARD_FAB2_LIB.BASEBOARD_FAB2(SCH_1):TP_XDP_OBSFN_B0    I26 @BASEBOARD_FAB2_LIB.BASEBOARD_FAB2(SCH_1):PAGE111
    23 TP_XDP_OBSFN_B1 @BASEBOARD_FAB2_LIB.BASEBOARD_FAB2(SCH_1):TP_XDP_OBSFN_B1    I26 @BASEBOARD_FAB2_LIB.BASEBOARD_FAB2(SCH_1):PAGE111
    25    GND @BASEBOARD_FAB2_LIB.BASEBOARD_FAB2(SCH_1):GND    I26 @BASEBOARD_FAB2_LIB.BASEBOARD_FAB2(SCH_1):PAGE111
    27 TP_XDP_OBSDATA_B0 @BASEBOARD_FAB2_LIB.BASEBOARD_FAB2(SCH_1):TP_XDP_OBSDATA_B0    I26 @BASEBOARD_FAB2_LIB.BASEBOARD_FAB2(SCH_1):PAGE111
    29 TP_XDP_OBSDATA_B1 @BASEBOARD_FAB2_LIB.BASEBOARD_FAB2(SCH_1):TP_XDP_OBSDATA_B1    I26 @BASEBOARD_FAB2_LIB.BASEBOARD_FAB2(SCH_1):PAGE111
    31    GND @BASEBOARD_FAB2_LIB.BASEBOARD_FAB2(SCH_1):GND    I26 @BASEBOARD_FAB2_LIB.BASEBOARD_FAB2(SCH_1):PAGE111
    33 TP_XDP_OBSDATA_B2 @BASEBOARD_FAB2_LIB.BASEBOARD_FAB2(SCH_1):TP_XDP_OBSDATA_B2    I26 @BASEBOARD_FAB2_LIB.BASEBOARD_FAB2(SCH_1):PAGE111
    35 TP_XDP_OBSDATA_B3 @BASEBOARD_FAB2_LIB.BASEBOARD_FAB2(SCH_1):TP_XDP_OBSDATA_B3    I26 @BASEBOARD_FAB2_LIB.BASEBOARD_FAB2(SCH_1):PAGE111
    37    GND @BASEBOARD_FAB2_LIB.BASEBOARD_FAB2(SCH_1):GND    I26 @BASEBOARD_FAB2_LIB.BASEBOARD_FAB2(SCH_1):PAGE111
    39 XDP_RSMRST_N @BASEBOARD_FAB2_LIB.BASEBOARD_FAB2(SCH_1):XDP_RSMRST_N    I26 @BASEBOARD_FAB2_LIB.BASEBOARD_FAB2(SCH_1):PAGE111
    41 XDP_PWRGD_RST_N @BASEBOARD_FAB2_LIB.BASEBOARD_FAB2(SCH_1):XDP_PWRGD_RST_N    I26 @BASEBOARD_FAB2_LIB.BASEBOARD_FAB2(SCH_1):PAGE111
    43 P1V05_PCH_STBY @BASEBOARD_FAB2_LIB.BASEBOARD_FAB2(SCH_1):P1V05_PCH_STBY    I26 @BASEBOARD_FAB2_LIB.BASEBOARD_FAB2(SCH_1):PAGE111
    45 XDP_CPU_PWR_DEBUG_N @BASEBOARD_FAB2_LIB.BASEBOARD_FAB2(SCH_1):XDP_CPU_PWR_DEBUG_N    I26 @BASEBOARD_FAB2_LIB.BASEBOARD_FAB2(SCH_1):PAGE111
    47 XDP_SYSPWROK @BASEBOARD_FAB2_LIB.BASEBOARD_FAB2(SCH_1):XDP_SYSPWROK    I26 @BASEBOARD_FAB2_LIB.BASEBOARD_FAB2(SCH_1):PAGE111
    49    GND @BASEBOARD_FAB2_LIB.BASEBOARD_FAB2(SCH_1):GND    I26 @BASEBOARD_FAB2_LIB.BASEBOARD_FAB2(SCH_1):PAGE111
     2    GND @BASEBOARD_FAB2_LIB.BASEBOARD_FAB2(SCH_1):GND    I26 @BASEBOARD_FAB2_LIB.BASEBOARD_FAB2(SCH_1):PAGE111
     4 TP_XDP_CPU_OBSFN_C0 @BASEBOARD_FAB2_LIB.BASEBOARD_FAB2(SCH_1):TP_XDP_CPU_OBSFN_C0    I26 @BASEBOARD_FAB2_LIB.BASEBOARD_FAB2(SCH_1):PAGE111
     6 XDP_SPI_PCH_MOSI_BOOT_HALT_N @BASEBOARD_FAB2_LIB.BASEBOARD_FAB2(SCH_1):XDP_SPI_PCH_MOSI_BOOT_HALT_N    I26 @BASEBOARD_FAB2_LIB.BASEBOARD_FAB2(SCH_1):PAGE111
     8    GND @BASEBOARD_FAB2_LIB.BASEBOARD_FAB2(SCH_1):GND    I26 @BASEBOARD_FAB2_LIB.BASEBOARD_FAB2(SCH_1):PAGE111
    10 TP_XDP_CPU_OBSDATA_C0 @BASEBOARD_FAB2_LIB.BASEBOARD_FAB2(SCH_1):TP_XDP_CPU_OBSDATA_C0    I26 @BASEBOARD_FAB2_LIB.BASEBOARD_FAB2(SCH_1):PAGE111
    12 TP_XDP_CPU_OBSDATA_C1 @BASEBOARD_FAB2_LIB.BASEBOARD_FAB2(SCH_1):TP_XDP_CPU_OBSDATA_C1    I26 @BASEBOARD_FAB2_LIB.BASEBOARD_FAB2(SCH_1):PAGE111
    14    GND @BASEBOARD_FAB2_LIB.BASEBOARD_FAB2(SCH_1):GND    I26 @BASEBOARD_FAB2_LIB.BASEBOARD_FAB2(SCH_1):PAGE111
    16 TP_XDP_CPU_OBSDATA_C2 @BASEBOARD_FAB2_LIB.BASEBOARD_FAB2(SCH_1):TP_XDP_CPU_OBSDATA_C2    I26 @BASEBOARD_FAB2_LIB.BASEBOARD_FAB2(SCH_1):PAGE111
    18 TP_XDP_CPU_OBSDATA_C3 @BASEBOARD_FAB2_LIB.BASEBOARD_FAB2(SCH_1):TP_XDP_CPU_OBSDATA_C3    I26 @BASEBOARD_FAB2_LIB.BASEBOARD_FAB2(SCH_1):PAGE111
    20    GND @BASEBOARD_FAB2_LIB.BASEBOARD_FAB2(SCH_1):GND    I26 @BASEBOARD_FAB2_LIB.BASEBOARD_FAB2(SCH_1):PAGE111
    22 XDP_OBSFN_B0_MBP6_N @BASEBOARD_FAB2_LIB.BASEBOARD_FAB2(SCH_1):XDP_OBSFN_B0_MBP6_N    I26 @BASEBOARD_FAB2_LIB.BASEBOARD_FAB2(SCH_1):PAGE111
    24 XDP_OBSFN_B1_MBP7_N @BASEBOARD_FAB2_LIB.BASEBOARD_FAB2(SCH_1):XDP_OBSFN_B1_MBP7_N    I26 @BASEBOARD_FAB2_LIB.BASEBOARD_FAB2(SCH_1):PAGE111
    26    GND @BASEBOARD_FAB2_LIB.BASEBOARD_FAB2(SCH_1):GND    I26 @BASEBOARD_FAB2_LIB.BASEBOARD_FAB2(SCH_1):PAGE111
    28 TP_XDP_CPU_OBSDATA_D0 @BASEBOARD_FAB2_LIB.BASEBOARD_FAB2(SCH_1):TP_XDP_CPU_OBSDATA_D0    I26 @BASEBOARD_FAB2_LIB.BASEBOARD_FAB2(SCH_1):PAGE111
    30 TP_XDP_CPU_OBSDATA_D1 @BASEBOARD_FAB2_LIB.BASEBOARD_FAB2(SCH_1):TP_XDP_CPU_OBSDATA_D1    I26 @BASEBOARD_FAB2_LIB.BASEBOARD_FAB2(SCH_1):PAGE111
    32    GND @BASEBOARD_FAB2_LIB.BASEBOARD_FAB2(SCH_1):GND    I26 @BASEBOARD_FAB2_LIB.BASEBOARD_FAB2(SCH_1):PAGE111
    34 TP_XDP_CPU_OBSDATA_D2 @BASEBOARD_FAB2_LIB.BASEBOARD_FAB2(SCH_1):TP_XDP_CPU_OBSDATA_D2    I26 @BASEBOARD_FAB2_LIB.BASEBOARD_FAB2(SCH_1):PAGE111
    36 TP_XDP_CPU_OBSDATA_D3 @BASEBOARD_FAB2_LIB.BASEBOARD_FAB2(SCH_1):TP_XDP_CPU_OBSDATA_D3    I26 @BASEBOARD_FAB2_LIB.BASEBOARD_FAB2(SCH_1):PAGE111
    38    GND @BASEBOARD_FAB2_LIB.BASEBOARD_FAB2(SCH_1):GND    I26 @BASEBOARD_FAB2_LIB.BASEBOARD_FAB2(SCH_1):PAGE111
    40 CLK_100M_PCH_XDP_DP @BASEBOARD_FAB2_LIB.BASEBOARD_FAB2(SCH_1):CLK_100M_PCH_XDP_DP    I26 @BASEBOARD_FAB2_LIB.BASEBOARD_FAB2(SCH_1):PAGE111
    42 CLK_100M_PCH_XDP_DN @BASEBOARD_FAB2_LIB.BASEBOARD_FAB2(SCH_1):CLK_100M_PCH_XDP_DN    I26 @BASEBOARD_FAB2_LIB.BASEBOARD_FAB2(SCH_1):PAGE111
    44 P1V05_PCH_STBY @BASEBOARD_FAB2_LIB.BASEBOARD_FAB2(SCH_1):P1V05_PCH_STBY    I26 @BASEBOARD_FAB2_LIB.BASEBOARD_FAB2(SCH_1):PAGE111
    46 XDP_ITP_PMODE @BASEBOARD_FAB2_LIB.BASEBOARD_FAB2(SCH_1):XDP_ITP_PMODE    I26 @BASEBOARD_FAB2_LIB.BASEBOARD_FAB2(SCH_1):PAGE111
    48 XDP_RST_CO_N @BASEBOARD_FAB2_LIB.BASEBOARD_FAB2(SCH_1):XDP_RST_CO_N    I26 @BASEBOARD_FAB2_LIB.BASEBOARD_FAB2(SCH_1):PAGE111
    50    GND @BASEBOARD_FAB2_LIB.BASEBOARD_FAB2(SCH_1):GND    I26 @BASEBOARD_FAB2_LIB.BASEBOARD_FAB2(SCH_1):PAGE111
    51 SMB_HOST_STBY_LVC3_SDA @BASEBOARD_FAB2_LIB.BASEBOARD_FAB2(SCH_1):SMB_HOST_STBY_LVC3_SDA    I26 @BASEBOARD_FAB2_LIB.BASEBOARD_FAB2(SCH_1):PAGE111
    52 XDP_TDO @BASEBOARD_FAB2_LIB.BASEBOARD_FAB2(SCH_1):XDP_TDO    I26 @BASEBOARD_FAB2_LIB.BASEBOARD_FAB2(SCH_1):PAGE111
    53 SMB_HOST_STBY_LVC3_SCL @BASEBOARD_FAB2_LIB.BASEBOARD_FAB2(SCH_1):SMB_HOST_STBY_LVC3_SCL    I26 @BASEBOARD_FAB2_LIB.BASEBOARD_FAB2(SCH_1):PAGE111
    54 XDP_TRST_N @BASEBOARD_FAB2_LIB.BASEBOARD_FAB2(SCH_1):XDP_TRST_N    I26 @BASEBOARD_FAB2_LIB.BASEBOARD_FAB2(SCH_1):PAGE111
    55 XDP_PCH_TCK1 @BASEBOARD_FAB2_LIB.BASEBOARD_FAB2(SCH_1):XDP_PCH_TCK1    I26 @BASEBOARD_FAB2_LIB.BASEBOARD_FAB2(SCH_1):PAGE111
    56 XDP_TDI @BASEBOARD_FAB2_LIB.BASEBOARD_FAB2(SCH_1):XDP_TDI    I26 @BASEBOARD_FAB2_LIB.BASEBOARD_FAB2(SCH_1):PAGE111
    57 XDP_CPU_TCK0 @BASEBOARD_FAB2_LIB.BASEBOARD_FAB2(SCH_1):XDP_CPU_TCK0    I26 @BASEBOARD_FAB2_LIB.BASEBOARD_FAB2(SCH_1):PAGE111
    58 XDP_TMS @BASEBOARD_FAB2_LIB.BASEBOARD_FAB2(SCH_1):XDP_TMS    I26 @BASEBOARD_FAB2_LIB.BASEBOARD_FAB2(SCH_1):PAGE111
    59    GND @BASEBOARD_FAB2_LIB.BASEBOARD_FAB2(SCH_1):GND    I26 @BASEBOARD_FAB2_LIB.BASEBOARD_FAB2(SCH_1):PAGE111
    60 XDP_PRESENT_N @BASEBOARD_FAB2_LIB.BASEBOARD_FAB2(SCH_1):XDP_PRESENT_N    I26 @BASEBOARD_FAB2_LIB.BASEBOARD_FAB2(SCH_1):PAGE111

J9B1 CONN9_H51826001_PIP2-CONN,H518A
     2 USB2_P01_ESD_DN @BASEBOARD_FAB2_LIB.BASEBOARD_FAB2(SCH_1):USB2_P01_ESD_DN    I69 @BASEBOARD_FAB2_LIB.BASEBOARD_FAB2(SCH_1):PAGE176
     3 USB2_P01_ESD_DP @BASEBOARD_FAB2_LIB.BASEBOARD_FAB2(SCH_1):USB2_P01_ESD_DP    I69 @BASEBOARD_FAB2_LIB.BASEBOARD_FAB2(SCH_1):PAGE176
     4    GND @BASEBOARD_FAB2_LIB.BASEBOARD_FAB2(SCH_1):GND    I69 @BASEBOARD_FAB2_LIB.BASEBOARD_FAB2(SCH_1):PAGE176
     7 FM_UART_SWITCH_N @BASEBOARD_FAB2_LIB.BASEBOARD_FAB2(SCH_1):FM_UART_SWITCH_N    I69 @BASEBOARD_FAB2_LIB.BASEBOARD_FAB2(SCH_1):PAGE176
   MH1    GND @BASEBOARD_FAB2_LIB.BASEBOARD_FAB2(SCH_1):GND    I69 @BASEBOARD_FAB2_LIB.BASEBOARD_FAB2(SCH_1):PAGE176
   MH2    GND @BASEBOARD_FAB2_LIB.BASEBOARD_FAB2(SCH_1):GND    I69 @BASEBOARD_FAB2_LIB.BASEBOARD_FAB2(SCH_1):PAGE176
   MH3    GND @BASEBOARD_FAB2_LIB.BASEBOARD_FAB2(SCH_1):GND    I69 @BASEBOARD_FAB2_LIB.BASEBOARD_FAB2(SCH_1):PAGE176
   MH4    GND @BASEBOARD_FAB2_LIB.BASEBOARD_FAB2(SCH_1):GND    I69 @BASEBOARD_FAB2_LIB.BASEBOARD_FAB2(SCH_1):PAGE176
     5 SMB_IPMB_3V3AUX_SCL @BASEBOARD_FAB2_LIB.BASEBOARD_FAB2(SCH_1):SMB_IPMB_3V3AUX_SCL    I69 @BASEBOARD_FAB2_LIB.BASEBOARD_FAB2(SCH_1):PAGE176
     6 SMB_IPMB_3V3AUX_SDA @BASEBOARD_FAB2_LIB.BASEBOARD_FAB2(SCH_1):SMB_IPMB_3V3AUX_SDA    I69 @BASEBOARD_FAB2_LIB.BASEBOARD_FAB2(SCH_1):PAGE176
     8 SPA_MID_DBG_TX @BASEBOARD_FAB2_LIB.BASEBOARD_FAB2(SCH_1):SPA_MID_DBG_TX    I69 @BASEBOARD_FAB2_LIB.BASEBOARD_FAB2(SCH_1):PAGE176
     9 SPA_MID_DBG2_RX @BASEBOARD_FAB2_LIB.BASEBOARD_FAB2(SCH_1):SPA_MID_DBG2_RX    I69 @BASEBOARD_FAB2_LIB.BASEBOARD_FAB2(SCH_1):PAGE176
     1 P5V_USB @BASEBOARD_FAB2_LIB.BASEBOARD_FAB2(SCH_1):P5V_USB    I69 @BASEBOARD_FAB2_LIB.BASEBOARD_FAB2(SCH_1):PAGE176

J9B2 CONN3_C95678002_PIP-CONN,C9567A
     1 SMB_SMLINK0_STBY_LVC3_SDA @BASEBOARD_FAB2_LIB.BASEBOARD_FAB2(SCH_1):SMB_SMLINK0_STBY_LVC3_SDA   I281 @BASEBOARD_FAB2_LIB.BASEBOARD_FAB2(SCH_1):PAGE156
     2    GND @BASEBOARD_FAB2_LIB.BASEBOARD_FAB2(SCH_1):GND   I281 @BASEBOARD_FAB2_LIB.BASEBOARD_FAB2(SCH_1):PAGE156
     3 SMB_SMLINK0_STBY_LVC3_SCL @BASEBOARD_FAB2_LIB.BASEBOARD_FAB2(SCH_1):SMB_SMLINK0_STBY_LVC3_SCL   I281 @BASEBOARD_FAB2_LIB.BASEBOARD_FAB2(SCH_1):PAGE156

J9B3 SCONN120_A28699018_SM-SCONN,A2A
     1 FM_MEZZA_PRSNT1_N @BASEBOARD_FAB2_LIB.BASEBOARD_FAB2(SCH_1):FM_MEZZA_PRSNT1_N   I336 @BASEBOARD_FAB2_LIB.BASEBOARD_FAB2(SCH_1):PAGE186
    10    GND @BASEBOARD_FAB2_LIB.BASEBOARD_FAB2(SCH_1):GND   I336 @BASEBOARD_FAB2_LIB.BASEBOARD_FAB2(SCH_1):PAGE186
   100    GND @BASEBOARD_FAB2_LIB.BASEBOARD_FAB2(SCH_1):GND   I336 @BASEBOARD_FAB2_LIB.BASEBOARD_FAB2(SCH_1):PAGE186
   101 P3E_CPU0_PE3_OCP_RXN<10> @BASEBOARD_FAB2_LIB.BASEBOARD_FAB2(SCH_1):P3E_CPU0_PE3_OCP_RXN(10)   I336 @BASEBOARD_FAB2_LIB.BASEBOARD_FAB2(SCH_1):PAGE186
   102    GND @BASEBOARD_FAB2_LIB.BASEBOARD_FAB2(SCH_1):GND   I336 @BASEBOARD_FAB2_LIB.BASEBOARD_FAB2(SCH_1):PAGE186
   103    GND @BASEBOARD_FAB2_LIB.BASEBOARD_FAB2(SCH_1):GND   I336 @BASEBOARD_FAB2_LIB.BASEBOARD_FAB2(SCH_1):PAGE186
   104 P3E_OCP_CPU0_PE3_C_TXP<9> @BASEBOARD_FAB2_LIB.BASEBOARD_FAB2(SCH_1):P3E_OCP_CPU0_PE3_C_TXP(9)   I336 @BASEBOARD_FAB2_LIB.BASEBOARD_FAB2(SCH_1):PAGE186
   105    GND @BASEBOARD_FAB2_LIB.BASEBOARD_FAB2(SCH_1):GND   I336 @BASEBOARD_FAB2_LIB.BASEBOARD_FAB2(SCH_1):PAGE186
   106 P3E_OCP_CPU0_PE3_C_TXN<9> @BASEBOARD_FAB2_LIB.BASEBOARD_FAB2(SCH_1):P3E_OCP_CPU0_PE3_C_TXN(9)   I336 @BASEBOARD_FAB2_LIB.BASEBOARD_FAB2(SCH_1):PAGE186
   107 P3E_CPU0_PE3_OCP_RXP<9> @BASEBOARD_FAB2_LIB.BASEBOARD_FAB2(SCH_1):P3E_CPU0_PE3_OCP_RXP(9)   I336 @BASEBOARD_FAB2_LIB.BASEBOARD_FAB2(SCH_1):PAGE186
   108    GND @BASEBOARD_FAB2_LIB.BASEBOARD_FAB2(SCH_1):GND   I336 @BASEBOARD_FAB2_LIB.BASEBOARD_FAB2(SCH_1):PAGE186
   109 P3E_CPU0_PE3_OCP_RXN<9> @BASEBOARD_FAB2_LIB.BASEBOARD_FAB2(SCH_1):P3E_CPU0_PE3_OCP_RXN(9)   I336 @BASEBOARD_FAB2_LIB.BASEBOARD_FAB2(SCH_1):PAGE186
    11    GND @BASEBOARD_FAB2_LIB.BASEBOARD_FAB2(SCH_1):GND   I336 @BASEBOARD_FAB2_LIB.BASEBOARD_FAB2(SCH_1):PAGE186
   110    GND @BASEBOARD_FAB2_LIB.BASEBOARD_FAB2(SCH_1):GND   I336 @BASEBOARD_FAB2_LIB.BASEBOARD_FAB2(SCH_1):PAGE186
   111    GND @BASEBOARD_FAB2_LIB.BASEBOARD_FAB2(SCH_1):GND   I336 @BASEBOARD_FAB2_LIB.BASEBOARD_FAB2(SCH_1):PAGE186
   112 P3E_OCP_CPU0_PE3_C_TXP<8> @BASEBOARD_FAB2_LIB.BASEBOARD_FAB2(SCH_1):P3E_OCP_CPU0_PE3_C_TXP(8)   I336 @BASEBOARD_FAB2_LIB.BASEBOARD_FAB2(SCH_1):PAGE186
   113    GND @BASEBOARD_FAB2_LIB.BASEBOARD_FAB2(SCH_1):GND   I336 @BASEBOARD_FAB2_LIB.BASEBOARD_FAB2(SCH_1):PAGE186
   114 P3E_OCP_CPU0_PE3_C_TXN<8> @BASEBOARD_FAB2_LIB.BASEBOARD_FAB2(SCH_1):P3E_OCP_CPU0_PE3_C_TXN(8)   I336 @BASEBOARD_FAB2_LIB.BASEBOARD_FAB2(SCH_1):PAGE186
   115 P3E_CPU0_PE3_OCP_RXP<8> @BASEBOARD_FAB2_LIB.BASEBOARD_FAB2(SCH_1):P3E_CPU0_PE3_OCP_RXP(8)   I336 @BASEBOARD_FAB2_LIB.BASEBOARD_FAB2(SCH_1):PAGE186
   116    GND @BASEBOARD_FAB2_LIB.BASEBOARD_FAB2(SCH_1):GND   I336 @BASEBOARD_FAB2_LIB.BASEBOARD_FAB2(SCH_1):PAGE186
   117 P3E_CPU0_PE3_OCP_RXN<8> @BASEBOARD_FAB2_LIB.BASEBOARD_FAB2(SCH_1):P3E_CPU0_PE3_OCP_RXN(8)   I336 @BASEBOARD_FAB2_LIB.BASEBOARD_FAB2(SCH_1):PAGE186
   118    GND @BASEBOARD_FAB2_LIB.BASEBOARD_FAB2(SCH_1):GND   I336 @BASEBOARD_FAB2_LIB.BASEBOARD_FAB2(SCH_1):PAGE186
   119    GND @BASEBOARD_FAB2_LIB.BASEBOARD_FAB2(SCH_1):GND   I336 @BASEBOARD_FAB2_LIB.BASEBOARD_FAB2(SCH_1):PAGE186
    12 P3V3_STBY @BASEBOARD_FAB2_LIB.BASEBOARD_FAB2(SCH_1):P3V3_STBY   I336 @BASEBOARD_FAB2_LIB.BASEBOARD_FAB2(SCH_1):PAGE186
   120 FM_OCP_MEZZA_PRES_N @BASEBOARD_FAB2_LIB.BASEBOARD_FAB2(SCH_1):FM_OCP_MEZZA_PRES_N   I336 @BASEBOARD_FAB2_LIB.BASEBOARD_FAB2(SCH_1):PAGE186
    13 P3V3_STBY @BASEBOARD_FAB2_LIB.BASEBOARD_FAB2(SCH_1):P3V3_STBY   I336 @BASEBOARD_FAB2_LIB.BASEBOARD_FAB2(SCH_1):PAGE186
    14    GND @BASEBOARD_FAB2_LIB.BASEBOARD_FAB2(SCH_1):GND   I336 @BASEBOARD_FAB2_LIB.BASEBOARD_FAB2(SCH_1):PAGE186
    15    GND @BASEBOARD_FAB2_LIB.BASEBOARD_FAB2(SCH_1):GND   I336 @BASEBOARD_FAB2_LIB.BASEBOARD_FAB2(SCH_1):PAGE186
    16    GND @BASEBOARD_FAB2_LIB.BASEBOARD_FAB2(SCH_1):GND   I336 @BASEBOARD_FAB2_LIB.BASEBOARD_FAB2(SCH_1):PAGE186
    17    GND @BASEBOARD_FAB2_LIB.BASEBOARD_FAB2(SCH_1):GND   I336 @BASEBOARD_FAB2_LIB.BASEBOARD_FAB2(SCH_1):PAGE186
    18   P3V3 @BASEBOARD_FAB2_LIB.BASEBOARD_FAB2(SCH_1):P3V3   I336 @BASEBOARD_FAB2_LIB.BASEBOARD_FAB2(SCH_1):PAGE186
    19   P3V3 @BASEBOARD_FAB2_LIB.BASEBOARD_FAB2(SCH_1):P3V3   I336 @BASEBOARD_FAB2_LIB.BASEBOARD_FAB2(SCH_1):PAGE186
     2 P12V_STBY @BASEBOARD_FAB2_LIB.BASEBOARD_FAB2(SCH_1):P12V_STBY   I336 @BASEBOARD_FAB2_LIB.BASEBOARD_FAB2(SCH_1):PAGE186
    20   P3V3 @BASEBOARD_FAB2_LIB.BASEBOARD_FAB2(SCH_1):P3V3   I336 @BASEBOARD_FAB2_LIB.BASEBOARD_FAB2(SCH_1):PAGE186
    21   P3V3 @BASEBOARD_FAB2_LIB.BASEBOARD_FAB2(SCH_1):P3V3   I336 @BASEBOARD_FAB2_LIB.BASEBOARD_FAB2(SCH_1):PAGE186
    22   P3V3 @BASEBOARD_FAB2_LIB.BASEBOARD_FAB2(SCH_1):P3V3   I336 @BASEBOARD_FAB2_LIB.BASEBOARD_FAB2(SCH_1):PAGE186
    23   P3V3 @BASEBOARD_FAB2_LIB.BASEBOARD_FAB2(SCH_1):P3V3   I336 @BASEBOARD_FAB2_LIB.BASEBOARD_FAB2(SCH_1):PAGE186
    24   P3V3 @BASEBOARD_FAB2_LIB.BASEBOARD_FAB2(SCH_1):P3V3   I336 @BASEBOARD_FAB2_LIB.BASEBOARD_FAB2(SCH_1):PAGE186
    25   P3V3 @BASEBOARD_FAB2_LIB.BASEBOARD_FAB2(SCH_1):P3V3   I336 @BASEBOARD_FAB2_LIB.BASEBOARD_FAB2(SCH_1):PAGE186
    26    GND @BASEBOARD_FAB2_LIB.BASEBOARD_FAB2(SCH_1):GND   I336 @BASEBOARD_FAB2_LIB.BASEBOARD_FAB2(SCH_1):PAGE186
    27 RMII_BMC_OCP_CRSDV_R @BASEBOARD_FAB2_LIB.BASEBOARD_FAB2(SCH_1):RMII_BMC_OCP_CRSDV_R   I336 @BASEBOARD_FAB2_LIB.BASEBOARD_FAB2(SCH_1):PAGE186
    28 IRQ_MEZZ_LAN_ALERT_N @BASEBOARD_FAB2_LIB.BASEBOARD_FAB2(SCH_1):IRQ_MEZZ_LAN_ALERT_N   I336 @BASEBOARD_FAB2_LIB.BASEBOARD_FAB2(SCH_1):PAGE186
    29 CLK_50M_CKMNG_OCP @BASEBOARD_FAB2_LIB.BASEBOARD_FAB2(SCH_1):CLK_50M_CKMNG_OCP   I336 @BASEBOARD_FAB2_LIB.BASEBOARD_FAB2(SCH_1):PAGE186
     3 P5V_STBY @BASEBOARD_FAB2_LIB.BASEBOARD_FAB2(SCH_1):P5V_STBY   I336 @BASEBOARD_FAB2_LIB.BASEBOARD_FAB2(SCH_1):PAGE186
    30 SMB_OCP_FRU_STBY_LVC3_SCL @BASEBOARD_FAB2_LIB.BASEBOARD_FAB2(SCH_1):SMB_OCP_FRU_STBY_LVC3_SCL   I336 @BASEBOARD_FAB2_LIB.BASEBOARD_FAB2(SCH_1):PAGE186
    31 RMII_BMC_OCP_TXEN @BASEBOARD_FAB2_LIB.BASEBOARD_FAB2(SCH_1):RMII_BMC_OCP_TXEN   I336 @BASEBOARD_FAB2_LIB.BASEBOARD_FAB2(SCH_1):PAGE186
    32 SMB_OCP_FRU_STBY_LVC3_SDA @BASEBOARD_FAB2_LIB.BASEBOARD_FAB2(SCH_1):SMB_OCP_FRU_STBY_LVC3_SDA   I336 @BASEBOARD_FAB2_LIB.BASEBOARD_FAB2(SCH_1):PAGE186
    33 RST_PCIE_CPU_DEV0_R_N @BASEBOARD_FAB2_LIB.BASEBOARD_FAB2(SCH_1):RST_PCIE_CPU_DEV0_R_N   I336 @BASEBOARD_FAB2_LIB.BASEBOARD_FAB2(SCH_1):PAGE186
    34 FM_PE_OCP_WAKE_N @BASEBOARD_FAB2_LIB.BASEBOARD_FAB2(SCH_1):FM_PE_OCP_WAKE_N   I336 @BASEBOARD_FAB2_LIB.BASEBOARD_FAB2(SCH_1):PAGE186
    35 SMB_OCP_LAN_STBY_LVC3_SCL @BASEBOARD_FAB2_LIB.BASEBOARD_FAB2(SCH_1):SMB_OCP_LAN_STBY_LVC3_SCL   I336 @BASEBOARD_FAB2_LIB.BASEBOARD_FAB2(SCH_1):PAGE186
    36 RMII_BMC_OCP_RXER_R @BASEBOARD_FAB2_LIB.BASEBOARD_FAB2(SCH_1):RMII_BMC_OCP_RXER_R   I336 @BASEBOARD_FAB2_LIB.BASEBOARD_FAB2(SCH_1):PAGE186
    37 SMB_OCP_LAN_STBY_LVC3_SDA @BASEBOARD_FAB2_LIB.BASEBOARD_FAB2(SCH_1):SMB_OCP_LAN_STBY_LVC3_SDA   I336 @BASEBOARD_FAB2_LIB.BASEBOARD_FAB2(SCH_1):PAGE186
    38    GND @BASEBOARD_FAB2_LIB.BASEBOARD_FAB2(SCH_1):GND   I336 @BASEBOARD_FAB2_LIB.BASEBOARD_FAB2(SCH_1):PAGE186
    39    GND @BASEBOARD_FAB2_LIB.BASEBOARD_FAB2(SCH_1):GND   I336 @BASEBOARD_FAB2_LIB.BASEBOARD_FAB2(SCH_1):PAGE186
     4 P12V_STBY @BASEBOARD_FAB2_LIB.BASEBOARD_FAB2(SCH_1):P12V_STBY   I336 @BASEBOARD_FAB2_LIB.BASEBOARD_FAB2(SCH_1):PAGE186
    40 RMII_BMC_OCP_TXD0 @BASEBOARD_FAB2_LIB.BASEBOARD_FAB2(SCH_1):RMII_BMC_OCP_TXD0   I336 @BASEBOARD_FAB2_LIB.BASEBOARD_FAB2(SCH_1):PAGE186
    41    GND @BASEBOARD_FAB2_LIB.BASEBOARD_FAB2(SCH_1):GND   I336 @BASEBOARD_FAB2_LIB.BASEBOARD_FAB2(SCH_1):PAGE186
    42 RMII_BMC_OCP_TXD1 @BASEBOARD_FAB2_LIB.BASEBOARD_FAB2(SCH_1):RMII_BMC_OCP_TXD1   I336 @BASEBOARD_FAB2_LIB.BASEBOARD_FAB2(SCH_1):PAGE186
    43 RMII_BMC_OCP_RXD0_R @BASEBOARD_FAB2_LIB.BASEBOARD_FAB2(SCH_1):RMII_BMC_OCP_RXD0_R   I336 @BASEBOARD_FAB2_LIB.BASEBOARD_FAB2(SCH_1):PAGE186
    44    GND @BASEBOARD_FAB2_LIB.BASEBOARD_FAB2(SCH_1):GND   I336 @BASEBOARD_FAB2_LIB.BASEBOARD_FAB2(SCH_1):PAGE186
    45 RMII_BMC_OCP_RXD1_R @BASEBOARD_FAB2_LIB.BASEBOARD_FAB2(SCH_1):RMII_BMC_OCP_RXD1_R   I336 @BASEBOARD_FAB2_LIB.BASEBOARD_FAB2(SCH_1):PAGE186
    46    GND @BASEBOARD_FAB2_LIB.BASEBOARD_FAB2(SCH_1):GND   I336 @BASEBOARD_FAB2_LIB.BASEBOARD_FAB2(SCH_1):PAGE186
    47    GND @BASEBOARD_FAB2_LIB.BASEBOARD_FAB2(SCH_1):GND   I336 @BASEBOARD_FAB2_LIB.BASEBOARD_FAB2(SCH_1):PAGE186
    48 CLK_100M_MEZZ1_DP @BASEBOARD_FAB2_LIB.BASEBOARD_FAB2(SCH_1):CLK_100M_MEZZ1_DP   I336 @BASEBOARD_FAB2_LIB.BASEBOARD_FAB2(SCH_1):PAGE186
    49    GND @BASEBOARD_FAB2_LIB.BASEBOARD_FAB2(SCH_1):GND   I336 @BASEBOARD_FAB2_LIB.BASEBOARD_FAB2(SCH_1):PAGE186
     5 P5V_STBY @BASEBOARD_FAB2_LIB.BASEBOARD_FAB2(SCH_1):P5V_STBY   I336 @BASEBOARD_FAB2_LIB.BASEBOARD_FAB2(SCH_1):PAGE186
    50 CLK_100M_MEZZ1_DN @BASEBOARD_FAB2_LIB.BASEBOARD_FAB2(SCH_1):CLK_100M_MEZZ1_DN   I336 @BASEBOARD_FAB2_LIB.BASEBOARD_FAB2(SCH_1):PAGE186
    51 CLK_100M_MEZZ2_DP @BASEBOARD_FAB2_LIB.BASEBOARD_FAB2(SCH_1):CLK_100M_MEZZ2_DP   I336 @BASEBOARD_FAB2_LIB.BASEBOARD_FAB2(SCH_1):PAGE186
    52    GND @BASEBOARD_FAB2_LIB.BASEBOARD_FAB2(SCH_1):GND   I336 @BASEBOARD_FAB2_LIB.BASEBOARD_FAB2(SCH_1):PAGE186
    53 CLK_100M_MEZZ2_DN @BASEBOARD_FAB2_LIB.BASEBOARD_FAB2(SCH_1):CLK_100M_MEZZ2_DN   I336 @BASEBOARD_FAB2_LIB.BASEBOARD_FAB2(SCH_1):PAGE186
    54    GND @BASEBOARD_FAB2_LIB.BASEBOARD_FAB2(SCH_1):GND   I336 @BASEBOARD_FAB2_LIB.BASEBOARD_FAB2(SCH_1):PAGE186
    55    GND @BASEBOARD_FAB2_LIB.BASEBOARD_FAB2(SCH_1):GND   I336 @BASEBOARD_FAB2_LIB.BASEBOARD_FAB2(SCH_1):PAGE186
    56 P3E_OCP_CPU0_PE3_C_TXP<15> @BASEBOARD_FAB2_LIB.BASEBOARD_FAB2(SCH_1):P3E_OCP_CPU0_PE3_C_TXP(15)   I336 @BASEBOARD_FAB2_LIB.BASEBOARD_FAB2(SCH_1):PAGE186
    57    GND @BASEBOARD_FAB2_LIB.BASEBOARD_FAB2(SCH_1):GND   I336 @BASEBOARD_FAB2_LIB.BASEBOARD_FAB2(SCH_1):PAGE186
    58 P3E_OCP_CPU0_PE3_C_TXN<15> @BASEBOARD_FAB2_LIB.BASEBOARD_FAB2(SCH_1):P3E_OCP_CPU0_PE3_C_TXN(15)   I336 @BASEBOARD_FAB2_LIB.BASEBOARD_FAB2(SCH_1):PAGE186
    59 P3E_CPU0_PE3_OCP_RXP<15> @BASEBOARD_FAB2_LIB.BASEBOARD_FAB2(SCH_1):P3E_CPU0_PE3_OCP_RXP(15)   I336 @BASEBOARD_FAB2_LIB.BASEBOARD_FAB2(SCH_1):PAGE186
     6 P12V_STBY @BASEBOARD_FAB2_LIB.BASEBOARD_FAB2(SCH_1):P12V_STBY   I336 @BASEBOARD_FAB2_LIB.BASEBOARD_FAB2(SCH_1):PAGE186
    60    GND @BASEBOARD_FAB2_LIB.BASEBOARD_FAB2(SCH_1):GND   I336 @BASEBOARD_FAB2_LIB.BASEBOARD_FAB2(SCH_1):PAGE186
    61 P3E_CPU0_PE3_OCP_RXN<15> @BASEBOARD_FAB2_LIB.BASEBOARD_FAB2(SCH_1):P3E_CPU0_PE3_OCP_RXN(15)   I336 @BASEBOARD_FAB2_LIB.BASEBOARD_FAB2(SCH_1):PAGE186
    62    GND @BASEBOARD_FAB2_LIB.BASEBOARD_FAB2(SCH_1):GND   I336 @BASEBOARD_FAB2_LIB.BASEBOARD_FAB2(SCH_1):PAGE186
    63    GND @BASEBOARD_FAB2_LIB.BASEBOARD_FAB2(SCH_1):GND   I336 @BASEBOARD_FAB2_LIB.BASEBOARD_FAB2(SCH_1):PAGE186
    64 P3E_OCP_CPU0_PE3_C_TXP<14> @BASEBOARD_FAB2_LIB.BASEBOARD_FAB2(SCH_1):P3E_OCP_CPU0_PE3_C_TXP(14)   I336 @BASEBOARD_FAB2_LIB.BASEBOARD_FAB2(SCH_1):PAGE186
    65    GND @BASEBOARD_FAB2_LIB.BASEBOARD_FAB2(SCH_1):GND   I336 @BASEBOARD_FAB2_LIB.BASEBOARD_FAB2(SCH_1):PAGE186
    66 P3E_OCP_CPU0_PE3_C_TXN<14> @BASEBOARD_FAB2_LIB.BASEBOARD_FAB2(SCH_1):P3E_OCP_CPU0_PE3_C_TXN(14)   I336 @BASEBOARD_FAB2_LIB.BASEBOARD_FAB2(SCH_1):PAGE186
    67 P3E_CPU0_PE3_OCP_RXP<14> @BASEBOARD_FAB2_LIB.BASEBOARD_FAB2(SCH_1):P3E_CPU0_PE3_OCP_RXP(14)   I336 @BASEBOARD_FAB2_LIB.BASEBOARD_FAB2(SCH_1):PAGE186
    68    GND @BASEBOARD_FAB2_LIB.BASEBOARD_FAB2(SCH_1):GND   I336 @BASEBOARD_FAB2_LIB.BASEBOARD_FAB2(SCH_1):PAGE186
    69 P3E_CPU0_PE3_OCP_RXN<14> @BASEBOARD_FAB2_LIB.BASEBOARD_FAB2(SCH_1):P3E_CPU0_PE3_OCP_RXN(14)   I336 @BASEBOARD_FAB2_LIB.BASEBOARD_FAB2(SCH_1):PAGE186
     7 P5V_STBY @BASEBOARD_FAB2_LIB.BASEBOARD_FAB2(SCH_1):P5V_STBY   I336 @BASEBOARD_FAB2_LIB.BASEBOARD_FAB2(SCH_1):PAGE186
    70    GND @BASEBOARD_FAB2_LIB.BASEBOARD_FAB2(SCH_1):GND   I336 @BASEBOARD_FAB2_LIB.BASEBOARD_FAB2(SCH_1):PAGE186
    71    GND @BASEBOARD_FAB2_LIB.BASEBOARD_FAB2(SCH_1):GND   I336 @BASEBOARD_FAB2_LIB.BASEBOARD_FAB2(SCH_1):PAGE186
    72 P3E_OCP_CPU0_PE3_C_TXP<13> @BASEBOARD_FAB2_LIB.BASEBOARD_FAB2(SCH_1):P3E_OCP_CPU0_PE3_C_TXP(13)   I336 @BASEBOARD_FAB2_LIB.BASEBOARD_FAB2(SCH_1):PAGE186
    73    GND @BASEBOARD_FAB2_LIB.BASEBOARD_FAB2(SCH_1):GND   I336 @BASEBOARD_FAB2_LIB.BASEBOARD_FAB2(SCH_1):PAGE186
    74 P3E_OCP_CPU0_PE3_C_TXN<13> @BASEBOARD_FAB2_LIB.BASEBOARD_FAB2(SCH_1):P3E_OCP_CPU0_PE3_C_TXN(13)   I336 @BASEBOARD_FAB2_LIB.BASEBOARD_FAB2(SCH_1):PAGE186
    75 P3E_CPU0_PE3_OCP_RXP<13> @BASEBOARD_FAB2_LIB.BASEBOARD_FAB2(SCH_1):P3E_CPU0_PE3_OCP_RXP(13)   I336 @BASEBOARD_FAB2_LIB.BASEBOARD_FAB2(SCH_1):PAGE186
    76    GND @BASEBOARD_FAB2_LIB.BASEBOARD_FAB2(SCH_1):GND   I336 @BASEBOARD_FAB2_LIB.BASEBOARD_FAB2(SCH_1):PAGE186
    77 P3E_CPU0_PE3_OCP_RXN<13> @BASEBOARD_FAB2_LIB.BASEBOARD_FAB2(SCH_1):P3E_CPU0_PE3_OCP_RXN(13)   I336 @BASEBOARD_FAB2_LIB.BASEBOARD_FAB2(SCH_1):PAGE186
    78    GND @BASEBOARD_FAB2_LIB.BASEBOARD_FAB2(SCH_1):GND   I336 @BASEBOARD_FAB2_LIB.BASEBOARD_FAB2(SCH_1):PAGE186
    79    GND @BASEBOARD_FAB2_LIB.BASEBOARD_FAB2(SCH_1):GND   I336 @BASEBOARD_FAB2_LIB.BASEBOARD_FAB2(SCH_1):PAGE186
     8    GND @BASEBOARD_FAB2_LIB.BASEBOARD_FAB2(SCH_1):GND   I336 @BASEBOARD_FAB2_LIB.BASEBOARD_FAB2(SCH_1):PAGE186
    80 P3E_OCP_CPU0_PE3_C_TXP<12> @BASEBOARD_FAB2_LIB.BASEBOARD_FAB2(SCH_1):P3E_OCP_CPU0_PE3_C_TXP(12)   I336 @BASEBOARD_FAB2_LIB.BASEBOARD_FAB2(SCH_1):PAGE186
    81    GND @BASEBOARD_FAB2_LIB.BASEBOARD_FAB2(SCH_1):GND   I336 @BASEBOARD_FAB2_LIB.BASEBOARD_FAB2(SCH_1):PAGE186
    82 P3E_OCP_CPU0_PE3_C_TXN<12> @BASEBOARD_FAB2_LIB.BASEBOARD_FAB2(SCH_1):P3E_OCP_CPU0_PE3_C_TXN(12)   I336 @BASEBOARD_FAB2_LIB.BASEBOARD_FAB2(SCH_1):PAGE186
    83 P3E_CPU0_PE3_OCP_RXP<12> @BASEBOARD_FAB2_LIB.BASEBOARD_FAB2(SCH_1):P3E_CPU0_PE3_OCP_RXP(12)   I336 @BASEBOARD_FAB2_LIB.BASEBOARD_FAB2(SCH_1):PAGE186
    84    GND @BASEBOARD_FAB2_LIB.BASEBOARD_FAB2(SCH_1):GND   I336 @BASEBOARD_FAB2_LIB.BASEBOARD_FAB2(SCH_1):PAGE186
    85 P3E_CPU0_PE3_OCP_RXN<12> @BASEBOARD_FAB2_LIB.BASEBOARD_FAB2(SCH_1):P3E_CPU0_PE3_OCP_RXN(12)   I336 @BASEBOARD_FAB2_LIB.BASEBOARD_FAB2(SCH_1):PAGE186
    86    GND @BASEBOARD_FAB2_LIB.BASEBOARD_FAB2(SCH_1):GND   I336 @BASEBOARD_FAB2_LIB.BASEBOARD_FAB2(SCH_1):PAGE186
    87    GND @BASEBOARD_FAB2_LIB.BASEBOARD_FAB2(SCH_1):GND   I336 @BASEBOARD_FAB2_LIB.BASEBOARD_FAB2(SCH_1):PAGE186
    88 P3E_OCP_CPU0_PE3_C_TXP<11> @BASEBOARD_FAB2_LIB.BASEBOARD_FAB2(SCH_1):P3E_OCP_CPU0_PE3_C_TXP(11)   I336 @BASEBOARD_FAB2_LIB.BASEBOARD_FAB2(SCH_1):PAGE186
    89    GND @BASEBOARD_FAB2_LIB.BASEBOARD_FAB2(SCH_1):GND   I336 @BASEBOARD_FAB2_LIB.BASEBOARD_FAB2(SCH_1):PAGE186
     9    GND @BASEBOARD_FAB2_LIB.BASEBOARD_FAB2(SCH_1):GND   I336 @BASEBOARD_FAB2_LIB.BASEBOARD_FAB2(SCH_1):PAGE186
    90 P3E_OCP_CPU0_PE3_C_TXN<11> @BASEBOARD_FAB2_LIB.BASEBOARD_FAB2(SCH_1):P3E_OCP_CPU0_PE3_C_TXN(11)   I336 @BASEBOARD_FAB2_LIB.BASEBOARD_FAB2(SCH_1):PAGE186
    91 P3E_CPU0_PE3_OCP_RXP<11> @BASEBOARD_FAB2_LIB.BASEBOARD_FAB2(SCH_1):P3E_CPU0_PE3_OCP_RXP(11)   I336 @BASEBOARD_FAB2_LIB.BASEBOARD_FAB2(SCH_1):PAGE186
    92    GND @BASEBOARD_FAB2_LIB.BASEBOARD_FAB2(SCH_1):GND   I336 @BASEBOARD_FAB2_LIB.BASEBOARD_FAB2(SCH_1):PAGE186
    93 P3E_CPU0_PE3_OCP_RXN<11> @BASEBOARD_FAB2_LIB.BASEBOARD_FAB2(SCH_1):P3E_CPU0_PE3_OCP_RXN(11)   I336 @BASEBOARD_FAB2_LIB.BASEBOARD_FAB2(SCH_1):PAGE186
    94    GND @BASEBOARD_FAB2_LIB.BASEBOARD_FAB2(SCH_1):GND   I336 @BASEBOARD_FAB2_LIB.BASEBOARD_FAB2(SCH_1):PAGE186
    95    GND @BASEBOARD_FAB2_LIB.BASEBOARD_FAB2(SCH_1):GND   I336 @BASEBOARD_FAB2_LIB.BASEBOARD_FAB2(SCH_1):PAGE186
    96 P3E_OCP_CPU0_PE3_C_TXP<10> @BASEBOARD_FAB2_LIB.BASEBOARD_FAB2(SCH_1):P3E_OCP_CPU0_PE3_C_TXP(10)   I336 @BASEBOARD_FAB2_LIB.BASEBOARD_FAB2(SCH_1):PAGE186
    97    GND @BASEBOARD_FAB2_LIB.BASEBOARD_FAB2(SCH_1):GND   I336 @BASEBOARD_FAB2_LIB.BASEBOARD_FAB2(SCH_1):PAGE186
    98 P3E_OCP_CPU0_PE3_C_TXN<10> @BASEBOARD_FAB2_LIB.BASEBOARD_FAB2(SCH_1):P3E_OCP_CPU0_PE3_C_TXN(10)   I336 @BASEBOARD_FAB2_LIB.BASEBOARD_FAB2(SCH_1):PAGE186
    99 P3E_CPU0_PE3_OCP_RXP<10> @BASEBOARD_FAB2_LIB.BASEBOARD_FAB2(SCH_1):P3E_CPU0_PE3_OCP_RXP(10)   I336 @BASEBOARD_FAB2_LIB.BASEBOARD_FAB2(SCH_1):PAGE186

J9B4 SCONN10_C12536004_SMLF-CONN,C1A
     1 JTAG_MCP_TCK_R @BASEBOARD_FAB2_LIB.BASEBOARD_FAB2(SCH_1):JTAG_MCP_TCK_R   I175 @BASEBOARD_FAB2_LIB.BASEBOARD_FAB2(SCH_1):PAGE113
     2    GND @BASEBOARD_FAB2_LIB.BASEBOARD_FAB2(SCH_1):GND   I175 @BASEBOARD_FAB2_LIB.BASEBOARD_FAB2(SCH_1):PAGE113
     3 JTAG_MCP_MUX_TDO @BASEBOARD_FAB2_LIB.BASEBOARD_FAB2(SCH_1):JTAG_MCP_MUX_TDO   I175 @BASEBOARD_FAB2_LIB.BASEBOARD_FAB2(SCH_1):PAGE113
     4 P1V8_MCP_CPU0 @BASEBOARD_FAB2_LIB.BASEBOARD_FAB2(SCH_1):P1V8_MCP_CPU0   I175 @BASEBOARD_FAB2_LIB.BASEBOARD_FAB2(SCH_1):PAGE113
     5 JTAG_MCP_TMS_R @BASEBOARD_FAB2_LIB.BASEBOARD_FAB2(SCH_1):JTAG_MCP_TMS_R   I175 @BASEBOARD_FAB2_LIB.BASEBOARD_FAB2(SCH_1):PAGE113
     6 JTAG_MCP_TRST_N @BASEBOARD_FAB2_LIB.BASEBOARD_FAB2(SCH_1):JTAG_MCP_TRST_N   I175 @BASEBOARD_FAB2_LIB.BASEBOARD_FAB2(SCH_1):PAGE113
     7 PWRGD_CPU0_G_R @BASEBOARD_FAB2_LIB.BASEBOARD_FAB2(SCH_1):PWRGD_CPU0_G_R   I175 @BASEBOARD_FAB2_LIB.BASEBOARD_FAB2(SCH_1):PAGE113
     8 TP_JTAG_MCP_IO8_RSVD @BASEBOARD_FAB2_LIB.BASEBOARD_FAB2(SCH_1):TP_JTAG_MCP_IO8_RSVD   I175 @BASEBOARD_FAB2_LIB.BASEBOARD_FAB2(SCH_1):PAGE113
     9 JTAG_MCP_MUX_TDI @BASEBOARD_FAB2_LIB.BASEBOARD_FAB2(SCH_1):JTAG_MCP_MUX_TDI   I175 @BASEBOARD_FAB2_LIB.BASEBOARD_FAB2(SCH_1):PAGE113
    10    GND @BASEBOARD_FAB2_LIB.BASEBOARD_FAB2(SCH_1):GND   I175 @BASEBOARD_FAB2_LIB.BASEBOARD_FAB2(SCH_1):PAGE113

J9G1 CONN12_C73564003_PIP-CONN,C735A
     1 TP_BMC_DISABLE @BASEBOARD_FAB2_LIB.BASEBOARD_FAB2(SCH_1):TP_BMC_DISABLE   I128 @BASEBOARD_FAB2_LIB.BASEBOARD_FAB2(SCH_1):PAGE137
    10 TP_JUMPER_BLOCK_2_10 @BASEBOARD_FAB2_LIB.BASEBOARD_FAB2(SCH_1):TP_JUMPER_BLOCK_2_10   I128 @BASEBOARD_FAB2_LIB.BASEBOARD_FAB2(SCH_1):PAGE137
    11 PD_IE_DEBUG_MODE @BASEBOARD_FAB2_LIB.BASEBOARD_FAB2(SCH_1):PD_IE_DEBUG_MODE   I128 @BASEBOARD_FAB2_LIB.BASEBOARD_FAB2(SCH_1):PAGE137
    12 TP_JUMPER_BLOCK_2_12 @BASEBOARD_FAB2_LIB.BASEBOARD_FAB2(SCH_1):TP_JUMPER_BLOCK_2_12   I128 @BASEBOARD_FAB2_LIB.BASEBOARD_FAB2(SCH_1):PAGE137
     2 TP_RST_RTCRST_N @BASEBOARD_FAB2_LIB.BASEBOARD_FAB2(SCH_1):TP_RST_RTCRST_N   I128 @BASEBOARD_FAB2_LIB.BASEBOARD_FAB2(SCH_1):PAGE137
     3 FM_ROMA<0> @BASEBOARD_FAB2_LIB.BASEBOARD_FAB2(SCH_1):FM_ROMA(0)   I128 @BASEBOARD_FAB2_LIB.BASEBOARD_FAB2(SCH_1):PAGE137
     4 RST_RTCRST_N @BASEBOARD_FAB2_LIB.BASEBOARD_FAB2(SCH_1):RST_RTCRST_N   I128 @BASEBOARD_FAB2_LIB.BASEBOARD_FAB2(SCH_1):PAGE137
     5 FM_BMC_DISABLE @BASEBOARD_FAB2_LIB.BASEBOARD_FAB2(SCH_1):FM_BMC_DISABLE   I128 @BASEBOARD_FAB2_LIB.BASEBOARD_FAB2(SCH_1):PAGE137
     6 PD_RST_RTCRST_N @BASEBOARD_FAB2_LIB.BASEBOARD_FAB2(SCH_1):PD_RST_RTCRST_N   I128 @BASEBOARD_FAB2_LIB.BASEBOARD_FAB2(SCH_1):PAGE137
     7 TP_IE_DEBUG_MODE @BASEBOARD_FAB2_LIB.BASEBOARD_FAB2(SCH_1):TP_IE_DEBUG_MODE   I128 @BASEBOARD_FAB2_LIB.BASEBOARD_FAB2(SCH_1):PAGE137
     8 TP_JUMPER_BLOCK_2_8 @BASEBOARD_FAB2_LIB.BASEBOARD_FAB2(SCH_1):TP_JUMPER_BLOCK_2_8   I128 @BASEBOARD_FAB2_LIB.BASEBOARD_FAB2(SCH_1):PAGE137
     9 FM_UART_PRES_N @BASEBOARD_FAB2_LIB.BASEBOARD_FAB2(SCH_1):FM_UART_PRES_N   I128 @BASEBOARD_FAB2_LIB.BASEBOARD_FAB2(SCH_1):PAGE137

J9L1 SCONN288_H44441003_PIP-SCONN,HA
    79 M_M_MA<0> @BASEBOARD_FAB2_LIB.BASEBOARD_FAB2(SCH_1):M_M_MA(0)   I111 @BASEBOARD_FAB2_LIB.BASEBOARD_FAB2(SCH_1):PAGE88
    72 M_M_MA<1> @BASEBOARD_FAB2_LIB.BASEBOARD_FAB2(SCH_1):M_M_MA(1)   I111 @BASEBOARD_FAB2_LIB.BASEBOARD_FAB2(SCH_1):PAGE88
   225 M_M_MA<10> @BASEBOARD_FAB2_LIB.BASEBOARD_FAB2(SCH_1):M_M_MA(10)   I111 @BASEBOARD_FAB2_LIB.BASEBOARD_FAB2(SCH_1):PAGE88
   210 M_M_MA<11> @BASEBOARD_FAB2_LIB.BASEBOARD_FAB2(SCH_1):M_M_MA(11)   I111 @BASEBOARD_FAB2_LIB.BASEBOARD_FAB2(SCH_1):PAGE88
    65 M_M_MA<12> @BASEBOARD_FAB2_LIB.BASEBOARD_FAB2(SCH_1):M_M_MA(12)   I111 @BASEBOARD_FAB2_LIB.BASEBOARD_FAB2(SCH_1):PAGE88
   232 M_M_MA<13> @BASEBOARD_FAB2_LIB.BASEBOARD_FAB2(SCH_1):M_M_MA(13)   I111 @BASEBOARD_FAB2_LIB.BASEBOARD_FAB2(SCH_1):PAGE88
   228 M_M_MA<14> @BASEBOARD_FAB2_LIB.BASEBOARD_FAB2(SCH_1):M_M_MA(14)   I111 @BASEBOARD_FAB2_LIB.BASEBOARD_FAB2(SCH_1):PAGE88
    86 M_M_MA<15> @BASEBOARD_FAB2_LIB.BASEBOARD_FAB2(SCH_1):M_M_MA(15)   I111 @BASEBOARD_FAB2_LIB.BASEBOARD_FAB2(SCH_1):PAGE88
    82 M_M_MA<16> @BASEBOARD_FAB2_LIB.BASEBOARD_FAB2(SCH_1):M_M_MA(16)   I111 @BASEBOARD_FAB2_LIB.BASEBOARD_FAB2(SCH_1):PAGE88
   234 M_M_MA<17> @BASEBOARD_FAB2_LIB.BASEBOARD_FAB2(SCH_1):M_M_MA(17)   I111 @BASEBOARD_FAB2_LIB.BASEBOARD_FAB2(SCH_1):PAGE88
   216 M_M_MA<2> @BASEBOARD_FAB2_LIB.BASEBOARD_FAB2(SCH_1):M_M_MA(2)   I111 @BASEBOARD_FAB2_LIB.BASEBOARD_FAB2(SCH_1):PAGE88
    71 M_M_MA<3> @BASEBOARD_FAB2_LIB.BASEBOARD_FAB2(SCH_1):M_M_MA(3)   I111 @BASEBOARD_FAB2_LIB.BASEBOARD_FAB2(SCH_1):PAGE88
   214 M_M_MA<4> @BASEBOARD_FAB2_LIB.BASEBOARD_FAB2(SCH_1):M_M_MA(4)   I111 @BASEBOARD_FAB2_LIB.BASEBOARD_FAB2(SCH_1):PAGE88
   213 M_M_MA<5> @BASEBOARD_FAB2_LIB.BASEBOARD_FAB2(SCH_1):M_M_MA(5)   I111 @BASEBOARD_FAB2_LIB.BASEBOARD_FAB2(SCH_1):PAGE88
    69 M_M_MA<6> @BASEBOARD_FAB2_LIB.BASEBOARD_FAB2(SCH_1):M_M_MA(6)   I111 @BASEBOARD_FAB2_LIB.BASEBOARD_FAB2(SCH_1):PAGE88
   211 M_M_MA<7> @BASEBOARD_FAB2_LIB.BASEBOARD_FAB2(SCH_1):M_M_MA(7)   I111 @BASEBOARD_FAB2_LIB.BASEBOARD_FAB2(SCH_1):PAGE88
    68 M_M_MA<8> @BASEBOARD_FAB2_LIB.BASEBOARD_FAB2(SCH_1):M_M_MA(8)   I111 @BASEBOARD_FAB2_LIB.BASEBOARD_FAB2(SCH_1):PAGE88
    66 M_M_MA<9> @BASEBOARD_FAB2_LIB.BASEBOARD_FAB2(SCH_1):M_M_MA(9)   I111 @BASEBOARD_FAB2_LIB.BASEBOARD_FAB2(SCH_1):PAGE88
    62 M_M_ACT_N @BASEBOARD_FAB2_LIB.BASEBOARD_FAB2(SCH_1):M_M_ACT_N   I111 @BASEBOARD_FAB2_LIB.BASEBOARD_FAB2(SCH_1):PAGE88
   208 M_M_ALERT_N @BASEBOARD_FAB2_LIB.BASEBOARD_FAB2(SCH_1):M_M_ALERT_N   I111 @BASEBOARD_FAB2_LIB.BASEBOARD_FAB2(SCH_1):PAGE88
   224 M_M_BA<1> @BASEBOARD_FAB2_LIB.BASEBOARD_FAB2(SCH_1):M_M_BA(1)   I111 @BASEBOARD_FAB2_LIB.BASEBOARD_FAB2(SCH_1):PAGE88
    81 M_M_BA<0> @BASEBOARD_FAB2_LIB.BASEBOARD_FAB2(SCH_1):M_M_BA(0)   I111 @BASEBOARD_FAB2_LIB.BASEBOARD_FAB2(SCH_1):PAGE88
   207 M_M_BG<1> @BASEBOARD_FAB2_LIB.BASEBOARD_FAB2(SCH_1):M_M_BG(1)   I111 @BASEBOARD_FAB2_LIB.BASEBOARD_FAB2(SCH_1):PAGE88
    63 M_M_BG<0> @BASEBOARD_FAB2_LIB.BASEBOARD_FAB2(SCH_1):M_M_BG(0)   I111 @BASEBOARD_FAB2_LIB.BASEBOARD_FAB2(SCH_1):PAGE88
   235 M_M_C<2> @BASEBOARD_FAB2_LIB.BASEBOARD_FAB2(SCH_1):M_M_C(2)   I111 @BASEBOARD_FAB2_LIB.BASEBOARD_FAB2(SCH_1):PAGE88
   199 M_M_ECC<7> @BASEBOARD_FAB2_LIB.BASEBOARD_FAB2(SCH_1):M_M_ECC(7)   I111 @BASEBOARD_FAB2_LIB.BASEBOARD_FAB2(SCH_1):PAGE88
    54 M_M_ECC<6> @BASEBOARD_FAB2_LIB.BASEBOARD_FAB2(SCH_1):M_M_ECC(6)   I111 @BASEBOARD_FAB2_LIB.BASEBOARD_FAB2(SCH_1):PAGE88
   192 M_M_ECC<5> @BASEBOARD_FAB2_LIB.BASEBOARD_FAB2(SCH_1):M_M_ECC(5)   I111 @BASEBOARD_FAB2_LIB.BASEBOARD_FAB2(SCH_1):PAGE88
    47 M_M_ECC<4> @BASEBOARD_FAB2_LIB.BASEBOARD_FAB2(SCH_1):M_M_ECC(4)   I111 @BASEBOARD_FAB2_LIB.BASEBOARD_FAB2(SCH_1):PAGE88
   201 M_M_ECC<3> @BASEBOARD_FAB2_LIB.BASEBOARD_FAB2(SCH_1):M_M_ECC(3)   I111 @BASEBOARD_FAB2_LIB.BASEBOARD_FAB2(SCH_1):PAGE88
    56 M_M_ECC<2> @BASEBOARD_FAB2_LIB.BASEBOARD_FAB2(SCH_1):M_M_ECC(2)   I111 @BASEBOARD_FAB2_LIB.BASEBOARD_FAB2(SCH_1):PAGE88
   194 M_M_ECC<1> @BASEBOARD_FAB2_LIB.BASEBOARD_FAB2(SCH_1):M_M_ECC(1)   I111 @BASEBOARD_FAB2_LIB.BASEBOARD_FAB2(SCH_1):PAGE88
    49 M_M_ECC<0> @BASEBOARD_FAB2_LIB.BASEBOARD_FAB2(SCH_1):M_M_ECC(0)   I111 @BASEBOARD_FAB2_LIB.BASEBOARD_FAB2(SCH_1):PAGE88
    75 M_M_CLK_DN<2> @BASEBOARD_FAB2_LIB.BASEBOARD_FAB2(SCH_1):M_M_CLK_DN(2)   I111 @BASEBOARD_FAB2_LIB.BASEBOARD_FAB2(SCH_1):PAGE88
    74 M_M_CLK_DP<2> @BASEBOARD_FAB2_LIB.BASEBOARD_FAB2(SCH_1):M_M_CLK_DP(2)   I111 @BASEBOARD_FAB2_LIB.BASEBOARD_FAB2(SCH_1):PAGE88
   219 M_M_CLK_DN<3> @BASEBOARD_FAB2_LIB.BASEBOARD_FAB2(SCH_1):M_M_CLK_DN(3)   I111 @BASEBOARD_FAB2_LIB.BASEBOARD_FAB2(SCH_1):PAGE88
   218 M_M_CLK_DP<3> @BASEBOARD_FAB2_LIB.BASEBOARD_FAB2(SCH_1):M_M_CLK_DP(3)   I111 @BASEBOARD_FAB2_LIB.BASEBOARD_FAB2(SCH_1):PAGE88
   203 M_M_CKE<3> @BASEBOARD_FAB2_LIB.BASEBOARD_FAB2(SCH_1):M_M_CKE(3)   I111 @BASEBOARD_FAB2_LIB.BASEBOARD_FAB2(SCH_1):PAGE88
    60 M_M_CKE<2> @BASEBOARD_FAB2_LIB.BASEBOARD_FAB2(SCH_1):M_M_CKE(2)   I111 @BASEBOARD_FAB2_LIB.BASEBOARD_FAB2(SCH_1):PAGE88
   280 M_M_DQ<63> @BASEBOARD_FAB2_LIB.BASEBOARD_FAB2(SCH_1):M_M_DQ(63)   I111 @BASEBOARD_FAB2_LIB.BASEBOARD_FAB2(SCH_1):PAGE88
   135 M_M_DQ<62> @BASEBOARD_FAB2_LIB.BASEBOARD_FAB2(SCH_1):M_M_DQ(62)   I111 @BASEBOARD_FAB2_LIB.BASEBOARD_FAB2(SCH_1):PAGE88
   273 M_M_DQ<61> @BASEBOARD_FAB2_LIB.BASEBOARD_FAB2(SCH_1):M_M_DQ(61)   I111 @BASEBOARD_FAB2_LIB.BASEBOARD_FAB2(SCH_1):PAGE88
   128 M_M_DQ<60> @BASEBOARD_FAB2_LIB.BASEBOARD_FAB2(SCH_1):M_M_DQ(60)   I111 @BASEBOARD_FAB2_LIB.BASEBOARD_FAB2(SCH_1):PAGE88
   282 M_M_DQ<59> @BASEBOARD_FAB2_LIB.BASEBOARD_FAB2(SCH_1):M_M_DQ(59)   I111 @BASEBOARD_FAB2_LIB.BASEBOARD_FAB2(SCH_1):PAGE88
   137 M_M_DQ<58> @BASEBOARD_FAB2_LIB.BASEBOARD_FAB2(SCH_1):M_M_DQ(58)   I111 @BASEBOARD_FAB2_LIB.BASEBOARD_FAB2(SCH_1):PAGE88
   275 M_M_DQ<57> @BASEBOARD_FAB2_LIB.BASEBOARD_FAB2(SCH_1):M_M_DQ(57)   I111 @BASEBOARD_FAB2_LIB.BASEBOARD_FAB2(SCH_1):PAGE88
   130 M_M_DQ<56> @BASEBOARD_FAB2_LIB.BASEBOARD_FAB2(SCH_1):M_M_DQ(56)   I111 @BASEBOARD_FAB2_LIB.BASEBOARD_FAB2(SCH_1):PAGE88
   269 M_M_DQ<55> @BASEBOARD_FAB2_LIB.BASEBOARD_FAB2(SCH_1):M_M_DQ(55)   I111 @BASEBOARD_FAB2_LIB.BASEBOARD_FAB2(SCH_1):PAGE88
   124 M_M_DQ<54> @BASEBOARD_FAB2_LIB.BASEBOARD_FAB2(SCH_1):M_M_DQ(54)   I111 @BASEBOARD_FAB2_LIB.BASEBOARD_FAB2(SCH_1):PAGE88
   262 M_M_DQ<53> @BASEBOARD_FAB2_LIB.BASEBOARD_FAB2(SCH_1):M_M_DQ(53)   I111 @BASEBOARD_FAB2_LIB.BASEBOARD_FAB2(SCH_1):PAGE88
   117 M_M_DQ<52> @BASEBOARD_FAB2_LIB.BASEBOARD_FAB2(SCH_1):M_M_DQ(52)   I111 @BASEBOARD_FAB2_LIB.BASEBOARD_FAB2(SCH_1):PAGE88
   271 M_M_DQ<51> @BASEBOARD_FAB2_LIB.BASEBOARD_FAB2(SCH_1):M_M_DQ(51)   I111 @BASEBOARD_FAB2_LIB.BASEBOARD_FAB2(SCH_1):PAGE88
   126 M_M_DQ<50> @BASEBOARD_FAB2_LIB.BASEBOARD_FAB2(SCH_1):M_M_DQ(50)   I111 @BASEBOARD_FAB2_LIB.BASEBOARD_FAB2(SCH_1):PAGE88
   264 M_M_DQ<49> @BASEBOARD_FAB2_LIB.BASEBOARD_FAB2(SCH_1):M_M_DQ(49)   I111 @BASEBOARD_FAB2_LIB.BASEBOARD_FAB2(SCH_1):PAGE88
   119 M_M_DQ<48> @BASEBOARD_FAB2_LIB.BASEBOARD_FAB2(SCH_1):M_M_DQ(48)   I111 @BASEBOARD_FAB2_LIB.BASEBOARD_FAB2(SCH_1):PAGE88
   258 M_M_DQ<47> @BASEBOARD_FAB2_LIB.BASEBOARD_FAB2(SCH_1):M_M_DQ(47)   I111 @BASEBOARD_FAB2_LIB.BASEBOARD_FAB2(SCH_1):PAGE88
   113 M_M_DQ<46> @BASEBOARD_FAB2_LIB.BASEBOARD_FAB2(SCH_1):M_M_DQ(46)   I111 @BASEBOARD_FAB2_LIB.BASEBOARD_FAB2(SCH_1):PAGE88
   251 M_M_DQ<45> @BASEBOARD_FAB2_LIB.BASEBOARD_FAB2(SCH_1):M_M_DQ(45)   I111 @BASEBOARD_FAB2_LIB.BASEBOARD_FAB2(SCH_1):PAGE88
   106 M_M_DQ<44> @BASEBOARD_FAB2_LIB.BASEBOARD_FAB2(SCH_1):M_M_DQ(44)   I111 @BASEBOARD_FAB2_LIB.BASEBOARD_FAB2(SCH_1):PAGE88
   260 M_M_DQ<43> @BASEBOARD_FAB2_LIB.BASEBOARD_FAB2(SCH_1):M_M_DQ(43)   I111 @BASEBOARD_FAB2_LIB.BASEBOARD_FAB2(SCH_1):PAGE88
   115 M_M_DQ<42> @BASEBOARD_FAB2_LIB.BASEBOARD_FAB2(SCH_1):M_M_DQ(42)   I111 @BASEBOARD_FAB2_LIB.BASEBOARD_FAB2(SCH_1):PAGE88
   253 M_M_DQ<41> @BASEBOARD_FAB2_LIB.BASEBOARD_FAB2(SCH_1):M_M_DQ(41)   I111 @BASEBOARD_FAB2_LIB.BASEBOARD_FAB2(SCH_1):PAGE88
   108 M_M_DQ<40> @BASEBOARD_FAB2_LIB.BASEBOARD_FAB2(SCH_1):M_M_DQ(40)   I111 @BASEBOARD_FAB2_LIB.BASEBOARD_FAB2(SCH_1):PAGE88
   247 M_M_DQ<39> @BASEBOARD_FAB2_LIB.BASEBOARD_FAB2(SCH_1):M_M_DQ(39)   I111 @BASEBOARD_FAB2_LIB.BASEBOARD_FAB2(SCH_1):PAGE88
   102 M_M_DQ<38> @BASEBOARD_FAB2_LIB.BASEBOARD_FAB2(SCH_1):M_M_DQ(38)   I111 @BASEBOARD_FAB2_LIB.BASEBOARD_FAB2(SCH_1):PAGE88
   240 M_M_DQ<37> @BASEBOARD_FAB2_LIB.BASEBOARD_FAB2(SCH_1):M_M_DQ(37)   I111 @BASEBOARD_FAB2_LIB.BASEBOARD_FAB2(SCH_1):PAGE88
    95 M_M_DQ<36> @BASEBOARD_FAB2_LIB.BASEBOARD_FAB2(SCH_1):M_M_DQ(36)   I111 @BASEBOARD_FAB2_LIB.BASEBOARD_FAB2(SCH_1):PAGE88
   249 M_M_DQ<35> @BASEBOARD_FAB2_LIB.BASEBOARD_FAB2(SCH_1):M_M_DQ(35)   I111 @BASEBOARD_FAB2_LIB.BASEBOARD_FAB2(SCH_1):PAGE88
   104 M_M_DQ<34> @BASEBOARD_FAB2_LIB.BASEBOARD_FAB2(SCH_1):M_M_DQ(34)   I111 @BASEBOARD_FAB2_LIB.BASEBOARD_FAB2(SCH_1):PAGE88
   242 M_M_DQ<33> @BASEBOARD_FAB2_LIB.BASEBOARD_FAB2(SCH_1):M_M_DQ(33)   I111 @BASEBOARD_FAB2_LIB.BASEBOARD_FAB2(SCH_1):PAGE88
    97 M_M_DQ<32> @BASEBOARD_FAB2_LIB.BASEBOARD_FAB2(SCH_1):M_M_DQ(32)   I111 @BASEBOARD_FAB2_LIB.BASEBOARD_FAB2(SCH_1):PAGE88
   188 M_M_DQ<31> @BASEBOARD_FAB2_LIB.BASEBOARD_FAB2(SCH_1):M_M_DQ(31)   I111 @BASEBOARD_FAB2_LIB.BASEBOARD_FAB2(SCH_1):PAGE88
    43 M_M_DQ<30> @BASEBOARD_FAB2_LIB.BASEBOARD_FAB2(SCH_1):M_M_DQ(30)   I111 @BASEBOARD_FAB2_LIB.BASEBOARD_FAB2(SCH_1):PAGE88
   181 M_M_DQ<29> @BASEBOARD_FAB2_LIB.BASEBOARD_FAB2(SCH_1):M_M_DQ(29)   I111 @BASEBOARD_FAB2_LIB.BASEBOARD_FAB2(SCH_1):PAGE88
    36 M_M_DQ<28> @BASEBOARD_FAB2_LIB.BASEBOARD_FAB2(SCH_1):M_M_DQ(28)   I111 @BASEBOARD_FAB2_LIB.BASEBOARD_FAB2(SCH_1):PAGE88
   190 M_M_DQ<27> @BASEBOARD_FAB2_LIB.BASEBOARD_FAB2(SCH_1):M_M_DQ(27)   I111 @BASEBOARD_FAB2_LIB.BASEBOARD_FAB2(SCH_1):PAGE88
    45 M_M_DQ<26> @BASEBOARD_FAB2_LIB.BASEBOARD_FAB2(SCH_1):M_M_DQ(26)   I111 @BASEBOARD_FAB2_LIB.BASEBOARD_FAB2(SCH_1):PAGE88
   183 M_M_DQ<25> @BASEBOARD_FAB2_LIB.BASEBOARD_FAB2(SCH_1):M_M_DQ(25)   I111 @BASEBOARD_FAB2_LIB.BASEBOARD_FAB2(SCH_1):PAGE88
    38 M_M_DQ<24> @BASEBOARD_FAB2_LIB.BASEBOARD_FAB2(SCH_1):M_M_DQ(24)   I111 @BASEBOARD_FAB2_LIB.BASEBOARD_FAB2(SCH_1):PAGE88
   177 M_M_DQ<23> @BASEBOARD_FAB2_LIB.BASEBOARD_FAB2(SCH_1):M_M_DQ(23)   I111 @BASEBOARD_FAB2_LIB.BASEBOARD_FAB2(SCH_1):PAGE88
    32 M_M_DQ<22> @BASEBOARD_FAB2_LIB.BASEBOARD_FAB2(SCH_1):M_M_DQ(22)   I111 @BASEBOARD_FAB2_LIB.BASEBOARD_FAB2(SCH_1):PAGE88
   170 M_M_DQ<21> @BASEBOARD_FAB2_LIB.BASEBOARD_FAB2(SCH_1):M_M_DQ(21)   I111 @BASEBOARD_FAB2_LIB.BASEBOARD_FAB2(SCH_1):PAGE88
    25 M_M_DQ<20> @BASEBOARD_FAB2_LIB.BASEBOARD_FAB2(SCH_1):M_M_DQ(20)   I111 @BASEBOARD_FAB2_LIB.BASEBOARD_FAB2(SCH_1):PAGE88
   179 M_M_DQ<19> @BASEBOARD_FAB2_LIB.BASEBOARD_FAB2(SCH_1):M_M_DQ(19)   I111 @BASEBOARD_FAB2_LIB.BASEBOARD_FAB2(SCH_1):PAGE88
    34 M_M_DQ<18> @BASEBOARD_FAB2_LIB.BASEBOARD_FAB2(SCH_1):M_M_DQ(18)   I111 @BASEBOARD_FAB2_LIB.BASEBOARD_FAB2(SCH_1):PAGE88
   172 M_M_DQ<17> @BASEBOARD_FAB2_LIB.BASEBOARD_FAB2(SCH_1):M_M_DQ(17)   I111 @BASEBOARD_FAB2_LIB.BASEBOARD_FAB2(SCH_1):PAGE88
    27 M_M_DQ<16> @BASEBOARD_FAB2_LIB.BASEBOARD_FAB2(SCH_1):M_M_DQ(16)   I111 @BASEBOARD_FAB2_LIB.BASEBOARD_FAB2(SCH_1):PAGE88
   166 M_M_DQ<15> @BASEBOARD_FAB2_LIB.BASEBOARD_FAB2(SCH_1):M_M_DQ(15)   I111 @BASEBOARD_FAB2_LIB.BASEBOARD_FAB2(SCH_1):PAGE88
    21 M_M_DQ<14> @BASEBOARD_FAB2_LIB.BASEBOARD_FAB2(SCH_1):M_M_DQ(14)   I111 @BASEBOARD_FAB2_LIB.BASEBOARD_FAB2(SCH_1):PAGE88
   159 M_M_DQ<13> @BASEBOARD_FAB2_LIB.BASEBOARD_FAB2(SCH_1):M_M_DQ(13)   I111 @BASEBOARD_FAB2_LIB.BASEBOARD_FAB2(SCH_1):PAGE88
    14 M_M_DQ<12> @BASEBOARD_FAB2_LIB.BASEBOARD_FAB2(SCH_1):M_M_DQ(12)   I111 @BASEBOARD_FAB2_LIB.BASEBOARD_FAB2(SCH_1):PAGE88
   168 M_M_DQ<11> @BASEBOARD_FAB2_LIB.BASEBOARD_FAB2(SCH_1):M_M_DQ(11)   I111 @BASEBOARD_FAB2_LIB.BASEBOARD_FAB2(SCH_1):PAGE88
    23 M_M_DQ<10> @BASEBOARD_FAB2_LIB.BASEBOARD_FAB2(SCH_1):M_M_DQ(10)   I111 @BASEBOARD_FAB2_LIB.BASEBOARD_FAB2(SCH_1):PAGE88
   161 M_M_DQ<9> @BASEBOARD_FAB2_LIB.BASEBOARD_FAB2(SCH_1):M_M_DQ(9)   I111 @BASEBOARD_FAB2_LIB.BASEBOARD_FAB2(SCH_1):PAGE88
    16 M_M_DQ<8> @BASEBOARD_FAB2_LIB.BASEBOARD_FAB2(SCH_1):M_M_DQ(8)   I111 @BASEBOARD_FAB2_LIB.BASEBOARD_FAB2(SCH_1):PAGE88
   155 M_M_DQ<7> @BASEBOARD_FAB2_LIB.BASEBOARD_FAB2(SCH_1):M_M_DQ(7)   I111 @BASEBOARD_FAB2_LIB.BASEBOARD_FAB2(SCH_1):PAGE88
    10 M_M_DQ<6> @BASEBOARD_FAB2_LIB.BASEBOARD_FAB2(SCH_1):M_M_DQ(6)   I111 @BASEBOARD_FAB2_LIB.BASEBOARD_FAB2(SCH_1):PAGE88
   148 M_M_DQ<5> @BASEBOARD_FAB2_LIB.BASEBOARD_FAB2(SCH_1):M_M_DQ(5)   I111 @BASEBOARD_FAB2_LIB.BASEBOARD_FAB2(SCH_1):PAGE88
     3 M_M_DQ<4> @BASEBOARD_FAB2_LIB.BASEBOARD_FAB2(SCH_1):M_M_DQ(4)   I111 @BASEBOARD_FAB2_LIB.BASEBOARD_FAB2(SCH_1):PAGE88
   157 M_M_DQ<3> @BASEBOARD_FAB2_LIB.BASEBOARD_FAB2(SCH_1):M_M_DQ(3)   I111 @BASEBOARD_FAB2_LIB.BASEBOARD_FAB2(SCH_1):PAGE88
    12 M_M_DQ<2> @BASEBOARD_FAB2_LIB.BASEBOARD_FAB2(SCH_1):M_M_DQ(2)   I111 @BASEBOARD_FAB2_LIB.BASEBOARD_FAB2(SCH_1):PAGE88
   150 M_M_DQ<1> @BASEBOARD_FAB2_LIB.BASEBOARD_FAB2(SCH_1):M_M_DQ(1)   I111 @BASEBOARD_FAB2_LIB.BASEBOARD_FAB2(SCH_1):PAGE88
     5 M_M_DQ<0> @BASEBOARD_FAB2_LIB.BASEBOARD_FAB2(SCH_1):M_M_DQ(0)   I111 @BASEBOARD_FAB2_LIB.BASEBOARD_FAB2(SCH_1):PAGE88
    78 FM_DIMM_EVENT_COD_N @BASEBOARD_FAB2_LIB.BASEBOARD_FAB2(SCH_1):FM_DIMM_EVENT_COD_N   I111 @BASEBOARD_FAB2_LIB.BASEBOARD_FAB2(SCH_1):PAGE88
    91 M_M_ODT<3> @BASEBOARD_FAB2_LIB.BASEBOARD_FAB2(SCH_1):M_M_ODT(3)   I111 @BASEBOARD_FAB2_LIB.BASEBOARD_FAB2(SCH_1):PAGE88
    87 M_M_ODT<2> @BASEBOARD_FAB2_LIB.BASEBOARD_FAB2(SCH_1):M_M_ODT(2)   I111 @BASEBOARD_FAB2_LIB.BASEBOARD_FAB2(SCH_1):PAGE88
   222 M_M_PAR @BASEBOARD_FAB2_LIB.BASEBOARD_FAB2(SCH_1):M_M_PAR   I111 @BASEBOARD_FAB2_LIB.BASEBOARD_FAB2(SCH_1):PAGE88
    58 M_KLM_RST_N @BASEBOARD_FAB2_LIB.BASEBOARD_FAB2(SCH_1):M_KLM_RST_N   I111 @BASEBOARD_FAB2_LIB.BASEBOARD_FAB2(SCH_1):PAGE88
   144 TP_CH_M_DIMM_M1_RFU_2 @BASEBOARD_FAB2_LIB.BASEBOARD_FAB2(SCH_1):TP_CH_M_DIMM_M1_RFU_2   I111 @BASEBOARD_FAB2_LIB.BASEBOARD_FAB2(SCH_1):PAGE88
   227 TP_CH_M_DIMM_M1_RFU_1 @BASEBOARD_FAB2_LIB.BASEBOARD_FAB2(SCH_1):TP_CH_M_DIMM_M1_RFU_1   I111 @BASEBOARD_FAB2_LIB.BASEBOARD_FAB2(SCH_1):PAGE88
   205 TP_CH_M_DIMM_M1_RFU_0 @BASEBOARD_FAB2_LIB.BASEBOARD_FAB2(SCH_1):TP_CH_M_DIMM_M1_RFU_0   I111 @BASEBOARD_FAB2_LIB.BASEBOARD_FAB2(SCH_1):PAGE88
    84 M_M_CS_N<4> @BASEBOARD_FAB2_LIB.BASEBOARD_FAB2(SCH_1):M_M_CS_N(4)   I111 @BASEBOARD_FAB2_LIB.BASEBOARD_FAB2(SCH_1):PAGE88
    89 M_M_CS_N<5> @BASEBOARD_FAB2_LIB.BASEBOARD_FAB2(SCH_1):M_M_CS_N(5)   I111 @BASEBOARD_FAB2_LIB.BASEBOARD_FAB2(SCH_1):PAGE88
    93 M_M_CS_N<6> @BASEBOARD_FAB2_LIB.BASEBOARD_FAB2(SCH_1):M_M_CS_N(6)   I111 @BASEBOARD_FAB2_LIB.BASEBOARD_FAB2(SCH_1):PAGE88
   237 M_M_CS_N<7> @BASEBOARD_FAB2_LIB.BASEBOARD_FAB2(SCH_1):M_M_CS_N(7)   I111 @BASEBOARD_FAB2_LIB.BASEBOARD_FAB2(SCH_1):PAGE88
   238 PVPP_KLM @BASEBOARD_FAB2_LIB.BASEBOARD_FAB2(SCH_1):PVPP_KLM   I111 @BASEBOARD_FAB2_LIB.BASEBOARD_FAB2(SCH_1):PAGE88
   140    GND @BASEBOARD_FAB2_LIB.BASEBOARD_FAB2(SCH_1):GND   I111 @BASEBOARD_FAB2_LIB.BASEBOARD_FAB2(SCH_1):PAGE88
   139 PVPP_KLM @BASEBOARD_FAB2_LIB.BASEBOARD_FAB2(SCH_1):PVPP_KLM   I111 @BASEBOARD_FAB2_LIB.BASEBOARD_FAB2(SCH_1):PAGE88
   230 FM_ADR_COMPLETE_KLM_N @BASEBOARD_FAB2_LIB.BASEBOARD_FAB2(SCH_1):FM_ADR_COMPLETE_KLM_N   I111 @BASEBOARD_FAB2_LIB.BASEBOARD_FAB2(SCH_1):PAGE88
   141 SMB_DDR_KLM_VPP_SCL @BASEBOARD_FAB2_LIB.BASEBOARD_FAB2(SCH_1):SMB_DDR_KLM_VPP_SCL   I111 @BASEBOARD_FAB2_LIB.BASEBOARD_FAB2(SCH_1):PAGE88
   285 SMB_DDR_KLM_VPP_SDA @BASEBOARD_FAB2_LIB.BASEBOARD_FAB2(SCH_1):SMB_DDR_KLM_VPP_SDA   I111 @BASEBOARD_FAB2_LIB.BASEBOARD_FAB2(SCH_1):PAGE88
   284 PVPP_KLM @BASEBOARD_FAB2_LIB.BASEBOARD_FAB2(SCH_1):PVPP_KLM   I111 @BASEBOARD_FAB2_LIB.BASEBOARD_FAB2(SCH_1):PAGE88
   146 M_M_VREF @BASEBOARD_FAB2_LIB.BASEBOARD_FAB2(SCH_1):M_M_VREF   I111 @BASEBOARD_FAB2_LIB.BASEBOARD_FAB2(SCH_1):PAGE88
   152 M_M_DQS_DN<0> @BASEBOARD_FAB2_LIB.BASEBOARD_FAB2(SCH_1):M_M_DQS_DN(0)    I87 @BASEBOARD_FAB2_LIB.BASEBOARD_FAB2(SCH_1):PAGE88
   153 M_M_DQS_DP<0> @BASEBOARD_FAB2_LIB.BASEBOARD_FAB2(SCH_1):M_M_DQS_DP(0)    I87 @BASEBOARD_FAB2_LIB.BASEBOARD_FAB2(SCH_1):PAGE88
    19 M_M_DQS_DN<10> @BASEBOARD_FAB2_LIB.BASEBOARD_FAB2(SCH_1):M_M_DQS_DN(10)    I87 @BASEBOARD_FAB2_LIB.BASEBOARD_FAB2(SCH_1):PAGE88
    18 M_M_DQS_DP<10> @BASEBOARD_FAB2_LIB.BASEBOARD_FAB2(SCH_1):M_M_DQS_DP(10)    I87 @BASEBOARD_FAB2_LIB.BASEBOARD_FAB2(SCH_1):PAGE88
    30 M_M_DQS_DN<11> @BASEBOARD_FAB2_LIB.BASEBOARD_FAB2(SCH_1):M_M_DQS_DN(11)    I87 @BASEBOARD_FAB2_LIB.BASEBOARD_FAB2(SCH_1):PAGE88
    29 M_M_DQS_DP<11> @BASEBOARD_FAB2_LIB.BASEBOARD_FAB2(SCH_1):M_M_DQS_DP(11)    I87 @BASEBOARD_FAB2_LIB.BASEBOARD_FAB2(SCH_1):PAGE88
    41 M_M_DQS_DN<12> @BASEBOARD_FAB2_LIB.BASEBOARD_FAB2(SCH_1):M_M_DQS_DN(12)    I87 @BASEBOARD_FAB2_LIB.BASEBOARD_FAB2(SCH_1):PAGE88
    40 M_M_DQS_DP<12> @BASEBOARD_FAB2_LIB.BASEBOARD_FAB2(SCH_1):M_M_DQS_DP(12)    I87 @BASEBOARD_FAB2_LIB.BASEBOARD_FAB2(SCH_1):PAGE88
   100 M_M_DQS_DN<13> @BASEBOARD_FAB2_LIB.BASEBOARD_FAB2(SCH_1):M_M_DQS_DN(13)    I87 @BASEBOARD_FAB2_LIB.BASEBOARD_FAB2(SCH_1):PAGE88
    99 M_M_DQS_DP<13> @BASEBOARD_FAB2_LIB.BASEBOARD_FAB2(SCH_1):M_M_DQS_DP(13)    I87 @BASEBOARD_FAB2_LIB.BASEBOARD_FAB2(SCH_1):PAGE88
   111 M_M_DQS_DN<14> @BASEBOARD_FAB2_LIB.BASEBOARD_FAB2(SCH_1):M_M_DQS_DN(14)    I87 @BASEBOARD_FAB2_LIB.BASEBOARD_FAB2(SCH_1):PAGE88
   110 M_M_DQS_DP<14> @BASEBOARD_FAB2_LIB.BASEBOARD_FAB2(SCH_1):M_M_DQS_DP(14)    I87 @BASEBOARD_FAB2_LIB.BASEBOARD_FAB2(SCH_1):PAGE88
   122 M_M_DQS_DN<15> @BASEBOARD_FAB2_LIB.BASEBOARD_FAB2(SCH_1):M_M_DQS_DN(15)    I87 @BASEBOARD_FAB2_LIB.BASEBOARD_FAB2(SCH_1):PAGE88
   121 M_M_DQS_DP<15> @BASEBOARD_FAB2_LIB.BASEBOARD_FAB2(SCH_1):M_M_DQS_DP(15)    I87 @BASEBOARD_FAB2_LIB.BASEBOARD_FAB2(SCH_1):PAGE88
   133 M_M_DQS_DN<16> @BASEBOARD_FAB2_LIB.BASEBOARD_FAB2(SCH_1):M_M_DQS_DN(16)    I87 @BASEBOARD_FAB2_LIB.BASEBOARD_FAB2(SCH_1):PAGE88
   132 M_M_DQS_DP<16> @BASEBOARD_FAB2_LIB.BASEBOARD_FAB2(SCH_1):M_M_DQS_DP(16)    I87 @BASEBOARD_FAB2_LIB.BASEBOARD_FAB2(SCH_1):PAGE88
    52 M_M_DQS_DN<17> @BASEBOARD_FAB2_LIB.BASEBOARD_FAB2(SCH_1):M_M_DQS_DN(17)    I87 @BASEBOARD_FAB2_LIB.BASEBOARD_FAB2(SCH_1):PAGE88
    51 M_M_DQS_DP<17> @BASEBOARD_FAB2_LIB.BASEBOARD_FAB2(SCH_1):M_M_DQS_DP(17)    I87 @BASEBOARD_FAB2_LIB.BASEBOARD_FAB2(SCH_1):PAGE88
   163 M_M_DQS_DN<1> @BASEBOARD_FAB2_LIB.BASEBOARD_FAB2(SCH_1):M_M_DQS_DN(1)    I87 @BASEBOARD_FAB2_LIB.BASEBOARD_FAB2(SCH_1):PAGE88
   164 M_M_DQS_DP<1> @BASEBOARD_FAB2_LIB.BASEBOARD_FAB2(SCH_1):M_M_DQS_DP(1)    I87 @BASEBOARD_FAB2_LIB.BASEBOARD_FAB2(SCH_1):PAGE88
   174 M_M_DQS_DN<2> @BASEBOARD_FAB2_LIB.BASEBOARD_FAB2(SCH_1):M_M_DQS_DN(2)    I87 @BASEBOARD_FAB2_LIB.BASEBOARD_FAB2(SCH_1):PAGE88
   175 M_M_DQS_DP<2> @BASEBOARD_FAB2_LIB.BASEBOARD_FAB2(SCH_1):M_M_DQS_DP(2)    I87 @BASEBOARD_FAB2_LIB.BASEBOARD_FAB2(SCH_1):PAGE88
   185 M_M_DQS_DN<3> @BASEBOARD_FAB2_LIB.BASEBOARD_FAB2(SCH_1):M_M_DQS_DN(3)    I87 @BASEBOARD_FAB2_LIB.BASEBOARD_FAB2(SCH_1):PAGE88
   186 M_M_DQS_DP<3> @BASEBOARD_FAB2_LIB.BASEBOARD_FAB2(SCH_1):M_M_DQS_DP(3)    I87 @BASEBOARD_FAB2_LIB.BASEBOARD_FAB2(SCH_1):PAGE88
   244 M_M_DQS_DN<4> @BASEBOARD_FAB2_LIB.BASEBOARD_FAB2(SCH_1):M_M_DQS_DN(4)    I87 @BASEBOARD_FAB2_LIB.BASEBOARD_FAB2(SCH_1):PAGE88
   245 M_M_DQS_DP<4> @BASEBOARD_FAB2_LIB.BASEBOARD_FAB2(SCH_1):M_M_DQS_DP(4)    I87 @BASEBOARD_FAB2_LIB.BASEBOARD_FAB2(SCH_1):PAGE88
   255 M_M_DQS_DN<5> @BASEBOARD_FAB2_LIB.BASEBOARD_FAB2(SCH_1):M_M_DQS_DN(5)    I87 @BASEBOARD_FAB2_LIB.BASEBOARD_FAB2(SCH_1):PAGE88
   256 M_M_DQS_DP<5> @BASEBOARD_FAB2_LIB.BASEBOARD_FAB2(SCH_1):M_M_DQS_DP(5)    I87 @BASEBOARD_FAB2_LIB.BASEBOARD_FAB2(SCH_1):PAGE88
   266 M_M_DQS_DN<6> @BASEBOARD_FAB2_LIB.BASEBOARD_FAB2(SCH_1):M_M_DQS_DN(6)    I87 @BASEBOARD_FAB2_LIB.BASEBOARD_FAB2(SCH_1):PAGE88
   267 M_M_DQS_DP<6> @BASEBOARD_FAB2_LIB.BASEBOARD_FAB2(SCH_1):M_M_DQS_DP(6)    I87 @BASEBOARD_FAB2_LIB.BASEBOARD_FAB2(SCH_1):PAGE88
   277 M_M_DQS_DN<7> @BASEBOARD_FAB2_LIB.BASEBOARD_FAB2(SCH_1):M_M_DQS_DN(7)    I87 @BASEBOARD_FAB2_LIB.BASEBOARD_FAB2(SCH_1):PAGE88
   278 M_M_DQS_DP<7> @BASEBOARD_FAB2_LIB.BASEBOARD_FAB2(SCH_1):M_M_DQS_DP(7)    I87 @BASEBOARD_FAB2_LIB.BASEBOARD_FAB2(SCH_1):PAGE88
   196 M_M_DQS_DN<8> @BASEBOARD_FAB2_LIB.BASEBOARD_FAB2(SCH_1):M_M_DQS_DN(8)    I87 @BASEBOARD_FAB2_LIB.BASEBOARD_FAB2(SCH_1):PAGE88
   197 M_M_DQS_DP<8> @BASEBOARD_FAB2_LIB.BASEBOARD_FAB2(SCH_1):M_M_DQS_DP(8)    I87 @BASEBOARD_FAB2_LIB.BASEBOARD_FAB2(SCH_1):PAGE88
     8 M_M_DQS_DN<9> @BASEBOARD_FAB2_LIB.BASEBOARD_FAB2(SCH_1):M_M_DQS_DN(9)    I87 @BASEBOARD_FAB2_LIB.BASEBOARD_FAB2(SCH_1):PAGE88
     7 M_M_DQS_DP<9> @BASEBOARD_FAB2_LIB.BASEBOARD_FAB2(SCH_1):M_M_DQS_DP(9)    I87 @BASEBOARD_FAB2_LIB.BASEBOARD_FAB2(SCH_1):PAGE88
     2    GND @BASEBOARD_FAB2_LIB.BASEBOARD_FAB2(SCH_1):GND    I25 @BASEBOARD_FAB2_LIB.BASEBOARD_FAB2(SCH_1):PAGE88
     4    GND @BASEBOARD_FAB2_LIB.BASEBOARD_FAB2(SCH_1):GND    I25 @BASEBOARD_FAB2_LIB.BASEBOARD_FAB2(SCH_1):PAGE88
     6    GND @BASEBOARD_FAB2_LIB.BASEBOARD_FAB2(SCH_1):GND    I25 @BASEBOARD_FAB2_LIB.BASEBOARD_FAB2(SCH_1):PAGE88
     9    GND @BASEBOARD_FAB2_LIB.BASEBOARD_FAB2(SCH_1):GND    I25 @BASEBOARD_FAB2_LIB.BASEBOARD_FAB2(SCH_1):PAGE88
    11    GND @BASEBOARD_FAB2_LIB.BASEBOARD_FAB2(SCH_1):GND    I25 @BASEBOARD_FAB2_LIB.BASEBOARD_FAB2(SCH_1):PAGE88
    13    GND @BASEBOARD_FAB2_LIB.BASEBOARD_FAB2(SCH_1):GND    I25 @BASEBOARD_FAB2_LIB.BASEBOARD_FAB2(SCH_1):PAGE88
    15    GND @BASEBOARD_FAB2_LIB.BASEBOARD_FAB2(SCH_1):GND    I25 @BASEBOARD_FAB2_LIB.BASEBOARD_FAB2(SCH_1):PAGE88
    17    GND @BASEBOARD_FAB2_LIB.BASEBOARD_FAB2(SCH_1):GND    I25 @BASEBOARD_FAB2_LIB.BASEBOARD_FAB2(SCH_1):PAGE88
    20    GND @BASEBOARD_FAB2_LIB.BASEBOARD_FAB2(SCH_1):GND    I25 @BASEBOARD_FAB2_LIB.BASEBOARD_FAB2(SCH_1):PAGE88
    22    GND @BASEBOARD_FAB2_LIB.BASEBOARD_FAB2(SCH_1):GND    I25 @BASEBOARD_FAB2_LIB.BASEBOARD_FAB2(SCH_1):PAGE88
    24    GND @BASEBOARD_FAB2_LIB.BASEBOARD_FAB2(SCH_1):GND    I25 @BASEBOARD_FAB2_LIB.BASEBOARD_FAB2(SCH_1):PAGE88
    26    GND @BASEBOARD_FAB2_LIB.BASEBOARD_FAB2(SCH_1):GND    I25 @BASEBOARD_FAB2_LIB.BASEBOARD_FAB2(SCH_1):PAGE88
    28    GND @BASEBOARD_FAB2_LIB.BASEBOARD_FAB2(SCH_1):GND    I25 @BASEBOARD_FAB2_LIB.BASEBOARD_FAB2(SCH_1):PAGE88
    31    GND @BASEBOARD_FAB2_LIB.BASEBOARD_FAB2(SCH_1):GND    I25 @BASEBOARD_FAB2_LIB.BASEBOARD_FAB2(SCH_1):PAGE88
    33    GND @BASEBOARD_FAB2_LIB.BASEBOARD_FAB2(SCH_1):GND    I25 @BASEBOARD_FAB2_LIB.BASEBOARD_FAB2(SCH_1):PAGE88
    35    GND @BASEBOARD_FAB2_LIB.BASEBOARD_FAB2(SCH_1):GND    I25 @BASEBOARD_FAB2_LIB.BASEBOARD_FAB2(SCH_1):PAGE88
    37    GND @BASEBOARD_FAB2_LIB.BASEBOARD_FAB2(SCH_1):GND    I25 @BASEBOARD_FAB2_LIB.BASEBOARD_FAB2(SCH_1):PAGE88
    39    GND @BASEBOARD_FAB2_LIB.BASEBOARD_FAB2(SCH_1):GND    I25 @BASEBOARD_FAB2_LIB.BASEBOARD_FAB2(SCH_1):PAGE88
    42    GND @BASEBOARD_FAB2_LIB.BASEBOARD_FAB2(SCH_1):GND    I25 @BASEBOARD_FAB2_LIB.BASEBOARD_FAB2(SCH_1):PAGE88
    44    GND @BASEBOARD_FAB2_LIB.BASEBOARD_FAB2(SCH_1):GND    I25 @BASEBOARD_FAB2_LIB.BASEBOARD_FAB2(SCH_1):PAGE88
    46    GND @BASEBOARD_FAB2_LIB.BASEBOARD_FAB2(SCH_1):GND    I25 @BASEBOARD_FAB2_LIB.BASEBOARD_FAB2(SCH_1):PAGE88
    48    GND @BASEBOARD_FAB2_LIB.BASEBOARD_FAB2(SCH_1):GND    I25 @BASEBOARD_FAB2_LIB.BASEBOARD_FAB2(SCH_1):PAGE88
    50    GND @BASEBOARD_FAB2_LIB.BASEBOARD_FAB2(SCH_1):GND    I25 @BASEBOARD_FAB2_LIB.BASEBOARD_FAB2(SCH_1):PAGE88
    53    GND @BASEBOARD_FAB2_LIB.BASEBOARD_FAB2(SCH_1):GND    I25 @BASEBOARD_FAB2_LIB.BASEBOARD_FAB2(SCH_1):PAGE88
    55    GND @BASEBOARD_FAB2_LIB.BASEBOARD_FAB2(SCH_1):GND    I25 @BASEBOARD_FAB2_LIB.BASEBOARD_FAB2(SCH_1):PAGE88
    57    GND @BASEBOARD_FAB2_LIB.BASEBOARD_FAB2(SCH_1):GND    I25 @BASEBOARD_FAB2_LIB.BASEBOARD_FAB2(SCH_1):PAGE88
    94    GND @BASEBOARD_FAB2_LIB.BASEBOARD_FAB2(SCH_1):GND    I25 @BASEBOARD_FAB2_LIB.BASEBOARD_FAB2(SCH_1):PAGE88
    96    GND @BASEBOARD_FAB2_LIB.BASEBOARD_FAB2(SCH_1):GND    I25 @BASEBOARD_FAB2_LIB.BASEBOARD_FAB2(SCH_1):PAGE88
    98    GND @BASEBOARD_FAB2_LIB.BASEBOARD_FAB2(SCH_1):GND    I25 @BASEBOARD_FAB2_LIB.BASEBOARD_FAB2(SCH_1):PAGE88
   101    GND @BASEBOARD_FAB2_LIB.BASEBOARD_FAB2(SCH_1):GND    I25 @BASEBOARD_FAB2_LIB.BASEBOARD_FAB2(SCH_1):PAGE88
   103    GND @BASEBOARD_FAB2_LIB.BASEBOARD_FAB2(SCH_1):GND    I25 @BASEBOARD_FAB2_LIB.BASEBOARD_FAB2(SCH_1):PAGE88
   105    GND @BASEBOARD_FAB2_LIB.BASEBOARD_FAB2(SCH_1):GND    I25 @BASEBOARD_FAB2_LIB.BASEBOARD_FAB2(SCH_1):PAGE88
   107    GND @BASEBOARD_FAB2_LIB.BASEBOARD_FAB2(SCH_1):GND    I25 @BASEBOARD_FAB2_LIB.BASEBOARD_FAB2(SCH_1):PAGE88
   109    GND @BASEBOARD_FAB2_LIB.BASEBOARD_FAB2(SCH_1):GND    I25 @BASEBOARD_FAB2_LIB.BASEBOARD_FAB2(SCH_1):PAGE88
   112    GND @BASEBOARD_FAB2_LIB.BASEBOARD_FAB2(SCH_1):GND    I25 @BASEBOARD_FAB2_LIB.BASEBOARD_FAB2(SCH_1):PAGE88
   114    GND @BASEBOARD_FAB2_LIB.BASEBOARD_FAB2(SCH_1):GND    I25 @BASEBOARD_FAB2_LIB.BASEBOARD_FAB2(SCH_1):PAGE88
   116    GND @BASEBOARD_FAB2_LIB.BASEBOARD_FAB2(SCH_1):GND    I25 @BASEBOARD_FAB2_LIB.BASEBOARD_FAB2(SCH_1):PAGE88
   118    GND @BASEBOARD_FAB2_LIB.BASEBOARD_FAB2(SCH_1):GND    I25 @BASEBOARD_FAB2_LIB.BASEBOARD_FAB2(SCH_1):PAGE88
   120    GND @BASEBOARD_FAB2_LIB.BASEBOARD_FAB2(SCH_1):GND    I25 @BASEBOARD_FAB2_LIB.BASEBOARD_FAB2(SCH_1):PAGE88
   123    GND @BASEBOARD_FAB2_LIB.BASEBOARD_FAB2(SCH_1):GND    I25 @BASEBOARD_FAB2_LIB.BASEBOARD_FAB2(SCH_1):PAGE88
   125    GND @BASEBOARD_FAB2_LIB.BASEBOARD_FAB2(SCH_1):GND    I25 @BASEBOARD_FAB2_LIB.BASEBOARD_FAB2(SCH_1):PAGE88
   127    GND @BASEBOARD_FAB2_LIB.BASEBOARD_FAB2(SCH_1):GND    I25 @BASEBOARD_FAB2_LIB.BASEBOARD_FAB2(SCH_1):PAGE88
   129    GND @BASEBOARD_FAB2_LIB.BASEBOARD_FAB2(SCH_1):GND    I25 @BASEBOARD_FAB2_LIB.BASEBOARD_FAB2(SCH_1):PAGE88
   131    GND @BASEBOARD_FAB2_LIB.BASEBOARD_FAB2(SCH_1):GND    I25 @BASEBOARD_FAB2_LIB.BASEBOARD_FAB2(SCH_1):PAGE88
   134    GND @BASEBOARD_FAB2_LIB.BASEBOARD_FAB2(SCH_1):GND    I25 @BASEBOARD_FAB2_LIB.BASEBOARD_FAB2(SCH_1):PAGE88
   136    GND @BASEBOARD_FAB2_LIB.BASEBOARD_FAB2(SCH_1):GND    I25 @BASEBOARD_FAB2_LIB.BASEBOARD_FAB2(SCH_1):PAGE88
   138    GND @BASEBOARD_FAB2_LIB.BASEBOARD_FAB2(SCH_1):GND    I25 @BASEBOARD_FAB2_LIB.BASEBOARD_FAB2(SCH_1):PAGE88
   147    GND @BASEBOARD_FAB2_LIB.BASEBOARD_FAB2(SCH_1):GND    I25 @BASEBOARD_FAB2_LIB.BASEBOARD_FAB2(SCH_1):PAGE88
   149    GND @BASEBOARD_FAB2_LIB.BASEBOARD_FAB2(SCH_1):GND    I25 @BASEBOARD_FAB2_LIB.BASEBOARD_FAB2(SCH_1):PAGE88
   151    GND @BASEBOARD_FAB2_LIB.BASEBOARD_FAB2(SCH_1):GND    I25 @BASEBOARD_FAB2_LIB.BASEBOARD_FAB2(SCH_1):PAGE88
   154    GND @BASEBOARD_FAB2_LIB.BASEBOARD_FAB2(SCH_1):GND    I25 @BASEBOARD_FAB2_LIB.BASEBOARD_FAB2(SCH_1):PAGE88
   156    GND @BASEBOARD_FAB2_LIB.BASEBOARD_FAB2(SCH_1):GND    I25 @BASEBOARD_FAB2_LIB.BASEBOARD_FAB2(SCH_1):PAGE88
   158    GND @BASEBOARD_FAB2_LIB.BASEBOARD_FAB2(SCH_1):GND    I25 @BASEBOARD_FAB2_LIB.BASEBOARD_FAB2(SCH_1):PAGE88
   160    GND @BASEBOARD_FAB2_LIB.BASEBOARD_FAB2(SCH_1):GND    I25 @BASEBOARD_FAB2_LIB.BASEBOARD_FAB2(SCH_1):PAGE88
   162    GND @BASEBOARD_FAB2_LIB.BASEBOARD_FAB2(SCH_1):GND    I25 @BASEBOARD_FAB2_LIB.BASEBOARD_FAB2(SCH_1):PAGE88
   165    GND @BASEBOARD_FAB2_LIB.BASEBOARD_FAB2(SCH_1):GND    I25 @BASEBOARD_FAB2_LIB.BASEBOARD_FAB2(SCH_1):PAGE88
   167    GND @BASEBOARD_FAB2_LIB.BASEBOARD_FAB2(SCH_1):GND    I25 @BASEBOARD_FAB2_LIB.BASEBOARD_FAB2(SCH_1):PAGE88
   169    GND @BASEBOARD_FAB2_LIB.BASEBOARD_FAB2(SCH_1):GND    I25 @BASEBOARD_FAB2_LIB.BASEBOARD_FAB2(SCH_1):PAGE88
   171    GND @BASEBOARD_FAB2_LIB.BASEBOARD_FAB2(SCH_1):GND    I25 @BASEBOARD_FAB2_LIB.BASEBOARD_FAB2(SCH_1):PAGE88
   173    GND @BASEBOARD_FAB2_LIB.BASEBOARD_FAB2(SCH_1):GND    I25 @BASEBOARD_FAB2_LIB.BASEBOARD_FAB2(SCH_1):PAGE88
   176    GND @BASEBOARD_FAB2_LIB.BASEBOARD_FAB2(SCH_1):GND    I25 @BASEBOARD_FAB2_LIB.BASEBOARD_FAB2(SCH_1):PAGE88
   178    GND @BASEBOARD_FAB2_LIB.BASEBOARD_FAB2(SCH_1):GND    I25 @BASEBOARD_FAB2_LIB.BASEBOARD_FAB2(SCH_1):PAGE88
   180    GND @BASEBOARD_FAB2_LIB.BASEBOARD_FAB2(SCH_1):GND    I25 @BASEBOARD_FAB2_LIB.BASEBOARD_FAB2(SCH_1):PAGE88
   182    GND @BASEBOARD_FAB2_LIB.BASEBOARD_FAB2(SCH_1):GND    I25 @BASEBOARD_FAB2_LIB.BASEBOARD_FAB2(SCH_1):PAGE88
   184    GND @BASEBOARD_FAB2_LIB.BASEBOARD_FAB2(SCH_1):GND    I25 @BASEBOARD_FAB2_LIB.BASEBOARD_FAB2(SCH_1):PAGE88
   187    GND @BASEBOARD_FAB2_LIB.BASEBOARD_FAB2(SCH_1):GND    I25 @BASEBOARD_FAB2_LIB.BASEBOARD_FAB2(SCH_1):PAGE88
   189    GND @BASEBOARD_FAB2_LIB.BASEBOARD_FAB2(SCH_1):GND    I25 @BASEBOARD_FAB2_LIB.BASEBOARD_FAB2(SCH_1):PAGE88
   191    GND @BASEBOARD_FAB2_LIB.BASEBOARD_FAB2(SCH_1):GND    I25 @BASEBOARD_FAB2_LIB.BASEBOARD_FAB2(SCH_1):PAGE88
   193    GND @BASEBOARD_FAB2_LIB.BASEBOARD_FAB2(SCH_1):GND    I25 @BASEBOARD_FAB2_LIB.BASEBOARD_FAB2(SCH_1):PAGE88
   195    GND @BASEBOARD_FAB2_LIB.BASEBOARD_FAB2(SCH_1):GND    I25 @BASEBOARD_FAB2_LIB.BASEBOARD_FAB2(SCH_1):PAGE88
   198    GND @BASEBOARD_FAB2_LIB.BASEBOARD_FAB2(SCH_1):GND    I25 @BASEBOARD_FAB2_LIB.BASEBOARD_FAB2(SCH_1):PAGE88
   200    GND @BASEBOARD_FAB2_LIB.BASEBOARD_FAB2(SCH_1):GND    I25 @BASEBOARD_FAB2_LIB.BASEBOARD_FAB2(SCH_1):PAGE88
   202    GND @BASEBOARD_FAB2_LIB.BASEBOARD_FAB2(SCH_1):GND    I25 @BASEBOARD_FAB2_LIB.BASEBOARD_FAB2(SCH_1):PAGE88
   239    GND @BASEBOARD_FAB2_LIB.BASEBOARD_FAB2(SCH_1):GND    I25 @BASEBOARD_FAB2_LIB.BASEBOARD_FAB2(SCH_1):PAGE88
   241    GND @BASEBOARD_FAB2_LIB.BASEBOARD_FAB2(SCH_1):GND    I25 @BASEBOARD_FAB2_LIB.BASEBOARD_FAB2(SCH_1):PAGE88
   243    GND @BASEBOARD_FAB2_LIB.BASEBOARD_FAB2(SCH_1):GND    I25 @BASEBOARD_FAB2_LIB.BASEBOARD_FAB2(SCH_1):PAGE88
   246    GND @BASEBOARD_FAB2_LIB.BASEBOARD_FAB2(SCH_1):GND    I25 @BASEBOARD_FAB2_LIB.BASEBOARD_FAB2(SCH_1):PAGE88
   248    GND @BASEBOARD_FAB2_LIB.BASEBOARD_FAB2(SCH_1):GND    I25 @BASEBOARD_FAB2_LIB.BASEBOARD_FAB2(SCH_1):PAGE88
   250    GND @BASEBOARD_FAB2_LIB.BASEBOARD_FAB2(SCH_1):GND    I25 @BASEBOARD_FAB2_LIB.BASEBOARD_FAB2(SCH_1):PAGE88
   252    GND @BASEBOARD_FAB2_LIB.BASEBOARD_FAB2(SCH_1):GND    I25 @BASEBOARD_FAB2_LIB.BASEBOARD_FAB2(SCH_1):PAGE88
   254    GND @BASEBOARD_FAB2_LIB.BASEBOARD_FAB2(SCH_1):GND    I25 @BASEBOARD_FAB2_LIB.BASEBOARD_FAB2(SCH_1):PAGE88
   257    GND @BASEBOARD_FAB2_LIB.BASEBOARD_FAB2(SCH_1):GND    I25 @BASEBOARD_FAB2_LIB.BASEBOARD_FAB2(SCH_1):PAGE88
   259    GND @BASEBOARD_FAB2_LIB.BASEBOARD_FAB2(SCH_1):GND    I25 @BASEBOARD_FAB2_LIB.BASEBOARD_FAB2(SCH_1):PAGE88
   261    GND @BASEBOARD_FAB2_LIB.BASEBOARD_FAB2(SCH_1):GND    I25 @BASEBOARD_FAB2_LIB.BASEBOARD_FAB2(SCH_1):PAGE88
   263    GND @BASEBOARD_FAB2_LIB.BASEBOARD_FAB2(SCH_1):GND    I25 @BASEBOARD_FAB2_LIB.BASEBOARD_FAB2(SCH_1):PAGE88
   265    GND @BASEBOARD_FAB2_LIB.BASEBOARD_FAB2(SCH_1):GND    I25 @BASEBOARD_FAB2_LIB.BASEBOARD_FAB2(SCH_1):PAGE88
   268    GND @BASEBOARD_FAB2_LIB.BASEBOARD_FAB2(SCH_1):GND    I25 @BASEBOARD_FAB2_LIB.BASEBOARD_FAB2(SCH_1):PAGE88
   270    GND @BASEBOARD_FAB2_LIB.BASEBOARD_FAB2(SCH_1):GND    I25 @BASEBOARD_FAB2_LIB.BASEBOARD_FAB2(SCH_1):PAGE88
   272    GND @BASEBOARD_FAB2_LIB.BASEBOARD_FAB2(SCH_1):GND    I25 @BASEBOARD_FAB2_LIB.BASEBOARD_FAB2(SCH_1):PAGE88
   274    GND @BASEBOARD_FAB2_LIB.BASEBOARD_FAB2(SCH_1):GND    I25 @BASEBOARD_FAB2_LIB.BASEBOARD_FAB2(SCH_1):PAGE88
   276    GND @BASEBOARD_FAB2_LIB.BASEBOARD_FAB2(SCH_1):GND    I25 @BASEBOARD_FAB2_LIB.BASEBOARD_FAB2(SCH_1):PAGE88
   279    GND @BASEBOARD_FAB2_LIB.BASEBOARD_FAB2(SCH_1):GND    I25 @BASEBOARD_FAB2_LIB.BASEBOARD_FAB2(SCH_1):PAGE88
   281    GND @BASEBOARD_FAB2_LIB.BASEBOARD_FAB2(SCH_1):GND    I25 @BASEBOARD_FAB2_LIB.BASEBOARD_FAB2(SCH_1):PAGE88
   283    GND @BASEBOARD_FAB2_LIB.BASEBOARD_FAB2(SCH_1):GND    I25 @BASEBOARD_FAB2_LIB.BASEBOARD_FAB2(SCH_1):PAGE88
     1 P12V_NVDIMM_KLM @BASEBOARD_FAB2_LIB.BASEBOARD_FAB2(SCH_1):P12V_NVDIMM_KLM   I168 @BASEBOARD_FAB2_LIB.BASEBOARD_FAB2(SCH_1):PAGE88
   145 P12V_NVDIMM_KLM @BASEBOARD_FAB2_LIB.BASEBOARD_FAB2(SCH_1):P12V_NVDIMM_KLM   I168 @BASEBOARD_FAB2_LIB.BASEBOARD_FAB2(SCH_1):PAGE88
    59 PVDDQ_KLM @BASEBOARD_FAB2_LIB.BASEBOARD_FAB2(SCH_1):PVDDQ_KLM   I168 @BASEBOARD_FAB2_LIB.BASEBOARD_FAB2(SCH_1):PAGE88
    61 PVDDQ_KLM @BASEBOARD_FAB2_LIB.BASEBOARD_FAB2(SCH_1):PVDDQ_KLM   I168 @BASEBOARD_FAB2_LIB.BASEBOARD_FAB2(SCH_1):PAGE88
    64 PVDDQ_KLM @BASEBOARD_FAB2_LIB.BASEBOARD_FAB2(SCH_1):PVDDQ_KLM   I168 @BASEBOARD_FAB2_LIB.BASEBOARD_FAB2(SCH_1):PAGE88
    67 PVDDQ_KLM @BASEBOARD_FAB2_LIB.BASEBOARD_FAB2(SCH_1):PVDDQ_KLM   I168 @BASEBOARD_FAB2_LIB.BASEBOARD_FAB2(SCH_1):PAGE88
    70 PVDDQ_KLM @BASEBOARD_FAB2_LIB.BASEBOARD_FAB2(SCH_1):PVDDQ_KLM   I168 @BASEBOARD_FAB2_LIB.BASEBOARD_FAB2(SCH_1):PAGE88
    73 PVDDQ_KLM @BASEBOARD_FAB2_LIB.BASEBOARD_FAB2(SCH_1):PVDDQ_KLM   I168 @BASEBOARD_FAB2_LIB.BASEBOARD_FAB2(SCH_1):PAGE88
    76 PVDDQ_KLM @BASEBOARD_FAB2_LIB.BASEBOARD_FAB2(SCH_1):PVDDQ_KLM   I168 @BASEBOARD_FAB2_LIB.BASEBOARD_FAB2(SCH_1):PAGE88
    80 PVDDQ_KLM @BASEBOARD_FAB2_LIB.BASEBOARD_FAB2(SCH_1):PVDDQ_KLM   I168 @BASEBOARD_FAB2_LIB.BASEBOARD_FAB2(SCH_1):PAGE88
    83 PVDDQ_KLM @BASEBOARD_FAB2_LIB.BASEBOARD_FAB2(SCH_1):PVDDQ_KLM   I168 @BASEBOARD_FAB2_LIB.BASEBOARD_FAB2(SCH_1):PAGE88
    85 PVDDQ_KLM @BASEBOARD_FAB2_LIB.BASEBOARD_FAB2(SCH_1):PVDDQ_KLM   I168 @BASEBOARD_FAB2_LIB.BASEBOARD_FAB2(SCH_1):PAGE88
    88 PVDDQ_KLM @BASEBOARD_FAB2_LIB.BASEBOARD_FAB2(SCH_1):PVDDQ_KLM   I168 @BASEBOARD_FAB2_LIB.BASEBOARD_FAB2(SCH_1):PAGE88
    90 PVDDQ_KLM @BASEBOARD_FAB2_LIB.BASEBOARD_FAB2(SCH_1):PVDDQ_KLM   I168 @BASEBOARD_FAB2_LIB.BASEBOARD_FAB2(SCH_1):PAGE88
    92 PVDDQ_KLM @BASEBOARD_FAB2_LIB.BASEBOARD_FAB2(SCH_1):PVDDQ_KLM   I168 @BASEBOARD_FAB2_LIB.BASEBOARD_FAB2(SCH_1):PAGE88
   204 PVDDQ_KLM @BASEBOARD_FAB2_LIB.BASEBOARD_FAB2(SCH_1):PVDDQ_KLM   I168 @BASEBOARD_FAB2_LIB.BASEBOARD_FAB2(SCH_1):PAGE88
   206 PVDDQ_KLM @BASEBOARD_FAB2_LIB.BASEBOARD_FAB2(SCH_1):PVDDQ_KLM   I168 @BASEBOARD_FAB2_LIB.BASEBOARD_FAB2(SCH_1):PAGE88
   209 PVDDQ_KLM @BASEBOARD_FAB2_LIB.BASEBOARD_FAB2(SCH_1):PVDDQ_KLM   I168 @BASEBOARD_FAB2_LIB.BASEBOARD_FAB2(SCH_1):PAGE88
   212 PVDDQ_KLM @BASEBOARD_FAB2_LIB.BASEBOARD_FAB2(SCH_1):PVDDQ_KLM   I168 @BASEBOARD_FAB2_LIB.BASEBOARD_FAB2(SCH_1):PAGE88
   215 PVDDQ_KLM @BASEBOARD_FAB2_LIB.BASEBOARD_FAB2(SCH_1):PVDDQ_KLM   I168 @BASEBOARD_FAB2_LIB.BASEBOARD_FAB2(SCH_1):PAGE88
   217 PVDDQ_KLM @BASEBOARD_FAB2_LIB.BASEBOARD_FAB2(SCH_1):PVDDQ_KLM   I168 @BASEBOARD_FAB2_LIB.BASEBOARD_FAB2(SCH_1):PAGE88
   220 PVDDQ_KLM @BASEBOARD_FAB2_LIB.BASEBOARD_FAB2(SCH_1):PVDDQ_KLM   I168 @BASEBOARD_FAB2_LIB.BASEBOARD_FAB2(SCH_1):PAGE88
   223 PVDDQ_KLM @BASEBOARD_FAB2_LIB.BASEBOARD_FAB2(SCH_1):PVDDQ_KLM   I168 @BASEBOARD_FAB2_LIB.BASEBOARD_FAB2(SCH_1):PAGE88
   226 PVDDQ_KLM @BASEBOARD_FAB2_LIB.BASEBOARD_FAB2(SCH_1):PVDDQ_KLM   I168 @BASEBOARD_FAB2_LIB.BASEBOARD_FAB2(SCH_1):PAGE88
   229 PVDDQ_KLM @BASEBOARD_FAB2_LIB.BASEBOARD_FAB2(SCH_1):PVDDQ_KLM   I168 @BASEBOARD_FAB2_LIB.BASEBOARD_FAB2(SCH_1):PAGE88
   231 PVDDQ_KLM @BASEBOARD_FAB2_LIB.BASEBOARD_FAB2(SCH_1):PVDDQ_KLM   I168 @BASEBOARD_FAB2_LIB.BASEBOARD_FAB2(SCH_1):PAGE88
   233 PVDDQ_KLM @BASEBOARD_FAB2_LIB.BASEBOARD_FAB2(SCH_1):PVDDQ_KLM   I168 @BASEBOARD_FAB2_LIB.BASEBOARD_FAB2(SCH_1):PAGE88
   236 PVDDQ_KLM @BASEBOARD_FAB2_LIB.BASEBOARD_FAB2(SCH_1):PVDDQ_KLM   I168 @BASEBOARD_FAB2_LIB.BASEBOARD_FAB2(SCH_1):PAGE88
   142 PVPP_KLM @BASEBOARD_FAB2_LIB.BASEBOARD_FAB2(SCH_1):PVPP_KLM   I168 @BASEBOARD_FAB2_LIB.BASEBOARD_FAB2(SCH_1):PAGE88
   143 PVPP_KLM @BASEBOARD_FAB2_LIB.BASEBOARD_FAB2(SCH_1):PVPP_KLM   I168 @BASEBOARD_FAB2_LIB.BASEBOARD_FAB2(SCH_1):PAGE88
   288 PVPP_KLM @BASEBOARD_FAB2_LIB.BASEBOARD_FAB2(SCH_1):PVPP_KLM   I168 @BASEBOARD_FAB2_LIB.BASEBOARD_FAB2(SCH_1):PAGE88
   286 PVPP_KLM @BASEBOARD_FAB2_LIB.BASEBOARD_FAB2(SCH_1):PVPP_KLM   I168 @BASEBOARD_FAB2_LIB.BASEBOARD_FAB2(SCH_1):PAGE88
   287 PVPP_KLM @BASEBOARD_FAB2_LIB.BASEBOARD_FAB2(SCH_1):PVPP_KLM   I168 @BASEBOARD_FAB2_LIB.BASEBOARD_FAB2(SCH_1):PAGE88
    77 PVTT_KLM @BASEBOARD_FAB2_LIB.BASEBOARD_FAB2(SCH_1):PVTT_KLM   I168 @BASEBOARD_FAB2_LIB.BASEBOARD_FAB2(SCH_1):PAGE88
   221 PVTT_KLM @BASEBOARD_FAB2_LIB.BASEBOARD_FAB2(SCH_1):PVTT_KLM   I168 @BASEBOARD_FAB2_LIB.BASEBOARD_FAB2(SCH_1):PAGE88

J9L2 SCONN288_H44441003_PIP-SCONN,HA
    79 M_L_MA<0> @BASEBOARD_FAB2_LIB.BASEBOARD_FAB2(SCH_1):M_L_MA(0)    I12 @BASEBOARD_FAB2_LIB.BASEBOARD_FAB2(SCH_1):PAGE86
    72 M_L_MA<1> @BASEBOARD_FAB2_LIB.BASEBOARD_FAB2(SCH_1):M_L_MA(1)    I12 @BASEBOARD_FAB2_LIB.BASEBOARD_FAB2(SCH_1):PAGE86
   225 M_L_MA<10> @BASEBOARD_FAB2_LIB.BASEBOARD_FAB2(SCH_1):M_L_MA(10)    I12 @BASEBOARD_FAB2_LIB.BASEBOARD_FAB2(SCH_1):PAGE86
   210 M_L_MA<11> @BASEBOARD_FAB2_LIB.BASEBOARD_FAB2(SCH_1):M_L_MA(11)    I12 @BASEBOARD_FAB2_LIB.BASEBOARD_FAB2(SCH_1):PAGE86
    65 M_L_MA<12> @BASEBOARD_FAB2_LIB.BASEBOARD_FAB2(SCH_1):M_L_MA(12)    I12 @BASEBOARD_FAB2_LIB.BASEBOARD_FAB2(SCH_1):PAGE86
   232 M_L_MA<13> @BASEBOARD_FAB2_LIB.BASEBOARD_FAB2(SCH_1):M_L_MA(13)    I12 @BASEBOARD_FAB2_LIB.BASEBOARD_FAB2(SCH_1):PAGE86
   228 M_L_MA<14> @BASEBOARD_FAB2_LIB.BASEBOARD_FAB2(SCH_1):M_L_MA(14)    I12 @BASEBOARD_FAB2_LIB.BASEBOARD_FAB2(SCH_1):PAGE86
    86 M_L_MA<15> @BASEBOARD_FAB2_LIB.BASEBOARD_FAB2(SCH_1):M_L_MA(15)    I12 @BASEBOARD_FAB2_LIB.BASEBOARD_FAB2(SCH_1):PAGE86
    82 M_L_MA<16> @BASEBOARD_FAB2_LIB.BASEBOARD_FAB2(SCH_1):M_L_MA(16)    I12 @BASEBOARD_FAB2_LIB.BASEBOARD_FAB2(SCH_1):PAGE86
   234 M_L_MA<17> @BASEBOARD_FAB2_LIB.BASEBOARD_FAB2(SCH_1):M_L_MA(17)    I12 @BASEBOARD_FAB2_LIB.BASEBOARD_FAB2(SCH_1):PAGE86
   216 M_L_MA<2> @BASEBOARD_FAB2_LIB.BASEBOARD_FAB2(SCH_1):M_L_MA(2)    I12 @BASEBOARD_FAB2_LIB.BASEBOARD_FAB2(SCH_1):PAGE86
    71 M_L_MA<3> @BASEBOARD_FAB2_LIB.BASEBOARD_FAB2(SCH_1):M_L_MA(3)    I12 @BASEBOARD_FAB2_LIB.BASEBOARD_FAB2(SCH_1):PAGE86
   214 M_L_MA<4> @BASEBOARD_FAB2_LIB.BASEBOARD_FAB2(SCH_1):M_L_MA(4)    I12 @BASEBOARD_FAB2_LIB.BASEBOARD_FAB2(SCH_1):PAGE86
   213 M_L_MA<5> @BASEBOARD_FAB2_LIB.BASEBOARD_FAB2(SCH_1):M_L_MA(5)    I12 @BASEBOARD_FAB2_LIB.BASEBOARD_FAB2(SCH_1):PAGE86
    69 M_L_MA<6> @BASEBOARD_FAB2_LIB.BASEBOARD_FAB2(SCH_1):M_L_MA(6)    I12 @BASEBOARD_FAB2_LIB.BASEBOARD_FAB2(SCH_1):PAGE86
   211 M_L_MA<7> @BASEBOARD_FAB2_LIB.BASEBOARD_FAB2(SCH_1):M_L_MA(7)    I12 @BASEBOARD_FAB2_LIB.BASEBOARD_FAB2(SCH_1):PAGE86
    68 M_L_MA<8> @BASEBOARD_FAB2_LIB.BASEBOARD_FAB2(SCH_1):M_L_MA(8)    I12 @BASEBOARD_FAB2_LIB.BASEBOARD_FAB2(SCH_1):PAGE86
    66 M_L_MA<9> @BASEBOARD_FAB2_LIB.BASEBOARD_FAB2(SCH_1):M_L_MA(9)    I12 @BASEBOARD_FAB2_LIB.BASEBOARD_FAB2(SCH_1):PAGE86
    62 M_L_ACT_N @BASEBOARD_FAB2_LIB.BASEBOARD_FAB2(SCH_1):M_L_ACT_N    I12 @BASEBOARD_FAB2_LIB.BASEBOARD_FAB2(SCH_1):PAGE86
   208 M_L_ALERT_N @BASEBOARD_FAB2_LIB.BASEBOARD_FAB2(SCH_1):M_L_ALERT_N    I12 @BASEBOARD_FAB2_LIB.BASEBOARD_FAB2(SCH_1):PAGE86
   224 M_L_BA<1> @BASEBOARD_FAB2_LIB.BASEBOARD_FAB2(SCH_1):M_L_BA(1)    I12 @BASEBOARD_FAB2_LIB.BASEBOARD_FAB2(SCH_1):PAGE86
    81 M_L_BA<0> @BASEBOARD_FAB2_LIB.BASEBOARD_FAB2(SCH_1):M_L_BA(0)    I12 @BASEBOARD_FAB2_LIB.BASEBOARD_FAB2(SCH_1):PAGE86
   207 M_L_BG<1> @BASEBOARD_FAB2_LIB.BASEBOARD_FAB2(SCH_1):M_L_BG(1)    I12 @BASEBOARD_FAB2_LIB.BASEBOARD_FAB2(SCH_1):PAGE86
    63 M_L_BG<0> @BASEBOARD_FAB2_LIB.BASEBOARD_FAB2(SCH_1):M_L_BG(0)    I12 @BASEBOARD_FAB2_LIB.BASEBOARD_FAB2(SCH_1):PAGE86
   235 M_L_C<2> @BASEBOARD_FAB2_LIB.BASEBOARD_FAB2(SCH_1):M_L_C(2)    I12 @BASEBOARD_FAB2_LIB.BASEBOARD_FAB2(SCH_1):PAGE86
   199 M_L_ECC<7> @BASEBOARD_FAB2_LIB.BASEBOARD_FAB2(SCH_1):M_L_ECC(7)    I12 @BASEBOARD_FAB2_LIB.BASEBOARD_FAB2(SCH_1):PAGE86
    54 M_L_ECC<6> @BASEBOARD_FAB2_LIB.BASEBOARD_FAB2(SCH_1):M_L_ECC(6)    I12 @BASEBOARD_FAB2_LIB.BASEBOARD_FAB2(SCH_1):PAGE86
   192 M_L_ECC<5> @BASEBOARD_FAB2_LIB.BASEBOARD_FAB2(SCH_1):M_L_ECC(5)    I12 @BASEBOARD_FAB2_LIB.BASEBOARD_FAB2(SCH_1):PAGE86
    47 M_L_ECC<4> @BASEBOARD_FAB2_LIB.BASEBOARD_FAB2(SCH_1):M_L_ECC(4)    I12 @BASEBOARD_FAB2_LIB.BASEBOARD_FAB2(SCH_1):PAGE86
   201 M_L_ECC<3> @BASEBOARD_FAB2_LIB.BASEBOARD_FAB2(SCH_1):M_L_ECC(3)    I12 @BASEBOARD_FAB2_LIB.BASEBOARD_FAB2(SCH_1):PAGE86
    56 M_L_ECC<2> @BASEBOARD_FAB2_LIB.BASEBOARD_FAB2(SCH_1):M_L_ECC(2)    I12 @BASEBOARD_FAB2_LIB.BASEBOARD_FAB2(SCH_1):PAGE86
   194 M_L_ECC<1> @BASEBOARD_FAB2_LIB.BASEBOARD_FAB2(SCH_1):M_L_ECC(1)    I12 @BASEBOARD_FAB2_LIB.BASEBOARD_FAB2(SCH_1):PAGE86
    49 M_L_ECC<0> @BASEBOARD_FAB2_LIB.BASEBOARD_FAB2(SCH_1):M_L_ECC(0)    I12 @BASEBOARD_FAB2_LIB.BASEBOARD_FAB2(SCH_1):PAGE86
    75 M_L_CLK_DN<2> @BASEBOARD_FAB2_LIB.BASEBOARD_FAB2(SCH_1):M_L_CLK_DN(2)    I12 @BASEBOARD_FAB2_LIB.BASEBOARD_FAB2(SCH_1):PAGE86
    74 M_L_CLK_DP<2> @BASEBOARD_FAB2_LIB.BASEBOARD_FAB2(SCH_1):M_L_CLK_DP(2)    I12 @BASEBOARD_FAB2_LIB.BASEBOARD_FAB2(SCH_1):PAGE86
   219 M_L_CLK_DN<3> @BASEBOARD_FAB2_LIB.BASEBOARD_FAB2(SCH_1):M_L_CLK_DN(3)    I12 @BASEBOARD_FAB2_LIB.BASEBOARD_FAB2(SCH_1):PAGE86
   218 M_L_CLK_DP<3> @BASEBOARD_FAB2_LIB.BASEBOARD_FAB2(SCH_1):M_L_CLK_DP(3)    I12 @BASEBOARD_FAB2_LIB.BASEBOARD_FAB2(SCH_1):PAGE86
   203 M_L_CKE<3> @BASEBOARD_FAB2_LIB.BASEBOARD_FAB2(SCH_1):M_L_CKE(3)    I12 @BASEBOARD_FAB2_LIB.BASEBOARD_FAB2(SCH_1):PAGE86
    60 M_L_CKE<2> @BASEBOARD_FAB2_LIB.BASEBOARD_FAB2(SCH_1):M_L_CKE(2)    I12 @BASEBOARD_FAB2_LIB.BASEBOARD_FAB2(SCH_1):PAGE86
   280 M_L_DQ<63> @BASEBOARD_FAB2_LIB.BASEBOARD_FAB2(SCH_1):M_L_DQ(63)    I12 @BASEBOARD_FAB2_LIB.BASEBOARD_FAB2(SCH_1):PAGE86
   135 M_L_DQ<62> @BASEBOARD_FAB2_LIB.BASEBOARD_FAB2(SCH_1):M_L_DQ(62)    I12 @BASEBOARD_FAB2_LIB.BASEBOARD_FAB2(SCH_1):PAGE86
   273 M_L_DQ<61> @BASEBOARD_FAB2_LIB.BASEBOARD_FAB2(SCH_1):M_L_DQ(61)    I12 @BASEBOARD_FAB2_LIB.BASEBOARD_FAB2(SCH_1):PAGE86
   128 M_L_DQ<60> @BASEBOARD_FAB2_LIB.BASEBOARD_FAB2(SCH_1):M_L_DQ(60)    I12 @BASEBOARD_FAB2_LIB.BASEBOARD_FAB2(SCH_1):PAGE86
   282 M_L_DQ<59> @BASEBOARD_FAB2_LIB.BASEBOARD_FAB2(SCH_1):M_L_DQ(59)    I12 @BASEBOARD_FAB2_LIB.BASEBOARD_FAB2(SCH_1):PAGE86
   137 M_L_DQ<58> @BASEBOARD_FAB2_LIB.BASEBOARD_FAB2(SCH_1):M_L_DQ(58)    I12 @BASEBOARD_FAB2_LIB.BASEBOARD_FAB2(SCH_1):PAGE86
   275 M_L_DQ<57> @BASEBOARD_FAB2_LIB.BASEBOARD_FAB2(SCH_1):M_L_DQ(57)    I12 @BASEBOARD_FAB2_LIB.BASEBOARD_FAB2(SCH_1):PAGE86
   130 M_L_DQ<56> @BASEBOARD_FAB2_LIB.BASEBOARD_FAB2(SCH_1):M_L_DQ(56)    I12 @BASEBOARD_FAB2_LIB.BASEBOARD_FAB2(SCH_1):PAGE86
   269 M_L_DQ<55> @BASEBOARD_FAB2_LIB.BASEBOARD_FAB2(SCH_1):M_L_DQ(55)    I12 @BASEBOARD_FAB2_LIB.BASEBOARD_FAB2(SCH_1):PAGE86
   124 M_L_DQ<54> @BASEBOARD_FAB2_LIB.BASEBOARD_FAB2(SCH_1):M_L_DQ(54)    I12 @BASEBOARD_FAB2_LIB.BASEBOARD_FAB2(SCH_1):PAGE86
   262 M_L_DQ<53> @BASEBOARD_FAB2_LIB.BASEBOARD_FAB2(SCH_1):M_L_DQ(53)    I12 @BASEBOARD_FAB2_LIB.BASEBOARD_FAB2(SCH_1):PAGE86
   117 M_L_DQ<52> @BASEBOARD_FAB2_LIB.BASEBOARD_FAB2(SCH_1):M_L_DQ(52)    I12 @BASEBOARD_FAB2_LIB.BASEBOARD_FAB2(SCH_1):PAGE86
   271 M_L_DQ<51> @BASEBOARD_FAB2_LIB.BASEBOARD_FAB2(SCH_1):M_L_DQ(51)    I12 @BASEBOARD_FAB2_LIB.BASEBOARD_FAB2(SCH_1):PAGE86
   126 M_L_DQ<50> @BASEBOARD_FAB2_LIB.BASEBOARD_FAB2(SCH_1):M_L_DQ(50)    I12 @BASEBOARD_FAB2_LIB.BASEBOARD_FAB2(SCH_1):PAGE86
   264 M_L_DQ<49> @BASEBOARD_FAB2_LIB.BASEBOARD_FAB2(SCH_1):M_L_DQ(49)    I12 @BASEBOARD_FAB2_LIB.BASEBOARD_FAB2(SCH_1):PAGE86
   119 M_L_DQ<48> @BASEBOARD_FAB2_LIB.BASEBOARD_FAB2(SCH_1):M_L_DQ(48)    I12 @BASEBOARD_FAB2_LIB.BASEBOARD_FAB2(SCH_1):PAGE86
   258 M_L_DQ<47> @BASEBOARD_FAB2_LIB.BASEBOARD_FAB2(SCH_1):M_L_DQ(47)    I12 @BASEBOARD_FAB2_LIB.BASEBOARD_FAB2(SCH_1):PAGE86
   113 M_L_DQ<46> @BASEBOARD_FAB2_LIB.BASEBOARD_FAB2(SCH_1):M_L_DQ(46)    I12 @BASEBOARD_FAB2_LIB.BASEBOARD_FAB2(SCH_1):PAGE86
   251 M_L_DQ<45> @BASEBOARD_FAB2_LIB.BASEBOARD_FAB2(SCH_1):M_L_DQ(45)    I12 @BASEBOARD_FAB2_LIB.BASEBOARD_FAB2(SCH_1):PAGE86
   106 M_L_DQ<44> @BASEBOARD_FAB2_LIB.BASEBOARD_FAB2(SCH_1):M_L_DQ(44)    I12 @BASEBOARD_FAB2_LIB.BASEBOARD_FAB2(SCH_1):PAGE86
   260 M_L_DQ<43> @BASEBOARD_FAB2_LIB.BASEBOARD_FAB2(SCH_1):M_L_DQ(43)    I12 @BASEBOARD_FAB2_LIB.BASEBOARD_FAB2(SCH_1):PAGE86
   115 M_L_DQ<42> @BASEBOARD_FAB2_LIB.BASEBOARD_FAB2(SCH_1):M_L_DQ(42)    I12 @BASEBOARD_FAB2_LIB.BASEBOARD_FAB2(SCH_1):PAGE86
   253 M_L_DQ<41> @BASEBOARD_FAB2_LIB.BASEBOARD_FAB2(SCH_1):M_L_DQ(41)    I12 @BASEBOARD_FAB2_LIB.BASEBOARD_FAB2(SCH_1):PAGE86
   108 M_L_DQ<40> @BASEBOARD_FAB2_LIB.BASEBOARD_FAB2(SCH_1):M_L_DQ(40)    I12 @BASEBOARD_FAB2_LIB.BASEBOARD_FAB2(SCH_1):PAGE86
   247 M_L_DQ<39> @BASEBOARD_FAB2_LIB.BASEBOARD_FAB2(SCH_1):M_L_DQ(39)    I12 @BASEBOARD_FAB2_LIB.BASEBOARD_FAB2(SCH_1):PAGE86
   102 M_L_DQ<38> @BASEBOARD_FAB2_LIB.BASEBOARD_FAB2(SCH_1):M_L_DQ(38)    I12 @BASEBOARD_FAB2_LIB.BASEBOARD_FAB2(SCH_1):PAGE86
   240 M_L_DQ<37> @BASEBOARD_FAB2_LIB.BASEBOARD_FAB2(SCH_1):M_L_DQ(37)    I12 @BASEBOARD_FAB2_LIB.BASEBOARD_FAB2(SCH_1):PAGE86
    95 M_L_DQ<36> @BASEBOARD_FAB2_LIB.BASEBOARD_FAB2(SCH_1):M_L_DQ(36)    I12 @BASEBOARD_FAB2_LIB.BASEBOARD_FAB2(SCH_1):PAGE86
   249 M_L_DQ<35> @BASEBOARD_FAB2_LIB.BASEBOARD_FAB2(SCH_1):M_L_DQ(35)    I12 @BASEBOARD_FAB2_LIB.BASEBOARD_FAB2(SCH_1):PAGE86
   104 M_L_DQ<34> @BASEBOARD_FAB2_LIB.BASEBOARD_FAB2(SCH_1):M_L_DQ(34)    I12 @BASEBOARD_FAB2_LIB.BASEBOARD_FAB2(SCH_1):PAGE86
   242 M_L_DQ<33> @BASEBOARD_FAB2_LIB.BASEBOARD_FAB2(SCH_1):M_L_DQ(33)    I12 @BASEBOARD_FAB2_LIB.BASEBOARD_FAB2(SCH_1):PAGE86
    97 M_L_DQ<32> @BASEBOARD_FAB2_LIB.BASEBOARD_FAB2(SCH_1):M_L_DQ(32)    I12 @BASEBOARD_FAB2_LIB.BASEBOARD_FAB2(SCH_1):PAGE86
   188 M_L_DQ<31> @BASEBOARD_FAB2_LIB.BASEBOARD_FAB2(SCH_1):M_L_DQ(31)    I12 @BASEBOARD_FAB2_LIB.BASEBOARD_FAB2(SCH_1):PAGE86
    43 M_L_DQ<30> @BASEBOARD_FAB2_LIB.BASEBOARD_FAB2(SCH_1):M_L_DQ(30)    I12 @BASEBOARD_FAB2_LIB.BASEBOARD_FAB2(SCH_1):PAGE86
   181 M_L_DQ<29> @BASEBOARD_FAB2_LIB.BASEBOARD_FAB2(SCH_1):M_L_DQ(29)    I12 @BASEBOARD_FAB2_LIB.BASEBOARD_FAB2(SCH_1):PAGE86
    36 M_L_DQ<28> @BASEBOARD_FAB2_LIB.BASEBOARD_FAB2(SCH_1):M_L_DQ(28)    I12 @BASEBOARD_FAB2_LIB.BASEBOARD_FAB2(SCH_1):PAGE86
   190 M_L_DQ<27> @BASEBOARD_FAB2_LIB.BASEBOARD_FAB2(SCH_1):M_L_DQ(27)    I12 @BASEBOARD_FAB2_LIB.BASEBOARD_FAB2(SCH_1):PAGE86
    45 M_L_DQ<26> @BASEBOARD_FAB2_LIB.BASEBOARD_FAB2(SCH_1):M_L_DQ(26)    I12 @BASEBOARD_FAB2_LIB.BASEBOARD_FAB2(SCH_1):PAGE86
   183 M_L_DQ<25> @BASEBOARD_FAB2_LIB.BASEBOARD_FAB2(SCH_1):M_L_DQ(25)    I12 @BASEBOARD_FAB2_LIB.BASEBOARD_FAB2(SCH_1):PAGE86
    38 M_L_DQ<24> @BASEBOARD_FAB2_LIB.BASEBOARD_FAB2(SCH_1):M_L_DQ(24)    I12 @BASEBOARD_FAB2_LIB.BASEBOARD_FAB2(SCH_1):PAGE86
   177 M_L_DQ<23> @BASEBOARD_FAB2_LIB.BASEBOARD_FAB2(SCH_1):M_L_DQ(23)    I12 @BASEBOARD_FAB2_LIB.BASEBOARD_FAB2(SCH_1):PAGE86
    32 M_L_DQ<22> @BASEBOARD_FAB2_LIB.BASEBOARD_FAB2(SCH_1):M_L_DQ(22)    I12 @BASEBOARD_FAB2_LIB.BASEBOARD_FAB2(SCH_1):PAGE86
   170 M_L_DQ<21> @BASEBOARD_FAB2_LIB.BASEBOARD_FAB2(SCH_1):M_L_DQ(21)    I12 @BASEBOARD_FAB2_LIB.BASEBOARD_FAB2(SCH_1):PAGE86
    25 M_L_DQ<20> @BASEBOARD_FAB2_LIB.BASEBOARD_FAB2(SCH_1):M_L_DQ(20)    I12 @BASEBOARD_FAB2_LIB.BASEBOARD_FAB2(SCH_1):PAGE86
   179 M_L_DQ<19> @BASEBOARD_FAB2_LIB.BASEBOARD_FAB2(SCH_1):M_L_DQ(19)    I12 @BASEBOARD_FAB2_LIB.BASEBOARD_FAB2(SCH_1):PAGE86
    34 M_L_DQ<18> @BASEBOARD_FAB2_LIB.BASEBOARD_FAB2(SCH_1):M_L_DQ(18)    I12 @BASEBOARD_FAB2_LIB.BASEBOARD_FAB2(SCH_1):PAGE86
   172 M_L_DQ<17> @BASEBOARD_FAB2_LIB.BASEBOARD_FAB2(SCH_1):M_L_DQ(17)    I12 @BASEBOARD_FAB2_LIB.BASEBOARD_FAB2(SCH_1):PAGE86
    27 M_L_DQ<16> @BASEBOARD_FAB2_LIB.BASEBOARD_FAB2(SCH_1):M_L_DQ(16)    I12 @BASEBOARD_FAB2_LIB.BASEBOARD_FAB2(SCH_1):PAGE86
   166 M_L_DQ<15> @BASEBOARD_FAB2_LIB.BASEBOARD_FAB2(SCH_1):M_L_DQ(15)    I12 @BASEBOARD_FAB2_LIB.BASEBOARD_FAB2(SCH_1):PAGE86
    21 M_L_DQ<14> @BASEBOARD_FAB2_LIB.BASEBOARD_FAB2(SCH_1):M_L_DQ(14)    I12 @BASEBOARD_FAB2_LIB.BASEBOARD_FAB2(SCH_1):PAGE86
   159 M_L_DQ<13> @BASEBOARD_FAB2_LIB.BASEBOARD_FAB2(SCH_1):M_L_DQ(13)    I12 @BASEBOARD_FAB2_LIB.BASEBOARD_FAB2(SCH_1):PAGE86
    14 M_L_DQ<12> @BASEBOARD_FAB2_LIB.BASEBOARD_FAB2(SCH_1):M_L_DQ(12)    I12 @BASEBOARD_FAB2_LIB.BASEBOARD_FAB2(SCH_1):PAGE86
   168 M_L_DQ<11> @BASEBOARD_FAB2_LIB.BASEBOARD_FAB2(SCH_1):M_L_DQ(11)    I12 @BASEBOARD_FAB2_LIB.BASEBOARD_FAB2(SCH_1):PAGE86
    23 M_L_DQ<10> @BASEBOARD_FAB2_LIB.BASEBOARD_FAB2(SCH_1):M_L_DQ(10)    I12 @BASEBOARD_FAB2_LIB.BASEBOARD_FAB2(SCH_1):PAGE86
   161 M_L_DQ<9> @BASEBOARD_FAB2_LIB.BASEBOARD_FAB2(SCH_1):M_L_DQ(9)    I12 @BASEBOARD_FAB2_LIB.BASEBOARD_FAB2(SCH_1):PAGE86
    16 M_L_DQ<8> @BASEBOARD_FAB2_LIB.BASEBOARD_FAB2(SCH_1):M_L_DQ(8)    I12 @BASEBOARD_FAB2_LIB.BASEBOARD_FAB2(SCH_1):PAGE86
   155 M_L_DQ<7> @BASEBOARD_FAB2_LIB.BASEBOARD_FAB2(SCH_1):M_L_DQ(7)    I12 @BASEBOARD_FAB2_LIB.BASEBOARD_FAB2(SCH_1):PAGE86
    10 M_L_DQ<6> @BASEBOARD_FAB2_LIB.BASEBOARD_FAB2(SCH_1):M_L_DQ(6)    I12 @BASEBOARD_FAB2_LIB.BASEBOARD_FAB2(SCH_1):PAGE86
   148 M_L_DQ<5> @BASEBOARD_FAB2_LIB.BASEBOARD_FAB2(SCH_1):M_L_DQ(5)    I12 @BASEBOARD_FAB2_LIB.BASEBOARD_FAB2(SCH_1):PAGE86
     3 M_L_DQ<4> @BASEBOARD_FAB2_LIB.BASEBOARD_FAB2(SCH_1):M_L_DQ(4)    I12 @BASEBOARD_FAB2_LIB.BASEBOARD_FAB2(SCH_1):PAGE86
   157 M_L_DQ<3> @BASEBOARD_FAB2_LIB.BASEBOARD_FAB2(SCH_1):M_L_DQ(3)    I12 @BASEBOARD_FAB2_LIB.BASEBOARD_FAB2(SCH_1):PAGE86
    12 M_L_DQ<2> @BASEBOARD_FAB2_LIB.BASEBOARD_FAB2(SCH_1):M_L_DQ(2)    I12 @BASEBOARD_FAB2_LIB.BASEBOARD_FAB2(SCH_1):PAGE86
   150 M_L_DQ<1> @BASEBOARD_FAB2_LIB.BASEBOARD_FAB2(SCH_1):M_L_DQ(1)    I12 @BASEBOARD_FAB2_LIB.BASEBOARD_FAB2(SCH_1):PAGE86
     5 M_L_DQ<0> @BASEBOARD_FAB2_LIB.BASEBOARD_FAB2(SCH_1):M_L_DQ(0)    I12 @BASEBOARD_FAB2_LIB.BASEBOARD_FAB2(SCH_1):PAGE86
    78 FM_DIMM_EVENT_COD_N @BASEBOARD_FAB2_LIB.BASEBOARD_FAB2(SCH_1):FM_DIMM_EVENT_COD_N    I12 @BASEBOARD_FAB2_LIB.BASEBOARD_FAB2(SCH_1):PAGE86
    91 M_L_ODT<3> @BASEBOARD_FAB2_LIB.BASEBOARD_FAB2(SCH_1):M_L_ODT(3)    I12 @BASEBOARD_FAB2_LIB.BASEBOARD_FAB2(SCH_1):PAGE86
    87 M_L_ODT<2> @BASEBOARD_FAB2_LIB.BASEBOARD_FAB2(SCH_1):M_L_ODT(2)    I12 @BASEBOARD_FAB2_LIB.BASEBOARD_FAB2(SCH_1):PAGE86
   222 M_L_PAR @BASEBOARD_FAB2_LIB.BASEBOARD_FAB2(SCH_1):M_L_PAR    I12 @BASEBOARD_FAB2_LIB.BASEBOARD_FAB2(SCH_1):PAGE86
    58 M_KLM_RST_N @BASEBOARD_FAB2_LIB.BASEBOARD_FAB2(SCH_1):M_KLM_RST_N    I12 @BASEBOARD_FAB2_LIB.BASEBOARD_FAB2(SCH_1):PAGE86
   144 TP_CH_L_DIMM0_RFU_2 @BASEBOARD_FAB2_LIB.BASEBOARD_FAB2(SCH_1):TP_CH_L_DIMM0_RFU_2    I12 @BASEBOARD_FAB2_LIB.BASEBOARD_FAB2(SCH_1):PAGE86
   227 TP_CH_L_DIMM0_RFU_1 @BASEBOARD_FAB2_LIB.BASEBOARD_FAB2(SCH_1):TP_CH_L_DIMM0_RFU_1    I12 @BASEBOARD_FAB2_LIB.BASEBOARD_FAB2(SCH_1):PAGE86
   205 TP_CH_L_DIMM0_RFU_0 @BASEBOARD_FAB2_LIB.BASEBOARD_FAB2(SCH_1):TP_CH_L_DIMM0_RFU_0    I12 @BASEBOARD_FAB2_LIB.BASEBOARD_FAB2(SCH_1):PAGE86
    84 M_L_CS_N<4> @BASEBOARD_FAB2_LIB.BASEBOARD_FAB2(SCH_1):M_L_CS_N(4)    I12 @BASEBOARD_FAB2_LIB.BASEBOARD_FAB2(SCH_1):PAGE86
    89 M_L_CS_N<5> @BASEBOARD_FAB2_LIB.BASEBOARD_FAB2(SCH_1):M_L_CS_N(5)    I12 @BASEBOARD_FAB2_LIB.BASEBOARD_FAB2(SCH_1):PAGE86
    93 M_L_CS_N<6> @BASEBOARD_FAB2_LIB.BASEBOARD_FAB2(SCH_1):M_L_CS_N(6)    I12 @BASEBOARD_FAB2_LIB.BASEBOARD_FAB2(SCH_1):PAGE86
   237 M_L_CS_N<7> @BASEBOARD_FAB2_LIB.BASEBOARD_FAB2(SCH_1):M_L_CS_N(7)    I12 @BASEBOARD_FAB2_LIB.BASEBOARD_FAB2(SCH_1):PAGE86
   238    GND @BASEBOARD_FAB2_LIB.BASEBOARD_FAB2(SCH_1):GND    I12 @BASEBOARD_FAB2_LIB.BASEBOARD_FAB2(SCH_1):PAGE86
   140 PVPP_KLM @BASEBOARD_FAB2_LIB.BASEBOARD_FAB2(SCH_1):PVPP_KLM    I12 @BASEBOARD_FAB2_LIB.BASEBOARD_FAB2(SCH_1):PAGE86
   139 PVPP_KLM @BASEBOARD_FAB2_LIB.BASEBOARD_FAB2(SCH_1):PVPP_KLM    I12 @BASEBOARD_FAB2_LIB.BASEBOARD_FAB2(SCH_1):PAGE86
   230 FM_ADR_COMPLETE_KLM_N @BASEBOARD_FAB2_LIB.BASEBOARD_FAB2(SCH_1):FM_ADR_COMPLETE_KLM_N    I12 @BASEBOARD_FAB2_LIB.BASEBOARD_FAB2(SCH_1):PAGE86
   141 SMB_DDR_KLM_VPP_SCL @BASEBOARD_FAB2_LIB.BASEBOARD_FAB2(SCH_1):SMB_DDR_KLM_VPP_SCL    I12 @BASEBOARD_FAB2_LIB.BASEBOARD_FAB2(SCH_1):PAGE86
   285 SMB_DDR_KLM_VPP_SDA @BASEBOARD_FAB2_LIB.BASEBOARD_FAB2(SCH_1):SMB_DDR_KLM_VPP_SDA    I12 @BASEBOARD_FAB2_LIB.BASEBOARD_FAB2(SCH_1):PAGE86
   284 PVPP_KLM @BASEBOARD_FAB2_LIB.BASEBOARD_FAB2(SCH_1):PVPP_KLM    I12 @BASEBOARD_FAB2_LIB.BASEBOARD_FAB2(SCH_1):PAGE86
   146 M_L_VREF @BASEBOARD_FAB2_LIB.BASEBOARD_FAB2(SCH_1):M_L_VREF    I12 @BASEBOARD_FAB2_LIB.BASEBOARD_FAB2(SCH_1):PAGE86
   152 M_L_DQS_DN<0> @BASEBOARD_FAB2_LIB.BASEBOARD_FAB2(SCH_1):M_L_DQS_DN(0)   I100 @BASEBOARD_FAB2_LIB.BASEBOARD_FAB2(SCH_1):PAGE86
   153 M_L_DQS_DP<0> @BASEBOARD_FAB2_LIB.BASEBOARD_FAB2(SCH_1):M_L_DQS_DP(0)   I100 @BASEBOARD_FAB2_LIB.BASEBOARD_FAB2(SCH_1):PAGE86
    19 M_L_DQS_DN<10> @BASEBOARD_FAB2_LIB.BASEBOARD_FAB2(SCH_1):M_L_DQS_DN(10)   I100 @BASEBOARD_FAB2_LIB.BASEBOARD_FAB2(SCH_1):PAGE86
    18 M_L_DQS_DP<10> @BASEBOARD_FAB2_LIB.BASEBOARD_FAB2(SCH_1):M_L_DQS_DP(10)   I100 @BASEBOARD_FAB2_LIB.BASEBOARD_FAB2(SCH_1):PAGE86
    30 M_L_DQS_DN<11> @BASEBOARD_FAB2_LIB.BASEBOARD_FAB2(SCH_1):M_L_DQS_DN(11)   I100 @BASEBOARD_FAB2_LIB.BASEBOARD_FAB2(SCH_1):PAGE86
    29 M_L_DQS_DP<11> @BASEBOARD_FAB2_LIB.BASEBOARD_FAB2(SCH_1):M_L_DQS_DP(11)   I100 @BASEBOARD_FAB2_LIB.BASEBOARD_FAB2(SCH_1):PAGE86
    41 M_L_DQS_DN<12> @BASEBOARD_FAB2_LIB.BASEBOARD_FAB2(SCH_1):M_L_DQS_DN(12)   I100 @BASEBOARD_FAB2_LIB.BASEBOARD_FAB2(SCH_1):PAGE86
    40 M_L_DQS_DP<12> @BASEBOARD_FAB2_LIB.BASEBOARD_FAB2(SCH_1):M_L_DQS_DP(12)   I100 @BASEBOARD_FAB2_LIB.BASEBOARD_FAB2(SCH_1):PAGE86
   100 M_L_DQS_DN<13> @BASEBOARD_FAB2_LIB.BASEBOARD_FAB2(SCH_1):M_L_DQS_DN(13)   I100 @BASEBOARD_FAB2_LIB.BASEBOARD_FAB2(SCH_1):PAGE86
    99 M_L_DQS_DP<13> @BASEBOARD_FAB2_LIB.BASEBOARD_FAB2(SCH_1):M_L_DQS_DP(13)   I100 @BASEBOARD_FAB2_LIB.BASEBOARD_FAB2(SCH_1):PAGE86
   111 M_L_DQS_DN<14> @BASEBOARD_FAB2_LIB.BASEBOARD_FAB2(SCH_1):M_L_DQS_DN(14)   I100 @BASEBOARD_FAB2_LIB.BASEBOARD_FAB2(SCH_1):PAGE86
   110 M_L_DQS_DP<14> @BASEBOARD_FAB2_LIB.BASEBOARD_FAB2(SCH_1):M_L_DQS_DP(14)   I100 @BASEBOARD_FAB2_LIB.BASEBOARD_FAB2(SCH_1):PAGE86
   122 M_L_DQS_DN<15> @BASEBOARD_FAB2_LIB.BASEBOARD_FAB2(SCH_1):M_L_DQS_DN(15)   I100 @BASEBOARD_FAB2_LIB.BASEBOARD_FAB2(SCH_1):PAGE86
   121 M_L_DQS_DP<15> @BASEBOARD_FAB2_LIB.BASEBOARD_FAB2(SCH_1):M_L_DQS_DP(15)   I100 @BASEBOARD_FAB2_LIB.BASEBOARD_FAB2(SCH_1):PAGE86
   133 M_L_DQS_DN<16> @BASEBOARD_FAB2_LIB.BASEBOARD_FAB2(SCH_1):M_L_DQS_DN(16)   I100 @BASEBOARD_FAB2_LIB.BASEBOARD_FAB2(SCH_1):PAGE86
   132 M_L_DQS_DP<16> @BASEBOARD_FAB2_LIB.BASEBOARD_FAB2(SCH_1):M_L_DQS_DP(16)   I100 @BASEBOARD_FAB2_LIB.BASEBOARD_FAB2(SCH_1):PAGE86
    52 M_L_DQS_DN<17> @BASEBOARD_FAB2_LIB.BASEBOARD_FAB2(SCH_1):M_L_DQS_DN(17)   I100 @BASEBOARD_FAB2_LIB.BASEBOARD_FAB2(SCH_1):PAGE86
    51 M_L_DQS_DP<17> @BASEBOARD_FAB2_LIB.BASEBOARD_FAB2(SCH_1):M_L_DQS_DP(17)   I100 @BASEBOARD_FAB2_LIB.BASEBOARD_FAB2(SCH_1):PAGE86
   163 M_L_DQS_DN<1> @BASEBOARD_FAB2_LIB.BASEBOARD_FAB2(SCH_1):M_L_DQS_DN(1)   I100 @BASEBOARD_FAB2_LIB.BASEBOARD_FAB2(SCH_1):PAGE86
   164 M_L_DQS_DP<1> @BASEBOARD_FAB2_LIB.BASEBOARD_FAB2(SCH_1):M_L_DQS_DP(1)   I100 @BASEBOARD_FAB2_LIB.BASEBOARD_FAB2(SCH_1):PAGE86
   174 M_L_DQS_DN<2> @BASEBOARD_FAB2_LIB.BASEBOARD_FAB2(SCH_1):M_L_DQS_DN(2)   I100 @BASEBOARD_FAB2_LIB.BASEBOARD_FAB2(SCH_1):PAGE86
   175 M_L_DQS_DP<2> @BASEBOARD_FAB2_LIB.BASEBOARD_FAB2(SCH_1):M_L_DQS_DP(2)   I100 @BASEBOARD_FAB2_LIB.BASEBOARD_FAB2(SCH_1):PAGE86
   185 M_L_DQS_DN<3> @BASEBOARD_FAB2_LIB.BASEBOARD_FAB2(SCH_1):M_L_DQS_DN(3)   I100 @BASEBOARD_FAB2_LIB.BASEBOARD_FAB2(SCH_1):PAGE86
   186 M_L_DQS_DP<3> @BASEBOARD_FAB2_LIB.BASEBOARD_FAB2(SCH_1):M_L_DQS_DP(3)   I100 @BASEBOARD_FAB2_LIB.BASEBOARD_FAB2(SCH_1):PAGE86
   244 M_L_DQS_DN<4> @BASEBOARD_FAB2_LIB.BASEBOARD_FAB2(SCH_1):M_L_DQS_DN(4)   I100 @BASEBOARD_FAB2_LIB.BASEBOARD_FAB2(SCH_1):PAGE86
   245 M_L_DQS_DP<4> @BASEBOARD_FAB2_LIB.BASEBOARD_FAB2(SCH_1):M_L_DQS_DP(4)   I100 @BASEBOARD_FAB2_LIB.BASEBOARD_FAB2(SCH_1):PAGE86
   255 M_L_DQS_DN<5> @BASEBOARD_FAB2_LIB.BASEBOARD_FAB2(SCH_1):M_L_DQS_DN(5)   I100 @BASEBOARD_FAB2_LIB.BASEBOARD_FAB2(SCH_1):PAGE86
   256 M_L_DQS_DP<5> @BASEBOARD_FAB2_LIB.BASEBOARD_FAB2(SCH_1):M_L_DQS_DP(5)   I100 @BASEBOARD_FAB2_LIB.BASEBOARD_FAB2(SCH_1):PAGE86
   266 M_L_DQS_DN<6> @BASEBOARD_FAB2_LIB.BASEBOARD_FAB2(SCH_1):M_L_DQS_DN(6)   I100 @BASEBOARD_FAB2_LIB.BASEBOARD_FAB2(SCH_1):PAGE86
   267 M_L_DQS_DP<6> @BASEBOARD_FAB2_LIB.BASEBOARD_FAB2(SCH_1):M_L_DQS_DP(6)   I100 @BASEBOARD_FAB2_LIB.BASEBOARD_FAB2(SCH_1):PAGE86
   277 M_L_DQS_DN<7> @BASEBOARD_FAB2_LIB.BASEBOARD_FAB2(SCH_1):M_L_DQS_DN(7)   I100 @BASEBOARD_FAB2_LIB.BASEBOARD_FAB2(SCH_1):PAGE86
   278 M_L_DQS_DP<7> @BASEBOARD_FAB2_LIB.BASEBOARD_FAB2(SCH_1):M_L_DQS_DP(7)   I100 @BASEBOARD_FAB2_LIB.BASEBOARD_FAB2(SCH_1):PAGE86
   196 M_L_DQS_DN<8> @BASEBOARD_FAB2_LIB.BASEBOARD_FAB2(SCH_1):M_L_DQS_DN(8)   I100 @BASEBOARD_FAB2_LIB.BASEBOARD_FAB2(SCH_1):PAGE86
   197 M_L_DQS_DP<8> @BASEBOARD_FAB2_LIB.BASEBOARD_FAB2(SCH_1):M_L_DQS_DP(8)   I100 @BASEBOARD_FAB2_LIB.BASEBOARD_FAB2(SCH_1):PAGE86
     8 M_L_DQS_DN<9> @BASEBOARD_FAB2_LIB.BASEBOARD_FAB2(SCH_1):M_L_DQS_DN(9)   I100 @BASEBOARD_FAB2_LIB.BASEBOARD_FAB2(SCH_1):PAGE86
     7 M_L_DQS_DP<9> @BASEBOARD_FAB2_LIB.BASEBOARD_FAB2(SCH_1):M_L_DQS_DP(9)   I100 @BASEBOARD_FAB2_LIB.BASEBOARD_FAB2(SCH_1):PAGE86
     2    GND @BASEBOARD_FAB2_LIB.BASEBOARD_FAB2(SCH_1):GND   I138 @BASEBOARD_FAB2_LIB.BASEBOARD_FAB2(SCH_1):PAGE86
     4    GND @BASEBOARD_FAB2_LIB.BASEBOARD_FAB2(SCH_1):GND   I138 @BASEBOARD_FAB2_LIB.BASEBOARD_FAB2(SCH_1):PAGE86
     6    GND @BASEBOARD_FAB2_LIB.BASEBOARD_FAB2(SCH_1):GND   I138 @BASEBOARD_FAB2_LIB.BASEBOARD_FAB2(SCH_1):PAGE86
     9    GND @BASEBOARD_FAB2_LIB.BASEBOARD_FAB2(SCH_1):GND   I138 @BASEBOARD_FAB2_LIB.BASEBOARD_FAB2(SCH_1):PAGE86
    11    GND @BASEBOARD_FAB2_LIB.BASEBOARD_FAB2(SCH_1):GND   I138 @BASEBOARD_FAB2_LIB.BASEBOARD_FAB2(SCH_1):PAGE86
    13    GND @BASEBOARD_FAB2_LIB.BASEBOARD_FAB2(SCH_1):GND   I138 @BASEBOARD_FAB2_LIB.BASEBOARD_FAB2(SCH_1):PAGE86
    15    GND @BASEBOARD_FAB2_LIB.BASEBOARD_FAB2(SCH_1):GND   I138 @BASEBOARD_FAB2_LIB.BASEBOARD_FAB2(SCH_1):PAGE86
    17    GND @BASEBOARD_FAB2_LIB.BASEBOARD_FAB2(SCH_1):GND   I138 @BASEBOARD_FAB2_LIB.BASEBOARD_FAB2(SCH_1):PAGE86
    20    GND @BASEBOARD_FAB2_LIB.BASEBOARD_FAB2(SCH_1):GND   I138 @BASEBOARD_FAB2_LIB.BASEBOARD_FAB2(SCH_1):PAGE86
    22    GND @BASEBOARD_FAB2_LIB.BASEBOARD_FAB2(SCH_1):GND   I138 @BASEBOARD_FAB2_LIB.BASEBOARD_FAB2(SCH_1):PAGE86
    24    GND @BASEBOARD_FAB2_LIB.BASEBOARD_FAB2(SCH_1):GND   I138 @BASEBOARD_FAB2_LIB.BASEBOARD_FAB2(SCH_1):PAGE86
    26    GND @BASEBOARD_FAB2_LIB.BASEBOARD_FAB2(SCH_1):GND   I138 @BASEBOARD_FAB2_LIB.BASEBOARD_FAB2(SCH_1):PAGE86
    28    GND @BASEBOARD_FAB2_LIB.BASEBOARD_FAB2(SCH_1):GND   I138 @BASEBOARD_FAB2_LIB.BASEBOARD_FAB2(SCH_1):PAGE86
    31    GND @BASEBOARD_FAB2_LIB.BASEBOARD_FAB2(SCH_1):GND   I138 @BASEBOARD_FAB2_LIB.BASEBOARD_FAB2(SCH_1):PAGE86
    33    GND @BASEBOARD_FAB2_LIB.BASEBOARD_FAB2(SCH_1):GND   I138 @BASEBOARD_FAB2_LIB.BASEBOARD_FAB2(SCH_1):PAGE86
    35    GND @BASEBOARD_FAB2_LIB.BASEBOARD_FAB2(SCH_1):GND   I138 @BASEBOARD_FAB2_LIB.BASEBOARD_FAB2(SCH_1):PAGE86
    37    GND @BASEBOARD_FAB2_LIB.BASEBOARD_FAB2(SCH_1):GND   I138 @BASEBOARD_FAB2_LIB.BASEBOARD_FAB2(SCH_1):PAGE86
    39    GND @BASEBOARD_FAB2_LIB.BASEBOARD_FAB2(SCH_1):GND   I138 @BASEBOARD_FAB2_LIB.BASEBOARD_FAB2(SCH_1):PAGE86
    42    GND @BASEBOARD_FAB2_LIB.BASEBOARD_FAB2(SCH_1):GND   I138 @BASEBOARD_FAB2_LIB.BASEBOARD_FAB2(SCH_1):PAGE86
    44    GND @BASEBOARD_FAB2_LIB.BASEBOARD_FAB2(SCH_1):GND   I138 @BASEBOARD_FAB2_LIB.BASEBOARD_FAB2(SCH_1):PAGE86
    46    GND @BASEBOARD_FAB2_LIB.BASEBOARD_FAB2(SCH_1):GND   I138 @BASEBOARD_FAB2_LIB.BASEBOARD_FAB2(SCH_1):PAGE86
    48    GND @BASEBOARD_FAB2_LIB.BASEBOARD_FAB2(SCH_1):GND   I138 @BASEBOARD_FAB2_LIB.BASEBOARD_FAB2(SCH_1):PAGE86
    50    GND @BASEBOARD_FAB2_LIB.BASEBOARD_FAB2(SCH_1):GND   I138 @BASEBOARD_FAB2_LIB.BASEBOARD_FAB2(SCH_1):PAGE86
    53    GND @BASEBOARD_FAB2_LIB.BASEBOARD_FAB2(SCH_1):GND   I138 @BASEBOARD_FAB2_LIB.BASEBOARD_FAB2(SCH_1):PAGE86
    55    GND @BASEBOARD_FAB2_LIB.BASEBOARD_FAB2(SCH_1):GND   I138 @BASEBOARD_FAB2_LIB.BASEBOARD_FAB2(SCH_1):PAGE86
    57    GND @BASEBOARD_FAB2_LIB.BASEBOARD_FAB2(SCH_1):GND   I138 @BASEBOARD_FAB2_LIB.BASEBOARD_FAB2(SCH_1):PAGE86
    94    GND @BASEBOARD_FAB2_LIB.BASEBOARD_FAB2(SCH_1):GND   I138 @BASEBOARD_FAB2_LIB.BASEBOARD_FAB2(SCH_1):PAGE86
    96    GND @BASEBOARD_FAB2_LIB.BASEBOARD_FAB2(SCH_1):GND   I138 @BASEBOARD_FAB2_LIB.BASEBOARD_FAB2(SCH_1):PAGE86
    98    GND @BASEBOARD_FAB2_LIB.BASEBOARD_FAB2(SCH_1):GND   I138 @BASEBOARD_FAB2_LIB.BASEBOARD_FAB2(SCH_1):PAGE86
   101    GND @BASEBOARD_FAB2_LIB.BASEBOARD_FAB2(SCH_1):GND   I138 @BASEBOARD_FAB2_LIB.BASEBOARD_FAB2(SCH_1):PAGE86
   103    GND @BASEBOARD_FAB2_LIB.BASEBOARD_FAB2(SCH_1):GND   I138 @BASEBOARD_FAB2_LIB.BASEBOARD_FAB2(SCH_1):PAGE86
   105    GND @BASEBOARD_FAB2_LIB.BASEBOARD_FAB2(SCH_1):GND   I138 @BASEBOARD_FAB2_LIB.BASEBOARD_FAB2(SCH_1):PAGE86
   107    GND @BASEBOARD_FAB2_LIB.BASEBOARD_FAB2(SCH_1):GND   I138 @BASEBOARD_FAB2_LIB.BASEBOARD_FAB2(SCH_1):PAGE86
   109    GND @BASEBOARD_FAB2_LIB.BASEBOARD_FAB2(SCH_1):GND   I138 @BASEBOARD_FAB2_LIB.BASEBOARD_FAB2(SCH_1):PAGE86
   112    GND @BASEBOARD_FAB2_LIB.BASEBOARD_FAB2(SCH_1):GND   I138 @BASEBOARD_FAB2_LIB.BASEBOARD_FAB2(SCH_1):PAGE86
   114    GND @BASEBOARD_FAB2_LIB.BASEBOARD_FAB2(SCH_1):GND   I138 @BASEBOARD_FAB2_LIB.BASEBOARD_FAB2(SCH_1):PAGE86
   116    GND @BASEBOARD_FAB2_LIB.BASEBOARD_FAB2(SCH_1):GND   I138 @BASEBOARD_FAB2_LIB.BASEBOARD_FAB2(SCH_1):PAGE86
   118    GND @BASEBOARD_FAB2_LIB.BASEBOARD_FAB2(SCH_1):GND   I138 @BASEBOARD_FAB2_LIB.BASEBOARD_FAB2(SCH_1):PAGE86
   120    GND @BASEBOARD_FAB2_LIB.BASEBOARD_FAB2(SCH_1):GND   I138 @BASEBOARD_FAB2_LIB.BASEBOARD_FAB2(SCH_1):PAGE86
   123    GND @BASEBOARD_FAB2_LIB.BASEBOARD_FAB2(SCH_1):GND   I138 @BASEBOARD_FAB2_LIB.BASEBOARD_FAB2(SCH_1):PAGE86
   125    GND @BASEBOARD_FAB2_LIB.BASEBOARD_FAB2(SCH_1):GND   I138 @BASEBOARD_FAB2_LIB.BASEBOARD_FAB2(SCH_1):PAGE86
   127    GND @BASEBOARD_FAB2_LIB.BASEBOARD_FAB2(SCH_1):GND   I138 @BASEBOARD_FAB2_LIB.BASEBOARD_FAB2(SCH_1):PAGE86
   129    GND @BASEBOARD_FAB2_LIB.BASEBOARD_FAB2(SCH_1):GND   I138 @BASEBOARD_FAB2_LIB.BASEBOARD_FAB2(SCH_1):PAGE86
   131    GND @BASEBOARD_FAB2_LIB.BASEBOARD_FAB2(SCH_1):GND   I138 @BASEBOARD_FAB2_LIB.BASEBOARD_FAB2(SCH_1):PAGE86
   134    GND @BASEBOARD_FAB2_LIB.BASEBOARD_FAB2(SCH_1):GND   I138 @BASEBOARD_FAB2_LIB.BASEBOARD_FAB2(SCH_1):PAGE86
   136    GND @BASEBOARD_FAB2_LIB.BASEBOARD_FAB2(SCH_1):GND   I138 @BASEBOARD_FAB2_LIB.BASEBOARD_FAB2(SCH_1):PAGE86
   138    GND @BASEBOARD_FAB2_LIB.BASEBOARD_FAB2(SCH_1):GND   I138 @BASEBOARD_FAB2_LIB.BASEBOARD_FAB2(SCH_1):PAGE86
   147    GND @BASEBOARD_FAB2_LIB.BASEBOARD_FAB2(SCH_1):GND   I138 @BASEBOARD_FAB2_LIB.BASEBOARD_FAB2(SCH_1):PAGE86
   149    GND @BASEBOARD_FAB2_LIB.BASEBOARD_FAB2(SCH_1):GND   I138 @BASEBOARD_FAB2_LIB.BASEBOARD_FAB2(SCH_1):PAGE86
   151    GND @BASEBOARD_FAB2_LIB.BASEBOARD_FAB2(SCH_1):GND   I138 @BASEBOARD_FAB2_LIB.BASEBOARD_FAB2(SCH_1):PAGE86
   154    GND @BASEBOARD_FAB2_LIB.BASEBOARD_FAB2(SCH_1):GND   I138 @BASEBOARD_FAB2_LIB.BASEBOARD_FAB2(SCH_1):PAGE86
   156    GND @BASEBOARD_FAB2_LIB.BASEBOARD_FAB2(SCH_1):GND   I138 @BASEBOARD_FAB2_LIB.BASEBOARD_FAB2(SCH_1):PAGE86
   158    GND @BASEBOARD_FAB2_LIB.BASEBOARD_FAB2(SCH_1):GND   I138 @BASEBOARD_FAB2_LIB.BASEBOARD_FAB2(SCH_1):PAGE86
   160    GND @BASEBOARD_FAB2_LIB.BASEBOARD_FAB2(SCH_1):GND   I138 @BASEBOARD_FAB2_LIB.BASEBOARD_FAB2(SCH_1):PAGE86
   162    GND @BASEBOARD_FAB2_LIB.BASEBOARD_FAB2(SCH_1):GND   I138 @BASEBOARD_FAB2_LIB.BASEBOARD_FAB2(SCH_1):PAGE86
   165    GND @BASEBOARD_FAB2_LIB.BASEBOARD_FAB2(SCH_1):GND   I138 @BASEBOARD_FAB2_LIB.BASEBOARD_FAB2(SCH_1):PAGE86
   167    GND @BASEBOARD_FAB2_LIB.BASEBOARD_FAB2(SCH_1):GND   I138 @BASEBOARD_FAB2_LIB.BASEBOARD_FAB2(SCH_1):PAGE86
   169    GND @BASEBOARD_FAB2_LIB.BASEBOARD_FAB2(SCH_1):GND   I138 @BASEBOARD_FAB2_LIB.BASEBOARD_FAB2(SCH_1):PAGE86
   171    GND @BASEBOARD_FAB2_LIB.BASEBOARD_FAB2(SCH_1):GND   I138 @BASEBOARD_FAB2_LIB.BASEBOARD_FAB2(SCH_1):PAGE86
   173    GND @BASEBOARD_FAB2_LIB.BASEBOARD_FAB2(SCH_1):GND   I138 @BASEBOARD_FAB2_LIB.BASEBOARD_FAB2(SCH_1):PAGE86
   176    GND @BASEBOARD_FAB2_LIB.BASEBOARD_FAB2(SCH_1):GND   I138 @BASEBOARD_FAB2_LIB.BASEBOARD_FAB2(SCH_1):PAGE86
   178    GND @BASEBOARD_FAB2_LIB.BASEBOARD_FAB2(SCH_1):GND   I138 @BASEBOARD_FAB2_LIB.BASEBOARD_FAB2(SCH_1):PAGE86
   180    GND @BASEBOARD_FAB2_LIB.BASEBOARD_FAB2(SCH_1):GND   I138 @BASEBOARD_FAB2_LIB.BASEBOARD_FAB2(SCH_1):PAGE86
   182    GND @BASEBOARD_FAB2_LIB.BASEBOARD_FAB2(SCH_1):GND   I138 @BASEBOARD_FAB2_LIB.BASEBOARD_FAB2(SCH_1):PAGE86
   184    GND @BASEBOARD_FAB2_LIB.BASEBOARD_FAB2(SCH_1):GND   I138 @BASEBOARD_FAB2_LIB.BASEBOARD_FAB2(SCH_1):PAGE86
   187    GND @BASEBOARD_FAB2_LIB.BASEBOARD_FAB2(SCH_1):GND   I138 @BASEBOARD_FAB2_LIB.BASEBOARD_FAB2(SCH_1):PAGE86
   189    GND @BASEBOARD_FAB2_LIB.BASEBOARD_FAB2(SCH_1):GND   I138 @BASEBOARD_FAB2_LIB.BASEBOARD_FAB2(SCH_1):PAGE86
   191    GND @BASEBOARD_FAB2_LIB.BASEBOARD_FAB2(SCH_1):GND   I138 @BASEBOARD_FAB2_LIB.BASEBOARD_FAB2(SCH_1):PAGE86
   193    GND @BASEBOARD_FAB2_LIB.BASEBOARD_FAB2(SCH_1):GND   I138 @BASEBOARD_FAB2_LIB.BASEBOARD_FAB2(SCH_1):PAGE86
   195    GND @BASEBOARD_FAB2_LIB.BASEBOARD_FAB2(SCH_1):GND   I138 @BASEBOARD_FAB2_LIB.BASEBOARD_FAB2(SCH_1):PAGE86
   198    GND @BASEBOARD_FAB2_LIB.BASEBOARD_FAB2(SCH_1):GND   I138 @BASEBOARD_FAB2_LIB.BASEBOARD_FAB2(SCH_1):PAGE86
   200    GND @BASEBOARD_FAB2_LIB.BASEBOARD_FAB2(SCH_1):GND   I138 @BASEBOARD_FAB2_LIB.BASEBOARD_FAB2(SCH_1):PAGE86
   202    GND @BASEBOARD_FAB2_LIB.BASEBOARD_FAB2(SCH_1):GND   I138 @BASEBOARD_FAB2_LIB.BASEBOARD_FAB2(SCH_1):PAGE86
   239    GND @BASEBOARD_FAB2_LIB.BASEBOARD_FAB2(SCH_1):GND   I138 @BASEBOARD_FAB2_LIB.BASEBOARD_FAB2(SCH_1):PAGE86
   241    GND @BASEBOARD_FAB2_LIB.BASEBOARD_FAB2(SCH_1):GND   I138 @BASEBOARD_FAB2_LIB.BASEBOARD_FAB2(SCH_1):PAGE86
   243    GND @BASEBOARD_FAB2_LIB.BASEBOARD_FAB2(SCH_1):GND   I138 @BASEBOARD_FAB2_LIB.BASEBOARD_FAB2(SCH_1):PAGE86
   246    GND @BASEBOARD_FAB2_LIB.BASEBOARD_FAB2(SCH_1):GND   I138 @BASEBOARD_FAB2_LIB.BASEBOARD_FAB2(SCH_1):PAGE86
   248    GND @BASEBOARD_FAB2_LIB.BASEBOARD_FAB2(SCH_1):GND   I138 @BASEBOARD_FAB2_LIB.BASEBOARD_FAB2(SCH_1):PAGE86
   250    GND @BASEBOARD_FAB2_LIB.BASEBOARD_FAB2(SCH_1):GND   I138 @BASEBOARD_FAB2_LIB.BASEBOARD_FAB2(SCH_1):PAGE86
   252    GND @BASEBOARD_FAB2_LIB.BASEBOARD_FAB2(SCH_1):GND   I138 @BASEBOARD_FAB2_LIB.BASEBOARD_FAB2(SCH_1):PAGE86
   254    GND @BASEBOARD_FAB2_LIB.BASEBOARD_FAB2(SCH_1):GND   I138 @BASEBOARD_FAB2_LIB.BASEBOARD_FAB2(SCH_1):PAGE86
   257    GND @BASEBOARD_FAB2_LIB.BASEBOARD_FAB2(SCH_1):GND   I138 @BASEBOARD_FAB2_LIB.BASEBOARD_FAB2(SCH_1):PAGE86
   259    GND @BASEBOARD_FAB2_LIB.BASEBOARD_FAB2(SCH_1):GND   I138 @BASEBOARD_FAB2_LIB.BASEBOARD_FAB2(SCH_1):PAGE86
   261    GND @BASEBOARD_FAB2_LIB.BASEBOARD_FAB2(SCH_1):GND   I138 @BASEBOARD_FAB2_LIB.BASEBOARD_FAB2(SCH_1):PAGE86
   263    GND @BASEBOARD_FAB2_LIB.BASEBOARD_FAB2(SCH_1):GND   I138 @BASEBOARD_FAB2_LIB.BASEBOARD_FAB2(SCH_1):PAGE86
   265    GND @BASEBOARD_FAB2_LIB.BASEBOARD_FAB2(SCH_1):GND   I138 @BASEBOARD_FAB2_LIB.BASEBOARD_FAB2(SCH_1):PAGE86
   268    GND @BASEBOARD_FAB2_LIB.BASEBOARD_FAB2(SCH_1):GND   I138 @BASEBOARD_FAB2_LIB.BASEBOARD_FAB2(SCH_1):PAGE86
   270    GND @BASEBOARD_FAB2_LIB.BASEBOARD_FAB2(SCH_1):GND   I138 @BASEBOARD_FAB2_LIB.BASEBOARD_FAB2(SCH_1):PAGE86
   272    GND @BASEBOARD_FAB2_LIB.BASEBOARD_FAB2(SCH_1):GND   I138 @BASEBOARD_FAB2_LIB.BASEBOARD_FAB2(SCH_1):PAGE86
   274    GND @BASEBOARD_FAB2_LIB.BASEBOARD_FAB2(SCH_1):GND   I138 @BASEBOARD_FAB2_LIB.BASEBOARD_FAB2(SCH_1):PAGE86
   276    GND @BASEBOARD_FAB2_LIB.BASEBOARD_FAB2(SCH_1):GND   I138 @BASEBOARD_FAB2_LIB.BASEBOARD_FAB2(SCH_1):PAGE86
   279    GND @BASEBOARD_FAB2_LIB.BASEBOARD_FAB2(SCH_1):GND   I138 @BASEBOARD_FAB2_LIB.BASEBOARD_FAB2(SCH_1):PAGE86
   281    GND @BASEBOARD_FAB2_LIB.BASEBOARD_FAB2(SCH_1):GND   I138 @BASEBOARD_FAB2_LIB.BASEBOARD_FAB2(SCH_1):PAGE86
   283    GND @BASEBOARD_FAB2_LIB.BASEBOARD_FAB2(SCH_1):GND   I138 @BASEBOARD_FAB2_LIB.BASEBOARD_FAB2(SCH_1):PAGE86
     1 P12V_NVDIMM_KLM @BASEBOARD_FAB2_LIB.BASEBOARD_FAB2(SCH_1):P12V_NVDIMM_KLM    I55 @BASEBOARD_FAB2_LIB.BASEBOARD_FAB2(SCH_1):PAGE86
   145 P12V_NVDIMM_KLM @BASEBOARD_FAB2_LIB.BASEBOARD_FAB2(SCH_1):P12V_NVDIMM_KLM    I55 @BASEBOARD_FAB2_LIB.BASEBOARD_FAB2(SCH_1):PAGE86
    59 PVDDQ_KLM @BASEBOARD_FAB2_LIB.BASEBOARD_FAB2(SCH_1):PVDDQ_KLM    I55 @BASEBOARD_FAB2_LIB.BASEBOARD_FAB2(SCH_1):PAGE86
    61 PVDDQ_KLM @BASEBOARD_FAB2_LIB.BASEBOARD_FAB2(SCH_1):PVDDQ_KLM    I55 @BASEBOARD_FAB2_LIB.BASEBOARD_FAB2(SCH_1):PAGE86
    64 PVDDQ_KLM @BASEBOARD_FAB2_LIB.BASEBOARD_FAB2(SCH_1):PVDDQ_KLM    I55 @BASEBOARD_FAB2_LIB.BASEBOARD_FAB2(SCH_1):PAGE86
    67 PVDDQ_KLM @BASEBOARD_FAB2_LIB.BASEBOARD_FAB2(SCH_1):PVDDQ_KLM    I55 @BASEBOARD_FAB2_LIB.BASEBOARD_FAB2(SCH_1):PAGE86
    70 PVDDQ_KLM @BASEBOARD_FAB2_LIB.BASEBOARD_FAB2(SCH_1):PVDDQ_KLM    I55 @BASEBOARD_FAB2_LIB.BASEBOARD_FAB2(SCH_1):PAGE86
    73 PVDDQ_KLM @BASEBOARD_FAB2_LIB.BASEBOARD_FAB2(SCH_1):PVDDQ_KLM    I55 @BASEBOARD_FAB2_LIB.BASEBOARD_FAB2(SCH_1):PAGE86
    76 PVDDQ_KLM @BASEBOARD_FAB2_LIB.BASEBOARD_FAB2(SCH_1):PVDDQ_KLM    I55 @BASEBOARD_FAB2_LIB.BASEBOARD_FAB2(SCH_1):PAGE86
    80 PVDDQ_KLM @BASEBOARD_FAB2_LIB.BASEBOARD_FAB2(SCH_1):PVDDQ_KLM    I55 @BASEBOARD_FAB2_LIB.BASEBOARD_FAB2(SCH_1):PAGE86
    83 PVDDQ_KLM @BASEBOARD_FAB2_LIB.BASEBOARD_FAB2(SCH_1):PVDDQ_KLM    I55 @BASEBOARD_FAB2_LIB.BASEBOARD_FAB2(SCH_1):PAGE86
    85 PVDDQ_KLM @BASEBOARD_FAB2_LIB.BASEBOARD_FAB2(SCH_1):PVDDQ_KLM    I55 @BASEBOARD_FAB2_LIB.BASEBOARD_FAB2(SCH_1):PAGE86
    88 PVDDQ_KLM @BASEBOARD_FAB2_LIB.BASEBOARD_FAB2(SCH_1):PVDDQ_KLM    I55 @BASEBOARD_FAB2_LIB.BASEBOARD_FAB2(SCH_1):PAGE86
    90 PVDDQ_KLM @BASEBOARD_FAB2_LIB.BASEBOARD_FAB2(SCH_1):PVDDQ_KLM    I55 @BASEBOARD_FAB2_LIB.BASEBOARD_FAB2(SCH_1):PAGE86
    92 PVDDQ_KLM @BASEBOARD_FAB2_LIB.BASEBOARD_FAB2(SCH_1):PVDDQ_KLM    I55 @BASEBOARD_FAB2_LIB.BASEBOARD_FAB2(SCH_1):PAGE86
   204 PVDDQ_KLM @BASEBOARD_FAB2_LIB.BASEBOARD_FAB2(SCH_1):PVDDQ_KLM    I55 @BASEBOARD_FAB2_LIB.BASEBOARD_FAB2(SCH_1):PAGE86
   206 PVDDQ_KLM @BASEBOARD_FAB2_LIB.BASEBOARD_FAB2(SCH_1):PVDDQ_KLM    I55 @BASEBOARD_FAB2_LIB.BASEBOARD_FAB2(SCH_1):PAGE86
   209 PVDDQ_KLM @BASEBOARD_FAB2_LIB.BASEBOARD_FAB2(SCH_1):PVDDQ_KLM    I55 @BASEBOARD_FAB2_LIB.BASEBOARD_FAB2(SCH_1):PAGE86
   212 PVDDQ_KLM @BASEBOARD_FAB2_LIB.BASEBOARD_FAB2(SCH_1):PVDDQ_KLM    I55 @BASEBOARD_FAB2_LIB.BASEBOARD_FAB2(SCH_1):PAGE86
   215 PVDDQ_KLM @BASEBOARD_FAB2_LIB.BASEBOARD_FAB2(SCH_1):PVDDQ_KLM    I55 @BASEBOARD_FAB2_LIB.BASEBOARD_FAB2(SCH_1):PAGE86
   217 PVDDQ_KLM @BASEBOARD_FAB2_LIB.BASEBOARD_FAB2(SCH_1):PVDDQ_KLM    I55 @BASEBOARD_FAB2_LIB.BASEBOARD_FAB2(SCH_1):PAGE86
   220 PVDDQ_KLM @BASEBOARD_FAB2_LIB.BASEBOARD_FAB2(SCH_1):PVDDQ_KLM    I55 @BASEBOARD_FAB2_LIB.BASEBOARD_FAB2(SCH_1):PAGE86
   223 PVDDQ_KLM @BASEBOARD_FAB2_LIB.BASEBOARD_FAB2(SCH_1):PVDDQ_KLM    I55 @BASEBOARD_FAB2_LIB.BASEBOARD_FAB2(SCH_1):PAGE86
   226 PVDDQ_KLM @BASEBOARD_FAB2_LIB.BASEBOARD_FAB2(SCH_1):PVDDQ_KLM    I55 @BASEBOARD_FAB2_LIB.BASEBOARD_FAB2(SCH_1):PAGE86
   229 PVDDQ_KLM @BASEBOARD_FAB2_LIB.BASEBOARD_FAB2(SCH_1):PVDDQ_KLM    I55 @BASEBOARD_FAB2_LIB.BASEBOARD_FAB2(SCH_1):PAGE86
   231 PVDDQ_KLM @BASEBOARD_FAB2_LIB.BASEBOARD_FAB2(SCH_1):PVDDQ_KLM    I55 @BASEBOARD_FAB2_LIB.BASEBOARD_FAB2(SCH_1):PAGE86
   233 PVDDQ_KLM @BASEBOARD_FAB2_LIB.BASEBOARD_FAB2(SCH_1):PVDDQ_KLM    I55 @BASEBOARD_FAB2_LIB.BASEBOARD_FAB2(SCH_1):PAGE86
   236 PVDDQ_KLM @BASEBOARD_FAB2_LIB.BASEBOARD_FAB2(SCH_1):PVDDQ_KLM    I55 @BASEBOARD_FAB2_LIB.BASEBOARD_FAB2(SCH_1):PAGE86
   142 PVPP_KLM @BASEBOARD_FAB2_LIB.BASEBOARD_FAB2(SCH_1):PVPP_KLM    I55 @BASEBOARD_FAB2_LIB.BASEBOARD_FAB2(SCH_1):PAGE86
   143 PVPP_KLM @BASEBOARD_FAB2_LIB.BASEBOARD_FAB2(SCH_1):PVPP_KLM    I55 @BASEBOARD_FAB2_LIB.BASEBOARD_FAB2(SCH_1):PAGE86
   288 PVPP_KLM @BASEBOARD_FAB2_LIB.BASEBOARD_FAB2(SCH_1):PVPP_KLM    I55 @BASEBOARD_FAB2_LIB.BASEBOARD_FAB2(SCH_1):PAGE86
   286 PVPP_KLM @BASEBOARD_FAB2_LIB.BASEBOARD_FAB2(SCH_1):PVPP_KLM    I55 @BASEBOARD_FAB2_LIB.BASEBOARD_FAB2(SCH_1):PAGE86
   287 PVPP_KLM @BASEBOARD_FAB2_LIB.BASEBOARD_FAB2(SCH_1):PVPP_KLM    I55 @BASEBOARD_FAB2_LIB.BASEBOARD_FAB2(SCH_1):PAGE86
    77 PVTT_KLM @BASEBOARD_FAB2_LIB.BASEBOARD_FAB2(SCH_1):PVTT_KLM    I55 @BASEBOARD_FAB2_LIB.BASEBOARD_FAB2(SCH_1):PAGE86
   221 PVTT_KLM @BASEBOARD_FAB2_LIB.BASEBOARD_FAB2(SCH_1):PVTT_KLM    I55 @BASEBOARD_FAB2_LIB.BASEBOARD_FAB2(SCH_1):PAGE86

J9M1 SCONN288_H44441003_PIP-SCONN,HA
    79 M_K_MA<0> @BASEBOARD_FAB2_LIB.BASEBOARD_FAB2(SCH_1):M_K_MA(0)    I14 @BASEBOARD_FAB2_LIB.BASEBOARD_FAB2(SCH_1):PAGE84
    72 M_K_MA<1> @BASEBOARD_FAB2_LIB.BASEBOARD_FAB2(SCH_1):M_K_MA(1)    I14 @BASEBOARD_FAB2_LIB.BASEBOARD_FAB2(SCH_1):PAGE84
   225 M_K_MA<10> @BASEBOARD_FAB2_LIB.BASEBOARD_FAB2(SCH_1):M_K_MA(10)    I14 @BASEBOARD_FAB2_LIB.BASEBOARD_FAB2(SCH_1):PAGE84
   210 M_K_MA<11> @BASEBOARD_FAB2_LIB.BASEBOARD_FAB2(SCH_1):M_K_MA(11)    I14 @BASEBOARD_FAB2_LIB.BASEBOARD_FAB2(SCH_1):PAGE84
    65 M_K_MA<12> @BASEBOARD_FAB2_LIB.BASEBOARD_FAB2(SCH_1):M_K_MA(12)    I14 @BASEBOARD_FAB2_LIB.BASEBOARD_FAB2(SCH_1):PAGE84
   232 M_K_MA<13> @BASEBOARD_FAB2_LIB.BASEBOARD_FAB2(SCH_1):M_K_MA(13)    I14 @BASEBOARD_FAB2_LIB.BASEBOARD_FAB2(SCH_1):PAGE84
   228 M_K_MA<14> @BASEBOARD_FAB2_LIB.BASEBOARD_FAB2(SCH_1):M_K_MA(14)    I14 @BASEBOARD_FAB2_LIB.BASEBOARD_FAB2(SCH_1):PAGE84
    86 M_K_MA<15> @BASEBOARD_FAB2_LIB.BASEBOARD_FAB2(SCH_1):M_K_MA(15)    I14 @BASEBOARD_FAB2_LIB.BASEBOARD_FAB2(SCH_1):PAGE84
    82 M_K_MA<16> @BASEBOARD_FAB2_LIB.BASEBOARD_FAB2(SCH_1):M_K_MA(16)    I14 @BASEBOARD_FAB2_LIB.BASEBOARD_FAB2(SCH_1):PAGE84
   234 M_K_MA<17> @BASEBOARD_FAB2_LIB.BASEBOARD_FAB2(SCH_1):M_K_MA(17)    I14 @BASEBOARD_FAB2_LIB.BASEBOARD_FAB2(SCH_1):PAGE84
   216 M_K_MA<2> @BASEBOARD_FAB2_LIB.BASEBOARD_FAB2(SCH_1):M_K_MA(2)    I14 @BASEBOARD_FAB2_LIB.BASEBOARD_FAB2(SCH_1):PAGE84
    71 M_K_MA<3> @BASEBOARD_FAB2_LIB.BASEBOARD_FAB2(SCH_1):M_K_MA(3)    I14 @BASEBOARD_FAB2_LIB.BASEBOARD_FAB2(SCH_1):PAGE84
   214 M_K_MA<4> @BASEBOARD_FAB2_LIB.BASEBOARD_FAB2(SCH_1):M_K_MA(4)    I14 @BASEBOARD_FAB2_LIB.BASEBOARD_FAB2(SCH_1):PAGE84
   213 M_K_MA<5> @BASEBOARD_FAB2_LIB.BASEBOARD_FAB2(SCH_1):M_K_MA(5)    I14 @BASEBOARD_FAB2_LIB.BASEBOARD_FAB2(SCH_1):PAGE84
    69 M_K_MA<6> @BASEBOARD_FAB2_LIB.BASEBOARD_FAB2(SCH_1):M_K_MA(6)    I14 @BASEBOARD_FAB2_LIB.BASEBOARD_FAB2(SCH_1):PAGE84
   211 M_K_MA<7> @BASEBOARD_FAB2_LIB.BASEBOARD_FAB2(SCH_1):M_K_MA(7)    I14 @BASEBOARD_FAB2_LIB.BASEBOARD_FAB2(SCH_1):PAGE84
    68 M_K_MA<8> @BASEBOARD_FAB2_LIB.BASEBOARD_FAB2(SCH_1):M_K_MA(8)    I14 @BASEBOARD_FAB2_LIB.BASEBOARD_FAB2(SCH_1):PAGE84
    66 M_K_MA<9> @BASEBOARD_FAB2_LIB.BASEBOARD_FAB2(SCH_1):M_K_MA(9)    I14 @BASEBOARD_FAB2_LIB.BASEBOARD_FAB2(SCH_1):PAGE84
    62 M_K_ACT_N @BASEBOARD_FAB2_LIB.BASEBOARD_FAB2(SCH_1):M_K_ACT_N    I14 @BASEBOARD_FAB2_LIB.BASEBOARD_FAB2(SCH_1):PAGE84
   208 M_K_ALERT_N @BASEBOARD_FAB2_LIB.BASEBOARD_FAB2(SCH_1):M_K_ALERT_N    I14 @BASEBOARD_FAB2_LIB.BASEBOARD_FAB2(SCH_1):PAGE84
   224 M_K_BA<1> @BASEBOARD_FAB2_LIB.BASEBOARD_FAB2(SCH_1):M_K_BA(1)    I14 @BASEBOARD_FAB2_LIB.BASEBOARD_FAB2(SCH_1):PAGE84
    81 M_K_BA<0> @BASEBOARD_FAB2_LIB.BASEBOARD_FAB2(SCH_1):M_K_BA(0)    I14 @BASEBOARD_FAB2_LIB.BASEBOARD_FAB2(SCH_1):PAGE84
   207 M_K_BG<1> @BASEBOARD_FAB2_LIB.BASEBOARD_FAB2(SCH_1):M_K_BG(1)    I14 @BASEBOARD_FAB2_LIB.BASEBOARD_FAB2(SCH_1):PAGE84
    63 M_K_BG<0> @BASEBOARD_FAB2_LIB.BASEBOARD_FAB2(SCH_1):M_K_BG(0)    I14 @BASEBOARD_FAB2_LIB.BASEBOARD_FAB2(SCH_1):PAGE84
   235 M_K_C<2> @BASEBOARD_FAB2_LIB.BASEBOARD_FAB2(SCH_1):M_K_C(2)    I14 @BASEBOARD_FAB2_LIB.BASEBOARD_FAB2(SCH_1):PAGE84
   199 M_K_ECC<7> @BASEBOARD_FAB2_LIB.BASEBOARD_FAB2(SCH_1):M_K_ECC(7)    I14 @BASEBOARD_FAB2_LIB.BASEBOARD_FAB2(SCH_1):PAGE84
    54 M_K_ECC<6> @BASEBOARD_FAB2_LIB.BASEBOARD_FAB2(SCH_1):M_K_ECC(6)    I14 @BASEBOARD_FAB2_LIB.BASEBOARD_FAB2(SCH_1):PAGE84
   192 M_K_ECC<5> @BASEBOARD_FAB2_LIB.BASEBOARD_FAB2(SCH_1):M_K_ECC(5)    I14 @BASEBOARD_FAB2_LIB.BASEBOARD_FAB2(SCH_1):PAGE84
    47 M_K_ECC<4> @BASEBOARD_FAB2_LIB.BASEBOARD_FAB2(SCH_1):M_K_ECC(4)    I14 @BASEBOARD_FAB2_LIB.BASEBOARD_FAB2(SCH_1):PAGE84
   201 M_K_ECC<3> @BASEBOARD_FAB2_LIB.BASEBOARD_FAB2(SCH_1):M_K_ECC(3)    I14 @BASEBOARD_FAB2_LIB.BASEBOARD_FAB2(SCH_1):PAGE84
    56 M_K_ECC<2> @BASEBOARD_FAB2_LIB.BASEBOARD_FAB2(SCH_1):M_K_ECC(2)    I14 @BASEBOARD_FAB2_LIB.BASEBOARD_FAB2(SCH_1):PAGE84
   194 M_K_ECC<1> @BASEBOARD_FAB2_LIB.BASEBOARD_FAB2(SCH_1):M_K_ECC(1)    I14 @BASEBOARD_FAB2_LIB.BASEBOARD_FAB2(SCH_1):PAGE84
    49 M_K_ECC<0> @BASEBOARD_FAB2_LIB.BASEBOARD_FAB2(SCH_1):M_K_ECC(0)    I14 @BASEBOARD_FAB2_LIB.BASEBOARD_FAB2(SCH_1):PAGE84
    75 M_K_CLK_DN<2> @BASEBOARD_FAB2_LIB.BASEBOARD_FAB2(SCH_1):M_K_CLK_DN(2)    I14 @BASEBOARD_FAB2_LIB.BASEBOARD_FAB2(SCH_1):PAGE84
    74 M_K_CLK_DP<2> @BASEBOARD_FAB2_LIB.BASEBOARD_FAB2(SCH_1):M_K_CLK_DP(2)    I14 @BASEBOARD_FAB2_LIB.BASEBOARD_FAB2(SCH_1):PAGE84
   219 M_K_CLK_DN<3> @BASEBOARD_FAB2_LIB.BASEBOARD_FAB2(SCH_1):M_K_CLK_DN(3)    I14 @BASEBOARD_FAB2_LIB.BASEBOARD_FAB2(SCH_1):PAGE84
   218 M_K_CLK_DP<3> @BASEBOARD_FAB2_LIB.BASEBOARD_FAB2(SCH_1):M_K_CLK_DP(3)    I14 @BASEBOARD_FAB2_LIB.BASEBOARD_FAB2(SCH_1):PAGE84
   203 M_K_CKE<3> @BASEBOARD_FAB2_LIB.BASEBOARD_FAB2(SCH_1):M_K_CKE(3)    I14 @BASEBOARD_FAB2_LIB.BASEBOARD_FAB2(SCH_1):PAGE84
    60 M_K_CKE<2> @BASEBOARD_FAB2_LIB.BASEBOARD_FAB2(SCH_1):M_K_CKE(2)    I14 @BASEBOARD_FAB2_LIB.BASEBOARD_FAB2(SCH_1):PAGE84
   280 M_K_DQ<63> @BASEBOARD_FAB2_LIB.BASEBOARD_FAB2(SCH_1):M_K_DQ(63)    I14 @BASEBOARD_FAB2_LIB.BASEBOARD_FAB2(SCH_1):PAGE84
   135 M_K_DQ<62> @BASEBOARD_FAB2_LIB.BASEBOARD_FAB2(SCH_1):M_K_DQ(62)    I14 @BASEBOARD_FAB2_LIB.BASEBOARD_FAB2(SCH_1):PAGE84
   273 M_K_DQ<61> @BASEBOARD_FAB2_LIB.BASEBOARD_FAB2(SCH_1):M_K_DQ(61)    I14 @BASEBOARD_FAB2_LIB.BASEBOARD_FAB2(SCH_1):PAGE84
   128 M_K_DQ<60> @BASEBOARD_FAB2_LIB.BASEBOARD_FAB2(SCH_1):M_K_DQ(60)    I14 @BASEBOARD_FAB2_LIB.BASEBOARD_FAB2(SCH_1):PAGE84
   282 M_K_DQ<59> @BASEBOARD_FAB2_LIB.BASEBOARD_FAB2(SCH_1):M_K_DQ(59)    I14 @BASEBOARD_FAB2_LIB.BASEBOARD_FAB2(SCH_1):PAGE84
   137 M_K_DQ<58> @BASEBOARD_FAB2_LIB.BASEBOARD_FAB2(SCH_1):M_K_DQ(58)    I14 @BASEBOARD_FAB2_LIB.BASEBOARD_FAB2(SCH_1):PAGE84
   275 M_K_DQ<57> @BASEBOARD_FAB2_LIB.BASEBOARD_FAB2(SCH_1):M_K_DQ(57)    I14 @BASEBOARD_FAB2_LIB.BASEBOARD_FAB2(SCH_1):PAGE84
   130 M_K_DQ<56> @BASEBOARD_FAB2_LIB.BASEBOARD_FAB2(SCH_1):M_K_DQ(56)    I14 @BASEBOARD_FAB2_LIB.BASEBOARD_FAB2(SCH_1):PAGE84
   269 M_K_DQ<55> @BASEBOARD_FAB2_LIB.BASEBOARD_FAB2(SCH_1):M_K_DQ(55)    I14 @BASEBOARD_FAB2_LIB.BASEBOARD_FAB2(SCH_1):PAGE84
   124 M_K_DQ<54> @BASEBOARD_FAB2_LIB.BASEBOARD_FAB2(SCH_1):M_K_DQ(54)    I14 @BASEBOARD_FAB2_LIB.BASEBOARD_FAB2(SCH_1):PAGE84
   262 M_K_DQ<53> @BASEBOARD_FAB2_LIB.BASEBOARD_FAB2(SCH_1):M_K_DQ(53)    I14 @BASEBOARD_FAB2_LIB.BASEBOARD_FAB2(SCH_1):PAGE84
   117 M_K_DQ<52> @BASEBOARD_FAB2_LIB.BASEBOARD_FAB2(SCH_1):M_K_DQ(52)    I14 @BASEBOARD_FAB2_LIB.BASEBOARD_FAB2(SCH_1):PAGE84
   271 M_K_DQ<51> @BASEBOARD_FAB2_LIB.BASEBOARD_FAB2(SCH_1):M_K_DQ(51)    I14 @BASEBOARD_FAB2_LIB.BASEBOARD_FAB2(SCH_1):PAGE84
   126 M_K_DQ<50> @BASEBOARD_FAB2_LIB.BASEBOARD_FAB2(SCH_1):M_K_DQ(50)    I14 @BASEBOARD_FAB2_LIB.BASEBOARD_FAB2(SCH_1):PAGE84
   264 M_K_DQ<49> @BASEBOARD_FAB2_LIB.BASEBOARD_FAB2(SCH_1):M_K_DQ(49)    I14 @BASEBOARD_FAB2_LIB.BASEBOARD_FAB2(SCH_1):PAGE84
   119 M_K_DQ<48> @BASEBOARD_FAB2_LIB.BASEBOARD_FAB2(SCH_1):M_K_DQ(48)    I14 @BASEBOARD_FAB2_LIB.BASEBOARD_FAB2(SCH_1):PAGE84
   258 M_K_DQ<47> @BASEBOARD_FAB2_LIB.BASEBOARD_FAB2(SCH_1):M_K_DQ(47)    I14 @BASEBOARD_FAB2_LIB.BASEBOARD_FAB2(SCH_1):PAGE84
   113 M_K_DQ<46> @BASEBOARD_FAB2_LIB.BASEBOARD_FAB2(SCH_1):M_K_DQ(46)    I14 @BASEBOARD_FAB2_LIB.BASEBOARD_FAB2(SCH_1):PAGE84
   251 M_K_DQ<45> @BASEBOARD_FAB2_LIB.BASEBOARD_FAB2(SCH_1):M_K_DQ(45)    I14 @BASEBOARD_FAB2_LIB.BASEBOARD_FAB2(SCH_1):PAGE84
   106 M_K_DQ<44> @BASEBOARD_FAB2_LIB.BASEBOARD_FAB2(SCH_1):M_K_DQ(44)    I14 @BASEBOARD_FAB2_LIB.BASEBOARD_FAB2(SCH_1):PAGE84
   260 M_K_DQ<43> @BASEBOARD_FAB2_LIB.BASEBOARD_FAB2(SCH_1):M_K_DQ(43)    I14 @BASEBOARD_FAB2_LIB.BASEBOARD_FAB2(SCH_1):PAGE84
   115 M_K_DQ<42> @BASEBOARD_FAB2_LIB.BASEBOARD_FAB2(SCH_1):M_K_DQ(42)    I14 @BASEBOARD_FAB2_LIB.BASEBOARD_FAB2(SCH_1):PAGE84
   253 M_K_DQ<41> @BASEBOARD_FAB2_LIB.BASEBOARD_FAB2(SCH_1):M_K_DQ(41)    I14 @BASEBOARD_FAB2_LIB.BASEBOARD_FAB2(SCH_1):PAGE84
   108 M_K_DQ<40> @BASEBOARD_FAB2_LIB.BASEBOARD_FAB2(SCH_1):M_K_DQ(40)    I14 @BASEBOARD_FAB2_LIB.BASEBOARD_FAB2(SCH_1):PAGE84
   247 M_K_DQ<39> @BASEBOARD_FAB2_LIB.BASEBOARD_FAB2(SCH_1):M_K_DQ(39)    I14 @BASEBOARD_FAB2_LIB.BASEBOARD_FAB2(SCH_1):PAGE84
   102 M_K_DQ<38> @BASEBOARD_FAB2_LIB.BASEBOARD_FAB2(SCH_1):M_K_DQ(38)    I14 @BASEBOARD_FAB2_LIB.BASEBOARD_FAB2(SCH_1):PAGE84
   240 M_K_DQ<37> @BASEBOARD_FAB2_LIB.BASEBOARD_FAB2(SCH_1):M_K_DQ(37)    I14 @BASEBOARD_FAB2_LIB.BASEBOARD_FAB2(SCH_1):PAGE84
    95 M_K_DQ<36> @BASEBOARD_FAB2_LIB.BASEBOARD_FAB2(SCH_1):M_K_DQ(36)    I14 @BASEBOARD_FAB2_LIB.BASEBOARD_FAB2(SCH_1):PAGE84
   249 M_K_DQ<35> @BASEBOARD_FAB2_LIB.BASEBOARD_FAB2(SCH_1):M_K_DQ(35)    I14 @BASEBOARD_FAB2_LIB.BASEBOARD_FAB2(SCH_1):PAGE84
   104 M_K_DQ<34> @BASEBOARD_FAB2_LIB.BASEBOARD_FAB2(SCH_1):M_K_DQ(34)    I14 @BASEBOARD_FAB2_LIB.BASEBOARD_FAB2(SCH_1):PAGE84
   242 M_K_DQ<33> @BASEBOARD_FAB2_LIB.BASEBOARD_FAB2(SCH_1):M_K_DQ(33)    I14 @BASEBOARD_FAB2_LIB.BASEBOARD_FAB2(SCH_1):PAGE84
    97 M_K_DQ<32> @BASEBOARD_FAB2_LIB.BASEBOARD_FAB2(SCH_1):M_K_DQ(32)    I14 @BASEBOARD_FAB2_LIB.BASEBOARD_FAB2(SCH_1):PAGE84
   188 M_K_DQ<31> @BASEBOARD_FAB2_LIB.BASEBOARD_FAB2(SCH_1):M_K_DQ(31)    I14 @BASEBOARD_FAB2_LIB.BASEBOARD_FAB2(SCH_1):PAGE84
    43 M_K_DQ<30> @BASEBOARD_FAB2_LIB.BASEBOARD_FAB2(SCH_1):M_K_DQ(30)    I14 @BASEBOARD_FAB2_LIB.BASEBOARD_FAB2(SCH_1):PAGE84
   181 M_K_DQ<29> @BASEBOARD_FAB2_LIB.BASEBOARD_FAB2(SCH_1):M_K_DQ(29)    I14 @BASEBOARD_FAB2_LIB.BASEBOARD_FAB2(SCH_1):PAGE84
    36 M_K_DQ<28> @BASEBOARD_FAB2_LIB.BASEBOARD_FAB2(SCH_1):M_K_DQ(28)    I14 @BASEBOARD_FAB2_LIB.BASEBOARD_FAB2(SCH_1):PAGE84
   190 M_K_DQ<27> @BASEBOARD_FAB2_LIB.BASEBOARD_FAB2(SCH_1):M_K_DQ(27)    I14 @BASEBOARD_FAB2_LIB.BASEBOARD_FAB2(SCH_1):PAGE84
    45 M_K_DQ<26> @BASEBOARD_FAB2_LIB.BASEBOARD_FAB2(SCH_1):M_K_DQ(26)    I14 @BASEBOARD_FAB2_LIB.BASEBOARD_FAB2(SCH_1):PAGE84
   183 M_K_DQ<25> @BASEBOARD_FAB2_LIB.BASEBOARD_FAB2(SCH_1):M_K_DQ(25)    I14 @BASEBOARD_FAB2_LIB.BASEBOARD_FAB2(SCH_1):PAGE84
    38 M_K_DQ<24> @BASEBOARD_FAB2_LIB.BASEBOARD_FAB2(SCH_1):M_K_DQ(24)    I14 @BASEBOARD_FAB2_LIB.BASEBOARD_FAB2(SCH_1):PAGE84
   177 M_K_DQ<23> @BASEBOARD_FAB2_LIB.BASEBOARD_FAB2(SCH_1):M_K_DQ(23)    I14 @BASEBOARD_FAB2_LIB.BASEBOARD_FAB2(SCH_1):PAGE84
    32 M_K_DQ<22> @BASEBOARD_FAB2_LIB.BASEBOARD_FAB2(SCH_1):M_K_DQ(22)    I14 @BASEBOARD_FAB2_LIB.BASEBOARD_FAB2(SCH_1):PAGE84
   170 M_K_DQ<21> @BASEBOARD_FAB2_LIB.BASEBOARD_FAB2(SCH_1):M_K_DQ(21)    I14 @BASEBOARD_FAB2_LIB.BASEBOARD_FAB2(SCH_1):PAGE84
    25 M_K_DQ<20> @BASEBOARD_FAB2_LIB.BASEBOARD_FAB2(SCH_1):M_K_DQ(20)    I14 @BASEBOARD_FAB2_LIB.BASEBOARD_FAB2(SCH_1):PAGE84
   179 M_K_DQ<19> @BASEBOARD_FAB2_LIB.BASEBOARD_FAB2(SCH_1):M_K_DQ(19)    I14 @BASEBOARD_FAB2_LIB.BASEBOARD_FAB2(SCH_1):PAGE84
    34 M_K_DQ<18> @BASEBOARD_FAB2_LIB.BASEBOARD_FAB2(SCH_1):M_K_DQ(18)    I14 @BASEBOARD_FAB2_LIB.BASEBOARD_FAB2(SCH_1):PAGE84
   172 M_K_DQ<17> @BASEBOARD_FAB2_LIB.BASEBOARD_FAB2(SCH_1):M_K_DQ(17)    I14 @BASEBOARD_FAB2_LIB.BASEBOARD_FAB2(SCH_1):PAGE84
    27 M_K_DQ<16> @BASEBOARD_FAB2_LIB.BASEBOARD_FAB2(SCH_1):M_K_DQ(16)    I14 @BASEBOARD_FAB2_LIB.BASEBOARD_FAB2(SCH_1):PAGE84
   166 M_K_DQ<15> @BASEBOARD_FAB2_LIB.BASEBOARD_FAB2(SCH_1):M_K_DQ(15)    I14 @BASEBOARD_FAB2_LIB.BASEBOARD_FAB2(SCH_1):PAGE84
    21 M_K_DQ<14> @BASEBOARD_FAB2_LIB.BASEBOARD_FAB2(SCH_1):M_K_DQ(14)    I14 @BASEBOARD_FAB2_LIB.BASEBOARD_FAB2(SCH_1):PAGE84
   159 M_K_DQ<13> @BASEBOARD_FAB2_LIB.BASEBOARD_FAB2(SCH_1):M_K_DQ(13)    I14 @BASEBOARD_FAB2_LIB.BASEBOARD_FAB2(SCH_1):PAGE84
    14 M_K_DQ<12> @BASEBOARD_FAB2_LIB.BASEBOARD_FAB2(SCH_1):M_K_DQ(12)    I14 @BASEBOARD_FAB2_LIB.BASEBOARD_FAB2(SCH_1):PAGE84
   168 M_K_DQ<11> @BASEBOARD_FAB2_LIB.BASEBOARD_FAB2(SCH_1):M_K_DQ(11)    I14 @BASEBOARD_FAB2_LIB.BASEBOARD_FAB2(SCH_1):PAGE84
    23 M_K_DQ<10> @BASEBOARD_FAB2_LIB.BASEBOARD_FAB2(SCH_1):M_K_DQ(10)    I14 @BASEBOARD_FAB2_LIB.BASEBOARD_FAB2(SCH_1):PAGE84
   161 M_K_DQ<9> @BASEBOARD_FAB2_LIB.BASEBOARD_FAB2(SCH_1):M_K_DQ(9)    I14 @BASEBOARD_FAB2_LIB.BASEBOARD_FAB2(SCH_1):PAGE84
    16 M_K_DQ<8> @BASEBOARD_FAB2_LIB.BASEBOARD_FAB2(SCH_1):M_K_DQ(8)    I14 @BASEBOARD_FAB2_LIB.BASEBOARD_FAB2(SCH_1):PAGE84
   155 M_K_DQ<7> @BASEBOARD_FAB2_LIB.BASEBOARD_FAB2(SCH_1):M_K_DQ(7)    I14 @BASEBOARD_FAB2_LIB.BASEBOARD_FAB2(SCH_1):PAGE84
    10 M_K_DQ<6> @BASEBOARD_FAB2_LIB.BASEBOARD_FAB2(SCH_1):M_K_DQ(6)    I14 @BASEBOARD_FAB2_LIB.BASEBOARD_FAB2(SCH_1):PAGE84
   148 M_K_DQ<5> @BASEBOARD_FAB2_LIB.BASEBOARD_FAB2(SCH_1):M_K_DQ(5)    I14 @BASEBOARD_FAB2_LIB.BASEBOARD_FAB2(SCH_1):PAGE84
     3 M_K_DQ<4> @BASEBOARD_FAB2_LIB.BASEBOARD_FAB2(SCH_1):M_K_DQ(4)    I14 @BASEBOARD_FAB2_LIB.BASEBOARD_FAB2(SCH_1):PAGE84
   157 M_K_DQ<3> @BASEBOARD_FAB2_LIB.BASEBOARD_FAB2(SCH_1):M_K_DQ(3)    I14 @BASEBOARD_FAB2_LIB.BASEBOARD_FAB2(SCH_1):PAGE84
    12 M_K_DQ<2> @BASEBOARD_FAB2_LIB.BASEBOARD_FAB2(SCH_1):M_K_DQ(2)    I14 @BASEBOARD_FAB2_LIB.BASEBOARD_FAB2(SCH_1):PAGE84
   150 M_K_DQ<1> @BASEBOARD_FAB2_LIB.BASEBOARD_FAB2(SCH_1):M_K_DQ(1)    I14 @BASEBOARD_FAB2_LIB.BASEBOARD_FAB2(SCH_1):PAGE84
     5 M_K_DQ<0> @BASEBOARD_FAB2_LIB.BASEBOARD_FAB2(SCH_1):M_K_DQ(0)    I14 @BASEBOARD_FAB2_LIB.BASEBOARD_FAB2(SCH_1):PAGE84
    78 FM_DIMM_EVENT_COD_N @BASEBOARD_FAB2_LIB.BASEBOARD_FAB2(SCH_1):FM_DIMM_EVENT_COD_N    I14 @BASEBOARD_FAB2_LIB.BASEBOARD_FAB2(SCH_1):PAGE84
    91 M_K_ODT<3> @BASEBOARD_FAB2_LIB.BASEBOARD_FAB2(SCH_1):M_K_ODT(3)    I14 @BASEBOARD_FAB2_LIB.BASEBOARD_FAB2(SCH_1):PAGE84
    87 M_K_ODT<2> @BASEBOARD_FAB2_LIB.BASEBOARD_FAB2(SCH_1):M_K_ODT(2)    I14 @BASEBOARD_FAB2_LIB.BASEBOARD_FAB2(SCH_1):PAGE84
   222 M_K_PAR @BASEBOARD_FAB2_LIB.BASEBOARD_FAB2(SCH_1):M_K_PAR    I14 @BASEBOARD_FAB2_LIB.BASEBOARD_FAB2(SCH_1):PAGE84
    58 M_KLM_RST_N @BASEBOARD_FAB2_LIB.BASEBOARD_FAB2(SCH_1):M_KLM_RST_N    I14 @BASEBOARD_FAB2_LIB.BASEBOARD_FAB2(SCH_1):PAGE84
   144 TP_CH_K_DIMM0_RFU_2 @BASEBOARD_FAB2_LIB.BASEBOARD_FAB2(SCH_1):TP_CH_K_DIMM0_RFU_2    I14 @BASEBOARD_FAB2_LIB.BASEBOARD_FAB2(SCH_1):PAGE84
   227 TP_CH_K_DIMM0_RFU_1 @BASEBOARD_FAB2_LIB.BASEBOARD_FAB2(SCH_1):TP_CH_K_DIMM0_RFU_1    I14 @BASEBOARD_FAB2_LIB.BASEBOARD_FAB2(SCH_1):PAGE84
   205 TP_CH_K_DIMM0_RFU_0 @BASEBOARD_FAB2_LIB.BASEBOARD_FAB2(SCH_1):TP_CH_K_DIMM0_RFU_0    I14 @BASEBOARD_FAB2_LIB.BASEBOARD_FAB2(SCH_1):PAGE84
    84 M_K_CS_N<4> @BASEBOARD_FAB2_LIB.BASEBOARD_FAB2(SCH_1):M_K_CS_N(4)    I14 @BASEBOARD_FAB2_LIB.BASEBOARD_FAB2(SCH_1):PAGE84
    89 M_K_CS_N<5> @BASEBOARD_FAB2_LIB.BASEBOARD_FAB2(SCH_1):M_K_CS_N(5)    I14 @BASEBOARD_FAB2_LIB.BASEBOARD_FAB2(SCH_1):PAGE84
    93 M_K_CS_N<6> @BASEBOARD_FAB2_LIB.BASEBOARD_FAB2(SCH_1):M_K_CS_N(6)    I14 @BASEBOARD_FAB2_LIB.BASEBOARD_FAB2(SCH_1):PAGE84
   237 M_K_CS_N<7> @BASEBOARD_FAB2_LIB.BASEBOARD_FAB2(SCH_1):M_K_CS_N(7)    I14 @BASEBOARD_FAB2_LIB.BASEBOARD_FAB2(SCH_1):PAGE84
   238    GND @BASEBOARD_FAB2_LIB.BASEBOARD_FAB2(SCH_1):GND    I14 @BASEBOARD_FAB2_LIB.BASEBOARD_FAB2(SCH_1):PAGE84
   140    GND @BASEBOARD_FAB2_LIB.BASEBOARD_FAB2(SCH_1):GND    I14 @BASEBOARD_FAB2_LIB.BASEBOARD_FAB2(SCH_1):PAGE84
   139 PVPP_KLM @BASEBOARD_FAB2_LIB.BASEBOARD_FAB2(SCH_1):PVPP_KLM    I14 @BASEBOARD_FAB2_LIB.BASEBOARD_FAB2(SCH_1):PAGE84
   230 FM_ADR_COMPLETE_KLM_N @BASEBOARD_FAB2_LIB.BASEBOARD_FAB2(SCH_1):FM_ADR_COMPLETE_KLM_N    I14 @BASEBOARD_FAB2_LIB.BASEBOARD_FAB2(SCH_1):PAGE84
   141 SMB_DDR_KLM_VPP_SCL @BASEBOARD_FAB2_LIB.BASEBOARD_FAB2(SCH_1):SMB_DDR_KLM_VPP_SCL    I14 @BASEBOARD_FAB2_LIB.BASEBOARD_FAB2(SCH_1):PAGE84
   285 SMB_DDR_KLM_VPP_SDA @BASEBOARD_FAB2_LIB.BASEBOARD_FAB2(SCH_1):SMB_DDR_KLM_VPP_SDA    I14 @BASEBOARD_FAB2_LIB.BASEBOARD_FAB2(SCH_1):PAGE84
   284 PVPP_KLM @BASEBOARD_FAB2_LIB.BASEBOARD_FAB2(SCH_1):PVPP_KLM    I14 @BASEBOARD_FAB2_LIB.BASEBOARD_FAB2(SCH_1):PAGE84
   146 M_K_VREF @BASEBOARD_FAB2_LIB.BASEBOARD_FAB2(SCH_1):M_K_VREF    I14 @BASEBOARD_FAB2_LIB.BASEBOARD_FAB2(SCH_1):PAGE84
   152 M_K_DQS_DN<0> @BASEBOARD_FAB2_LIB.BASEBOARD_FAB2(SCH_1):M_K_DQS_DN(0)   I102 @BASEBOARD_FAB2_LIB.BASEBOARD_FAB2(SCH_1):PAGE84
   153 M_K_DQS_DP<0> @BASEBOARD_FAB2_LIB.BASEBOARD_FAB2(SCH_1):M_K_DQS_DP(0)   I102 @BASEBOARD_FAB2_LIB.BASEBOARD_FAB2(SCH_1):PAGE84
    19 M_K_DQS_DN<10> @BASEBOARD_FAB2_LIB.BASEBOARD_FAB2(SCH_1):M_K_DQS_DN(10)   I102 @BASEBOARD_FAB2_LIB.BASEBOARD_FAB2(SCH_1):PAGE84
    18 M_K_DQS_DP<10> @BASEBOARD_FAB2_LIB.BASEBOARD_FAB2(SCH_1):M_K_DQS_DP(10)   I102 @BASEBOARD_FAB2_LIB.BASEBOARD_FAB2(SCH_1):PAGE84
    30 M_K_DQS_DN<11> @BASEBOARD_FAB2_LIB.BASEBOARD_FAB2(SCH_1):M_K_DQS_DN(11)   I102 @BASEBOARD_FAB2_LIB.BASEBOARD_FAB2(SCH_1):PAGE84
    29 M_K_DQS_DP<11> @BASEBOARD_FAB2_LIB.BASEBOARD_FAB2(SCH_1):M_K_DQS_DP(11)   I102 @BASEBOARD_FAB2_LIB.BASEBOARD_FAB2(SCH_1):PAGE84
    41 M_K_DQS_DN<12> @BASEBOARD_FAB2_LIB.BASEBOARD_FAB2(SCH_1):M_K_DQS_DN(12)   I102 @BASEBOARD_FAB2_LIB.BASEBOARD_FAB2(SCH_1):PAGE84
    40 M_K_DQS_DP<12> @BASEBOARD_FAB2_LIB.BASEBOARD_FAB2(SCH_1):M_K_DQS_DP(12)   I102 @BASEBOARD_FAB2_LIB.BASEBOARD_FAB2(SCH_1):PAGE84
   100 M_K_DQS_DN<13> @BASEBOARD_FAB2_LIB.BASEBOARD_FAB2(SCH_1):M_K_DQS_DN(13)   I102 @BASEBOARD_FAB2_LIB.BASEBOARD_FAB2(SCH_1):PAGE84
    99 M_K_DQS_DP<13> @BASEBOARD_FAB2_LIB.BASEBOARD_FAB2(SCH_1):M_K_DQS_DP(13)   I102 @BASEBOARD_FAB2_LIB.BASEBOARD_FAB2(SCH_1):PAGE84
   111 M_K_DQS_DN<14> @BASEBOARD_FAB2_LIB.BASEBOARD_FAB2(SCH_1):M_K_DQS_DN(14)   I102 @BASEBOARD_FAB2_LIB.BASEBOARD_FAB2(SCH_1):PAGE84
   110 M_K_DQS_DP<14> @BASEBOARD_FAB2_LIB.BASEBOARD_FAB2(SCH_1):M_K_DQS_DP(14)   I102 @BASEBOARD_FAB2_LIB.BASEBOARD_FAB2(SCH_1):PAGE84
   122 M_K_DQS_DN<15> @BASEBOARD_FAB2_LIB.BASEBOARD_FAB2(SCH_1):M_K_DQS_DN(15)   I102 @BASEBOARD_FAB2_LIB.BASEBOARD_FAB2(SCH_1):PAGE84
   121 M_K_DQS_DP<15> @BASEBOARD_FAB2_LIB.BASEBOARD_FAB2(SCH_1):M_K_DQS_DP(15)   I102 @BASEBOARD_FAB2_LIB.BASEBOARD_FAB2(SCH_1):PAGE84
   133 M_K_DQS_DN<16> @BASEBOARD_FAB2_LIB.BASEBOARD_FAB2(SCH_1):M_K_DQS_DN(16)   I102 @BASEBOARD_FAB2_LIB.BASEBOARD_FAB2(SCH_1):PAGE84
   132 M_K_DQS_DP<16> @BASEBOARD_FAB2_LIB.BASEBOARD_FAB2(SCH_1):M_K_DQS_DP(16)   I102 @BASEBOARD_FAB2_LIB.BASEBOARD_FAB2(SCH_1):PAGE84
    52 M_K_DQS_DN<17> @BASEBOARD_FAB2_LIB.BASEBOARD_FAB2(SCH_1):M_K_DQS_DN(17)   I102 @BASEBOARD_FAB2_LIB.BASEBOARD_FAB2(SCH_1):PAGE84
    51 M_K_DQS_DP<17> @BASEBOARD_FAB2_LIB.BASEBOARD_FAB2(SCH_1):M_K_DQS_DP(17)   I102 @BASEBOARD_FAB2_LIB.BASEBOARD_FAB2(SCH_1):PAGE84
   163 M_K_DQS_DN<1> @BASEBOARD_FAB2_LIB.BASEBOARD_FAB2(SCH_1):M_K_DQS_DN(1)   I102 @BASEBOARD_FAB2_LIB.BASEBOARD_FAB2(SCH_1):PAGE84
   164 M_K_DQS_DP<1> @BASEBOARD_FAB2_LIB.BASEBOARD_FAB2(SCH_1):M_K_DQS_DP(1)   I102 @BASEBOARD_FAB2_LIB.BASEBOARD_FAB2(SCH_1):PAGE84
   174 M_K_DQS_DN<2> @BASEBOARD_FAB2_LIB.BASEBOARD_FAB2(SCH_1):M_K_DQS_DN(2)   I102 @BASEBOARD_FAB2_LIB.BASEBOARD_FAB2(SCH_1):PAGE84
   175 M_K_DQS_DP<2> @BASEBOARD_FAB2_LIB.BASEBOARD_FAB2(SCH_1):M_K_DQS_DP(2)   I102 @BASEBOARD_FAB2_LIB.BASEBOARD_FAB2(SCH_1):PAGE84
   185 M_K_DQS_DN<3> @BASEBOARD_FAB2_LIB.BASEBOARD_FAB2(SCH_1):M_K_DQS_DN(3)   I102 @BASEBOARD_FAB2_LIB.BASEBOARD_FAB2(SCH_1):PAGE84
   186 M_K_DQS_DP<3> @BASEBOARD_FAB2_LIB.BASEBOARD_FAB2(SCH_1):M_K_DQS_DP(3)   I102 @BASEBOARD_FAB2_LIB.BASEBOARD_FAB2(SCH_1):PAGE84
   244 M_K_DQS_DN<4> @BASEBOARD_FAB2_LIB.BASEBOARD_FAB2(SCH_1):M_K_DQS_DN(4)   I102 @BASEBOARD_FAB2_LIB.BASEBOARD_FAB2(SCH_1):PAGE84
   245 M_K_DQS_DP<4> @BASEBOARD_FAB2_LIB.BASEBOARD_FAB2(SCH_1):M_K_DQS_DP(4)   I102 @BASEBOARD_FAB2_LIB.BASEBOARD_FAB2(SCH_1):PAGE84
   255 M_K_DQS_DN<5> @BASEBOARD_FAB2_LIB.BASEBOARD_FAB2(SCH_1):M_K_DQS_DN(5)   I102 @BASEBOARD_FAB2_LIB.BASEBOARD_FAB2(SCH_1):PAGE84
   256 M_K_DQS_DP<5> @BASEBOARD_FAB2_LIB.BASEBOARD_FAB2(SCH_1):M_K_DQS_DP(5)   I102 @BASEBOARD_FAB2_LIB.BASEBOARD_FAB2(SCH_1):PAGE84
   266 M_K_DQS_DN<6> @BASEBOARD_FAB2_LIB.BASEBOARD_FAB2(SCH_1):M_K_DQS_DN(6)   I102 @BASEBOARD_FAB2_LIB.BASEBOARD_FAB2(SCH_1):PAGE84
   267 M_K_DQS_DP<6> @BASEBOARD_FAB2_LIB.BASEBOARD_FAB2(SCH_1):M_K_DQS_DP(6)   I102 @BASEBOARD_FAB2_LIB.BASEBOARD_FAB2(SCH_1):PAGE84
   277 M_K_DQS_DN<7> @BASEBOARD_FAB2_LIB.BASEBOARD_FAB2(SCH_1):M_K_DQS_DN(7)   I102 @BASEBOARD_FAB2_LIB.BASEBOARD_FAB2(SCH_1):PAGE84
   278 M_K_DQS_DP<7> @BASEBOARD_FAB2_LIB.BASEBOARD_FAB2(SCH_1):M_K_DQS_DP(7)   I102 @BASEBOARD_FAB2_LIB.BASEBOARD_FAB2(SCH_1):PAGE84
   196 M_K_DQS_DN<8> @BASEBOARD_FAB2_LIB.BASEBOARD_FAB2(SCH_1):M_K_DQS_DN(8)   I102 @BASEBOARD_FAB2_LIB.BASEBOARD_FAB2(SCH_1):PAGE84
   197 M_K_DQS_DP<8> @BASEBOARD_FAB2_LIB.BASEBOARD_FAB2(SCH_1):M_K_DQS_DP(8)   I102 @BASEBOARD_FAB2_LIB.BASEBOARD_FAB2(SCH_1):PAGE84
     8 M_K_DQS_DN<9> @BASEBOARD_FAB2_LIB.BASEBOARD_FAB2(SCH_1):M_K_DQS_DN(9)   I102 @BASEBOARD_FAB2_LIB.BASEBOARD_FAB2(SCH_1):PAGE84
     7 M_K_DQS_DP<9> @BASEBOARD_FAB2_LIB.BASEBOARD_FAB2(SCH_1):M_K_DQS_DP(9)   I102 @BASEBOARD_FAB2_LIB.BASEBOARD_FAB2(SCH_1):PAGE84
     2    GND @BASEBOARD_FAB2_LIB.BASEBOARD_FAB2(SCH_1):GND   I138 @BASEBOARD_FAB2_LIB.BASEBOARD_FAB2(SCH_1):PAGE84
     4    GND @BASEBOARD_FAB2_LIB.BASEBOARD_FAB2(SCH_1):GND   I138 @BASEBOARD_FAB2_LIB.BASEBOARD_FAB2(SCH_1):PAGE84
     6    GND @BASEBOARD_FAB2_LIB.BASEBOARD_FAB2(SCH_1):GND   I138 @BASEBOARD_FAB2_LIB.BASEBOARD_FAB2(SCH_1):PAGE84
     9    GND @BASEBOARD_FAB2_LIB.BASEBOARD_FAB2(SCH_1):GND   I138 @BASEBOARD_FAB2_LIB.BASEBOARD_FAB2(SCH_1):PAGE84
    11    GND @BASEBOARD_FAB2_LIB.BASEBOARD_FAB2(SCH_1):GND   I138 @BASEBOARD_FAB2_LIB.BASEBOARD_FAB2(SCH_1):PAGE84
    13    GND @BASEBOARD_FAB2_LIB.BASEBOARD_FAB2(SCH_1):GND   I138 @BASEBOARD_FAB2_LIB.BASEBOARD_FAB2(SCH_1):PAGE84
    15    GND @BASEBOARD_FAB2_LIB.BASEBOARD_FAB2(SCH_1):GND   I138 @BASEBOARD_FAB2_LIB.BASEBOARD_FAB2(SCH_1):PAGE84
    17    GND @BASEBOARD_FAB2_LIB.BASEBOARD_FAB2(SCH_1):GND   I138 @BASEBOARD_FAB2_LIB.BASEBOARD_FAB2(SCH_1):PAGE84
    20    GND @BASEBOARD_FAB2_LIB.BASEBOARD_FAB2(SCH_1):GND   I138 @BASEBOARD_FAB2_LIB.BASEBOARD_FAB2(SCH_1):PAGE84
    22    GND @BASEBOARD_FAB2_LIB.BASEBOARD_FAB2(SCH_1):GND   I138 @BASEBOARD_FAB2_LIB.BASEBOARD_FAB2(SCH_1):PAGE84
    24    GND @BASEBOARD_FAB2_LIB.BASEBOARD_FAB2(SCH_1):GND   I138 @BASEBOARD_FAB2_LIB.BASEBOARD_FAB2(SCH_1):PAGE84
    26    GND @BASEBOARD_FAB2_LIB.BASEBOARD_FAB2(SCH_1):GND   I138 @BASEBOARD_FAB2_LIB.BASEBOARD_FAB2(SCH_1):PAGE84
    28    GND @BASEBOARD_FAB2_LIB.BASEBOARD_FAB2(SCH_1):GND   I138 @BASEBOARD_FAB2_LIB.BASEBOARD_FAB2(SCH_1):PAGE84
    31    GND @BASEBOARD_FAB2_LIB.BASEBOARD_FAB2(SCH_1):GND   I138 @BASEBOARD_FAB2_LIB.BASEBOARD_FAB2(SCH_1):PAGE84
    33    GND @BASEBOARD_FAB2_LIB.BASEBOARD_FAB2(SCH_1):GND   I138 @BASEBOARD_FAB2_LIB.BASEBOARD_FAB2(SCH_1):PAGE84
    35    GND @BASEBOARD_FAB2_LIB.BASEBOARD_FAB2(SCH_1):GND   I138 @BASEBOARD_FAB2_LIB.BASEBOARD_FAB2(SCH_1):PAGE84
    37    GND @BASEBOARD_FAB2_LIB.BASEBOARD_FAB2(SCH_1):GND   I138 @BASEBOARD_FAB2_LIB.BASEBOARD_FAB2(SCH_1):PAGE84
    39    GND @BASEBOARD_FAB2_LIB.BASEBOARD_FAB2(SCH_1):GND   I138 @BASEBOARD_FAB2_LIB.BASEBOARD_FAB2(SCH_1):PAGE84
    42    GND @BASEBOARD_FAB2_LIB.BASEBOARD_FAB2(SCH_1):GND   I138 @BASEBOARD_FAB2_LIB.BASEBOARD_FAB2(SCH_1):PAGE84
    44    GND @BASEBOARD_FAB2_LIB.BASEBOARD_FAB2(SCH_1):GND   I138 @BASEBOARD_FAB2_LIB.BASEBOARD_FAB2(SCH_1):PAGE84
    46    GND @BASEBOARD_FAB2_LIB.BASEBOARD_FAB2(SCH_1):GND   I138 @BASEBOARD_FAB2_LIB.BASEBOARD_FAB2(SCH_1):PAGE84
    48    GND @BASEBOARD_FAB2_LIB.BASEBOARD_FAB2(SCH_1):GND   I138 @BASEBOARD_FAB2_LIB.BASEBOARD_FAB2(SCH_1):PAGE84
    50    GND @BASEBOARD_FAB2_LIB.BASEBOARD_FAB2(SCH_1):GND   I138 @BASEBOARD_FAB2_LIB.BASEBOARD_FAB2(SCH_1):PAGE84
    53    GND @BASEBOARD_FAB2_LIB.BASEBOARD_FAB2(SCH_1):GND   I138 @BASEBOARD_FAB2_LIB.BASEBOARD_FAB2(SCH_1):PAGE84
    55    GND @BASEBOARD_FAB2_LIB.BASEBOARD_FAB2(SCH_1):GND   I138 @BASEBOARD_FAB2_LIB.BASEBOARD_FAB2(SCH_1):PAGE84
    57    GND @BASEBOARD_FAB2_LIB.BASEBOARD_FAB2(SCH_1):GND   I138 @BASEBOARD_FAB2_LIB.BASEBOARD_FAB2(SCH_1):PAGE84
    94    GND @BASEBOARD_FAB2_LIB.BASEBOARD_FAB2(SCH_1):GND   I138 @BASEBOARD_FAB2_LIB.BASEBOARD_FAB2(SCH_1):PAGE84
    96    GND @BASEBOARD_FAB2_LIB.BASEBOARD_FAB2(SCH_1):GND   I138 @BASEBOARD_FAB2_LIB.BASEBOARD_FAB2(SCH_1):PAGE84
    98    GND @BASEBOARD_FAB2_LIB.BASEBOARD_FAB2(SCH_1):GND   I138 @BASEBOARD_FAB2_LIB.BASEBOARD_FAB2(SCH_1):PAGE84
   101    GND @BASEBOARD_FAB2_LIB.BASEBOARD_FAB2(SCH_1):GND   I138 @BASEBOARD_FAB2_LIB.BASEBOARD_FAB2(SCH_1):PAGE84
   103    GND @BASEBOARD_FAB2_LIB.BASEBOARD_FAB2(SCH_1):GND   I138 @BASEBOARD_FAB2_LIB.BASEBOARD_FAB2(SCH_1):PAGE84
   105    GND @BASEBOARD_FAB2_LIB.BASEBOARD_FAB2(SCH_1):GND   I138 @BASEBOARD_FAB2_LIB.BASEBOARD_FAB2(SCH_1):PAGE84
   107    GND @BASEBOARD_FAB2_LIB.BASEBOARD_FAB2(SCH_1):GND   I138 @BASEBOARD_FAB2_LIB.BASEBOARD_FAB2(SCH_1):PAGE84
   109    GND @BASEBOARD_FAB2_LIB.BASEBOARD_FAB2(SCH_1):GND   I138 @BASEBOARD_FAB2_LIB.BASEBOARD_FAB2(SCH_1):PAGE84
   112    GND @BASEBOARD_FAB2_LIB.BASEBOARD_FAB2(SCH_1):GND   I138 @BASEBOARD_FAB2_LIB.BASEBOARD_FAB2(SCH_1):PAGE84
   114    GND @BASEBOARD_FAB2_LIB.BASEBOARD_FAB2(SCH_1):GND   I138 @BASEBOARD_FAB2_LIB.BASEBOARD_FAB2(SCH_1):PAGE84
   116    GND @BASEBOARD_FAB2_LIB.BASEBOARD_FAB2(SCH_1):GND   I138 @BASEBOARD_FAB2_LIB.BASEBOARD_FAB2(SCH_1):PAGE84
   118    GND @BASEBOARD_FAB2_LIB.BASEBOARD_FAB2(SCH_1):GND   I138 @BASEBOARD_FAB2_LIB.BASEBOARD_FAB2(SCH_1):PAGE84
   120    GND @BASEBOARD_FAB2_LIB.BASEBOARD_FAB2(SCH_1):GND   I138 @BASEBOARD_FAB2_LIB.BASEBOARD_FAB2(SCH_1):PAGE84
   123    GND @BASEBOARD_FAB2_LIB.BASEBOARD_FAB2(SCH_1):GND   I138 @BASEBOARD_FAB2_LIB.BASEBOARD_FAB2(SCH_1):PAGE84
   125    GND @BASEBOARD_FAB2_LIB.BASEBOARD_FAB2(SCH_1):GND   I138 @BASEBOARD_FAB2_LIB.BASEBOARD_FAB2(SCH_1):PAGE84
   127    GND @BASEBOARD_FAB2_LIB.BASEBOARD_FAB2(SCH_1):GND   I138 @BASEBOARD_FAB2_LIB.BASEBOARD_FAB2(SCH_1):PAGE84
   129    GND @BASEBOARD_FAB2_LIB.BASEBOARD_FAB2(SCH_1):GND   I138 @BASEBOARD_FAB2_LIB.BASEBOARD_FAB2(SCH_1):PAGE84
   131    GND @BASEBOARD_FAB2_LIB.BASEBOARD_FAB2(SCH_1):GND   I138 @BASEBOARD_FAB2_LIB.BASEBOARD_FAB2(SCH_1):PAGE84
   134    GND @BASEBOARD_FAB2_LIB.BASEBOARD_FAB2(SCH_1):GND   I138 @BASEBOARD_FAB2_LIB.BASEBOARD_FAB2(SCH_1):PAGE84
   136    GND @BASEBOARD_FAB2_LIB.BASEBOARD_FAB2(SCH_1):GND   I138 @BASEBOARD_FAB2_LIB.BASEBOARD_FAB2(SCH_1):PAGE84
   138    GND @BASEBOARD_FAB2_LIB.BASEBOARD_FAB2(SCH_1):GND   I138 @BASEBOARD_FAB2_LIB.BASEBOARD_FAB2(SCH_1):PAGE84
   147    GND @BASEBOARD_FAB2_LIB.BASEBOARD_FAB2(SCH_1):GND   I138 @BASEBOARD_FAB2_LIB.BASEBOARD_FAB2(SCH_1):PAGE84
   149    GND @BASEBOARD_FAB2_LIB.BASEBOARD_FAB2(SCH_1):GND   I138 @BASEBOARD_FAB2_LIB.BASEBOARD_FAB2(SCH_1):PAGE84
   151    GND @BASEBOARD_FAB2_LIB.BASEBOARD_FAB2(SCH_1):GND   I138 @BASEBOARD_FAB2_LIB.BASEBOARD_FAB2(SCH_1):PAGE84
   154    GND @BASEBOARD_FAB2_LIB.BASEBOARD_FAB2(SCH_1):GND   I138 @BASEBOARD_FAB2_LIB.BASEBOARD_FAB2(SCH_1):PAGE84
   156    GND @BASEBOARD_FAB2_LIB.BASEBOARD_FAB2(SCH_1):GND   I138 @BASEBOARD_FAB2_LIB.BASEBOARD_FAB2(SCH_1):PAGE84
   158    GND @BASEBOARD_FAB2_LIB.BASEBOARD_FAB2(SCH_1):GND   I138 @BASEBOARD_FAB2_LIB.BASEBOARD_FAB2(SCH_1):PAGE84
   160    GND @BASEBOARD_FAB2_LIB.BASEBOARD_FAB2(SCH_1):GND   I138 @BASEBOARD_FAB2_LIB.BASEBOARD_FAB2(SCH_1):PAGE84
   162    GND @BASEBOARD_FAB2_LIB.BASEBOARD_FAB2(SCH_1):GND   I138 @BASEBOARD_FAB2_LIB.BASEBOARD_FAB2(SCH_1):PAGE84
   165    GND @BASEBOARD_FAB2_LIB.BASEBOARD_FAB2(SCH_1):GND   I138 @BASEBOARD_FAB2_LIB.BASEBOARD_FAB2(SCH_1):PAGE84
   167    GND @BASEBOARD_FAB2_LIB.BASEBOARD_FAB2(SCH_1):GND   I138 @BASEBOARD_FAB2_LIB.BASEBOARD_FAB2(SCH_1):PAGE84
   169    GND @BASEBOARD_FAB2_LIB.BASEBOARD_FAB2(SCH_1):GND   I138 @BASEBOARD_FAB2_LIB.BASEBOARD_FAB2(SCH_1):PAGE84
   171    GND @BASEBOARD_FAB2_LIB.BASEBOARD_FAB2(SCH_1):GND   I138 @BASEBOARD_FAB2_LIB.BASEBOARD_FAB2(SCH_1):PAGE84
   173    GND @BASEBOARD_FAB2_LIB.BASEBOARD_FAB2(SCH_1):GND   I138 @BASEBOARD_FAB2_LIB.BASEBOARD_FAB2(SCH_1):PAGE84
   176    GND @BASEBOARD_FAB2_LIB.BASEBOARD_FAB2(SCH_1):GND   I138 @BASEBOARD_FAB2_LIB.BASEBOARD_FAB2(SCH_1):PAGE84
   178    GND @BASEBOARD_FAB2_LIB.BASEBOARD_FAB2(SCH_1):GND   I138 @BASEBOARD_FAB2_LIB.BASEBOARD_FAB2(SCH_1):PAGE84
   180    GND @BASEBOARD_FAB2_LIB.BASEBOARD_FAB2(SCH_1):GND   I138 @BASEBOARD_FAB2_LIB.BASEBOARD_FAB2(SCH_1):PAGE84
   182    GND @BASEBOARD_FAB2_LIB.BASEBOARD_FAB2(SCH_1):GND   I138 @BASEBOARD_FAB2_LIB.BASEBOARD_FAB2(SCH_1):PAGE84
   184    GND @BASEBOARD_FAB2_LIB.BASEBOARD_FAB2(SCH_1):GND   I138 @BASEBOARD_FAB2_LIB.BASEBOARD_FAB2(SCH_1):PAGE84
   187    GND @BASEBOARD_FAB2_LIB.BASEBOARD_FAB2(SCH_1):GND   I138 @BASEBOARD_FAB2_LIB.BASEBOARD_FAB2(SCH_1):PAGE84
   189    GND @BASEBOARD_FAB2_LIB.BASEBOARD_FAB2(SCH_1):GND   I138 @BASEBOARD_FAB2_LIB.BASEBOARD_FAB2(SCH_1):PAGE84
   191    GND @BASEBOARD_FAB2_LIB.BASEBOARD_FAB2(SCH_1):GND   I138 @BASEBOARD_FAB2_LIB.BASEBOARD_FAB2(SCH_1):PAGE84
   193    GND @BASEBOARD_FAB2_LIB.BASEBOARD_FAB2(SCH_1):GND   I138 @BASEBOARD_FAB2_LIB.BASEBOARD_FAB2(SCH_1):PAGE84
   195    GND @BASEBOARD_FAB2_LIB.BASEBOARD_FAB2(SCH_1):GND   I138 @BASEBOARD_FAB2_LIB.BASEBOARD_FAB2(SCH_1):PAGE84
   198    GND @BASEBOARD_FAB2_LIB.BASEBOARD_FAB2(SCH_1):GND   I138 @BASEBOARD_FAB2_LIB.BASEBOARD_FAB2(SCH_1):PAGE84
   200    GND @BASEBOARD_FAB2_LIB.BASEBOARD_FAB2(SCH_1):GND   I138 @BASEBOARD_FAB2_LIB.BASEBOARD_FAB2(SCH_1):PAGE84
   202    GND @BASEBOARD_FAB2_LIB.BASEBOARD_FAB2(SCH_1):GND   I138 @BASEBOARD_FAB2_LIB.BASEBOARD_FAB2(SCH_1):PAGE84
   239    GND @BASEBOARD_FAB2_LIB.BASEBOARD_FAB2(SCH_1):GND   I138 @BASEBOARD_FAB2_LIB.BASEBOARD_FAB2(SCH_1):PAGE84
   241    GND @BASEBOARD_FAB2_LIB.BASEBOARD_FAB2(SCH_1):GND   I138 @BASEBOARD_FAB2_LIB.BASEBOARD_FAB2(SCH_1):PAGE84
   243    GND @BASEBOARD_FAB2_LIB.BASEBOARD_FAB2(SCH_1):GND   I138 @BASEBOARD_FAB2_LIB.BASEBOARD_FAB2(SCH_1):PAGE84
   246    GND @BASEBOARD_FAB2_LIB.BASEBOARD_FAB2(SCH_1):GND   I138 @BASEBOARD_FAB2_LIB.BASEBOARD_FAB2(SCH_1):PAGE84
   248    GND @BASEBOARD_FAB2_LIB.BASEBOARD_FAB2(SCH_1):GND   I138 @BASEBOARD_FAB2_LIB.BASEBOARD_FAB2(SCH_1):PAGE84
   250    GND @BASEBOARD_FAB2_LIB.BASEBOARD_FAB2(SCH_1):GND   I138 @BASEBOARD_FAB2_LIB.BASEBOARD_FAB2(SCH_1):PAGE84
   252    GND @BASEBOARD_FAB2_LIB.BASEBOARD_FAB2(SCH_1):GND   I138 @BASEBOARD_FAB2_LIB.BASEBOARD_FAB2(SCH_1):PAGE84
   254    GND @BASEBOARD_FAB2_LIB.BASEBOARD_FAB2(SCH_1):GND   I138 @BASEBOARD_FAB2_LIB.BASEBOARD_FAB2(SCH_1):PAGE84
   257    GND @BASEBOARD_FAB2_LIB.BASEBOARD_FAB2(SCH_1):GND   I138 @BASEBOARD_FAB2_LIB.BASEBOARD_FAB2(SCH_1):PAGE84
   259    GND @BASEBOARD_FAB2_LIB.BASEBOARD_FAB2(SCH_1):GND   I138 @BASEBOARD_FAB2_LIB.BASEBOARD_FAB2(SCH_1):PAGE84
   261    GND @BASEBOARD_FAB2_LIB.BASEBOARD_FAB2(SCH_1):GND   I138 @BASEBOARD_FAB2_LIB.BASEBOARD_FAB2(SCH_1):PAGE84
   263    GND @BASEBOARD_FAB2_LIB.BASEBOARD_FAB2(SCH_1):GND   I138 @BASEBOARD_FAB2_LIB.BASEBOARD_FAB2(SCH_1):PAGE84
   265    GND @BASEBOARD_FAB2_LIB.BASEBOARD_FAB2(SCH_1):GND   I138 @BASEBOARD_FAB2_LIB.BASEBOARD_FAB2(SCH_1):PAGE84
   268    GND @BASEBOARD_FAB2_LIB.BASEBOARD_FAB2(SCH_1):GND   I138 @BASEBOARD_FAB2_LIB.BASEBOARD_FAB2(SCH_1):PAGE84
   270    GND @BASEBOARD_FAB2_LIB.BASEBOARD_FAB2(SCH_1):GND   I138 @BASEBOARD_FAB2_LIB.BASEBOARD_FAB2(SCH_1):PAGE84
   272    GND @BASEBOARD_FAB2_LIB.BASEBOARD_FAB2(SCH_1):GND   I138 @BASEBOARD_FAB2_LIB.BASEBOARD_FAB2(SCH_1):PAGE84
   274    GND @BASEBOARD_FAB2_LIB.BASEBOARD_FAB2(SCH_1):GND   I138 @BASEBOARD_FAB2_LIB.BASEBOARD_FAB2(SCH_1):PAGE84
   276    GND @BASEBOARD_FAB2_LIB.BASEBOARD_FAB2(SCH_1):GND   I138 @BASEBOARD_FAB2_LIB.BASEBOARD_FAB2(SCH_1):PAGE84
   279    GND @BASEBOARD_FAB2_LIB.BASEBOARD_FAB2(SCH_1):GND   I138 @BASEBOARD_FAB2_LIB.BASEBOARD_FAB2(SCH_1):PAGE84
   281    GND @BASEBOARD_FAB2_LIB.BASEBOARD_FAB2(SCH_1):GND   I138 @BASEBOARD_FAB2_LIB.BASEBOARD_FAB2(SCH_1):PAGE84
   283    GND @BASEBOARD_FAB2_LIB.BASEBOARD_FAB2(SCH_1):GND   I138 @BASEBOARD_FAB2_LIB.BASEBOARD_FAB2(SCH_1):PAGE84
     1 P12V_NVDIMM_KLM @BASEBOARD_FAB2_LIB.BASEBOARD_FAB2(SCH_1):P12V_NVDIMM_KLM    I57 @BASEBOARD_FAB2_LIB.BASEBOARD_FAB2(SCH_1):PAGE84
   145 P12V_NVDIMM_KLM @BASEBOARD_FAB2_LIB.BASEBOARD_FAB2(SCH_1):P12V_NVDIMM_KLM    I57 @BASEBOARD_FAB2_LIB.BASEBOARD_FAB2(SCH_1):PAGE84
    59 PVDDQ_KLM @BASEBOARD_FAB2_LIB.BASEBOARD_FAB2(SCH_1):PVDDQ_KLM    I57 @BASEBOARD_FAB2_LIB.BASEBOARD_FAB2(SCH_1):PAGE84
    61 PVDDQ_KLM @BASEBOARD_FAB2_LIB.BASEBOARD_FAB2(SCH_1):PVDDQ_KLM    I57 @BASEBOARD_FAB2_LIB.BASEBOARD_FAB2(SCH_1):PAGE84
    64 PVDDQ_KLM @BASEBOARD_FAB2_LIB.BASEBOARD_FAB2(SCH_1):PVDDQ_KLM    I57 @BASEBOARD_FAB2_LIB.BASEBOARD_FAB2(SCH_1):PAGE84
    67 PVDDQ_KLM @BASEBOARD_FAB2_LIB.BASEBOARD_FAB2(SCH_1):PVDDQ_KLM    I57 @BASEBOARD_FAB2_LIB.BASEBOARD_FAB2(SCH_1):PAGE84
    70 PVDDQ_KLM @BASEBOARD_FAB2_LIB.BASEBOARD_FAB2(SCH_1):PVDDQ_KLM    I57 @BASEBOARD_FAB2_LIB.BASEBOARD_FAB2(SCH_1):PAGE84
    73 PVDDQ_KLM @BASEBOARD_FAB2_LIB.BASEBOARD_FAB2(SCH_1):PVDDQ_KLM    I57 @BASEBOARD_FAB2_LIB.BASEBOARD_FAB2(SCH_1):PAGE84
    76 PVDDQ_KLM @BASEBOARD_FAB2_LIB.BASEBOARD_FAB2(SCH_1):PVDDQ_KLM    I57 @BASEBOARD_FAB2_LIB.BASEBOARD_FAB2(SCH_1):PAGE84
    80 PVDDQ_KLM @BASEBOARD_FAB2_LIB.BASEBOARD_FAB2(SCH_1):PVDDQ_KLM    I57 @BASEBOARD_FAB2_LIB.BASEBOARD_FAB2(SCH_1):PAGE84
    83 PVDDQ_KLM @BASEBOARD_FAB2_LIB.BASEBOARD_FAB2(SCH_1):PVDDQ_KLM    I57 @BASEBOARD_FAB2_LIB.BASEBOARD_FAB2(SCH_1):PAGE84
    85 PVDDQ_KLM @BASEBOARD_FAB2_LIB.BASEBOARD_FAB2(SCH_1):PVDDQ_KLM    I57 @BASEBOARD_FAB2_LIB.BASEBOARD_FAB2(SCH_1):PAGE84
    88 PVDDQ_KLM @BASEBOARD_FAB2_LIB.BASEBOARD_FAB2(SCH_1):PVDDQ_KLM    I57 @BASEBOARD_FAB2_LIB.BASEBOARD_FAB2(SCH_1):PAGE84
    90 PVDDQ_KLM @BASEBOARD_FAB2_LIB.BASEBOARD_FAB2(SCH_1):PVDDQ_KLM    I57 @BASEBOARD_FAB2_LIB.BASEBOARD_FAB2(SCH_1):PAGE84
    92 PVDDQ_KLM @BASEBOARD_FAB2_LIB.BASEBOARD_FAB2(SCH_1):PVDDQ_KLM    I57 @BASEBOARD_FAB2_LIB.BASEBOARD_FAB2(SCH_1):PAGE84
   204 PVDDQ_KLM @BASEBOARD_FAB2_LIB.BASEBOARD_FAB2(SCH_1):PVDDQ_KLM    I57 @BASEBOARD_FAB2_LIB.BASEBOARD_FAB2(SCH_1):PAGE84
   206 PVDDQ_KLM @BASEBOARD_FAB2_LIB.BASEBOARD_FAB2(SCH_1):PVDDQ_KLM    I57 @BASEBOARD_FAB2_LIB.BASEBOARD_FAB2(SCH_1):PAGE84
   209 PVDDQ_KLM @BASEBOARD_FAB2_LIB.BASEBOARD_FAB2(SCH_1):PVDDQ_KLM    I57 @BASEBOARD_FAB2_LIB.BASEBOARD_FAB2(SCH_1):PAGE84
   212 PVDDQ_KLM @BASEBOARD_FAB2_LIB.BASEBOARD_FAB2(SCH_1):PVDDQ_KLM    I57 @BASEBOARD_FAB2_LIB.BASEBOARD_FAB2(SCH_1):PAGE84
   215 PVDDQ_KLM @BASEBOARD_FAB2_LIB.BASEBOARD_FAB2(SCH_1):PVDDQ_KLM    I57 @BASEBOARD_FAB2_LIB.BASEBOARD_FAB2(SCH_1):PAGE84
   217 PVDDQ_KLM @BASEBOARD_FAB2_LIB.BASEBOARD_FAB2(SCH_1):PVDDQ_KLM    I57 @BASEBOARD_FAB2_LIB.BASEBOARD_FAB2(SCH_1):PAGE84
   220 PVDDQ_KLM @BASEBOARD_FAB2_LIB.BASEBOARD_FAB2(SCH_1):PVDDQ_KLM    I57 @BASEBOARD_FAB2_LIB.BASEBOARD_FAB2(SCH_1):PAGE84
   223 PVDDQ_KLM @BASEBOARD_FAB2_LIB.BASEBOARD_FAB2(SCH_1):PVDDQ_KLM    I57 @BASEBOARD_FAB2_LIB.BASEBOARD_FAB2(SCH_1):PAGE84
   226 PVDDQ_KLM @BASEBOARD_FAB2_LIB.BASEBOARD_FAB2(SCH_1):PVDDQ_KLM    I57 @BASEBOARD_FAB2_LIB.BASEBOARD_FAB2(SCH_1):PAGE84
   229 PVDDQ_KLM @BASEBOARD_FAB2_LIB.BASEBOARD_FAB2(SCH_1):PVDDQ_KLM    I57 @BASEBOARD_FAB2_LIB.BASEBOARD_FAB2(SCH_1):PAGE84
   231 PVDDQ_KLM @BASEBOARD_FAB2_LIB.BASEBOARD_FAB2(SCH_1):PVDDQ_KLM    I57 @BASEBOARD_FAB2_LIB.BASEBOARD_FAB2(SCH_1):PAGE84
   233 PVDDQ_KLM @BASEBOARD_FAB2_LIB.BASEBOARD_FAB2(SCH_1):PVDDQ_KLM    I57 @BASEBOARD_FAB2_LIB.BASEBOARD_FAB2(SCH_1):PAGE84
   236 PVDDQ_KLM @BASEBOARD_FAB2_LIB.BASEBOARD_FAB2(SCH_1):PVDDQ_KLM    I57 @BASEBOARD_FAB2_LIB.BASEBOARD_FAB2(SCH_1):PAGE84
   142 PVPP_KLM @BASEBOARD_FAB2_LIB.BASEBOARD_FAB2(SCH_1):PVPP_KLM    I57 @BASEBOARD_FAB2_LIB.BASEBOARD_FAB2(SCH_1):PAGE84
   143 PVPP_KLM @BASEBOARD_FAB2_LIB.BASEBOARD_FAB2(SCH_1):PVPP_KLM    I57 @BASEBOARD_FAB2_LIB.BASEBOARD_FAB2(SCH_1):PAGE84
   288 PVPP_KLM @BASEBOARD_FAB2_LIB.BASEBOARD_FAB2(SCH_1):PVPP_KLM    I57 @BASEBOARD_FAB2_LIB.BASEBOARD_FAB2(SCH_1):PAGE84
   286 PVPP_KLM @BASEBOARD_FAB2_LIB.BASEBOARD_FAB2(SCH_1):PVPP_KLM    I57 @BASEBOARD_FAB2_LIB.BASEBOARD_FAB2(SCH_1):PAGE84
   287 PVPP_KLM @BASEBOARD_FAB2_LIB.BASEBOARD_FAB2(SCH_1):PVPP_KLM    I57 @BASEBOARD_FAB2_LIB.BASEBOARD_FAB2(SCH_1):PAGE84
    77 PVTT_KLM @BASEBOARD_FAB2_LIB.BASEBOARD_FAB2(SCH_1):PVTT_KLM    I57 @BASEBOARD_FAB2_LIB.BASEBOARD_FAB2(SCH_1):PAGE84
   221 PVTT_KLM @BASEBOARD_FAB2_LIB.BASEBOARD_FAB2(SCH_1):PVTT_KLM    I57 @BASEBOARD_FAB2_LIB.BASEBOARD_FAB2(SCH_1):PAGE84

J9T1 SCONN288_H44441003_PIP-SCONN,HA
    79 M_G_MA<0> @BASEBOARD_FAB2_LIB.BASEBOARD_FAB2(SCH_1):M_G_MA(0)    I13 @BASEBOARD_FAB2_LIB.BASEBOARD_FAB2(SCH_1):PAGE78
    72 M_G_MA<1> @BASEBOARD_FAB2_LIB.BASEBOARD_FAB2(SCH_1):M_G_MA(1)    I13 @BASEBOARD_FAB2_LIB.BASEBOARD_FAB2(SCH_1):PAGE78
   225 M_G_MA<10> @BASEBOARD_FAB2_LIB.BASEBOARD_FAB2(SCH_1):M_G_MA(10)    I13 @BASEBOARD_FAB2_LIB.BASEBOARD_FAB2(SCH_1):PAGE78
   210 M_G_MA<11> @BASEBOARD_FAB2_LIB.BASEBOARD_FAB2(SCH_1):M_G_MA(11)    I13 @BASEBOARD_FAB2_LIB.BASEBOARD_FAB2(SCH_1):PAGE78
    65 M_G_MA<12> @BASEBOARD_FAB2_LIB.BASEBOARD_FAB2(SCH_1):M_G_MA(12)    I13 @BASEBOARD_FAB2_LIB.BASEBOARD_FAB2(SCH_1):PAGE78
   232 M_G_MA<13> @BASEBOARD_FAB2_LIB.BASEBOARD_FAB2(SCH_1):M_G_MA(13)    I13 @BASEBOARD_FAB2_LIB.BASEBOARD_FAB2(SCH_1):PAGE78
   228 M_G_MA<14> @BASEBOARD_FAB2_LIB.BASEBOARD_FAB2(SCH_1):M_G_MA(14)    I13 @BASEBOARD_FAB2_LIB.BASEBOARD_FAB2(SCH_1):PAGE78
    86 M_G_MA<15> @BASEBOARD_FAB2_LIB.BASEBOARD_FAB2(SCH_1):M_G_MA(15)    I13 @BASEBOARD_FAB2_LIB.BASEBOARD_FAB2(SCH_1):PAGE78
    82 M_G_MA<16> @BASEBOARD_FAB2_LIB.BASEBOARD_FAB2(SCH_1):M_G_MA(16)    I13 @BASEBOARD_FAB2_LIB.BASEBOARD_FAB2(SCH_1):PAGE78
   234 M_G_MA<17> @BASEBOARD_FAB2_LIB.BASEBOARD_FAB2(SCH_1):M_G_MA(17)    I13 @BASEBOARD_FAB2_LIB.BASEBOARD_FAB2(SCH_1):PAGE78
   216 M_G_MA<2> @BASEBOARD_FAB2_LIB.BASEBOARD_FAB2(SCH_1):M_G_MA(2)    I13 @BASEBOARD_FAB2_LIB.BASEBOARD_FAB2(SCH_1):PAGE78
    71 M_G_MA<3> @BASEBOARD_FAB2_LIB.BASEBOARD_FAB2(SCH_1):M_G_MA(3)    I13 @BASEBOARD_FAB2_LIB.BASEBOARD_FAB2(SCH_1):PAGE78
   214 M_G_MA<4> @BASEBOARD_FAB2_LIB.BASEBOARD_FAB2(SCH_1):M_G_MA(4)    I13 @BASEBOARD_FAB2_LIB.BASEBOARD_FAB2(SCH_1):PAGE78
   213 M_G_MA<5> @BASEBOARD_FAB2_LIB.BASEBOARD_FAB2(SCH_1):M_G_MA(5)    I13 @BASEBOARD_FAB2_LIB.BASEBOARD_FAB2(SCH_1):PAGE78
    69 M_G_MA<6> @BASEBOARD_FAB2_LIB.BASEBOARD_FAB2(SCH_1):M_G_MA(6)    I13 @BASEBOARD_FAB2_LIB.BASEBOARD_FAB2(SCH_1):PAGE78
   211 M_G_MA<7> @BASEBOARD_FAB2_LIB.BASEBOARD_FAB2(SCH_1):M_G_MA(7)    I13 @BASEBOARD_FAB2_LIB.BASEBOARD_FAB2(SCH_1):PAGE78
    68 M_G_MA<8> @BASEBOARD_FAB2_LIB.BASEBOARD_FAB2(SCH_1):M_G_MA(8)    I13 @BASEBOARD_FAB2_LIB.BASEBOARD_FAB2(SCH_1):PAGE78
    66 M_G_MA<9> @BASEBOARD_FAB2_LIB.BASEBOARD_FAB2(SCH_1):M_G_MA(9)    I13 @BASEBOARD_FAB2_LIB.BASEBOARD_FAB2(SCH_1):PAGE78
    62 M_G_ACT_N @BASEBOARD_FAB2_LIB.BASEBOARD_FAB2(SCH_1):M_G_ACT_N    I13 @BASEBOARD_FAB2_LIB.BASEBOARD_FAB2(SCH_1):PAGE78
   208 M_G_ALERT_N @BASEBOARD_FAB2_LIB.BASEBOARD_FAB2(SCH_1):M_G_ALERT_N    I13 @BASEBOARD_FAB2_LIB.BASEBOARD_FAB2(SCH_1):PAGE78
   224 M_G_BA<1> @BASEBOARD_FAB2_LIB.BASEBOARD_FAB2(SCH_1):M_G_BA(1)    I13 @BASEBOARD_FAB2_LIB.BASEBOARD_FAB2(SCH_1):PAGE78
    81 M_G_BA<0> @BASEBOARD_FAB2_LIB.BASEBOARD_FAB2(SCH_1):M_G_BA(0)    I13 @BASEBOARD_FAB2_LIB.BASEBOARD_FAB2(SCH_1):PAGE78
   207 M_G_BG<1> @BASEBOARD_FAB2_LIB.BASEBOARD_FAB2(SCH_1):M_G_BG(1)    I13 @BASEBOARD_FAB2_LIB.BASEBOARD_FAB2(SCH_1):PAGE78
    63 M_G_BG<0> @BASEBOARD_FAB2_LIB.BASEBOARD_FAB2(SCH_1):M_G_BG(0)    I13 @BASEBOARD_FAB2_LIB.BASEBOARD_FAB2(SCH_1):PAGE78
   235 M_G_C<2> @BASEBOARD_FAB2_LIB.BASEBOARD_FAB2(SCH_1):M_G_C(2)    I13 @BASEBOARD_FAB2_LIB.BASEBOARD_FAB2(SCH_1):PAGE78
   199 M_G_ECC<7> @BASEBOARD_FAB2_LIB.BASEBOARD_FAB2(SCH_1):M_G_ECC(7)    I13 @BASEBOARD_FAB2_LIB.BASEBOARD_FAB2(SCH_1):PAGE78
    54 M_G_ECC<6> @BASEBOARD_FAB2_LIB.BASEBOARD_FAB2(SCH_1):M_G_ECC(6)    I13 @BASEBOARD_FAB2_LIB.BASEBOARD_FAB2(SCH_1):PAGE78
   192 M_G_ECC<5> @BASEBOARD_FAB2_LIB.BASEBOARD_FAB2(SCH_1):M_G_ECC(5)    I13 @BASEBOARD_FAB2_LIB.BASEBOARD_FAB2(SCH_1):PAGE78
    47 M_G_ECC<4> @BASEBOARD_FAB2_LIB.BASEBOARD_FAB2(SCH_1):M_G_ECC(4)    I13 @BASEBOARD_FAB2_LIB.BASEBOARD_FAB2(SCH_1):PAGE78
   201 M_G_ECC<3> @BASEBOARD_FAB2_LIB.BASEBOARD_FAB2(SCH_1):M_G_ECC(3)    I13 @BASEBOARD_FAB2_LIB.BASEBOARD_FAB2(SCH_1):PAGE78
    56 M_G_ECC<2> @BASEBOARD_FAB2_LIB.BASEBOARD_FAB2(SCH_1):M_G_ECC(2)    I13 @BASEBOARD_FAB2_LIB.BASEBOARD_FAB2(SCH_1):PAGE78
   194 M_G_ECC<1> @BASEBOARD_FAB2_LIB.BASEBOARD_FAB2(SCH_1):M_G_ECC(1)    I13 @BASEBOARD_FAB2_LIB.BASEBOARD_FAB2(SCH_1):PAGE78
    49 M_G_ECC<0> @BASEBOARD_FAB2_LIB.BASEBOARD_FAB2(SCH_1):M_G_ECC(0)    I13 @BASEBOARD_FAB2_LIB.BASEBOARD_FAB2(SCH_1):PAGE78
    75 M_G_CLK_DN<2> @BASEBOARD_FAB2_LIB.BASEBOARD_FAB2(SCH_1):M_G_CLK_DN(2)    I13 @BASEBOARD_FAB2_LIB.BASEBOARD_FAB2(SCH_1):PAGE78
    74 M_G_CLK_DP<2> @BASEBOARD_FAB2_LIB.BASEBOARD_FAB2(SCH_1):M_G_CLK_DP(2)    I13 @BASEBOARD_FAB2_LIB.BASEBOARD_FAB2(SCH_1):PAGE78
   219 M_G_CLK_DN<3> @BASEBOARD_FAB2_LIB.BASEBOARD_FAB2(SCH_1):M_G_CLK_DN(3)    I13 @BASEBOARD_FAB2_LIB.BASEBOARD_FAB2(SCH_1):PAGE78
   218 M_G_CLK_DP<3> @BASEBOARD_FAB2_LIB.BASEBOARD_FAB2(SCH_1):M_G_CLK_DP(3)    I13 @BASEBOARD_FAB2_LIB.BASEBOARD_FAB2(SCH_1):PAGE78
   203 M_G_CKE<3> @BASEBOARD_FAB2_LIB.BASEBOARD_FAB2(SCH_1):M_G_CKE(3)    I13 @BASEBOARD_FAB2_LIB.BASEBOARD_FAB2(SCH_1):PAGE78
    60 M_G_CKE<2> @BASEBOARD_FAB2_LIB.BASEBOARD_FAB2(SCH_1):M_G_CKE(2)    I13 @BASEBOARD_FAB2_LIB.BASEBOARD_FAB2(SCH_1):PAGE78
   280 M_G_DQ<63> @BASEBOARD_FAB2_LIB.BASEBOARD_FAB2(SCH_1):M_G_DQ(63)    I13 @BASEBOARD_FAB2_LIB.BASEBOARD_FAB2(SCH_1):PAGE78
   135 M_G_DQ<62> @BASEBOARD_FAB2_LIB.BASEBOARD_FAB2(SCH_1):M_G_DQ(62)    I13 @BASEBOARD_FAB2_LIB.BASEBOARD_FAB2(SCH_1):PAGE78
   273 M_G_DQ<61> @BASEBOARD_FAB2_LIB.BASEBOARD_FAB2(SCH_1):M_G_DQ(61)    I13 @BASEBOARD_FAB2_LIB.BASEBOARD_FAB2(SCH_1):PAGE78
   128 M_G_DQ<60> @BASEBOARD_FAB2_LIB.BASEBOARD_FAB2(SCH_1):M_G_DQ(60)    I13 @BASEBOARD_FAB2_LIB.BASEBOARD_FAB2(SCH_1):PAGE78
   282 M_G_DQ<59> @BASEBOARD_FAB2_LIB.BASEBOARD_FAB2(SCH_1):M_G_DQ(59)    I13 @BASEBOARD_FAB2_LIB.BASEBOARD_FAB2(SCH_1):PAGE78
   137 M_G_DQ<58> @BASEBOARD_FAB2_LIB.BASEBOARD_FAB2(SCH_1):M_G_DQ(58)    I13 @BASEBOARD_FAB2_LIB.BASEBOARD_FAB2(SCH_1):PAGE78
   275 M_G_DQ<57> @BASEBOARD_FAB2_LIB.BASEBOARD_FAB2(SCH_1):M_G_DQ(57)    I13 @BASEBOARD_FAB2_LIB.BASEBOARD_FAB2(SCH_1):PAGE78
   130 M_G_DQ<56> @BASEBOARD_FAB2_LIB.BASEBOARD_FAB2(SCH_1):M_G_DQ(56)    I13 @BASEBOARD_FAB2_LIB.BASEBOARD_FAB2(SCH_1):PAGE78
   269 M_G_DQ<55> @BASEBOARD_FAB2_LIB.BASEBOARD_FAB2(SCH_1):M_G_DQ(55)    I13 @BASEBOARD_FAB2_LIB.BASEBOARD_FAB2(SCH_1):PAGE78
   124 M_G_DQ<54> @BASEBOARD_FAB2_LIB.BASEBOARD_FAB2(SCH_1):M_G_DQ(54)    I13 @BASEBOARD_FAB2_LIB.BASEBOARD_FAB2(SCH_1):PAGE78
   262 M_G_DQ<53> @BASEBOARD_FAB2_LIB.BASEBOARD_FAB2(SCH_1):M_G_DQ(53)    I13 @BASEBOARD_FAB2_LIB.BASEBOARD_FAB2(SCH_1):PAGE78
   117 M_G_DQ<52> @BASEBOARD_FAB2_LIB.BASEBOARD_FAB2(SCH_1):M_G_DQ(52)    I13 @BASEBOARD_FAB2_LIB.BASEBOARD_FAB2(SCH_1):PAGE78
   271 M_G_DQ<51> @BASEBOARD_FAB2_LIB.BASEBOARD_FAB2(SCH_1):M_G_DQ(51)    I13 @BASEBOARD_FAB2_LIB.BASEBOARD_FAB2(SCH_1):PAGE78
   126 M_G_DQ<50> @BASEBOARD_FAB2_LIB.BASEBOARD_FAB2(SCH_1):M_G_DQ(50)    I13 @BASEBOARD_FAB2_LIB.BASEBOARD_FAB2(SCH_1):PAGE78
   264 M_G_DQ<49> @BASEBOARD_FAB2_LIB.BASEBOARD_FAB2(SCH_1):M_G_DQ(49)    I13 @BASEBOARD_FAB2_LIB.BASEBOARD_FAB2(SCH_1):PAGE78
   119 M_G_DQ<48> @BASEBOARD_FAB2_LIB.BASEBOARD_FAB2(SCH_1):M_G_DQ(48)    I13 @BASEBOARD_FAB2_LIB.BASEBOARD_FAB2(SCH_1):PAGE78
   258 M_G_DQ<47> @BASEBOARD_FAB2_LIB.BASEBOARD_FAB2(SCH_1):M_G_DQ(47)    I13 @BASEBOARD_FAB2_LIB.BASEBOARD_FAB2(SCH_1):PAGE78
   113 M_G_DQ<46> @BASEBOARD_FAB2_LIB.BASEBOARD_FAB2(SCH_1):M_G_DQ(46)    I13 @BASEBOARD_FAB2_LIB.BASEBOARD_FAB2(SCH_1):PAGE78
   251 M_G_DQ<45> @BASEBOARD_FAB2_LIB.BASEBOARD_FAB2(SCH_1):M_G_DQ(45)    I13 @BASEBOARD_FAB2_LIB.BASEBOARD_FAB2(SCH_1):PAGE78
   106 M_G_DQ<44> @BASEBOARD_FAB2_LIB.BASEBOARD_FAB2(SCH_1):M_G_DQ(44)    I13 @BASEBOARD_FAB2_LIB.BASEBOARD_FAB2(SCH_1):PAGE78
   260 M_G_DQ<43> @BASEBOARD_FAB2_LIB.BASEBOARD_FAB2(SCH_1):M_G_DQ(43)    I13 @BASEBOARD_FAB2_LIB.BASEBOARD_FAB2(SCH_1):PAGE78
   115 M_G_DQ<42> @BASEBOARD_FAB2_LIB.BASEBOARD_FAB2(SCH_1):M_G_DQ(42)    I13 @BASEBOARD_FAB2_LIB.BASEBOARD_FAB2(SCH_1):PAGE78
   253 M_G_DQ<41> @BASEBOARD_FAB2_LIB.BASEBOARD_FAB2(SCH_1):M_G_DQ(41)    I13 @BASEBOARD_FAB2_LIB.BASEBOARD_FAB2(SCH_1):PAGE78
   108 M_G_DQ<40> @BASEBOARD_FAB2_LIB.BASEBOARD_FAB2(SCH_1):M_G_DQ(40)    I13 @BASEBOARD_FAB2_LIB.BASEBOARD_FAB2(SCH_1):PAGE78
   247 M_G_DQ<39> @BASEBOARD_FAB2_LIB.BASEBOARD_FAB2(SCH_1):M_G_DQ(39)    I13 @BASEBOARD_FAB2_LIB.BASEBOARD_FAB2(SCH_1):PAGE78
   102 M_G_DQ<38> @BASEBOARD_FAB2_LIB.BASEBOARD_FAB2(SCH_1):M_G_DQ(38)    I13 @BASEBOARD_FAB2_LIB.BASEBOARD_FAB2(SCH_1):PAGE78
   240 M_G_DQ<37> @BASEBOARD_FAB2_LIB.BASEBOARD_FAB2(SCH_1):M_G_DQ(37)    I13 @BASEBOARD_FAB2_LIB.BASEBOARD_FAB2(SCH_1):PAGE78
    95 M_G_DQ<36> @BASEBOARD_FAB2_LIB.BASEBOARD_FAB2(SCH_1):M_G_DQ(36)    I13 @BASEBOARD_FAB2_LIB.BASEBOARD_FAB2(SCH_1):PAGE78
   249 M_G_DQ<35> @BASEBOARD_FAB2_LIB.BASEBOARD_FAB2(SCH_1):M_G_DQ(35)    I13 @BASEBOARD_FAB2_LIB.BASEBOARD_FAB2(SCH_1):PAGE78
   104 M_G_DQ<34> @BASEBOARD_FAB2_LIB.BASEBOARD_FAB2(SCH_1):M_G_DQ(34)    I13 @BASEBOARD_FAB2_LIB.BASEBOARD_FAB2(SCH_1):PAGE78
   242 M_G_DQ<33> @BASEBOARD_FAB2_LIB.BASEBOARD_FAB2(SCH_1):M_G_DQ(33)    I13 @BASEBOARD_FAB2_LIB.BASEBOARD_FAB2(SCH_1):PAGE78
    97 M_G_DQ<32> @BASEBOARD_FAB2_LIB.BASEBOARD_FAB2(SCH_1):M_G_DQ(32)    I13 @BASEBOARD_FAB2_LIB.BASEBOARD_FAB2(SCH_1):PAGE78
   188 M_G_DQ<31> @BASEBOARD_FAB2_LIB.BASEBOARD_FAB2(SCH_1):M_G_DQ(31)    I13 @BASEBOARD_FAB2_LIB.BASEBOARD_FAB2(SCH_1):PAGE78
    43 M_G_DQ<30> @BASEBOARD_FAB2_LIB.BASEBOARD_FAB2(SCH_1):M_G_DQ(30)    I13 @BASEBOARD_FAB2_LIB.BASEBOARD_FAB2(SCH_1):PAGE78
   181 M_G_DQ<29> @BASEBOARD_FAB2_LIB.BASEBOARD_FAB2(SCH_1):M_G_DQ(29)    I13 @BASEBOARD_FAB2_LIB.BASEBOARD_FAB2(SCH_1):PAGE78
    36 M_G_DQ<28> @BASEBOARD_FAB2_LIB.BASEBOARD_FAB2(SCH_1):M_G_DQ(28)    I13 @BASEBOARD_FAB2_LIB.BASEBOARD_FAB2(SCH_1):PAGE78
   190 M_G_DQ<27> @BASEBOARD_FAB2_LIB.BASEBOARD_FAB2(SCH_1):M_G_DQ(27)    I13 @BASEBOARD_FAB2_LIB.BASEBOARD_FAB2(SCH_1):PAGE78
    45 M_G_DQ<26> @BASEBOARD_FAB2_LIB.BASEBOARD_FAB2(SCH_1):M_G_DQ(26)    I13 @BASEBOARD_FAB2_LIB.BASEBOARD_FAB2(SCH_1):PAGE78
   183 M_G_DQ<25> @BASEBOARD_FAB2_LIB.BASEBOARD_FAB2(SCH_1):M_G_DQ(25)    I13 @BASEBOARD_FAB2_LIB.BASEBOARD_FAB2(SCH_1):PAGE78
    38 M_G_DQ<24> @BASEBOARD_FAB2_LIB.BASEBOARD_FAB2(SCH_1):M_G_DQ(24)    I13 @BASEBOARD_FAB2_LIB.BASEBOARD_FAB2(SCH_1):PAGE78
   177 M_G_DQ<23> @BASEBOARD_FAB2_LIB.BASEBOARD_FAB2(SCH_1):M_G_DQ(23)    I13 @BASEBOARD_FAB2_LIB.BASEBOARD_FAB2(SCH_1):PAGE78
    32 M_G_DQ<22> @BASEBOARD_FAB2_LIB.BASEBOARD_FAB2(SCH_1):M_G_DQ(22)    I13 @BASEBOARD_FAB2_LIB.BASEBOARD_FAB2(SCH_1):PAGE78
   170 M_G_DQ<21> @BASEBOARD_FAB2_LIB.BASEBOARD_FAB2(SCH_1):M_G_DQ(21)    I13 @BASEBOARD_FAB2_LIB.BASEBOARD_FAB2(SCH_1):PAGE78
    25 M_G_DQ<20> @BASEBOARD_FAB2_LIB.BASEBOARD_FAB2(SCH_1):M_G_DQ(20)    I13 @BASEBOARD_FAB2_LIB.BASEBOARD_FAB2(SCH_1):PAGE78
   179 M_G_DQ<19> @BASEBOARD_FAB2_LIB.BASEBOARD_FAB2(SCH_1):M_G_DQ(19)    I13 @BASEBOARD_FAB2_LIB.BASEBOARD_FAB2(SCH_1):PAGE78
    34 M_G_DQ<18> @BASEBOARD_FAB2_LIB.BASEBOARD_FAB2(SCH_1):M_G_DQ(18)    I13 @BASEBOARD_FAB2_LIB.BASEBOARD_FAB2(SCH_1):PAGE78
   172 M_G_DQ<17> @BASEBOARD_FAB2_LIB.BASEBOARD_FAB2(SCH_1):M_G_DQ(17)    I13 @BASEBOARD_FAB2_LIB.BASEBOARD_FAB2(SCH_1):PAGE78
    27 M_G_DQ<16> @BASEBOARD_FAB2_LIB.BASEBOARD_FAB2(SCH_1):M_G_DQ(16)    I13 @BASEBOARD_FAB2_LIB.BASEBOARD_FAB2(SCH_1):PAGE78
   166 M_G_DQ<15> @BASEBOARD_FAB2_LIB.BASEBOARD_FAB2(SCH_1):M_G_DQ(15)    I13 @BASEBOARD_FAB2_LIB.BASEBOARD_FAB2(SCH_1):PAGE78
    21 M_G_DQ<14> @BASEBOARD_FAB2_LIB.BASEBOARD_FAB2(SCH_1):M_G_DQ(14)    I13 @BASEBOARD_FAB2_LIB.BASEBOARD_FAB2(SCH_1):PAGE78
   159 M_G_DQ<13> @BASEBOARD_FAB2_LIB.BASEBOARD_FAB2(SCH_1):M_G_DQ(13)    I13 @BASEBOARD_FAB2_LIB.BASEBOARD_FAB2(SCH_1):PAGE78
    14 M_G_DQ<12> @BASEBOARD_FAB2_LIB.BASEBOARD_FAB2(SCH_1):M_G_DQ(12)    I13 @BASEBOARD_FAB2_LIB.BASEBOARD_FAB2(SCH_1):PAGE78
   168 M_G_DQ<11> @BASEBOARD_FAB2_LIB.BASEBOARD_FAB2(SCH_1):M_G_DQ(11)    I13 @BASEBOARD_FAB2_LIB.BASEBOARD_FAB2(SCH_1):PAGE78
    23 M_G_DQ<10> @BASEBOARD_FAB2_LIB.BASEBOARD_FAB2(SCH_1):M_G_DQ(10)    I13 @BASEBOARD_FAB2_LIB.BASEBOARD_FAB2(SCH_1):PAGE78
   161 M_G_DQ<9> @BASEBOARD_FAB2_LIB.BASEBOARD_FAB2(SCH_1):M_G_DQ(9)    I13 @BASEBOARD_FAB2_LIB.BASEBOARD_FAB2(SCH_1):PAGE78
    16 M_G_DQ<8> @BASEBOARD_FAB2_LIB.BASEBOARD_FAB2(SCH_1):M_G_DQ(8)    I13 @BASEBOARD_FAB2_LIB.BASEBOARD_FAB2(SCH_1):PAGE78
   155 M_G_DQ<7> @BASEBOARD_FAB2_LIB.BASEBOARD_FAB2(SCH_1):M_G_DQ(7)    I13 @BASEBOARD_FAB2_LIB.BASEBOARD_FAB2(SCH_1):PAGE78
    10 M_G_DQ<6> @BASEBOARD_FAB2_LIB.BASEBOARD_FAB2(SCH_1):M_G_DQ(6)    I13 @BASEBOARD_FAB2_LIB.BASEBOARD_FAB2(SCH_1):PAGE78
   148 M_G_DQ<5> @BASEBOARD_FAB2_LIB.BASEBOARD_FAB2(SCH_1):M_G_DQ(5)    I13 @BASEBOARD_FAB2_LIB.BASEBOARD_FAB2(SCH_1):PAGE78
     3 M_G_DQ<4> @BASEBOARD_FAB2_LIB.BASEBOARD_FAB2(SCH_1):M_G_DQ(4)    I13 @BASEBOARD_FAB2_LIB.BASEBOARD_FAB2(SCH_1):PAGE78
   157 M_G_DQ<3> @BASEBOARD_FAB2_LIB.BASEBOARD_FAB2(SCH_1):M_G_DQ(3)    I13 @BASEBOARD_FAB2_LIB.BASEBOARD_FAB2(SCH_1):PAGE78
    12 M_G_DQ<2> @BASEBOARD_FAB2_LIB.BASEBOARD_FAB2(SCH_1):M_G_DQ(2)    I13 @BASEBOARD_FAB2_LIB.BASEBOARD_FAB2(SCH_1):PAGE78
   150 M_G_DQ<1> @BASEBOARD_FAB2_LIB.BASEBOARD_FAB2(SCH_1):M_G_DQ(1)    I13 @BASEBOARD_FAB2_LIB.BASEBOARD_FAB2(SCH_1):PAGE78
     5 M_G_DQ<0> @BASEBOARD_FAB2_LIB.BASEBOARD_FAB2(SCH_1):M_G_DQ(0)    I13 @BASEBOARD_FAB2_LIB.BASEBOARD_FAB2(SCH_1):PAGE78
    78 FM_DIMM_EVENT_COD_N @BASEBOARD_FAB2_LIB.BASEBOARD_FAB2(SCH_1):FM_DIMM_EVENT_COD_N    I13 @BASEBOARD_FAB2_LIB.BASEBOARD_FAB2(SCH_1):PAGE78
    91 M_G_ODT<3> @BASEBOARD_FAB2_LIB.BASEBOARD_FAB2(SCH_1):M_G_ODT(3)    I13 @BASEBOARD_FAB2_LIB.BASEBOARD_FAB2(SCH_1):PAGE78
    87 M_G_ODT<2> @BASEBOARD_FAB2_LIB.BASEBOARD_FAB2(SCH_1):M_G_ODT(2)    I13 @BASEBOARD_FAB2_LIB.BASEBOARD_FAB2(SCH_1):PAGE78
   222 M_G_PAR @BASEBOARD_FAB2_LIB.BASEBOARD_FAB2(SCH_1):M_G_PAR    I13 @BASEBOARD_FAB2_LIB.BASEBOARD_FAB2(SCH_1):PAGE78
    58 M_GHJ_RST_N @BASEBOARD_FAB2_LIB.BASEBOARD_FAB2(SCH_1):M_GHJ_RST_N    I13 @BASEBOARD_FAB2_LIB.BASEBOARD_FAB2(SCH_1):PAGE78
   144 TP_CH_G_DIMM0_RFU_2 @BASEBOARD_FAB2_LIB.BASEBOARD_FAB2(SCH_1):TP_CH_G_DIMM0_RFU_2    I13 @BASEBOARD_FAB2_LIB.BASEBOARD_FAB2(SCH_1):PAGE78
   227 TP_CH_G_DIMM0_RFU_1 @BASEBOARD_FAB2_LIB.BASEBOARD_FAB2(SCH_1):TP_CH_G_DIMM0_RFU_1    I13 @BASEBOARD_FAB2_LIB.BASEBOARD_FAB2(SCH_1):PAGE78
   205 TP_CH_G_DIMM0_RFU_0 @BASEBOARD_FAB2_LIB.BASEBOARD_FAB2(SCH_1):TP_CH_G_DIMM0_RFU_0    I13 @BASEBOARD_FAB2_LIB.BASEBOARD_FAB2(SCH_1):PAGE78
    84 M_G_CS_N<4> @BASEBOARD_FAB2_LIB.BASEBOARD_FAB2(SCH_1):M_G_CS_N(4)    I13 @BASEBOARD_FAB2_LIB.BASEBOARD_FAB2(SCH_1):PAGE78
    89 M_G_CS_N<5> @BASEBOARD_FAB2_LIB.BASEBOARD_FAB2(SCH_1):M_G_CS_N(5)    I13 @BASEBOARD_FAB2_LIB.BASEBOARD_FAB2(SCH_1):PAGE78
    93 M_G_CS_N<6> @BASEBOARD_FAB2_LIB.BASEBOARD_FAB2(SCH_1):M_G_CS_N(6)    I13 @BASEBOARD_FAB2_LIB.BASEBOARD_FAB2(SCH_1):PAGE78
   237 M_G_CS_N<7> @BASEBOARD_FAB2_LIB.BASEBOARD_FAB2(SCH_1):M_G_CS_N(7)    I13 @BASEBOARD_FAB2_LIB.BASEBOARD_FAB2(SCH_1):PAGE78
   238    GND @BASEBOARD_FAB2_LIB.BASEBOARD_FAB2(SCH_1):GND    I13 @BASEBOARD_FAB2_LIB.BASEBOARD_FAB2(SCH_1):PAGE78
   140    GND @BASEBOARD_FAB2_LIB.BASEBOARD_FAB2(SCH_1):GND    I13 @BASEBOARD_FAB2_LIB.BASEBOARD_FAB2(SCH_1):PAGE78
   139 PVPP_GHJ @BASEBOARD_FAB2_LIB.BASEBOARD_FAB2(SCH_1):PVPP_GHJ    I13 @BASEBOARD_FAB2_LIB.BASEBOARD_FAB2(SCH_1):PAGE78
   230 FM_ADR_COMPLETE_GHJ_N @BASEBOARD_FAB2_LIB.BASEBOARD_FAB2(SCH_1):FM_ADR_COMPLETE_GHJ_N    I13 @BASEBOARD_FAB2_LIB.BASEBOARD_FAB2(SCH_1):PAGE78
   141 SMB_DDR_GHJ_VPP_SCL @BASEBOARD_FAB2_LIB.BASEBOARD_FAB2(SCH_1):SMB_DDR_GHJ_VPP_SCL    I13 @BASEBOARD_FAB2_LIB.BASEBOARD_FAB2(SCH_1):PAGE78
   285 SMB_DDR_GHJ_VPP_SDA @BASEBOARD_FAB2_LIB.BASEBOARD_FAB2(SCH_1):SMB_DDR_GHJ_VPP_SDA    I13 @BASEBOARD_FAB2_LIB.BASEBOARD_FAB2(SCH_1):PAGE78
   284 PVPP_GHJ @BASEBOARD_FAB2_LIB.BASEBOARD_FAB2(SCH_1):PVPP_GHJ    I13 @BASEBOARD_FAB2_LIB.BASEBOARD_FAB2(SCH_1):PAGE78
   146 M_G_VREF @BASEBOARD_FAB2_LIB.BASEBOARD_FAB2(SCH_1):M_G_VREF    I13 @BASEBOARD_FAB2_LIB.BASEBOARD_FAB2(SCH_1):PAGE78
   152 M_G_DQS_DN<0> @BASEBOARD_FAB2_LIB.BASEBOARD_FAB2(SCH_1):M_G_DQS_DN(0)   I120 @BASEBOARD_FAB2_LIB.BASEBOARD_FAB2(SCH_1):PAGE78
   153 M_G_DQS_DP<0> @BASEBOARD_FAB2_LIB.BASEBOARD_FAB2(SCH_1):M_G_DQS_DP(0)   I120 @BASEBOARD_FAB2_LIB.BASEBOARD_FAB2(SCH_1):PAGE78
    19 M_G_DQS_DN<10> @BASEBOARD_FAB2_LIB.BASEBOARD_FAB2(SCH_1):M_G_DQS_DN(10)   I120 @BASEBOARD_FAB2_LIB.BASEBOARD_FAB2(SCH_1):PAGE78
    18 M_G_DQS_DP<10> @BASEBOARD_FAB2_LIB.BASEBOARD_FAB2(SCH_1):M_G_DQS_DP(10)   I120 @BASEBOARD_FAB2_LIB.BASEBOARD_FAB2(SCH_1):PAGE78
    30 M_G_DQS_DN<11> @BASEBOARD_FAB2_LIB.BASEBOARD_FAB2(SCH_1):M_G_DQS_DN(11)   I120 @BASEBOARD_FAB2_LIB.BASEBOARD_FAB2(SCH_1):PAGE78
    29 M_G_DQS_DP<11> @BASEBOARD_FAB2_LIB.BASEBOARD_FAB2(SCH_1):M_G_DQS_DP(11)   I120 @BASEBOARD_FAB2_LIB.BASEBOARD_FAB2(SCH_1):PAGE78
    41 M_G_DQS_DN<12> @BASEBOARD_FAB2_LIB.BASEBOARD_FAB2(SCH_1):M_G_DQS_DN(12)   I120 @BASEBOARD_FAB2_LIB.BASEBOARD_FAB2(SCH_1):PAGE78
    40 M_G_DQS_DP<12> @BASEBOARD_FAB2_LIB.BASEBOARD_FAB2(SCH_1):M_G_DQS_DP(12)   I120 @BASEBOARD_FAB2_LIB.BASEBOARD_FAB2(SCH_1):PAGE78
   100 M_G_DQS_DN<13> @BASEBOARD_FAB2_LIB.BASEBOARD_FAB2(SCH_1):M_G_DQS_DN(13)   I120 @BASEBOARD_FAB2_LIB.BASEBOARD_FAB2(SCH_1):PAGE78
    99 M_G_DQS_DP<13> @BASEBOARD_FAB2_LIB.BASEBOARD_FAB2(SCH_1):M_G_DQS_DP(13)   I120 @BASEBOARD_FAB2_LIB.BASEBOARD_FAB2(SCH_1):PAGE78
   111 M_G_DQS_DN<14> @BASEBOARD_FAB2_LIB.BASEBOARD_FAB2(SCH_1):M_G_DQS_DN(14)   I120 @BASEBOARD_FAB2_LIB.BASEBOARD_FAB2(SCH_1):PAGE78
   110 M_G_DQS_DP<14> @BASEBOARD_FAB2_LIB.BASEBOARD_FAB2(SCH_1):M_G_DQS_DP(14)   I120 @BASEBOARD_FAB2_LIB.BASEBOARD_FAB2(SCH_1):PAGE78
   122 M_G_DQS_DN<15> @BASEBOARD_FAB2_LIB.BASEBOARD_FAB2(SCH_1):M_G_DQS_DN(15)   I120 @BASEBOARD_FAB2_LIB.BASEBOARD_FAB2(SCH_1):PAGE78
   121 M_G_DQS_DP<15> @BASEBOARD_FAB2_LIB.BASEBOARD_FAB2(SCH_1):M_G_DQS_DP(15)   I120 @BASEBOARD_FAB2_LIB.BASEBOARD_FAB2(SCH_1):PAGE78
   133 M_G_DQS_DN<16> @BASEBOARD_FAB2_LIB.BASEBOARD_FAB2(SCH_1):M_G_DQS_DN(16)   I120 @BASEBOARD_FAB2_LIB.BASEBOARD_FAB2(SCH_1):PAGE78
   132 M_G_DQS_DP<16> @BASEBOARD_FAB2_LIB.BASEBOARD_FAB2(SCH_1):M_G_DQS_DP(16)   I120 @BASEBOARD_FAB2_LIB.BASEBOARD_FAB2(SCH_1):PAGE78
    52 M_G_DQS_DN<17> @BASEBOARD_FAB2_LIB.BASEBOARD_FAB2(SCH_1):M_G_DQS_DN(17)   I120 @BASEBOARD_FAB2_LIB.BASEBOARD_FAB2(SCH_1):PAGE78
    51 M_G_DQS_DP<17> @BASEBOARD_FAB2_LIB.BASEBOARD_FAB2(SCH_1):M_G_DQS_DP(17)   I120 @BASEBOARD_FAB2_LIB.BASEBOARD_FAB2(SCH_1):PAGE78
   163 M_G_DQS_DN<1> @BASEBOARD_FAB2_LIB.BASEBOARD_FAB2(SCH_1):M_G_DQS_DN(1)   I120 @BASEBOARD_FAB2_LIB.BASEBOARD_FAB2(SCH_1):PAGE78
   164 M_G_DQS_DP<1> @BASEBOARD_FAB2_LIB.BASEBOARD_FAB2(SCH_1):M_G_DQS_DP(1)   I120 @BASEBOARD_FAB2_LIB.BASEBOARD_FAB2(SCH_1):PAGE78
   174 M_G_DQS_DN<2> @BASEBOARD_FAB2_LIB.BASEBOARD_FAB2(SCH_1):M_G_DQS_DN(2)   I120 @BASEBOARD_FAB2_LIB.BASEBOARD_FAB2(SCH_1):PAGE78
   175 M_G_DQS_DP<2> @BASEBOARD_FAB2_LIB.BASEBOARD_FAB2(SCH_1):M_G_DQS_DP(2)   I120 @BASEBOARD_FAB2_LIB.BASEBOARD_FAB2(SCH_1):PAGE78
   185 M_G_DQS_DN<3> @BASEBOARD_FAB2_LIB.BASEBOARD_FAB2(SCH_1):M_G_DQS_DN(3)   I120 @BASEBOARD_FAB2_LIB.BASEBOARD_FAB2(SCH_1):PAGE78
   186 M_G_DQS_DP<3> @BASEBOARD_FAB2_LIB.BASEBOARD_FAB2(SCH_1):M_G_DQS_DP(3)   I120 @BASEBOARD_FAB2_LIB.BASEBOARD_FAB2(SCH_1):PAGE78
   244 M_G_DQS_DN<4> @BASEBOARD_FAB2_LIB.BASEBOARD_FAB2(SCH_1):M_G_DQS_DN(4)   I120 @BASEBOARD_FAB2_LIB.BASEBOARD_FAB2(SCH_1):PAGE78
   245 M_G_DQS_DP<4> @BASEBOARD_FAB2_LIB.BASEBOARD_FAB2(SCH_1):M_G_DQS_DP(4)   I120 @BASEBOARD_FAB2_LIB.BASEBOARD_FAB2(SCH_1):PAGE78
   255 M_G_DQS_DN<5> @BASEBOARD_FAB2_LIB.BASEBOARD_FAB2(SCH_1):M_G_DQS_DN(5)   I120 @BASEBOARD_FAB2_LIB.BASEBOARD_FAB2(SCH_1):PAGE78
   256 M_G_DQS_DP<5> @BASEBOARD_FAB2_LIB.BASEBOARD_FAB2(SCH_1):M_G_DQS_DP(5)   I120 @BASEBOARD_FAB2_LIB.BASEBOARD_FAB2(SCH_1):PAGE78
   266 M_G_DQS_DN<6> @BASEBOARD_FAB2_LIB.BASEBOARD_FAB2(SCH_1):M_G_DQS_DN(6)   I120 @BASEBOARD_FAB2_LIB.BASEBOARD_FAB2(SCH_1):PAGE78
   267 M_G_DQS_DP<6> @BASEBOARD_FAB2_LIB.BASEBOARD_FAB2(SCH_1):M_G_DQS_DP(6)   I120 @BASEBOARD_FAB2_LIB.BASEBOARD_FAB2(SCH_1):PAGE78
   277 M_G_DQS_DN<7> @BASEBOARD_FAB2_LIB.BASEBOARD_FAB2(SCH_1):M_G_DQS_DN(7)   I120 @BASEBOARD_FAB2_LIB.BASEBOARD_FAB2(SCH_1):PAGE78
   278 M_G_DQS_DP<7> @BASEBOARD_FAB2_LIB.BASEBOARD_FAB2(SCH_1):M_G_DQS_DP(7)   I120 @BASEBOARD_FAB2_LIB.BASEBOARD_FAB2(SCH_1):PAGE78
   196 M_G_DQS_DN<8> @BASEBOARD_FAB2_LIB.BASEBOARD_FAB2(SCH_1):M_G_DQS_DN(8)   I120 @BASEBOARD_FAB2_LIB.BASEBOARD_FAB2(SCH_1):PAGE78
   197 M_G_DQS_DP<8> @BASEBOARD_FAB2_LIB.BASEBOARD_FAB2(SCH_1):M_G_DQS_DP(8)   I120 @BASEBOARD_FAB2_LIB.BASEBOARD_FAB2(SCH_1):PAGE78
     8 M_G_DQS_DN<9> @BASEBOARD_FAB2_LIB.BASEBOARD_FAB2(SCH_1):M_G_DQS_DN(9)   I120 @BASEBOARD_FAB2_LIB.BASEBOARD_FAB2(SCH_1):PAGE78
     7 M_G_DQS_DP<9> @BASEBOARD_FAB2_LIB.BASEBOARD_FAB2(SCH_1):M_G_DQS_DP(9)   I120 @BASEBOARD_FAB2_LIB.BASEBOARD_FAB2(SCH_1):PAGE78
     2    GND @BASEBOARD_FAB2_LIB.BASEBOARD_FAB2(SCH_1):GND   I144 @BASEBOARD_FAB2_LIB.BASEBOARD_FAB2(SCH_1):PAGE78
     4    GND @BASEBOARD_FAB2_LIB.BASEBOARD_FAB2(SCH_1):GND   I144 @BASEBOARD_FAB2_LIB.BASEBOARD_FAB2(SCH_1):PAGE78
     6    GND @BASEBOARD_FAB2_LIB.BASEBOARD_FAB2(SCH_1):GND   I144 @BASEBOARD_FAB2_LIB.BASEBOARD_FAB2(SCH_1):PAGE78
     9    GND @BASEBOARD_FAB2_LIB.BASEBOARD_FAB2(SCH_1):GND   I144 @BASEBOARD_FAB2_LIB.BASEBOARD_FAB2(SCH_1):PAGE78
    11    GND @BASEBOARD_FAB2_LIB.BASEBOARD_FAB2(SCH_1):GND   I144 @BASEBOARD_FAB2_LIB.BASEBOARD_FAB2(SCH_1):PAGE78
    13    GND @BASEBOARD_FAB2_LIB.BASEBOARD_FAB2(SCH_1):GND   I144 @BASEBOARD_FAB2_LIB.BASEBOARD_FAB2(SCH_1):PAGE78
    15    GND @BASEBOARD_FAB2_LIB.BASEBOARD_FAB2(SCH_1):GND   I144 @BASEBOARD_FAB2_LIB.BASEBOARD_FAB2(SCH_1):PAGE78
    17    GND @BASEBOARD_FAB2_LIB.BASEBOARD_FAB2(SCH_1):GND   I144 @BASEBOARD_FAB2_LIB.BASEBOARD_FAB2(SCH_1):PAGE78
    20    GND @BASEBOARD_FAB2_LIB.BASEBOARD_FAB2(SCH_1):GND   I144 @BASEBOARD_FAB2_LIB.BASEBOARD_FAB2(SCH_1):PAGE78
    22    GND @BASEBOARD_FAB2_LIB.BASEBOARD_FAB2(SCH_1):GND   I144 @BASEBOARD_FAB2_LIB.BASEBOARD_FAB2(SCH_1):PAGE78
    24    GND @BASEBOARD_FAB2_LIB.BASEBOARD_FAB2(SCH_1):GND   I144 @BASEBOARD_FAB2_LIB.BASEBOARD_FAB2(SCH_1):PAGE78
    26    GND @BASEBOARD_FAB2_LIB.BASEBOARD_FAB2(SCH_1):GND   I144 @BASEBOARD_FAB2_LIB.BASEBOARD_FAB2(SCH_1):PAGE78
    28    GND @BASEBOARD_FAB2_LIB.BASEBOARD_FAB2(SCH_1):GND   I144 @BASEBOARD_FAB2_LIB.BASEBOARD_FAB2(SCH_1):PAGE78
    31    GND @BASEBOARD_FAB2_LIB.BASEBOARD_FAB2(SCH_1):GND   I144 @BASEBOARD_FAB2_LIB.BASEBOARD_FAB2(SCH_1):PAGE78
    33    GND @BASEBOARD_FAB2_LIB.BASEBOARD_FAB2(SCH_1):GND   I144 @BASEBOARD_FAB2_LIB.BASEBOARD_FAB2(SCH_1):PAGE78
    35    GND @BASEBOARD_FAB2_LIB.BASEBOARD_FAB2(SCH_1):GND   I144 @BASEBOARD_FAB2_LIB.BASEBOARD_FAB2(SCH_1):PAGE78
    37    GND @BASEBOARD_FAB2_LIB.BASEBOARD_FAB2(SCH_1):GND   I144 @BASEBOARD_FAB2_LIB.BASEBOARD_FAB2(SCH_1):PAGE78
    39    GND @BASEBOARD_FAB2_LIB.BASEBOARD_FAB2(SCH_1):GND   I144 @BASEBOARD_FAB2_LIB.BASEBOARD_FAB2(SCH_1):PAGE78
    42    GND @BASEBOARD_FAB2_LIB.BASEBOARD_FAB2(SCH_1):GND   I144 @BASEBOARD_FAB2_LIB.BASEBOARD_FAB2(SCH_1):PAGE78
    44    GND @BASEBOARD_FAB2_LIB.BASEBOARD_FAB2(SCH_1):GND   I144 @BASEBOARD_FAB2_LIB.BASEBOARD_FAB2(SCH_1):PAGE78
    46    GND @BASEBOARD_FAB2_LIB.BASEBOARD_FAB2(SCH_1):GND   I144 @BASEBOARD_FAB2_LIB.BASEBOARD_FAB2(SCH_1):PAGE78
    48    GND @BASEBOARD_FAB2_LIB.BASEBOARD_FAB2(SCH_1):GND   I144 @BASEBOARD_FAB2_LIB.BASEBOARD_FAB2(SCH_1):PAGE78
    50    GND @BASEBOARD_FAB2_LIB.BASEBOARD_FAB2(SCH_1):GND   I144 @BASEBOARD_FAB2_LIB.BASEBOARD_FAB2(SCH_1):PAGE78
    53    GND @BASEBOARD_FAB2_LIB.BASEBOARD_FAB2(SCH_1):GND   I144 @BASEBOARD_FAB2_LIB.BASEBOARD_FAB2(SCH_1):PAGE78
    55    GND @BASEBOARD_FAB2_LIB.BASEBOARD_FAB2(SCH_1):GND   I144 @BASEBOARD_FAB2_LIB.BASEBOARD_FAB2(SCH_1):PAGE78
    57    GND @BASEBOARD_FAB2_LIB.BASEBOARD_FAB2(SCH_1):GND   I144 @BASEBOARD_FAB2_LIB.BASEBOARD_FAB2(SCH_1):PAGE78
    94    GND @BASEBOARD_FAB2_LIB.BASEBOARD_FAB2(SCH_1):GND   I144 @BASEBOARD_FAB2_LIB.BASEBOARD_FAB2(SCH_1):PAGE78
    96    GND @BASEBOARD_FAB2_LIB.BASEBOARD_FAB2(SCH_1):GND   I144 @BASEBOARD_FAB2_LIB.BASEBOARD_FAB2(SCH_1):PAGE78
    98    GND @BASEBOARD_FAB2_LIB.BASEBOARD_FAB2(SCH_1):GND   I144 @BASEBOARD_FAB2_LIB.BASEBOARD_FAB2(SCH_1):PAGE78
   101    GND @BASEBOARD_FAB2_LIB.BASEBOARD_FAB2(SCH_1):GND   I144 @BASEBOARD_FAB2_LIB.BASEBOARD_FAB2(SCH_1):PAGE78
   103    GND @BASEBOARD_FAB2_LIB.BASEBOARD_FAB2(SCH_1):GND   I144 @BASEBOARD_FAB2_LIB.BASEBOARD_FAB2(SCH_1):PAGE78
   105    GND @BASEBOARD_FAB2_LIB.BASEBOARD_FAB2(SCH_1):GND   I144 @BASEBOARD_FAB2_LIB.BASEBOARD_FAB2(SCH_1):PAGE78
   107    GND @BASEBOARD_FAB2_LIB.BASEBOARD_FAB2(SCH_1):GND   I144 @BASEBOARD_FAB2_LIB.BASEBOARD_FAB2(SCH_1):PAGE78
   109    GND @BASEBOARD_FAB2_LIB.BASEBOARD_FAB2(SCH_1):GND   I144 @BASEBOARD_FAB2_LIB.BASEBOARD_FAB2(SCH_1):PAGE78
   112    GND @BASEBOARD_FAB2_LIB.BASEBOARD_FAB2(SCH_1):GND   I144 @BASEBOARD_FAB2_LIB.BASEBOARD_FAB2(SCH_1):PAGE78
   114    GND @BASEBOARD_FAB2_LIB.BASEBOARD_FAB2(SCH_1):GND   I144 @BASEBOARD_FAB2_LIB.BASEBOARD_FAB2(SCH_1):PAGE78
   116    GND @BASEBOARD_FAB2_LIB.BASEBOARD_FAB2(SCH_1):GND   I144 @BASEBOARD_FAB2_LIB.BASEBOARD_FAB2(SCH_1):PAGE78
   118    GND @BASEBOARD_FAB2_LIB.BASEBOARD_FAB2(SCH_1):GND   I144 @BASEBOARD_FAB2_LIB.BASEBOARD_FAB2(SCH_1):PAGE78
   120    GND @BASEBOARD_FAB2_LIB.BASEBOARD_FAB2(SCH_1):GND   I144 @BASEBOARD_FAB2_LIB.BASEBOARD_FAB2(SCH_1):PAGE78
   123    GND @BASEBOARD_FAB2_LIB.BASEBOARD_FAB2(SCH_1):GND   I144 @BASEBOARD_FAB2_LIB.BASEBOARD_FAB2(SCH_1):PAGE78
   125    GND @BASEBOARD_FAB2_LIB.BASEBOARD_FAB2(SCH_1):GND   I144 @BASEBOARD_FAB2_LIB.BASEBOARD_FAB2(SCH_1):PAGE78
   127    GND @BASEBOARD_FAB2_LIB.BASEBOARD_FAB2(SCH_1):GND   I144 @BASEBOARD_FAB2_LIB.BASEBOARD_FAB2(SCH_1):PAGE78
   129    GND @BASEBOARD_FAB2_LIB.BASEBOARD_FAB2(SCH_1):GND   I144 @BASEBOARD_FAB2_LIB.BASEBOARD_FAB2(SCH_1):PAGE78
   131    GND @BASEBOARD_FAB2_LIB.BASEBOARD_FAB2(SCH_1):GND   I144 @BASEBOARD_FAB2_LIB.BASEBOARD_FAB2(SCH_1):PAGE78
   134    GND @BASEBOARD_FAB2_LIB.BASEBOARD_FAB2(SCH_1):GND   I144 @BASEBOARD_FAB2_LIB.BASEBOARD_FAB2(SCH_1):PAGE78
   136    GND @BASEBOARD_FAB2_LIB.BASEBOARD_FAB2(SCH_1):GND   I144 @BASEBOARD_FAB2_LIB.BASEBOARD_FAB2(SCH_1):PAGE78
   138    GND @BASEBOARD_FAB2_LIB.BASEBOARD_FAB2(SCH_1):GND   I144 @BASEBOARD_FAB2_LIB.BASEBOARD_FAB2(SCH_1):PAGE78
   147    GND @BASEBOARD_FAB2_LIB.BASEBOARD_FAB2(SCH_1):GND   I144 @BASEBOARD_FAB2_LIB.BASEBOARD_FAB2(SCH_1):PAGE78
   149    GND @BASEBOARD_FAB2_LIB.BASEBOARD_FAB2(SCH_1):GND   I144 @BASEBOARD_FAB2_LIB.BASEBOARD_FAB2(SCH_1):PAGE78
   151    GND @BASEBOARD_FAB2_LIB.BASEBOARD_FAB2(SCH_1):GND   I144 @BASEBOARD_FAB2_LIB.BASEBOARD_FAB2(SCH_1):PAGE78
   154    GND @BASEBOARD_FAB2_LIB.BASEBOARD_FAB2(SCH_1):GND   I144 @BASEBOARD_FAB2_LIB.BASEBOARD_FAB2(SCH_1):PAGE78
   156    GND @BASEBOARD_FAB2_LIB.BASEBOARD_FAB2(SCH_1):GND   I144 @BASEBOARD_FAB2_LIB.BASEBOARD_FAB2(SCH_1):PAGE78
   158    GND @BASEBOARD_FAB2_LIB.BASEBOARD_FAB2(SCH_1):GND   I144 @BASEBOARD_FAB2_LIB.BASEBOARD_FAB2(SCH_1):PAGE78
   160    GND @BASEBOARD_FAB2_LIB.BASEBOARD_FAB2(SCH_1):GND   I144 @BASEBOARD_FAB2_LIB.BASEBOARD_FAB2(SCH_1):PAGE78
   162    GND @BASEBOARD_FAB2_LIB.BASEBOARD_FAB2(SCH_1):GND   I144 @BASEBOARD_FAB2_LIB.BASEBOARD_FAB2(SCH_1):PAGE78
   165    GND @BASEBOARD_FAB2_LIB.BASEBOARD_FAB2(SCH_1):GND   I144 @BASEBOARD_FAB2_LIB.BASEBOARD_FAB2(SCH_1):PAGE78
   167    GND @BASEBOARD_FAB2_LIB.BASEBOARD_FAB2(SCH_1):GND   I144 @BASEBOARD_FAB2_LIB.BASEBOARD_FAB2(SCH_1):PAGE78
   169    GND @BASEBOARD_FAB2_LIB.BASEBOARD_FAB2(SCH_1):GND   I144 @BASEBOARD_FAB2_LIB.BASEBOARD_FAB2(SCH_1):PAGE78
   171    GND @BASEBOARD_FAB2_LIB.BASEBOARD_FAB2(SCH_1):GND   I144 @BASEBOARD_FAB2_LIB.BASEBOARD_FAB2(SCH_1):PAGE78
   173    GND @BASEBOARD_FAB2_LIB.BASEBOARD_FAB2(SCH_1):GND   I144 @BASEBOARD_FAB2_LIB.BASEBOARD_FAB2(SCH_1):PAGE78
   176    GND @BASEBOARD_FAB2_LIB.BASEBOARD_FAB2(SCH_1):GND   I144 @BASEBOARD_FAB2_LIB.BASEBOARD_FAB2(SCH_1):PAGE78
   178    GND @BASEBOARD_FAB2_LIB.BASEBOARD_FAB2(SCH_1):GND   I144 @BASEBOARD_FAB2_LIB.BASEBOARD_FAB2(SCH_1):PAGE78
   180    GND @BASEBOARD_FAB2_LIB.BASEBOARD_FAB2(SCH_1):GND   I144 @BASEBOARD_FAB2_LIB.BASEBOARD_FAB2(SCH_1):PAGE78
   182    GND @BASEBOARD_FAB2_LIB.BASEBOARD_FAB2(SCH_1):GND   I144 @BASEBOARD_FAB2_LIB.BASEBOARD_FAB2(SCH_1):PAGE78
   184    GND @BASEBOARD_FAB2_LIB.BASEBOARD_FAB2(SCH_1):GND   I144 @BASEBOARD_FAB2_LIB.BASEBOARD_FAB2(SCH_1):PAGE78
   187    GND @BASEBOARD_FAB2_LIB.BASEBOARD_FAB2(SCH_1):GND   I144 @BASEBOARD_FAB2_LIB.BASEBOARD_FAB2(SCH_1):PAGE78
   189    GND @BASEBOARD_FAB2_LIB.BASEBOARD_FAB2(SCH_1):GND   I144 @BASEBOARD_FAB2_LIB.BASEBOARD_FAB2(SCH_1):PAGE78
   191    GND @BASEBOARD_FAB2_LIB.BASEBOARD_FAB2(SCH_1):GND   I144 @BASEBOARD_FAB2_LIB.BASEBOARD_FAB2(SCH_1):PAGE78
   193    GND @BASEBOARD_FAB2_LIB.BASEBOARD_FAB2(SCH_1):GND   I144 @BASEBOARD_FAB2_LIB.BASEBOARD_FAB2(SCH_1):PAGE78
   195    GND @BASEBOARD_FAB2_LIB.BASEBOARD_FAB2(SCH_1):GND   I144 @BASEBOARD_FAB2_LIB.BASEBOARD_FAB2(SCH_1):PAGE78
   198    GND @BASEBOARD_FAB2_LIB.BASEBOARD_FAB2(SCH_1):GND   I144 @BASEBOARD_FAB2_LIB.BASEBOARD_FAB2(SCH_1):PAGE78
   200    GND @BASEBOARD_FAB2_LIB.BASEBOARD_FAB2(SCH_1):GND   I144 @BASEBOARD_FAB2_LIB.BASEBOARD_FAB2(SCH_1):PAGE78
   202    GND @BASEBOARD_FAB2_LIB.BASEBOARD_FAB2(SCH_1):GND   I144 @BASEBOARD_FAB2_LIB.BASEBOARD_FAB2(SCH_1):PAGE78
   239    GND @BASEBOARD_FAB2_LIB.BASEBOARD_FAB2(SCH_1):GND   I144 @BASEBOARD_FAB2_LIB.BASEBOARD_FAB2(SCH_1):PAGE78
   241    GND @BASEBOARD_FAB2_LIB.BASEBOARD_FAB2(SCH_1):GND   I144 @BASEBOARD_FAB2_LIB.BASEBOARD_FAB2(SCH_1):PAGE78
   243    GND @BASEBOARD_FAB2_LIB.BASEBOARD_FAB2(SCH_1):GND   I144 @BASEBOARD_FAB2_LIB.BASEBOARD_FAB2(SCH_1):PAGE78
   246    GND @BASEBOARD_FAB2_LIB.BASEBOARD_FAB2(SCH_1):GND   I144 @BASEBOARD_FAB2_LIB.BASEBOARD_FAB2(SCH_1):PAGE78
   248    GND @BASEBOARD_FAB2_LIB.BASEBOARD_FAB2(SCH_1):GND   I144 @BASEBOARD_FAB2_LIB.BASEBOARD_FAB2(SCH_1):PAGE78
   250    GND @BASEBOARD_FAB2_LIB.BASEBOARD_FAB2(SCH_1):GND   I144 @BASEBOARD_FAB2_LIB.BASEBOARD_FAB2(SCH_1):PAGE78
   252    GND @BASEBOARD_FAB2_LIB.BASEBOARD_FAB2(SCH_1):GND   I144 @BASEBOARD_FAB2_LIB.BASEBOARD_FAB2(SCH_1):PAGE78
   254    GND @BASEBOARD_FAB2_LIB.BASEBOARD_FAB2(SCH_1):GND   I144 @BASEBOARD_FAB2_LIB.BASEBOARD_FAB2(SCH_1):PAGE78
   257    GND @BASEBOARD_FAB2_LIB.BASEBOARD_FAB2(SCH_1):GND   I144 @BASEBOARD_FAB2_LIB.BASEBOARD_FAB2(SCH_1):PAGE78
   259    GND @BASEBOARD_FAB2_LIB.BASEBOARD_FAB2(SCH_1):GND   I144 @BASEBOARD_FAB2_LIB.BASEBOARD_FAB2(SCH_1):PAGE78
   261    GND @BASEBOARD_FAB2_LIB.BASEBOARD_FAB2(SCH_1):GND   I144 @BASEBOARD_FAB2_LIB.BASEBOARD_FAB2(SCH_1):PAGE78
   263    GND @BASEBOARD_FAB2_LIB.BASEBOARD_FAB2(SCH_1):GND   I144 @BASEBOARD_FAB2_LIB.BASEBOARD_FAB2(SCH_1):PAGE78
   265    GND @BASEBOARD_FAB2_LIB.BASEBOARD_FAB2(SCH_1):GND   I144 @BASEBOARD_FAB2_LIB.BASEBOARD_FAB2(SCH_1):PAGE78
   268    GND @BASEBOARD_FAB2_LIB.BASEBOARD_FAB2(SCH_1):GND   I144 @BASEBOARD_FAB2_LIB.BASEBOARD_FAB2(SCH_1):PAGE78
   270    GND @BASEBOARD_FAB2_LIB.BASEBOARD_FAB2(SCH_1):GND   I144 @BASEBOARD_FAB2_LIB.BASEBOARD_FAB2(SCH_1):PAGE78
   272    GND @BASEBOARD_FAB2_LIB.BASEBOARD_FAB2(SCH_1):GND   I144 @BASEBOARD_FAB2_LIB.BASEBOARD_FAB2(SCH_1):PAGE78
   274    GND @BASEBOARD_FAB2_LIB.BASEBOARD_FAB2(SCH_1):GND   I144 @BASEBOARD_FAB2_LIB.BASEBOARD_FAB2(SCH_1):PAGE78
   276    GND @BASEBOARD_FAB2_LIB.BASEBOARD_FAB2(SCH_1):GND   I144 @BASEBOARD_FAB2_LIB.BASEBOARD_FAB2(SCH_1):PAGE78
   279    GND @BASEBOARD_FAB2_LIB.BASEBOARD_FAB2(SCH_1):GND   I144 @BASEBOARD_FAB2_LIB.BASEBOARD_FAB2(SCH_1):PAGE78
   281    GND @BASEBOARD_FAB2_LIB.BASEBOARD_FAB2(SCH_1):GND   I144 @BASEBOARD_FAB2_LIB.BASEBOARD_FAB2(SCH_1):PAGE78
   283    GND @BASEBOARD_FAB2_LIB.BASEBOARD_FAB2(SCH_1):GND   I144 @BASEBOARD_FAB2_LIB.BASEBOARD_FAB2(SCH_1):PAGE78
     1 P12V_NVDIMM_GHJ @BASEBOARD_FAB2_LIB.BASEBOARD_FAB2(SCH_1):P12V_NVDIMM_GHJ    I75 @BASEBOARD_FAB2_LIB.BASEBOARD_FAB2(SCH_1):PAGE78
   145 P12V_NVDIMM_GHJ @BASEBOARD_FAB2_LIB.BASEBOARD_FAB2(SCH_1):P12V_NVDIMM_GHJ    I75 @BASEBOARD_FAB2_LIB.BASEBOARD_FAB2(SCH_1):PAGE78
    59 PVDDQ_GHJ @BASEBOARD_FAB2_LIB.BASEBOARD_FAB2(SCH_1):PVDDQ_GHJ    I75 @BASEBOARD_FAB2_LIB.BASEBOARD_FAB2(SCH_1):PAGE78
    61 PVDDQ_GHJ @BASEBOARD_FAB2_LIB.BASEBOARD_FAB2(SCH_1):PVDDQ_GHJ    I75 @BASEBOARD_FAB2_LIB.BASEBOARD_FAB2(SCH_1):PAGE78
    64 PVDDQ_GHJ @BASEBOARD_FAB2_LIB.BASEBOARD_FAB2(SCH_1):PVDDQ_GHJ    I75 @BASEBOARD_FAB2_LIB.BASEBOARD_FAB2(SCH_1):PAGE78
    67 PVDDQ_GHJ @BASEBOARD_FAB2_LIB.BASEBOARD_FAB2(SCH_1):PVDDQ_GHJ    I75 @BASEBOARD_FAB2_LIB.BASEBOARD_FAB2(SCH_1):PAGE78
    70 PVDDQ_GHJ @BASEBOARD_FAB2_LIB.BASEBOARD_FAB2(SCH_1):PVDDQ_GHJ    I75 @BASEBOARD_FAB2_LIB.BASEBOARD_FAB2(SCH_1):PAGE78
    73 PVDDQ_GHJ @BASEBOARD_FAB2_LIB.BASEBOARD_FAB2(SCH_1):PVDDQ_GHJ    I75 @BASEBOARD_FAB2_LIB.BASEBOARD_FAB2(SCH_1):PAGE78
    76 PVDDQ_GHJ @BASEBOARD_FAB2_LIB.BASEBOARD_FAB2(SCH_1):PVDDQ_GHJ    I75 @BASEBOARD_FAB2_LIB.BASEBOARD_FAB2(SCH_1):PAGE78
    80 PVDDQ_GHJ @BASEBOARD_FAB2_LIB.BASEBOARD_FAB2(SCH_1):PVDDQ_GHJ    I75 @BASEBOARD_FAB2_LIB.BASEBOARD_FAB2(SCH_1):PAGE78
    83 PVDDQ_GHJ @BASEBOARD_FAB2_LIB.BASEBOARD_FAB2(SCH_1):PVDDQ_GHJ    I75 @BASEBOARD_FAB2_LIB.BASEBOARD_FAB2(SCH_1):PAGE78
    85 PVDDQ_GHJ @BASEBOARD_FAB2_LIB.BASEBOARD_FAB2(SCH_1):PVDDQ_GHJ    I75 @BASEBOARD_FAB2_LIB.BASEBOARD_FAB2(SCH_1):PAGE78
    88 PVDDQ_GHJ @BASEBOARD_FAB2_LIB.BASEBOARD_FAB2(SCH_1):PVDDQ_GHJ    I75 @BASEBOARD_FAB2_LIB.BASEBOARD_FAB2(SCH_1):PAGE78
    90 PVDDQ_GHJ @BASEBOARD_FAB2_LIB.BASEBOARD_FAB2(SCH_1):PVDDQ_GHJ    I75 @BASEBOARD_FAB2_LIB.BASEBOARD_FAB2(SCH_1):PAGE78
    92 PVDDQ_GHJ @BASEBOARD_FAB2_LIB.BASEBOARD_FAB2(SCH_1):PVDDQ_GHJ    I75 @BASEBOARD_FAB2_LIB.BASEBOARD_FAB2(SCH_1):PAGE78
   204 PVDDQ_GHJ @BASEBOARD_FAB2_LIB.BASEBOARD_FAB2(SCH_1):PVDDQ_GHJ    I75 @BASEBOARD_FAB2_LIB.BASEBOARD_FAB2(SCH_1):PAGE78
   206 PVDDQ_GHJ @BASEBOARD_FAB2_LIB.BASEBOARD_FAB2(SCH_1):PVDDQ_GHJ    I75 @BASEBOARD_FAB2_LIB.BASEBOARD_FAB2(SCH_1):PAGE78
   209 PVDDQ_GHJ @BASEBOARD_FAB2_LIB.BASEBOARD_FAB2(SCH_1):PVDDQ_GHJ    I75 @BASEBOARD_FAB2_LIB.BASEBOARD_FAB2(SCH_1):PAGE78
   212 PVDDQ_GHJ @BASEBOARD_FAB2_LIB.BASEBOARD_FAB2(SCH_1):PVDDQ_GHJ    I75 @BASEBOARD_FAB2_LIB.BASEBOARD_FAB2(SCH_1):PAGE78
   215 PVDDQ_GHJ @BASEBOARD_FAB2_LIB.BASEBOARD_FAB2(SCH_1):PVDDQ_GHJ    I75 @BASEBOARD_FAB2_LIB.BASEBOARD_FAB2(SCH_1):PAGE78
   217 PVDDQ_GHJ @BASEBOARD_FAB2_LIB.BASEBOARD_FAB2(SCH_1):PVDDQ_GHJ    I75 @BASEBOARD_FAB2_LIB.BASEBOARD_FAB2(SCH_1):PAGE78
   220 PVDDQ_GHJ @BASEBOARD_FAB2_LIB.BASEBOARD_FAB2(SCH_1):PVDDQ_GHJ    I75 @BASEBOARD_FAB2_LIB.BASEBOARD_FAB2(SCH_1):PAGE78
   223 PVDDQ_GHJ @BASEBOARD_FAB2_LIB.BASEBOARD_FAB2(SCH_1):PVDDQ_GHJ    I75 @BASEBOARD_FAB2_LIB.BASEBOARD_FAB2(SCH_1):PAGE78
   226 PVDDQ_GHJ @BASEBOARD_FAB2_LIB.BASEBOARD_FAB2(SCH_1):PVDDQ_GHJ    I75 @BASEBOARD_FAB2_LIB.BASEBOARD_FAB2(SCH_1):PAGE78
   229 PVDDQ_GHJ @BASEBOARD_FAB2_LIB.BASEBOARD_FAB2(SCH_1):PVDDQ_GHJ    I75 @BASEBOARD_FAB2_LIB.BASEBOARD_FAB2(SCH_1):PAGE78
   231 PVDDQ_GHJ @BASEBOARD_FAB2_LIB.BASEBOARD_FAB2(SCH_1):PVDDQ_GHJ    I75 @BASEBOARD_FAB2_LIB.BASEBOARD_FAB2(SCH_1):PAGE78
   233 PVDDQ_GHJ @BASEBOARD_FAB2_LIB.BASEBOARD_FAB2(SCH_1):PVDDQ_GHJ    I75 @BASEBOARD_FAB2_LIB.BASEBOARD_FAB2(SCH_1):PAGE78
   236 PVDDQ_GHJ @BASEBOARD_FAB2_LIB.BASEBOARD_FAB2(SCH_1):PVDDQ_GHJ    I75 @BASEBOARD_FAB2_LIB.BASEBOARD_FAB2(SCH_1):PAGE78
   142 PVPP_GHJ @BASEBOARD_FAB2_LIB.BASEBOARD_FAB2(SCH_1):PVPP_GHJ    I75 @BASEBOARD_FAB2_LIB.BASEBOARD_FAB2(SCH_1):PAGE78
   143 PVPP_GHJ @BASEBOARD_FAB2_LIB.BASEBOARD_FAB2(SCH_1):PVPP_GHJ    I75 @BASEBOARD_FAB2_LIB.BASEBOARD_FAB2(SCH_1):PAGE78
   288 PVPP_GHJ @BASEBOARD_FAB2_LIB.BASEBOARD_FAB2(SCH_1):PVPP_GHJ    I75 @BASEBOARD_FAB2_LIB.BASEBOARD_FAB2(SCH_1):PAGE78
   286 PVPP_GHJ @BASEBOARD_FAB2_LIB.BASEBOARD_FAB2(SCH_1):PVPP_GHJ    I75 @BASEBOARD_FAB2_LIB.BASEBOARD_FAB2(SCH_1):PAGE78
   287 PVPP_GHJ @BASEBOARD_FAB2_LIB.BASEBOARD_FAB2(SCH_1):PVPP_GHJ    I75 @BASEBOARD_FAB2_LIB.BASEBOARD_FAB2(SCH_1):PAGE78
    77 PVTT_GHJ @BASEBOARD_FAB2_LIB.BASEBOARD_FAB2(SCH_1):PVTT_GHJ    I75 @BASEBOARD_FAB2_LIB.BASEBOARD_FAB2(SCH_1):PAGE78
   221 PVTT_GHJ @BASEBOARD_FAB2_LIB.BASEBOARD_FAB2(SCH_1):PVTT_GHJ    I75 @BASEBOARD_FAB2_LIB.BASEBOARD_FAB2(SCH_1):PAGE78

J9U1 SCONN288_H44441003_PIP-SCONN,HA
    79 M_H_MA<0> @BASEBOARD_FAB2_LIB.BASEBOARD_FAB2(SCH_1):M_H_MA(0)    I24 @BASEBOARD_FAB2_LIB.BASEBOARD_FAB2(SCH_1):PAGE80
    72 M_H_MA<1> @BASEBOARD_FAB2_LIB.BASEBOARD_FAB2(SCH_1):M_H_MA(1)    I24 @BASEBOARD_FAB2_LIB.BASEBOARD_FAB2(SCH_1):PAGE80
   225 M_H_MA<10> @BASEBOARD_FAB2_LIB.BASEBOARD_FAB2(SCH_1):M_H_MA(10)    I24 @BASEBOARD_FAB2_LIB.BASEBOARD_FAB2(SCH_1):PAGE80
   210 M_H_MA<11> @BASEBOARD_FAB2_LIB.BASEBOARD_FAB2(SCH_1):M_H_MA(11)    I24 @BASEBOARD_FAB2_LIB.BASEBOARD_FAB2(SCH_1):PAGE80
    65 M_H_MA<12> @BASEBOARD_FAB2_LIB.BASEBOARD_FAB2(SCH_1):M_H_MA(12)    I24 @BASEBOARD_FAB2_LIB.BASEBOARD_FAB2(SCH_1):PAGE80
   232 M_H_MA<13> @BASEBOARD_FAB2_LIB.BASEBOARD_FAB2(SCH_1):M_H_MA(13)    I24 @BASEBOARD_FAB2_LIB.BASEBOARD_FAB2(SCH_1):PAGE80
   228 M_H_MA<14> @BASEBOARD_FAB2_LIB.BASEBOARD_FAB2(SCH_1):M_H_MA(14)    I24 @BASEBOARD_FAB2_LIB.BASEBOARD_FAB2(SCH_1):PAGE80
    86 M_H_MA<15> @BASEBOARD_FAB2_LIB.BASEBOARD_FAB2(SCH_1):M_H_MA(15)    I24 @BASEBOARD_FAB2_LIB.BASEBOARD_FAB2(SCH_1):PAGE80
    82 M_H_MA<16> @BASEBOARD_FAB2_LIB.BASEBOARD_FAB2(SCH_1):M_H_MA(16)    I24 @BASEBOARD_FAB2_LIB.BASEBOARD_FAB2(SCH_1):PAGE80
   234 M_H_MA<17> @BASEBOARD_FAB2_LIB.BASEBOARD_FAB2(SCH_1):M_H_MA(17)    I24 @BASEBOARD_FAB2_LIB.BASEBOARD_FAB2(SCH_1):PAGE80
   216 M_H_MA<2> @BASEBOARD_FAB2_LIB.BASEBOARD_FAB2(SCH_1):M_H_MA(2)    I24 @BASEBOARD_FAB2_LIB.BASEBOARD_FAB2(SCH_1):PAGE80
    71 M_H_MA<3> @BASEBOARD_FAB2_LIB.BASEBOARD_FAB2(SCH_1):M_H_MA(3)    I24 @BASEBOARD_FAB2_LIB.BASEBOARD_FAB2(SCH_1):PAGE80
   214 M_H_MA<4> @BASEBOARD_FAB2_LIB.BASEBOARD_FAB2(SCH_1):M_H_MA(4)    I24 @BASEBOARD_FAB2_LIB.BASEBOARD_FAB2(SCH_1):PAGE80
   213 M_H_MA<5> @BASEBOARD_FAB2_LIB.BASEBOARD_FAB2(SCH_1):M_H_MA(5)    I24 @BASEBOARD_FAB2_LIB.BASEBOARD_FAB2(SCH_1):PAGE80
    69 M_H_MA<6> @BASEBOARD_FAB2_LIB.BASEBOARD_FAB2(SCH_1):M_H_MA(6)    I24 @BASEBOARD_FAB2_LIB.BASEBOARD_FAB2(SCH_1):PAGE80
   211 M_H_MA<7> @BASEBOARD_FAB2_LIB.BASEBOARD_FAB2(SCH_1):M_H_MA(7)    I24 @BASEBOARD_FAB2_LIB.BASEBOARD_FAB2(SCH_1):PAGE80
    68 M_H_MA<8> @BASEBOARD_FAB2_LIB.BASEBOARD_FAB2(SCH_1):M_H_MA(8)    I24 @BASEBOARD_FAB2_LIB.BASEBOARD_FAB2(SCH_1):PAGE80
    66 M_H_MA<9> @BASEBOARD_FAB2_LIB.BASEBOARD_FAB2(SCH_1):M_H_MA(9)    I24 @BASEBOARD_FAB2_LIB.BASEBOARD_FAB2(SCH_1):PAGE80
    62 M_H_ACT_N @BASEBOARD_FAB2_LIB.BASEBOARD_FAB2(SCH_1):M_H_ACT_N    I24 @BASEBOARD_FAB2_LIB.BASEBOARD_FAB2(SCH_1):PAGE80
   208 M_H_ALERT_N @BASEBOARD_FAB2_LIB.BASEBOARD_FAB2(SCH_1):M_H_ALERT_N    I24 @BASEBOARD_FAB2_LIB.BASEBOARD_FAB2(SCH_1):PAGE80
   224 M_H_BA<1> @BASEBOARD_FAB2_LIB.BASEBOARD_FAB2(SCH_1):M_H_BA(1)    I24 @BASEBOARD_FAB2_LIB.BASEBOARD_FAB2(SCH_1):PAGE80
    81 M_H_BA<0> @BASEBOARD_FAB2_LIB.BASEBOARD_FAB2(SCH_1):M_H_BA(0)    I24 @BASEBOARD_FAB2_LIB.BASEBOARD_FAB2(SCH_1):PAGE80
   207 M_H_BG<1> @BASEBOARD_FAB2_LIB.BASEBOARD_FAB2(SCH_1):M_H_BG(1)    I24 @BASEBOARD_FAB2_LIB.BASEBOARD_FAB2(SCH_1):PAGE80
    63 M_H_BG<0> @BASEBOARD_FAB2_LIB.BASEBOARD_FAB2(SCH_1):M_H_BG(0)    I24 @BASEBOARD_FAB2_LIB.BASEBOARD_FAB2(SCH_1):PAGE80
   235 M_H_C<2> @BASEBOARD_FAB2_LIB.BASEBOARD_FAB2(SCH_1):M_H_C(2)    I24 @BASEBOARD_FAB2_LIB.BASEBOARD_FAB2(SCH_1):PAGE80
   199 M_H_ECC<7> @BASEBOARD_FAB2_LIB.BASEBOARD_FAB2(SCH_1):M_H_ECC(7)    I24 @BASEBOARD_FAB2_LIB.BASEBOARD_FAB2(SCH_1):PAGE80
    54 M_H_ECC<6> @BASEBOARD_FAB2_LIB.BASEBOARD_FAB2(SCH_1):M_H_ECC(6)    I24 @BASEBOARD_FAB2_LIB.BASEBOARD_FAB2(SCH_1):PAGE80
   192 M_H_ECC<5> @BASEBOARD_FAB2_LIB.BASEBOARD_FAB2(SCH_1):M_H_ECC(5)    I24 @BASEBOARD_FAB2_LIB.BASEBOARD_FAB2(SCH_1):PAGE80
    47 M_H_ECC<4> @BASEBOARD_FAB2_LIB.BASEBOARD_FAB2(SCH_1):M_H_ECC(4)    I24 @BASEBOARD_FAB2_LIB.BASEBOARD_FAB2(SCH_1):PAGE80
   201 M_H_ECC<3> @BASEBOARD_FAB2_LIB.BASEBOARD_FAB2(SCH_1):M_H_ECC(3)    I24 @BASEBOARD_FAB2_LIB.BASEBOARD_FAB2(SCH_1):PAGE80
    56 M_H_ECC<2> @BASEBOARD_FAB2_LIB.BASEBOARD_FAB2(SCH_1):M_H_ECC(2)    I24 @BASEBOARD_FAB2_LIB.BASEBOARD_FAB2(SCH_1):PAGE80
   194 M_H_ECC<1> @BASEBOARD_FAB2_LIB.BASEBOARD_FAB2(SCH_1):M_H_ECC(1)    I24 @BASEBOARD_FAB2_LIB.BASEBOARD_FAB2(SCH_1):PAGE80
    49 M_H_ECC<0> @BASEBOARD_FAB2_LIB.BASEBOARD_FAB2(SCH_1):M_H_ECC(0)    I24 @BASEBOARD_FAB2_LIB.BASEBOARD_FAB2(SCH_1):PAGE80
    75 M_H_CLK_DN<2> @BASEBOARD_FAB2_LIB.BASEBOARD_FAB2(SCH_1):M_H_CLK_DN(2)    I24 @BASEBOARD_FAB2_LIB.BASEBOARD_FAB2(SCH_1):PAGE80
    74 M_H_CLK_DP<2> @BASEBOARD_FAB2_LIB.BASEBOARD_FAB2(SCH_1):M_H_CLK_DP(2)    I24 @BASEBOARD_FAB2_LIB.BASEBOARD_FAB2(SCH_1):PAGE80
   219 M_H_CLK_DN<3> @BASEBOARD_FAB2_LIB.BASEBOARD_FAB2(SCH_1):M_H_CLK_DN(3)    I24 @BASEBOARD_FAB2_LIB.BASEBOARD_FAB2(SCH_1):PAGE80
   218 M_H_CLK_DP<3> @BASEBOARD_FAB2_LIB.BASEBOARD_FAB2(SCH_1):M_H_CLK_DP(3)    I24 @BASEBOARD_FAB2_LIB.BASEBOARD_FAB2(SCH_1):PAGE80
   203 M_H_CKE<3> @BASEBOARD_FAB2_LIB.BASEBOARD_FAB2(SCH_1):M_H_CKE(3)    I24 @BASEBOARD_FAB2_LIB.BASEBOARD_FAB2(SCH_1):PAGE80
    60 M_H_CKE<2> @BASEBOARD_FAB2_LIB.BASEBOARD_FAB2(SCH_1):M_H_CKE(2)    I24 @BASEBOARD_FAB2_LIB.BASEBOARD_FAB2(SCH_1):PAGE80
   280 M_H_DQ<63> @BASEBOARD_FAB2_LIB.BASEBOARD_FAB2(SCH_1):M_H_DQ(63)    I24 @BASEBOARD_FAB2_LIB.BASEBOARD_FAB2(SCH_1):PAGE80
   135 M_H_DQ<62> @BASEBOARD_FAB2_LIB.BASEBOARD_FAB2(SCH_1):M_H_DQ(62)    I24 @BASEBOARD_FAB2_LIB.BASEBOARD_FAB2(SCH_1):PAGE80
   273 M_H_DQ<61> @BASEBOARD_FAB2_LIB.BASEBOARD_FAB2(SCH_1):M_H_DQ(61)    I24 @BASEBOARD_FAB2_LIB.BASEBOARD_FAB2(SCH_1):PAGE80
   128 M_H_DQ<60> @BASEBOARD_FAB2_LIB.BASEBOARD_FAB2(SCH_1):M_H_DQ(60)    I24 @BASEBOARD_FAB2_LIB.BASEBOARD_FAB2(SCH_1):PAGE80
   282 M_H_DQ<59> @BASEBOARD_FAB2_LIB.BASEBOARD_FAB2(SCH_1):M_H_DQ(59)    I24 @BASEBOARD_FAB2_LIB.BASEBOARD_FAB2(SCH_1):PAGE80
   137 M_H_DQ<58> @BASEBOARD_FAB2_LIB.BASEBOARD_FAB2(SCH_1):M_H_DQ(58)    I24 @BASEBOARD_FAB2_LIB.BASEBOARD_FAB2(SCH_1):PAGE80
   275 M_H_DQ<57> @BASEBOARD_FAB2_LIB.BASEBOARD_FAB2(SCH_1):M_H_DQ(57)    I24 @BASEBOARD_FAB2_LIB.BASEBOARD_FAB2(SCH_1):PAGE80
   130 M_H_DQ<56> @BASEBOARD_FAB2_LIB.BASEBOARD_FAB2(SCH_1):M_H_DQ(56)    I24 @BASEBOARD_FAB2_LIB.BASEBOARD_FAB2(SCH_1):PAGE80
   269 M_H_DQ<55> @BASEBOARD_FAB2_LIB.BASEBOARD_FAB2(SCH_1):M_H_DQ(55)    I24 @BASEBOARD_FAB2_LIB.BASEBOARD_FAB2(SCH_1):PAGE80
   124 M_H_DQ<54> @BASEBOARD_FAB2_LIB.BASEBOARD_FAB2(SCH_1):M_H_DQ(54)    I24 @BASEBOARD_FAB2_LIB.BASEBOARD_FAB2(SCH_1):PAGE80
   262 M_H_DQ<53> @BASEBOARD_FAB2_LIB.BASEBOARD_FAB2(SCH_1):M_H_DQ(53)    I24 @BASEBOARD_FAB2_LIB.BASEBOARD_FAB2(SCH_1):PAGE80
   117 M_H_DQ<52> @BASEBOARD_FAB2_LIB.BASEBOARD_FAB2(SCH_1):M_H_DQ(52)    I24 @BASEBOARD_FAB2_LIB.BASEBOARD_FAB2(SCH_1):PAGE80
   271 M_H_DQ<51> @BASEBOARD_FAB2_LIB.BASEBOARD_FAB2(SCH_1):M_H_DQ(51)    I24 @BASEBOARD_FAB2_LIB.BASEBOARD_FAB2(SCH_1):PAGE80
   126 M_H_DQ<50> @BASEBOARD_FAB2_LIB.BASEBOARD_FAB2(SCH_1):M_H_DQ(50)    I24 @BASEBOARD_FAB2_LIB.BASEBOARD_FAB2(SCH_1):PAGE80
   264 M_H_DQ<49> @BASEBOARD_FAB2_LIB.BASEBOARD_FAB2(SCH_1):M_H_DQ(49)    I24 @BASEBOARD_FAB2_LIB.BASEBOARD_FAB2(SCH_1):PAGE80
   119 M_H_DQ<48> @BASEBOARD_FAB2_LIB.BASEBOARD_FAB2(SCH_1):M_H_DQ(48)    I24 @BASEBOARD_FAB2_LIB.BASEBOARD_FAB2(SCH_1):PAGE80
   258 M_H_DQ<47> @BASEBOARD_FAB2_LIB.BASEBOARD_FAB2(SCH_1):M_H_DQ(47)    I24 @BASEBOARD_FAB2_LIB.BASEBOARD_FAB2(SCH_1):PAGE80
   113 M_H_DQ<46> @BASEBOARD_FAB2_LIB.BASEBOARD_FAB2(SCH_1):M_H_DQ(46)    I24 @BASEBOARD_FAB2_LIB.BASEBOARD_FAB2(SCH_1):PAGE80
   251 M_H_DQ<45> @BASEBOARD_FAB2_LIB.BASEBOARD_FAB2(SCH_1):M_H_DQ(45)    I24 @BASEBOARD_FAB2_LIB.BASEBOARD_FAB2(SCH_1):PAGE80
   106 M_H_DQ<44> @BASEBOARD_FAB2_LIB.BASEBOARD_FAB2(SCH_1):M_H_DQ(44)    I24 @BASEBOARD_FAB2_LIB.BASEBOARD_FAB2(SCH_1):PAGE80
   260 M_H_DQ<43> @BASEBOARD_FAB2_LIB.BASEBOARD_FAB2(SCH_1):M_H_DQ(43)    I24 @BASEBOARD_FAB2_LIB.BASEBOARD_FAB2(SCH_1):PAGE80
   115 M_H_DQ<42> @BASEBOARD_FAB2_LIB.BASEBOARD_FAB2(SCH_1):M_H_DQ(42)    I24 @BASEBOARD_FAB2_LIB.BASEBOARD_FAB2(SCH_1):PAGE80
   253 M_H_DQ<41> @BASEBOARD_FAB2_LIB.BASEBOARD_FAB2(SCH_1):M_H_DQ(41)    I24 @BASEBOARD_FAB2_LIB.BASEBOARD_FAB2(SCH_1):PAGE80
   108 M_H_DQ<40> @BASEBOARD_FAB2_LIB.BASEBOARD_FAB2(SCH_1):M_H_DQ(40)    I24 @BASEBOARD_FAB2_LIB.BASEBOARD_FAB2(SCH_1):PAGE80
   247 M_H_DQ<39> @BASEBOARD_FAB2_LIB.BASEBOARD_FAB2(SCH_1):M_H_DQ(39)    I24 @BASEBOARD_FAB2_LIB.BASEBOARD_FAB2(SCH_1):PAGE80
   102 M_H_DQ<38> @BASEBOARD_FAB2_LIB.BASEBOARD_FAB2(SCH_1):M_H_DQ(38)    I24 @BASEBOARD_FAB2_LIB.BASEBOARD_FAB2(SCH_1):PAGE80
   240 M_H_DQ<37> @BASEBOARD_FAB2_LIB.BASEBOARD_FAB2(SCH_1):M_H_DQ(37)    I24 @BASEBOARD_FAB2_LIB.BASEBOARD_FAB2(SCH_1):PAGE80
    95 M_H_DQ<36> @BASEBOARD_FAB2_LIB.BASEBOARD_FAB2(SCH_1):M_H_DQ(36)    I24 @BASEBOARD_FAB2_LIB.BASEBOARD_FAB2(SCH_1):PAGE80
   249 M_H_DQ<35> @BASEBOARD_FAB2_LIB.BASEBOARD_FAB2(SCH_1):M_H_DQ(35)    I24 @BASEBOARD_FAB2_LIB.BASEBOARD_FAB2(SCH_1):PAGE80
   104 M_H_DQ<34> @BASEBOARD_FAB2_LIB.BASEBOARD_FAB2(SCH_1):M_H_DQ(34)    I24 @BASEBOARD_FAB2_LIB.BASEBOARD_FAB2(SCH_1):PAGE80
   242 M_H_DQ<33> @BASEBOARD_FAB2_LIB.BASEBOARD_FAB2(SCH_1):M_H_DQ(33)    I24 @BASEBOARD_FAB2_LIB.BASEBOARD_FAB2(SCH_1):PAGE80
    97 M_H_DQ<32> @BASEBOARD_FAB2_LIB.BASEBOARD_FAB2(SCH_1):M_H_DQ(32)    I24 @BASEBOARD_FAB2_LIB.BASEBOARD_FAB2(SCH_1):PAGE80
   188 M_H_DQ<31> @BASEBOARD_FAB2_LIB.BASEBOARD_FAB2(SCH_1):M_H_DQ(31)    I24 @BASEBOARD_FAB2_LIB.BASEBOARD_FAB2(SCH_1):PAGE80
    43 M_H_DQ<30> @BASEBOARD_FAB2_LIB.BASEBOARD_FAB2(SCH_1):M_H_DQ(30)    I24 @BASEBOARD_FAB2_LIB.BASEBOARD_FAB2(SCH_1):PAGE80
   181 M_H_DQ<29> @BASEBOARD_FAB2_LIB.BASEBOARD_FAB2(SCH_1):M_H_DQ(29)    I24 @BASEBOARD_FAB2_LIB.BASEBOARD_FAB2(SCH_1):PAGE80
    36 M_H_DQ<28> @BASEBOARD_FAB2_LIB.BASEBOARD_FAB2(SCH_1):M_H_DQ(28)    I24 @BASEBOARD_FAB2_LIB.BASEBOARD_FAB2(SCH_1):PAGE80
   190 M_H_DQ<27> @BASEBOARD_FAB2_LIB.BASEBOARD_FAB2(SCH_1):M_H_DQ(27)    I24 @BASEBOARD_FAB2_LIB.BASEBOARD_FAB2(SCH_1):PAGE80
    45 M_H_DQ<26> @BASEBOARD_FAB2_LIB.BASEBOARD_FAB2(SCH_1):M_H_DQ(26)    I24 @BASEBOARD_FAB2_LIB.BASEBOARD_FAB2(SCH_1):PAGE80
   183 M_H_DQ<25> @BASEBOARD_FAB2_LIB.BASEBOARD_FAB2(SCH_1):M_H_DQ(25)    I24 @BASEBOARD_FAB2_LIB.BASEBOARD_FAB2(SCH_1):PAGE80
    38 M_H_DQ<24> @BASEBOARD_FAB2_LIB.BASEBOARD_FAB2(SCH_1):M_H_DQ(24)    I24 @BASEBOARD_FAB2_LIB.BASEBOARD_FAB2(SCH_1):PAGE80
   177 M_H_DQ<23> @BASEBOARD_FAB2_LIB.BASEBOARD_FAB2(SCH_1):M_H_DQ(23)    I24 @BASEBOARD_FAB2_LIB.BASEBOARD_FAB2(SCH_1):PAGE80
    32 M_H_DQ<22> @BASEBOARD_FAB2_LIB.BASEBOARD_FAB2(SCH_1):M_H_DQ(22)    I24 @BASEBOARD_FAB2_LIB.BASEBOARD_FAB2(SCH_1):PAGE80
   170 M_H_DQ<21> @BASEBOARD_FAB2_LIB.BASEBOARD_FAB2(SCH_1):M_H_DQ(21)    I24 @BASEBOARD_FAB2_LIB.BASEBOARD_FAB2(SCH_1):PAGE80
    25 M_H_DQ<20> @BASEBOARD_FAB2_LIB.BASEBOARD_FAB2(SCH_1):M_H_DQ(20)    I24 @BASEBOARD_FAB2_LIB.BASEBOARD_FAB2(SCH_1):PAGE80
   179 M_H_DQ<19> @BASEBOARD_FAB2_LIB.BASEBOARD_FAB2(SCH_1):M_H_DQ(19)    I24 @BASEBOARD_FAB2_LIB.BASEBOARD_FAB2(SCH_1):PAGE80
    34 M_H_DQ<18> @BASEBOARD_FAB2_LIB.BASEBOARD_FAB2(SCH_1):M_H_DQ(18)    I24 @BASEBOARD_FAB2_LIB.BASEBOARD_FAB2(SCH_1):PAGE80
   172 M_H_DQ<17> @BASEBOARD_FAB2_LIB.BASEBOARD_FAB2(SCH_1):M_H_DQ(17)    I24 @BASEBOARD_FAB2_LIB.BASEBOARD_FAB2(SCH_1):PAGE80
    27 M_H_DQ<16> @BASEBOARD_FAB2_LIB.BASEBOARD_FAB2(SCH_1):M_H_DQ(16)    I24 @BASEBOARD_FAB2_LIB.BASEBOARD_FAB2(SCH_1):PAGE80
   166 M_H_DQ<15> @BASEBOARD_FAB2_LIB.BASEBOARD_FAB2(SCH_1):M_H_DQ(15)    I24 @BASEBOARD_FAB2_LIB.BASEBOARD_FAB2(SCH_1):PAGE80
    21 M_H_DQ<14> @BASEBOARD_FAB2_LIB.BASEBOARD_FAB2(SCH_1):M_H_DQ(14)    I24 @BASEBOARD_FAB2_LIB.BASEBOARD_FAB2(SCH_1):PAGE80
   159 M_H_DQ<13> @BASEBOARD_FAB2_LIB.BASEBOARD_FAB2(SCH_1):M_H_DQ(13)    I24 @BASEBOARD_FAB2_LIB.BASEBOARD_FAB2(SCH_1):PAGE80
    14 M_H_DQ<12> @BASEBOARD_FAB2_LIB.BASEBOARD_FAB2(SCH_1):M_H_DQ(12)    I24 @BASEBOARD_FAB2_LIB.BASEBOARD_FAB2(SCH_1):PAGE80
   168 M_H_DQ<11> @BASEBOARD_FAB2_LIB.BASEBOARD_FAB2(SCH_1):M_H_DQ(11)    I24 @BASEBOARD_FAB2_LIB.BASEBOARD_FAB2(SCH_1):PAGE80
    23 M_H_DQ<10> @BASEBOARD_FAB2_LIB.BASEBOARD_FAB2(SCH_1):M_H_DQ(10)    I24 @BASEBOARD_FAB2_LIB.BASEBOARD_FAB2(SCH_1):PAGE80
   161 M_H_DQ<9> @BASEBOARD_FAB2_LIB.BASEBOARD_FAB2(SCH_1):M_H_DQ(9)    I24 @BASEBOARD_FAB2_LIB.BASEBOARD_FAB2(SCH_1):PAGE80
    16 M_H_DQ<8> @BASEBOARD_FAB2_LIB.BASEBOARD_FAB2(SCH_1):M_H_DQ(8)    I24 @BASEBOARD_FAB2_LIB.BASEBOARD_FAB2(SCH_1):PAGE80
   155 M_H_DQ<7> @BASEBOARD_FAB2_LIB.BASEBOARD_FAB2(SCH_1):M_H_DQ(7)    I24 @BASEBOARD_FAB2_LIB.BASEBOARD_FAB2(SCH_1):PAGE80
    10 M_H_DQ<6> @BASEBOARD_FAB2_LIB.BASEBOARD_FAB2(SCH_1):M_H_DQ(6)    I24 @BASEBOARD_FAB2_LIB.BASEBOARD_FAB2(SCH_1):PAGE80
   148 M_H_DQ<5> @BASEBOARD_FAB2_LIB.BASEBOARD_FAB2(SCH_1):M_H_DQ(5)    I24 @BASEBOARD_FAB2_LIB.BASEBOARD_FAB2(SCH_1):PAGE80
     3 M_H_DQ<4> @BASEBOARD_FAB2_LIB.BASEBOARD_FAB2(SCH_1):M_H_DQ(4)    I24 @BASEBOARD_FAB2_LIB.BASEBOARD_FAB2(SCH_1):PAGE80
   157 M_H_DQ<3> @BASEBOARD_FAB2_LIB.BASEBOARD_FAB2(SCH_1):M_H_DQ(3)    I24 @BASEBOARD_FAB2_LIB.BASEBOARD_FAB2(SCH_1):PAGE80
    12 M_H_DQ<2> @BASEBOARD_FAB2_LIB.BASEBOARD_FAB2(SCH_1):M_H_DQ(2)    I24 @BASEBOARD_FAB2_LIB.BASEBOARD_FAB2(SCH_1):PAGE80
   150 M_H_DQ<1> @BASEBOARD_FAB2_LIB.BASEBOARD_FAB2(SCH_1):M_H_DQ(1)    I24 @BASEBOARD_FAB2_LIB.BASEBOARD_FAB2(SCH_1):PAGE80
     5 M_H_DQ<0> @BASEBOARD_FAB2_LIB.BASEBOARD_FAB2(SCH_1):M_H_DQ(0)    I24 @BASEBOARD_FAB2_LIB.BASEBOARD_FAB2(SCH_1):PAGE80
    78 FM_DIMM_EVENT_COD_N @BASEBOARD_FAB2_LIB.BASEBOARD_FAB2(SCH_1):FM_DIMM_EVENT_COD_N    I24 @BASEBOARD_FAB2_LIB.BASEBOARD_FAB2(SCH_1):PAGE80
    91 M_H_ODT<3> @BASEBOARD_FAB2_LIB.BASEBOARD_FAB2(SCH_1):M_H_ODT(3)    I24 @BASEBOARD_FAB2_LIB.BASEBOARD_FAB2(SCH_1):PAGE80
    87 M_H_ODT<2> @BASEBOARD_FAB2_LIB.BASEBOARD_FAB2(SCH_1):M_H_ODT(2)    I24 @BASEBOARD_FAB2_LIB.BASEBOARD_FAB2(SCH_1):PAGE80
   222 M_H_PAR @BASEBOARD_FAB2_LIB.BASEBOARD_FAB2(SCH_1):M_H_PAR    I24 @BASEBOARD_FAB2_LIB.BASEBOARD_FAB2(SCH_1):PAGE80
    58 M_GHJ_RST_N @BASEBOARD_FAB2_LIB.BASEBOARD_FAB2(SCH_1):M_GHJ_RST_N    I24 @BASEBOARD_FAB2_LIB.BASEBOARD_FAB2(SCH_1):PAGE80
   144 TP_CH_H_DIMM0_RFU_2 @BASEBOARD_FAB2_LIB.BASEBOARD_FAB2(SCH_1):TP_CH_H_DIMM0_RFU_2    I24 @BASEBOARD_FAB2_LIB.BASEBOARD_FAB2(SCH_1):PAGE80
   227 TP_CH_H_DIMM0_RFU_1 @BASEBOARD_FAB2_LIB.BASEBOARD_FAB2(SCH_1):TP_CH_H_DIMM0_RFU_1    I24 @BASEBOARD_FAB2_LIB.BASEBOARD_FAB2(SCH_1):PAGE80
   205 TP_CH_H_DIMM0_RFU_0 @BASEBOARD_FAB2_LIB.BASEBOARD_FAB2(SCH_1):TP_CH_H_DIMM0_RFU_0    I24 @BASEBOARD_FAB2_LIB.BASEBOARD_FAB2(SCH_1):PAGE80
    84 M_H_CS_N<4> @BASEBOARD_FAB2_LIB.BASEBOARD_FAB2(SCH_1):M_H_CS_N(4)    I24 @BASEBOARD_FAB2_LIB.BASEBOARD_FAB2(SCH_1):PAGE80
    89 M_H_CS_N<5> @BASEBOARD_FAB2_LIB.BASEBOARD_FAB2(SCH_1):M_H_CS_N(5)    I24 @BASEBOARD_FAB2_LIB.BASEBOARD_FAB2(SCH_1):PAGE80
    93 M_H_CS_N<6> @BASEBOARD_FAB2_LIB.BASEBOARD_FAB2(SCH_1):M_H_CS_N(6)    I24 @BASEBOARD_FAB2_LIB.BASEBOARD_FAB2(SCH_1):PAGE80
   237 M_H_CS_N<7> @BASEBOARD_FAB2_LIB.BASEBOARD_FAB2(SCH_1):M_H_CS_N(7)    I24 @BASEBOARD_FAB2_LIB.BASEBOARD_FAB2(SCH_1):PAGE80
   238    GND @BASEBOARD_FAB2_LIB.BASEBOARD_FAB2(SCH_1):GND    I24 @BASEBOARD_FAB2_LIB.BASEBOARD_FAB2(SCH_1):PAGE80
   140 PVPP_GHJ @BASEBOARD_FAB2_LIB.BASEBOARD_FAB2(SCH_1):PVPP_GHJ    I24 @BASEBOARD_FAB2_LIB.BASEBOARD_FAB2(SCH_1):PAGE80
   139 PVPP_GHJ @BASEBOARD_FAB2_LIB.BASEBOARD_FAB2(SCH_1):PVPP_GHJ    I24 @BASEBOARD_FAB2_LIB.BASEBOARD_FAB2(SCH_1):PAGE80
   230 FM_ADR_COMPLETE_GHJ_N @BASEBOARD_FAB2_LIB.BASEBOARD_FAB2(SCH_1):FM_ADR_COMPLETE_GHJ_N    I24 @BASEBOARD_FAB2_LIB.BASEBOARD_FAB2(SCH_1):PAGE80
   141 SMB_DDR_GHJ_VPP_SCL @BASEBOARD_FAB2_LIB.BASEBOARD_FAB2(SCH_1):SMB_DDR_GHJ_VPP_SCL    I24 @BASEBOARD_FAB2_LIB.BASEBOARD_FAB2(SCH_1):PAGE80
   285 SMB_DDR_GHJ_VPP_SDA @BASEBOARD_FAB2_LIB.BASEBOARD_FAB2(SCH_1):SMB_DDR_GHJ_VPP_SDA    I24 @BASEBOARD_FAB2_LIB.BASEBOARD_FAB2(SCH_1):PAGE80
   284 PVPP_GHJ @BASEBOARD_FAB2_LIB.BASEBOARD_FAB2(SCH_1):PVPP_GHJ    I24 @BASEBOARD_FAB2_LIB.BASEBOARD_FAB2(SCH_1):PAGE80
   146 M_H_VREF @BASEBOARD_FAB2_LIB.BASEBOARD_FAB2(SCH_1):M_H_VREF    I24 @BASEBOARD_FAB2_LIB.BASEBOARD_FAB2(SCH_1):PAGE80
   152 M_H_DQS_DN<0> @BASEBOARD_FAB2_LIB.BASEBOARD_FAB2(SCH_1):M_H_DQS_DN(0)   I101 @BASEBOARD_FAB2_LIB.BASEBOARD_FAB2(SCH_1):PAGE80
   153 M_H_DQS_DP<0> @BASEBOARD_FAB2_LIB.BASEBOARD_FAB2(SCH_1):M_H_DQS_DP(0)   I101 @BASEBOARD_FAB2_LIB.BASEBOARD_FAB2(SCH_1):PAGE80
    19 M_H_DQS_DN<10> @BASEBOARD_FAB2_LIB.BASEBOARD_FAB2(SCH_1):M_H_DQS_DN(10)   I101 @BASEBOARD_FAB2_LIB.BASEBOARD_FAB2(SCH_1):PAGE80
    18 M_H_DQS_DP<10> @BASEBOARD_FAB2_LIB.BASEBOARD_FAB2(SCH_1):M_H_DQS_DP(10)   I101 @BASEBOARD_FAB2_LIB.BASEBOARD_FAB2(SCH_1):PAGE80
    30 M_H_DQS_DN<11> @BASEBOARD_FAB2_LIB.BASEBOARD_FAB2(SCH_1):M_H_DQS_DN(11)   I101 @BASEBOARD_FAB2_LIB.BASEBOARD_FAB2(SCH_1):PAGE80
    29 M_H_DQS_DP<11> @BASEBOARD_FAB2_LIB.BASEBOARD_FAB2(SCH_1):M_H_DQS_DP(11)   I101 @BASEBOARD_FAB2_LIB.BASEBOARD_FAB2(SCH_1):PAGE80
    41 M_H_DQS_DN<12> @BASEBOARD_FAB2_LIB.BASEBOARD_FAB2(SCH_1):M_H_DQS_DN(12)   I101 @BASEBOARD_FAB2_LIB.BASEBOARD_FAB2(SCH_1):PAGE80
    40 M_H_DQS_DP<12> @BASEBOARD_FAB2_LIB.BASEBOARD_FAB2(SCH_1):M_H_DQS_DP(12)   I101 @BASEBOARD_FAB2_LIB.BASEBOARD_FAB2(SCH_1):PAGE80
   100 M_H_DQS_DN<13> @BASEBOARD_FAB2_LIB.BASEBOARD_FAB2(SCH_1):M_H_DQS_DN(13)   I101 @BASEBOARD_FAB2_LIB.BASEBOARD_FAB2(SCH_1):PAGE80
    99 M_H_DQS_DP<13> @BASEBOARD_FAB2_LIB.BASEBOARD_FAB2(SCH_1):M_H_DQS_DP(13)   I101 @BASEBOARD_FAB2_LIB.BASEBOARD_FAB2(SCH_1):PAGE80
   111 M_H_DQS_DN<14> @BASEBOARD_FAB2_LIB.BASEBOARD_FAB2(SCH_1):M_H_DQS_DN(14)   I101 @BASEBOARD_FAB2_LIB.BASEBOARD_FAB2(SCH_1):PAGE80
   110 M_H_DQS_DP<14> @BASEBOARD_FAB2_LIB.BASEBOARD_FAB2(SCH_1):M_H_DQS_DP(14)   I101 @BASEBOARD_FAB2_LIB.BASEBOARD_FAB2(SCH_1):PAGE80
   122 M_H_DQS_DN<15> @BASEBOARD_FAB2_LIB.BASEBOARD_FAB2(SCH_1):M_H_DQS_DN(15)   I101 @BASEBOARD_FAB2_LIB.BASEBOARD_FAB2(SCH_1):PAGE80
   121 M_H_DQS_DP<15> @BASEBOARD_FAB2_LIB.BASEBOARD_FAB2(SCH_1):M_H_DQS_DP(15)   I101 @BASEBOARD_FAB2_LIB.BASEBOARD_FAB2(SCH_1):PAGE80
   133 M_H_DQS_DN<16> @BASEBOARD_FAB2_LIB.BASEBOARD_FAB2(SCH_1):M_H_DQS_DN(16)   I101 @BASEBOARD_FAB2_LIB.BASEBOARD_FAB2(SCH_1):PAGE80
   132 M_H_DQS_DP<16> @BASEBOARD_FAB2_LIB.BASEBOARD_FAB2(SCH_1):M_H_DQS_DP(16)   I101 @BASEBOARD_FAB2_LIB.BASEBOARD_FAB2(SCH_1):PAGE80
    52 M_H_DQS_DN<17> @BASEBOARD_FAB2_LIB.BASEBOARD_FAB2(SCH_1):M_H_DQS_DN(17)   I101 @BASEBOARD_FAB2_LIB.BASEBOARD_FAB2(SCH_1):PAGE80
    51 M_H_DQS_DP<17> @BASEBOARD_FAB2_LIB.BASEBOARD_FAB2(SCH_1):M_H_DQS_DP(17)   I101 @BASEBOARD_FAB2_LIB.BASEBOARD_FAB2(SCH_1):PAGE80
   163 M_H_DQS_DN<1> @BASEBOARD_FAB2_LIB.BASEBOARD_FAB2(SCH_1):M_H_DQS_DN(1)   I101 @BASEBOARD_FAB2_LIB.BASEBOARD_FAB2(SCH_1):PAGE80
   164 M_H_DQS_DP<1> @BASEBOARD_FAB2_LIB.BASEBOARD_FAB2(SCH_1):M_H_DQS_DP(1)   I101 @BASEBOARD_FAB2_LIB.BASEBOARD_FAB2(SCH_1):PAGE80
   174 M_H_DQS_DN<2> @BASEBOARD_FAB2_LIB.BASEBOARD_FAB2(SCH_1):M_H_DQS_DN(2)   I101 @BASEBOARD_FAB2_LIB.BASEBOARD_FAB2(SCH_1):PAGE80
   175 M_H_DQS_DP<2> @BASEBOARD_FAB2_LIB.BASEBOARD_FAB2(SCH_1):M_H_DQS_DP(2)   I101 @BASEBOARD_FAB2_LIB.BASEBOARD_FAB2(SCH_1):PAGE80
   185 M_H_DQS_DN<3> @BASEBOARD_FAB2_LIB.BASEBOARD_FAB2(SCH_1):M_H_DQS_DN(3)   I101 @BASEBOARD_FAB2_LIB.BASEBOARD_FAB2(SCH_1):PAGE80
   186 M_H_DQS_DP<3> @BASEBOARD_FAB2_LIB.BASEBOARD_FAB2(SCH_1):M_H_DQS_DP(3)   I101 @BASEBOARD_FAB2_LIB.BASEBOARD_FAB2(SCH_1):PAGE80
   244 M_H_DQS_DN<4> @BASEBOARD_FAB2_LIB.BASEBOARD_FAB2(SCH_1):M_H_DQS_DN(4)   I101 @BASEBOARD_FAB2_LIB.BASEBOARD_FAB2(SCH_1):PAGE80
   245 M_H_DQS_DP<4> @BASEBOARD_FAB2_LIB.BASEBOARD_FAB2(SCH_1):M_H_DQS_DP(4)   I101 @BASEBOARD_FAB2_LIB.BASEBOARD_FAB2(SCH_1):PAGE80
   255 M_H_DQS_DN<5> @BASEBOARD_FAB2_LIB.BASEBOARD_FAB2(SCH_1):M_H_DQS_DN(5)   I101 @BASEBOARD_FAB2_LIB.BASEBOARD_FAB2(SCH_1):PAGE80
   256 M_H_DQS_DP<5> @BASEBOARD_FAB2_LIB.BASEBOARD_FAB2(SCH_1):M_H_DQS_DP(5)   I101 @BASEBOARD_FAB2_LIB.BASEBOARD_FAB2(SCH_1):PAGE80
   266 M_H_DQS_DN<6> @BASEBOARD_FAB2_LIB.BASEBOARD_FAB2(SCH_1):M_H_DQS_DN(6)   I101 @BASEBOARD_FAB2_LIB.BASEBOARD_FAB2(SCH_1):PAGE80
   267 M_H_DQS_DP<6> @BASEBOARD_FAB2_LIB.BASEBOARD_FAB2(SCH_1):M_H_DQS_DP(6)   I101 @BASEBOARD_FAB2_LIB.BASEBOARD_FAB2(SCH_1):PAGE80
   277 M_H_DQS_DN<7> @BASEBOARD_FAB2_LIB.BASEBOARD_FAB2(SCH_1):M_H_DQS_DN(7)   I101 @BASEBOARD_FAB2_LIB.BASEBOARD_FAB2(SCH_1):PAGE80
   278 M_H_DQS_DP<7> @BASEBOARD_FAB2_LIB.BASEBOARD_FAB2(SCH_1):M_H_DQS_DP(7)   I101 @BASEBOARD_FAB2_LIB.BASEBOARD_FAB2(SCH_1):PAGE80
   196 M_H_DQS_DN<8> @BASEBOARD_FAB2_LIB.BASEBOARD_FAB2(SCH_1):M_H_DQS_DN(8)   I101 @BASEBOARD_FAB2_LIB.BASEBOARD_FAB2(SCH_1):PAGE80
   197 M_H_DQS_DP<8> @BASEBOARD_FAB2_LIB.BASEBOARD_FAB2(SCH_1):M_H_DQS_DP(8)   I101 @BASEBOARD_FAB2_LIB.BASEBOARD_FAB2(SCH_1):PAGE80
     8 M_H_DQS_DN<9> @BASEBOARD_FAB2_LIB.BASEBOARD_FAB2(SCH_1):M_H_DQS_DN(9)   I101 @BASEBOARD_FAB2_LIB.BASEBOARD_FAB2(SCH_1):PAGE80
     7 M_H_DQS_DP<9> @BASEBOARD_FAB2_LIB.BASEBOARD_FAB2(SCH_1):M_H_DQS_DP(9)   I101 @BASEBOARD_FAB2_LIB.BASEBOARD_FAB2(SCH_1):PAGE80
     2    GND @BASEBOARD_FAB2_LIB.BASEBOARD_FAB2(SCH_1):GND   I138 @BASEBOARD_FAB2_LIB.BASEBOARD_FAB2(SCH_1):PAGE80
     4    GND @BASEBOARD_FAB2_LIB.BASEBOARD_FAB2(SCH_1):GND   I138 @BASEBOARD_FAB2_LIB.BASEBOARD_FAB2(SCH_1):PAGE80
     6    GND @BASEBOARD_FAB2_LIB.BASEBOARD_FAB2(SCH_1):GND   I138 @BASEBOARD_FAB2_LIB.BASEBOARD_FAB2(SCH_1):PAGE80
     9    GND @BASEBOARD_FAB2_LIB.BASEBOARD_FAB2(SCH_1):GND   I138 @BASEBOARD_FAB2_LIB.BASEBOARD_FAB2(SCH_1):PAGE80
    11    GND @BASEBOARD_FAB2_LIB.BASEBOARD_FAB2(SCH_1):GND   I138 @BASEBOARD_FAB2_LIB.BASEBOARD_FAB2(SCH_1):PAGE80
    13    GND @BASEBOARD_FAB2_LIB.BASEBOARD_FAB2(SCH_1):GND   I138 @BASEBOARD_FAB2_LIB.BASEBOARD_FAB2(SCH_1):PAGE80
    15    GND @BASEBOARD_FAB2_LIB.BASEBOARD_FAB2(SCH_1):GND   I138 @BASEBOARD_FAB2_LIB.BASEBOARD_FAB2(SCH_1):PAGE80
    17    GND @BASEBOARD_FAB2_LIB.BASEBOARD_FAB2(SCH_1):GND   I138 @BASEBOARD_FAB2_LIB.BASEBOARD_FAB2(SCH_1):PAGE80
    20    GND @BASEBOARD_FAB2_LIB.BASEBOARD_FAB2(SCH_1):GND   I138 @BASEBOARD_FAB2_LIB.BASEBOARD_FAB2(SCH_1):PAGE80
    22    GND @BASEBOARD_FAB2_LIB.BASEBOARD_FAB2(SCH_1):GND   I138 @BASEBOARD_FAB2_LIB.BASEBOARD_FAB2(SCH_1):PAGE80
    24    GND @BASEBOARD_FAB2_LIB.BASEBOARD_FAB2(SCH_1):GND   I138 @BASEBOARD_FAB2_LIB.BASEBOARD_FAB2(SCH_1):PAGE80
    26    GND @BASEBOARD_FAB2_LIB.BASEBOARD_FAB2(SCH_1):GND   I138 @BASEBOARD_FAB2_LIB.BASEBOARD_FAB2(SCH_1):PAGE80
    28    GND @BASEBOARD_FAB2_LIB.BASEBOARD_FAB2(SCH_1):GND   I138 @BASEBOARD_FAB2_LIB.BASEBOARD_FAB2(SCH_1):PAGE80
    31    GND @BASEBOARD_FAB2_LIB.BASEBOARD_FAB2(SCH_1):GND   I138 @BASEBOARD_FAB2_LIB.BASEBOARD_FAB2(SCH_1):PAGE80
    33    GND @BASEBOARD_FAB2_LIB.BASEBOARD_FAB2(SCH_1):GND   I138 @BASEBOARD_FAB2_LIB.BASEBOARD_FAB2(SCH_1):PAGE80
    35    GND @BASEBOARD_FAB2_LIB.BASEBOARD_FAB2(SCH_1):GND   I138 @BASEBOARD_FAB2_LIB.BASEBOARD_FAB2(SCH_1):PAGE80
    37    GND @BASEBOARD_FAB2_LIB.BASEBOARD_FAB2(SCH_1):GND   I138 @BASEBOARD_FAB2_LIB.BASEBOARD_FAB2(SCH_1):PAGE80
    39    GND @BASEBOARD_FAB2_LIB.BASEBOARD_FAB2(SCH_1):GND   I138 @BASEBOARD_FAB2_LIB.BASEBOARD_FAB2(SCH_1):PAGE80
    42    GND @BASEBOARD_FAB2_LIB.BASEBOARD_FAB2(SCH_1):GND   I138 @BASEBOARD_FAB2_LIB.BASEBOARD_FAB2(SCH_1):PAGE80
    44    GND @BASEBOARD_FAB2_LIB.BASEBOARD_FAB2(SCH_1):GND   I138 @BASEBOARD_FAB2_LIB.BASEBOARD_FAB2(SCH_1):PAGE80
    46    GND @BASEBOARD_FAB2_LIB.BASEBOARD_FAB2(SCH_1):GND   I138 @BASEBOARD_FAB2_LIB.BASEBOARD_FAB2(SCH_1):PAGE80
    48    GND @BASEBOARD_FAB2_LIB.BASEBOARD_FAB2(SCH_1):GND   I138 @BASEBOARD_FAB2_LIB.BASEBOARD_FAB2(SCH_1):PAGE80
    50    GND @BASEBOARD_FAB2_LIB.BASEBOARD_FAB2(SCH_1):GND   I138 @BASEBOARD_FAB2_LIB.BASEBOARD_FAB2(SCH_1):PAGE80
    53    GND @BASEBOARD_FAB2_LIB.BASEBOARD_FAB2(SCH_1):GND   I138 @BASEBOARD_FAB2_LIB.BASEBOARD_FAB2(SCH_1):PAGE80
    55    GND @BASEBOARD_FAB2_LIB.BASEBOARD_FAB2(SCH_1):GND   I138 @BASEBOARD_FAB2_LIB.BASEBOARD_FAB2(SCH_1):PAGE80
    57    GND @BASEBOARD_FAB2_LIB.BASEBOARD_FAB2(SCH_1):GND   I138 @BASEBOARD_FAB2_LIB.BASEBOARD_FAB2(SCH_1):PAGE80
    94    GND @BASEBOARD_FAB2_LIB.BASEBOARD_FAB2(SCH_1):GND   I138 @BASEBOARD_FAB2_LIB.BASEBOARD_FAB2(SCH_1):PAGE80
    96    GND @BASEBOARD_FAB2_LIB.BASEBOARD_FAB2(SCH_1):GND   I138 @BASEBOARD_FAB2_LIB.BASEBOARD_FAB2(SCH_1):PAGE80
    98    GND @BASEBOARD_FAB2_LIB.BASEBOARD_FAB2(SCH_1):GND   I138 @BASEBOARD_FAB2_LIB.BASEBOARD_FAB2(SCH_1):PAGE80
   101    GND @BASEBOARD_FAB2_LIB.BASEBOARD_FAB2(SCH_1):GND   I138 @BASEBOARD_FAB2_LIB.BASEBOARD_FAB2(SCH_1):PAGE80
   103    GND @BASEBOARD_FAB2_LIB.BASEBOARD_FAB2(SCH_1):GND   I138 @BASEBOARD_FAB2_LIB.BASEBOARD_FAB2(SCH_1):PAGE80
   105    GND @BASEBOARD_FAB2_LIB.BASEBOARD_FAB2(SCH_1):GND   I138 @BASEBOARD_FAB2_LIB.BASEBOARD_FAB2(SCH_1):PAGE80
   107    GND @BASEBOARD_FAB2_LIB.BASEBOARD_FAB2(SCH_1):GND   I138 @BASEBOARD_FAB2_LIB.BASEBOARD_FAB2(SCH_1):PAGE80
   109    GND @BASEBOARD_FAB2_LIB.BASEBOARD_FAB2(SCH_1):GND   I138 @BASEBOARD_FAB2_LIB.BASEBOARD_FAB2(SCH_1):PAGE80
   112    GND @BASEBOARD_FAB2_LIB.BASEBOARD_FAB2(SCH_1):GND   I138 @BASEBOARD_FAB2_LIB.BASEBOARD_FAB2(SCH_1):PAGE80
   114    GND @BASEBOARD_FAB2_LIB.BASEBOARD_FAB2(SCH_1):GND   I138 @BASEBOARD_FAB2_LIB.BASEBOARD_FAB2(SCH_1):PAGE80
   116    GND @BASEBOARD_FAB2_LIB.BASEBOARD_FAB2(SCH_1):GND   I138 @BASEBOARD_FAB2_LIB.BASEBOARD_FAB2(SCH_1):PAGE80
   118    GND @BASEBOARD_FAB2_LIB.BASEBOARD_FAB2(SCH_1):GND   I138 @BASEBOARD_FAB2_LIB.BASEBOARD_FAB2(SCH_1):PAGE80
   120    GND @BASEBOARD_FAB2_LIB.BASEBOARD_FAB2(SCH_1):GND   I138 @BASEBOARD_FAB2_LIB.BASEBOARD_FAB2(SCH_1):PAGE80
   123    GND @BASEBOARD_FAB2_LIB.BASEBOARD_FAB2(SCH_1):GND   I138 @BASEBOARD_FAB2_LIB.BASEBOARD_FAB2(SCH_1):PAGE80
   125    GND @BASEBOARD_FAB2_LIB.BASEBOARD_FAB2(SCH_1):GND   I138 @BASEBOARD_FAB2_LIB.BASEBOARD_FAB2(SCH_1):PAGE80
   127    GND @BASEBOARD_FAB2_LIB.BASEBOARD_FAB2(SCH_1):GND   I138 @BASEBOARD_FAB2_LIB.BASEBOARD_FAB2(SCH_1):PAGE80
   129    GND @BASEBOARD_FAB2_LIB.BASEBOARD_FAB2(SCH_1):GND   I138 @BASEBOARD_FAB2_LIB.BASEBOARD_FAB2(SCH_1):PAGE80
   131    GND @BASEBOARD_FAB2_LIB.BASEBOARD_FAB2(SCH_1):GND   I138 @BASEBOARD_FAB2_LIB.BASEBOARD_FAB2(SCH_1):PAGE80
   134    GND @BASEBOARD_FAB2_LIB.BASEBOARD_FAB2(SCH_1):GND   I138 @BASEBOARD_FAB2_LIB.BASEBOARD_FAB2(SCH_1):PAGE80
   136    GND @BASEBOARD_FAB2_LIB.BASEBOARD_FAB2(SCH_1):GND   I138 @BASEBOARD_FAB2_LIB.BASEBOARD_FAB2(SCH_1):PAGE80
   138    GND @BASEBOARD_FAB2_LIB.BASEBOARD_FAB2(SCH_1):GND   I138 @BASEBOARD_FAB2_LIB.BASEBOARD_FAB2(SCH_1):PAGE80
   147    GND @BASEBOARD_FAB2_LIB.BASEBOARD_FAB2(SCH_1):GND   I138 @BASEBOARD_FAB2_LIB.BASEBOARD_FAB2(SCH_1):PAGE80
   149    GND @BASEBOARD_FAB2_LIB.BASEBOARD_FAB2(SCH_1):GND   I138 @BASEBOARD_FAB2_LIB.BASEBOARD_FAB2(SCH_1):PAGE80
   151    GND @BASEBOARD_FAB2_LIB.BASEBOARD_FAB2(SCH_1):GND   I138 @BASEBOARD_FAB2_LIB.BASEBOARD_FAB2(SCH_1):PAGE80
   154    GND @BASEBOARD_FAB2_LIB.BASEBOARD_FAB2(SCH_1):GND   I138 @BASEBOARD_FAB2_LIB.BASEBOARD_FAB2(SCH_1):PAGE80
   156    GND @BASEBOARD_FAB2_LIB.BASEBOARD_FAB2(SCH_1):GND   I138 @BASEBOARD_FAB2_LIB.BASEBOARD_FAB2(SCH_1):PAGE80
   158    GND @BASEBOARD_FAB2_LIB.BASEBOARD_FAB2(SCH_1):GND   I138 @BASEBOARD_FAB2_LIB.BASEBOARD_FAB2(SCH_1):PAGE80
   160    GND @BASEBOARD_FAB2_LIB.BASEBOARD_FAB2(SCH_1):GND   I138 @BASEBOARD_FAB2_LIB.BASEBOARD_FAB2(SCH_1):PAGE80
   162    GND @BASEBOARD_FAB2_LIB.BASEBOARD_FAB2(SCH_1):GND   I138 @BASEBOARD_FAB2_LIB.BASEBOARD_FAB2(SCH_1):PAGE80
   165    GND @BASEBOARD_FAB2_LIB.BASEBOARD_FAB2(SCH_1):GND   I138 @BASEBOARD_FAB2_LIB.BASEBOARD_FAB2(SCH_1):PAGE80
   167    GND @BASEBOARD_FAB2_LIB.BASEBOARD_FAB2(SCH_1):GND   I138 @BASEBOARD_FAB2_LIB.BASEBOARD_FAB2(SCH_1):PAGE80
   169    GND @BASEBOARD_FAB2_LIB.BASEBOARD_FAB2(SCH_1):GND   I138 @BASEBOARD_FAB2_LIB.BASEBOARD_FAB2(SCH_1):PAGE80
   171    GND @BASEBOARD_FAB2_LIB.BASEBOARD_FAB2(SCH_1):GND   I138 @BASEBOARD_FAB2_LIB.BASEBOARD_FAB2(SCH_1):PAGE80
   173    GND @BASEBOARD_FAB2_LIB.BASEBOARD_FAB2(SCH_1):GND   I138 @BASEBOARD_FAB2_LIB.BASEBOARD_FAB2(SCH_1):PAGE80
   176    GND @BASEBOARD_FAB2_LIB.BASEBOARD_FAB2(SCH_1):GND   I138 @BASEBOARD_FAB2_LIB.BASEBOARD_FAB2(SCH_1):PAGE80
   178    GND @BASEBOARD_FAB2_LIB.BASEBOARD_FAB2(SCH_1):GND   I138 @BASEBOARD_FAB2_LIB.BASEBOARD_FAB2(SCH_1):PAGE80
   180    GND @BASEBOARD_FAB2_LIB.BASEBOARD_FAB2(SCH_1):GND   I138 @BASEBOARD_FAB2_LIB.BASEBOARD_FAB2(SCH_1):PAGE80
   182    GND @BASEBOARD_FAB2_LIB.BASEBOARD_FAB2(SCH_1):GND   I138 @BASEBOARD_FAB2_LIB.BASEBOARD_FAB2(SCH_1):PAGE80
   184    GND @BASEBOARD_FAB2_LIB.BASEBOARD_FAB2(SCH_1):GND   I138 @BASEBOARD_FAB2_LIB.BASEBOARD_FAB2(SCH_1):PAGE80
   187    GND @BASEBOARD_FAB2_LIB.BASEBOARD_FAB2(SCH_1):GND   I138 @BASEBOARD_FAB2_LIB.BASEBOARD_FAB2(SCH_1):PAGE80
   189    GND @BASEBOARD_FAB2_LIB.BASEBOARD_FAB2(SCH_1):GND   I138 @BASEBOARD_FAB2_LIB.BASEBOARD_FAB2(SCH_1):PAGE80
   191    GND @BASEBOARD_FAB2_LIB.BASEBOARD_FAB2(SCH_1):GND   I138 @BASEBOARD_FAB2_LIB.BASEBOARD_FAB2(SCH_1):PAGE80
   193    GND @BASEBOARD_FAB2_LIB.BASEBOARD_FAB2(SCH_1):GND   I138 @BASEBOARD_FAB2_LIB.BASEBOARD_FAB2(SCH_1):PAGE80
   195    GND @BASEBOARD_FAB2_LIB.BASEBOARD_FAB2(SCH_1):GND   I138 @BASEBOARD_FAB2_LIB.BASEBOARD_FAB2(SCH_1):PAGE80
   198    GND @BASEBOARD_FAB2_LIB.BASEBOARD_FAB2(SCH_1):GND   I138 @BASEBOARD_FAB2_LIB.BASEBOARD_FAB2(SCH_1):PAGE80
   200    GND @BASEBOARD_FAB2_LIB.BASEBOARD_FAB2(SCH_1):GND   I138 @BASEBOARD_FAB2_LIB.BASEBOARD_FAB2(SCH_1):PAGE80
   202    GND @BASEBOARD_FAB2_LIB.BASEBOARD_FAB2(SCH_1):GND   I138 @BASEBOARD_FAB2_LIB.BASEBOARD_FAB2(SCH_1):PAGE80
   239    GND @BASEBOARD_FAB2_LIB.BASEBOARD_FAB2(SCH_1):GND   I138 @BASEBOARD_FAB2_LIB.BASEBOARD_FAB2(SCH_1):PAGE80
   241    GND @BASEBOARD_FAB2_LIB.BASEBOARD_FAB2(SCH_1):GND   I138 @BASEBOARD_FAB2_LIB.BASEBOARD_FAB2(SCH_1):PAGE80
   243    GND @BASEBOARD_FAB2_LIB.BASEBOARD_FAB2(SCH_1):GND   I138 @BASEBOARD_FAB2_LIB.BASEBOARD_FAB2(SCH_1):PAGE80
   246    GND @BASEBOARD_FAB2_LIB.BASEBOARD_FAB2(SCH_1):GND   I138 @BASEBOARD_FAB2_LIB.BASEBOARD_FAB2(SCH_1):PAGE80
   248    GND @BASEBOARD_FAB2_LIB.BASEBOARD_FAB2(SCH_1):GND   I138 @BASEBOARD_FAB2_LIB.BASEBOARD_FAB2(SCH_1):PAGE80
   250    GND @BASEBOARD_FAB2_LIB.BASEBOARD_FAB2(SCH_1):GND   I138 @BASEBOARD_FAB2_LIB.BASEBOARD_FAB2(SCH_1):PAGE80
   252    GND @BASEBOARD_FAB2_LIB.BASEBOARD_FAB2(SCH_1):GND   I138 @BASEBOARD_FAB2_LIB.BASEBOARD_FAB2(SCH_1):PAGE80
   254    GND @BASEBOARD_FAB2_LIB.BASEBOARD_FAB2(SCH_1):GND   I138 @BASEBOARD_FAB2_LIB.BASEBOARD_FAB2(SCH_1):PAGE80
   257    GND @BASEBOARD_FAB2_LIB.BASEBOARD_FAB2(SCH_1):GND   I138 @BASEBOARD_FAB2_LIB.BASEBOARD_FAB2(SCH_1):PAGE80
   259    GND @BASEBOARD_FAB2_LIB.BASEBOARD_FAB2(SCH_1):GND   I138 @BASEBOARD_FAB2_LIB.BASEBOARD_FAB2(SCH_1):PAGE80
   261    GND @BASEBOARD_FAB2_LIB.BASEBOARD_FAB2(SCH_1):GND   I138 @BASEBOARD_FAB2_LIB.BASEBOARD_FAB2(SCH_1):PAGE80
   263    GND @BASEBOARD_FAB2_LIB.BASEBOARD_FAB2(SCH_1):GND   I138 @BASEBOARD_FAB2_LIB.BASEBOARD_FAB2(SCH_1):PAGE80
   265    GND @BASEBOARD_FAB2_LIB.BASEBOARD_FAB2(SCH_1):GND   I138 @BASEBOARD_FAB2_LIB.BASEBOARD_FAB2(SCH_1):PAGE80
   268    GND @BASEBOARD_FAB2_LIB.BASEBOARD_FAB2(SCH_1):GND   I138 @BASEBOARD_FAB2_LIB.BASEBOARD_FAB2(SCH_1):PAGE80
   270    GND @BASEBOARD_FAB2_LIB.BASEBOARD_FAB2(SCH_1):GND   I138 @BASEBOARD_FAB2_LIB.BASEBOARD_FAB2(SCH_1):PAGE80
   272    GND @BASEBOARD_FAB2_LIB.BASEBOARD_FAB2(SCH_1):GND   I138 @BASEBOARD_FAB2_LIB.BASEBOARD_FAB2(SCH_1):PAGE80
   274    GND @BASEBOARD_FAB2_LIB.BASEBOARD_FAB2(SCH_1):GND   I138 @BASEBOARD_FAB2_LIB.BASEBOARD_FAB2(SCH_1):PAGE80
   276    GND @BASEBOARD_FAB2_LIB.BASEBOARD_FAB2(SCH_1):GND   I138 @BASEBOARD_FAB2_LIB.BASEBOARD_FAB2(SCH_1):PAGE80
   279    GND @BASEBOARD_FAB2_LIB.BASEBOARD_FAB2(SCH_1):GND   I138 @BASEBOARD_FAB2_LIB.BASEBOARD_FAB2(SCH_1):PAGE80
   281    GND @BASEBOARD_FAB2_LIB.BASEBOARD_FAB2(SCH_1):GND   I138 @BASEBOARD_FAB2_LIB.BASEBOARD_FAB2(SCH_1):PAGE80
   283    GND @BASEBOARD_FAB2_LIB.BASEBOARD_FAB2(SCH_1):GND   I138 @BASEBOARD_FAB2_LIB.BASEBOARD_FAB2(SCH_1):PAGE80
     1 P12V_NVDIMM_GHJ @BASEBOARD_FAB2_LIB.BASEBOARD_FAB2(SCH_1):P12V_NVDIMM_GHJ    I56 @BASEBOARD_FAB2_LIB.BASEBOARD_FAB2(SCH_1):PAGE80
   145 P12V_NVDIMM_GHJ @BASEBOARD_FAB2_LIB.BASEBOARD_FAB2(SCH_1):P12V_NVDIMM_GHJ    I56 @BASEBOARD_FAB2_LIB.BASEBOARD_FAB2(SCH_1):PAGE80
    59 PVDDQ_GHJ @BASEBOARD_FAB2_LIB.BASEBOARD_FAB2(SCH_1):PVDDQ_GHJ    I56 @BASEBOARD_FAB2_LIB.BASEBOARD_FAB2(SCH_1):PAGE80
    61 PVDDQ_GHJ @BASEBOARD_FAB2_LIB.BASEBOARD_FAB2(SCH_1):PVDDQ_GHJ    I56 @BASEBOARD_FAB2_LIB.BASEBOARD_FAB2(SCH_1):PAGE80
    64 PVDDQ_GHJ @BASEBOARD_FAB2_LIB.BASEBOARD_FAB2(SCH_1):PVDDQ_GHJ    I56 @BASEBOARD_FAB2_LIB.BASEBOARD_FAB2(SCH_1):PAGE80
    67 PVDDQ_GHJ @BASEBOARD_FAB2_LIB.BASEBOARD_FAB2(SCH_1):PVDDQ_GHJ    I56 @BASEBOARD_FAB2_LIB.BASEBOARD_FAB2(SCH_1):PAGE80
    70 PVDDQ_GHJ @BASEBOARD_FAB2_LIB.BASEBOARD_FAB2(SCH_1):PVDDQ_GHJ    I56 @BASEBOARD_FAB2_LIB.BASEBOARD_FAB2(SCH_1):PAGE80
    73 PVDDQ_GHJ @BASEBOARD_FAB2_LIB.BASEBOARD_FAB2(SCH_1):PVDDQ_GHJ    I56 @BASEBOARD_FAB2_LIB.BASEBOARD_FAB2(SCH_1):PAGE80
    76 PVDDQ_GHJ @BASEBOARD_FAB2_LIB.BASEBOARD_FAB2(SCH_1):PVDDQ_GHJ    I56 @BASEBOARD_FAB2_LIB.BASEBOARD_FAB2(SCH_1):PAGE80
    80 PVDDQ_GHJ @BASEBOARD_FAB2_LIB.BASEBOARD_FAB2(SCH_1):PVDDQ_GHJ    I56 @BASEBOARD_FAB2_LIB.BASEBOARD_FAB2(SCH_1):PAGE80
    83 PVDDQ_GHJ @BASEBOARD_FAB2_LIB.BASEBOARD_FAB2(SCH_1):PVDDQ_GHJ    I56 @BASEBOARD_FAB2_LIB.BASEBOARD_FAB2(SCH_1):PAGE80
    85 PVDDQ_GHJ @BASEBOARD_FAB2_LIB.BASEBOARD_FAB2(SCH_1):PVDDQ_GHJ    I56 @BASEBOARD_FAB2_LIB.BASEBOARD_FAB2(SCH_1):PAGE80
    88 PVDDQ_GHJ @BASEBOARD_FAB2_LIB.BASEBOARD_FAB2(SCH_1):PVDDQ_GHJ    I56 @BASEBOARD_FAB2_LIB.BASEBOARD_FAB2(SCH_1):PAGE80
    90 PVDDQ_GHJ @BASEBOARD_FAB2_LIB.BASEBOARD_FAB2(SCH_1):PVDDQ_GHJ    I56 @BASEBOARD_FAB2_LIB.BASEBOARD_FAB2(SCH_1):PAGE80
    92 PVDDQ_GHJ @BASEBOARD_FAB2_LIB.BASEBOARD_FAB2(SCH_1):PVDDQ_GHJ    I56 @BASEBOARD_FAB2_LIB.BASEBOARD_FAB2(SCH_1):PAGE80
   204 PVDDQ_GHJ @BASEBOARD_FAB2_LIB.BASEBOARD_FAB2(SCH_1):PVDDQ_GHJ    I56 @BASEBOARD_FAB2_LIB.BASEBOARD_FAB2(SCH_1):PAGE80
   206 PVDDQ_GHJ @BASEBOARD_FAB2_LIB.BASEBOARD_FAB2(SCH_1):PVDDQ_GHJ    I56 @BASEBOARD_FAB2_LIB.BASEBOARD_FAB2(SCH_1):PAGE80
   209 PVDDQ_GHJ @BASEBOARD_FAB2_LIB.BASEBOARD_FAB2(SCH_1):PVDDQ_GHJ    I56 @BASEBOARD_FAB2_LIB.BASEBOARD_FAB2(SCH_1):PAGE80
   212 PVDDQ_GHJ @BASEBOARD_FAB2_LIB.BASEBOARD_FAB2(SCH_1):PVDDQ_GHJ    I56 @BASEBOARD_FAB2_LIB.BASEBOARD_FAB2(SCH_1):PAGE80
   215 PVDDQ_GHJ @BASEBOARD_FAB2_LIB.BASEBOARD_FAB2(SCH_1):PVDDQ_GHJ    I56 @BASEBOARD_FAB2_LIB.BASEBOARD_FAB2(SCH_1):PAGE80
   217 PVDDQ_GHJ @BASEBOARD_FAB2_LIB.BASEBOARD_FAB2(SCH_1):PVDDQ_GHJ    I56 @BASEBOARD_FAB2_LIB.BASEBOARD_FAB2(SCH_1):PAGE80
   220 PVDDQ_GHJ @BASEBOARD_FAB2_LIB.BASEBOARD_FAB2(SCH_1):PVDDQ_GHJ    I56 @BASEBOARD_FAB2_LIB.BASEBOARD_FAB2(SCH_1):PAGE80
   223 PVDDQ_GHJ @BASEBOARD_FAB2_LIB.BASEBOARD_FAB2(SCH_1):PVDDQ_GHJ    I56 @BASEBOARD_FAB2_LIB.BASEBOARD_FAB2(SCH_1):PAGE80
   226 PVDDQ_GHJ @BASEBOARD_FAB2_LIB.BASEBOARD_FAB2(SCH_1):PVDDQ_GHJ    I56 @BASEBOARD_FAB2_LIB.BASEBOARD_FAB2(SCH_1):PAGE80
   229 PVDDQ_GHJ @BASEBOARD_FAB2_LIB.BASEBOARD_FAB2(SCH_1):PVDDQ_GHJ    I56 @BASEBOARD_FAB2_LIB.BASEBOARD_FAB2(SCH_1):PAGE80
   231 PVDDQ_GHJ @BASEBOARD_FAB2_LIB.BASEBOARD_FAB2(SCH_1):PVDDQ_GHJ    I56 @BASEBOARD_FAB2_LIB.BASEBOARD_FAB2(SCH_1):PAGE80
   233 PVDDQ_GHJ @BASEBOARD_FAB2_LIB.BASEBOARD_FAB2(SCH_1):PVDDQ_GHJ    I56 @BASEBOARD_FAB2_LIB.BASEBOARD_FAB2(SCH_1):PAGE80
   236 PVDDQ_GHJ @BASEBOARD_FAB2_LIB.BASEBOARD_FAB2(SCH_1):PVDDQ_GHJ    I56 @BASEBOARD_FAB2_LIB.BASEBOARD_FAB2(SCH_1):PAGE80
   142 PVPP_GHJ @BASEBOARD_FAB2_LIB.BASEBOARD_FAB2(SCH_1):PVPP_GHJ    I56 @BASEBOARD_FAB2_LIB.BASEBOARD_FAB2(SCH_1):PAGE80
   143 PVPP_GHJ @BASEBOARD_FAB2_LIB.BASEBOARD_FAB2(SCH_1):PVPP_GHJ    I56 @BASEBOARD_FAB2_LIB.BASEBOARD_FAB2(SCH_1):PAGE80
   288 PVPP_GHJ @BASEBOARD_FAB2_LIB.BASEBOARD_FAB2(SCH_1):PVPP_GHJ    I56 @BASEBOARD_FAB2_LIB.BASEBOARD_FAB2(SCH_1):PAGE80
   286 PVPP_GHJ @BASEBOARD_FAB2_LIB.BASEBOARD_FAB2(SCH_1):PVPP_GHJ    I56 @BASEBOARD_FAB2_LIB.BASEBOARD_FAB2(SCH_1):PAGE80
   287 PVPP_GHJ @BASEBOARD_FAB2_LIB.BASEBOARD_FAB2(SCH_1):PVPP_GHJ    I56 @BASEBOARD_FAB2_LIB.BASEBOARD_FAB2(SCH_1):PAGE80
    77 PVTT_GHJ @BASEBOARD_FAB2_LIB.BASEBOARD_FAB2(SCH_1):PVTT_GHJ    I56 @BASEBOARD_FAB2_LIB.BASEBOARD_FAB2(SCH_1):PAGE80
   221 PVTT_GHJ @BASEBOARD_FAB2_LIB.BASEBOARD_FAB2(SCH_1):PVTT_GHJ    I56 @BASEBOARD_FAB2_LIB.BASEBOARD_FAB2(SCH_1):PAGE80

J9U2 SCONN288_H44441003_PIP-SCONN,HA
    79 M_J_MA<0> @BASEBOARD_FAB2_LIB.BASEBOARD_FAB2(SCH_1):M_J_MA(0)   I187 @BASEBOARD_FAB2_LIB.BASEBOARD_FAB2(SCH_1):PAGE82
    72 M_J_MA<1> @BASEBOARD_FAB2_LIB.BASEBOARD_FAB2(SCH_1):M_J_MA(1)   I187 @BASEBOARD_FAB2_LIB.BASEBOARD_FAB2(SCH_1):PAGE82
   225 M_J_MA<10> @BASEBOARD_FAB2_LIB.BASEBOARD_FAB2(SCH_1):M_J_MA(10)   I187 @BASEBOARD_FAB2_LIB.BASEBOARD_FAB2(SCH_1):PAGE82
   210 M_J_MA<11> @BASEBOARD_FAB2_LIB.BASEBOARD_FAB2(SCH_1):M_J_MA(11)   I187 @BASEBOARD_FAB2_LIB.BASEBOARD_FAB2(SCH_1):PAGE82
    65 M_J_MA<12> @BASEBOARD_FAB2_LIB.BASEBOARD_FAB2(SCH_1):M_J_MA(12)   I187 @BASEBOARD_FAB2_LIB.BASEBOARD_FAB2(SCH_1):PAGE82
   232 M_J_MA<13> @BASEBOARD_FAB2_LIB.BASEBOARD_FAB2(SCH_1):M_J_MA(13)   I187 @BASEBOARD_FAB2_LIB.BASEBOARD_FAB2(SCH_1):PAGE82
   228 M_J_MA<14> @BASEBOARD_FAB2_LIB.BASEBOARD_FAB2(SCH_1):M_J_MA(14)   I187 @BASEBOARD_FAB2_LIB.BASEBOARD_FAB2(SCH_1):PAGE82
    86 M_J_MA<15> @BASEBOARD_FAB2_LIB.BASEBOARD_FAB2(SCH_1):M_J_MA(15)   I187 @BASEBOARD_FAB2_LIB.BASEBOARD_FAB2(SCH_1):PAGE82
    82 M_J_MA<16> @BASEBOARD_FAB2_LIB.BASEBOARD_FAB2(SCH_1):M_J_MA(16)   I187 @BASEBOARD_FAB2_LIB.BASEBOARD_FAB2(SCH_1):PAGE82
   234 M_J_MA<17> @BASEBOARD_FAB2_LIB.BASEBOARD_FAB2(SCH_1):M_J_MA(17)   I187 @BASEBOARD_FAB2_LIB.BASEBOARD_FAB2(SCH_1):PAGE82
   216 M_J_MA<2> @BASEBOARD_FAB2_LIB.BASEBOARD_FAB2(SCH_1):M_J_MA(2)   I187 @BASEBOARD_FAB2_LIB.BASEBOARD_FAB2(SCH_1):PAGE82
    71 M_J_MA<3> @BASEBOARD_FAB2_LIB.BASEBOARD_FAB2(SCH_1):M_J_MA(3)   I187 @BASEBOARD_FAB2_LIB.BASEBOARD_FAB2(SCH_1):PAGE82
   214 M_J_MA<4> @BASEBOARD_FAB2_LIB.BASEBOARD_FAB2(SCH_1):M_J_MA(4)   I187 @BASEBOARD_FAB2_LIB.BASEBOARD_FAB2(SCH_1):PAGE82
   213 M_J_MA<5> @BASEBOARD_FAB2_LIB.BASEBOARD_FAB2(SCH_1):M_J_MA(5)   I187 @BASEBOARD_FAB2_LIB.BASEBOARD_FAB2(SCH_1):PAGE82
    69 M_J_MA<6> @BASEBOARD_FAB2_LIB.BASEBOARD_FAB2(SCH_1):M_J_MA(6)   I187 @BASEBOARD_FAB2_LIB.BASEBOARD_FAB2(SCH_1):PAGE82
   211 M_J_MA<7> @BASEBOARD_FAB2_LIB.BASEBOARD_FAB2(SCH_1):M_J_MA(7)   I187 @BASEBOARD_FAB2_LIB.BASEBOARD_FAB2(SCH_1):PAGE82
    68 M_J_MA<8> @BASEBOARD_FAB2_LIB.BASEBOARD_FAB2(SCH_1):M_J_MA(8)   I187 @BASEBOARD_FAB2_LIB.BASEBOARD_FAB2(SCH_1):PAGE82
    66 M_J_MA<9> @BASEBOARD_FAB2_LIB.BASEBOARD_FAB2(SCH_1):M_J_MA(9)   I187 @BASEBOARD_FAB2_LIB.BASEBOARD_FAB2(SCH_1):PAGE82
    62 M_J_ACT_N @BASEBOARD_FAB2_LIB.BASEBOARD_FAB2(SCH_1):M_J_ACT_N   I187 @BASEBOARD_FAB2_LIB.BASEBOARD_FAB2(SCH_1):PAGE82
   208 M_J_ALERT_N @BASEBOARD_FAB2_LIB.BASEBOARD_FAB2(SCH_1):M_J_ALERT_N   I187 @BASEBOARD_FAB2_LIB.BASEBOARD_FAB2(SCH_1):PAGE82
   224 M_J_BA<1> @BASEBOARD_FAB2_LIB.BASEBOARD_FAB2(SCH_1):M_J_BA(1)   I187 @BASEBOARD_FAB2_LIB.BASEBOARD_FAB2(SCH_1):PAGE82
    81 M_J_BA<0> @BASEBOARD_FAB2_LIB.BASEBOARD_FAB2(SCH_1):M_J_BA(0)   I187 @BASEBOARD_FAB2_LIB.BASEBOARD_FAB2(SCH_1):PAGE82
   207 M_J_BG<1> @BASEBOARD_FAB2_LIB.BASEBOARD_FAB2(SCH_1):M_J_BG(1)   I187 @BASEBOARD_FAB2_LIB.BASEBOARD_FAB2(SCH_1):PAGE82
    63 M_J_BG<0> @BASEBOARD_FAB2_LIB.BASEBOARD_FAB2(SCH_1):M_J_BG(0)   I187 @BASEBOARD_FAB2_LIB.BASEBOARD_FAB2(SCH_1):PAGE82
   235 M_J_C<2> @BASEBOARD_FAB2_LIB.BASEBOARD_FAB2(SCH_1):M_J_C(2)   I187 @BASEBOARD_FAB2_LIB.BASEBOARD_FAB2(SCH_1):PAGE82
   199 M_J_ECC<7> @BASEBOARD_FAB2_LIB.BASEBOARD_FAB2(SCH_1):M_J_ECC(7)   I187 @BASEBOARD_FAB2_LIB.BASEBOARD_FAB2(SCH_1):PAGE82
    54 M_J_ECC<6> @BASEBOARD_FAB2_LIB.BASEBOARD_FAB2(SCH_1):M_J_ECC(6)   I187 @BASEBOARD_FAB2_LIB.BASEBOARD_FAB2(SCH_1):PAGE82
   192 M_J_ECC<5> @BASEBOARD_FAB2_LIB.BASEBOARD_FAB2(SCH_1):M_J_ECC(5)   I187 @BASEBOARD_FAB2_LIB.BASEBOARD_FAB2(SCH_1):PAGE82
    47 M_J_ECC<4> @BASEBOARD_FAB2_LIB.BASEBOARD_FAB2(SCH_1):M_J_ECC(4)   I187 @BASEBOARD_FAB2_LIB.BASEBOARD_FAB2(SCH_1):PAGE82
   201 M_J_ECC<3> @BASEBOARD_FAB2_LIB.BASEBOARD_FAB2(SCH_1):M_J_ECC(3)   I187 @BASEBOARD_FAB2_LIB.BASEBOARD_FAB2(SCH_1):PAGE82
    56 M_J_ECC<2> @BASEBOARD_FAB2_LIB.BASEBOARD_FAB2(SCH_1):M_J_ECC(2)   I187 @BASEBOARD_FAB2_LIB.BASEBOARD_FAB2(SCH_1):PAGE82
   194 M_J_ECC<1> @BASEBOARD_FAB2_LIB.BASEBOARD_FAB2(SCH_1):M_J_ECC(1)   I187 @BASEBOARD_FAB2_LIB.BASEBOARD_FAB2(SCH_1):PAGE82
    49 M_J_ECC<0> @BASEBOARD_FAB2_LIB.BASEBOARD_FAB2(SCH_1):M_J_ECC(0)   I187 @BASEBOARD_FAB2_LIB.BASEBOARD_FAB2(SCH_1):PAGE82
    75 M_J_CLK_DN<2> @BASEBOARD_FAB2_LIB.BASEBOARD_FAB2(SCH_1):M_J_CLK_DN(2)   I187 @BASEBOARD_FAB2_LIB.BASEBOARD_FAB2(SCH_1):PAGE82
    74 M_J_CLK_DP<2> @BASEBOARD_FAB2_LIB.BASEBOARD_FAB2(SCH_1):M_J_CLK_DP(2)   I187 @BASEBOARD_FAB2_LIB.BASEBOARD_FAB2(SCH_1):PAGE82
   219 M_J_CLK_DN<3> @BASEBOARD_FAB2_LIB.BASEBOARD_FAB2(SCH_1):M_J_CLK_DN(3)   I187 @BASEBOARD_FAB2_LIB.BASEBOARD_FAB2(SCH_1):PAGE82
   218 M_J_CLK_DP<3> @BASEBOARD_FAB2_LIB.BASEBOARD_FAB2(SCH_1):M_J_CLK_DP(3)   I187 @BASEBOARD_FAB2_LIB.BASEBOARD_FAB2(SCH_1):PAGE82
   203 M_J_CKE<3> @BASEBOARD_FAB2_LIB.BASEBOARD_FAB2(SCH_1):M_J_CKE(3)   I187 @BASEBOARD_FAB2_LIB.BASEBOARD_FAB2(SCH_1):PAGE82
    60 M_J_CKE<2> @BASEBOARD_FAB2_LIB.BASEBOARD_FAB2(SCH_1):M_J_CKE(2)   I187 @BASEBOARD_FAB2_LIB.BASEBOARD_FAB2(SCH_1):PAGE82
   280 M_J_DQ<63> @BASEBOARD_FAB2_LIB.BASEBOARD_FAB2(SCH_1):M_J_DQ(63)   I187 @BASEBOARD_FAB2_LIB.BASEBOARD_FAB2(SCH_1):PAGE82
   135 M_J_DQ<62> @BASEBOARD_FAB2_LIB.BASEBOARD_FAB2(SCH_1):M_J_DQ(62)   I187 @BASEBOARD_FAB2_LIB.BASEBOARD_FAB2(SCH_1):PAGE82
   273 M_J_DQ<61> @BASEBOARD_FAB2_LIB.BASEBOARD_FAB2(SCH_1):M_J_DQ(61)   I187 @BASEBOARD_FAB2_LIB.BASEBOARD_FAB2(SCH_1):PAGE82
   128 M_J_DQ<60> @BASEBOARD_FAB2_LIB.BASEBOARD_FAB2(SCH_1):M_J_DQ(60)   I187 @BASEBOARD_FAB2_LIB.BASEBOARD_FAB2(SCH_1):PAGE82
   282 M_J_DQ<59> @BASEBOARD_FAB2_LIB.BASEBOARD_FAB2(SCH_1):M_J_DQ(59)   I187 @BASEBOARD_FAB2_LIB.BASEBOARD_FAB2(SCH_1):PAGE82
   137 M_J_DQ<58> @BASEBOARD_FAB2_LIB.BASEBOARD_FAB2(SCH_1):M_J_DQ(58)   I187 @BASEBOARD_FAB2_LIB.BASEBOARD_FAB2(SCH_1):PAGE82
   275 M_J_DQ<57> @BASEBOARD_FAB2_LIB.BASEBOARD_FAB2(SCH_1):M_J_DQ(57)   I187 @BASEBOARD_FAB2_LIB.BASEBOARD_FAB2(SCH_1):PAGE82
   130 M_J_DQ<56> @BASEBOARD_FAB2_LIB.BASEBOARD_FAB2(SCH_1):M_J_DQ(56)   I187 @BASEBOARD_FAB2_LIB.BASEBOARD_FAB2(SCH_1):PAGE82
   269 M_J_DQ<55> @BASEBOARD_FAB2_LIB.BASEBOARD_FAB2(SCH_1):M_J_DQ(55)   I187 @BASEBOARD_FAB2_LIB.BASEBOARD_FAB2(SCH_1):PAGE82
   124 M_J_DQ<54> @BASEBOARD_FAB2_LIB.BASEBOARD_FAB2(SCH_1):M_J_DQ(54)   I187 @BASEBOARD_FAB2_LIB.BASEBOARD_FAB2(SCH_1):PAGE82
   262 M_J_DQ<53> @BASEBOARD_FAB2_LIB.BASEBOARD_FAB2(SCH_1):M_J_DQ(53)   I187 @BASEBOARD_FAB2_LIB.BASEBOARD_FAB2(SCH_1):PAGE82
   117 M_J_DQ<52> @BASEBOARD_FAB2_LIB.BASEBOARD_FAB2(SCH_1):M_J_DQ(52)   I187 @BASEBOARD_FAB2_LIB.BASEBOARD_FAB2(SCH_1):PAGE82
   271 M_J_DQ<51> @BASEBOARD_FAB2_LIB.BASEBOARD_FAB2(SCH_1):M_J_DQ(51)   I187 @BASEBOARD_FAB2_LIB.BASEBOARD_FAB2(SCH_1):PAGE82
   126 M_J_DQ<50> @BASEBOARD_FAB2_LIB.BASEBOARD_FAB2(SCH_1):M_J_DQ(50)   I187 @BASEBOARD_FAB2_LIB.BASEBOARD_FAB2(SCH_1):PAGE82
   264 M_J_DQ<49> @BASEBOARD_FAB2_LIB.BASEBOARD_FAB2(SCH_1):M_J_DQ(49)   I187 @BASEBOARD_FAB2_LIB.BASEBOARD_FAB2(SCH_1):PAGE82
   119 M_J_DQ<48> @BASEBOARD_FAB2_LIB.BASEBOARD_FAB2(SCH_1):M_J_DQ(48)   I187 @BASEBOARD_FAB2_LIB.BASEBOARD_FAB2(SCH_1):PAGE82
   258 M_J_DQ<47> @BASEBOARD_FAB2_LIB.BASEBOARD_FAB2(SCH_1):M_J_DQ(47)   I187 @BASEBOARD_FAB2_LIB.BASEBOARD_FAB2(SCH_1):PAGE82
   113 M_J_DQ<46> @BASEBOARD_FAB2_LIB.BASEBOARD_FAB2(SCH_1):M_J_DQ(46)   I187 @BASEBOARD_FAB2_LIB.BASEBOARD_FAB2(SCH_1):PAGE82
   251 M_J_DQ<45> @BASEBOARD_FAB2_LIB.BASEBOARD_FAB2(SCH_1):M_J_DQ(45)   I187 @BASEBOARD_FAB2_LIB.BASEBOARD_FAB2(SCH_1):PAGE82
   106 M_J_DQ<44> @BASEBOARD_FAB2_LIB.BASEBOARD_FAB2(SCH_1):M_J_DQ(44)   I187 @BASEBOARD_FAB2_LIB.BASEBOARD_FAB2(SCH_1):PAGE82
   260 M_J_DQ<43> @BASEBOARD_FAB2_LIB.BASEBOARD_FAB2(SCH_1):M_J_DQ(43)   I187 @BASEBOARD_FAB2_LIB.BASEBOARD_FAB2(SCH_1):PAGE82
   115 M_J_DQ<42> @BASEBOARD_FAB2_LIB.BASEBOARD_FAB2(SCH_1):M_J_DQ(42)   I187 @BASEBOARD_FAB2_LIB.BASEBOARD_FAB2(SCH_1):PAGE82
   253 M_J_DQ<41> @BASEBOARD_FAB2_LIB.BASEBOARD_FAB2(SCH_1):M_J_DQ(41)   I187 @BASEBOARD_FAB2_LIB.BASEBOARD_FAB2(SCH_1):PAGE82
   108 M_J_DQ<40> @BASEBOARD_FAB2_LIB.BASEBOARD_FAB2(SCH_1):M_J_DQ(40)   I187 @BASEBOARD_FAB2_LIB.BASEBOARD_FAB2(SCH_1):PAGE82
   247 M_J_DQ<39> @BASEBOARD_FAB2_LIB.BASEBOARD_FAB2(SCH_1):M_J_DQ(39)   I187 @BASEBOARD_FAB2_LIB.BASEBOARD_FAB2(SCH_1):PAGE82
   102 M_J_DQ<38> @BASEBOARD_FAB2_LIB.BASEBOARD_FAB2(SCH_1):M_J_DQ(38)   I187 @BASEBOARD_FAB2_LIB.BASEBOARD_FAB2(SCH_1):PAGE82
   240 M_J_DQ<37> @BASEBOARD_FAB2_LIB.BASEBOARD_FAB2(SCH_1):M_J_DQ(37)   I187 @BASEBOARD_FAB2_LIB.BASEBOARD_FAB2(SCH_1):PAGE82
    95 M_J_DQ<36> @BASEBOARD_FAB2_LIB.BASEBOARD_FAB2(SCH_1):M_J_DQ(36)   I187 @BASEBOARD_FAB2_LIB.BASEBOARD_FAB2(SCH_1):PAGE82
   249 M_J_DQ<35> @BASEBOARD_FAB2_LIB.BASEBOARD_FAB2(SCH_1):M_J_DQ(35)   I187 @BASEBOARD_FAB2_LIB.BASEBOARD_FAB2(SCH_1):PAGE82
   104 M_J_DQ<34> @BASEBOARD_FAB2_LIB.BASEBOARD_FAB2(SCH_1):M_J_DQ(34)   I187 @BASEBOARD_FAB2_LIB.BASEBOARD_FAB2(SCH_1):PAGE82
   242 M_J_DQ<33> @BASEBOARD_FAB2_LIB.BASEBOARD_FAB2(SCH_1):M_J_DQ(33)   I187 @BASEBOARD_FAB2_LIB.BASEBOARD_FAB2(SCH_1):PAGE82
    97 M_J_DQ<32> @BASEBOARD_FAB2_LIB.BASEBOARD_FAB2(SCH_1):M_J_DQ(32)   I187 @BASEBOARD_FAB2_LIB.BASEBOARD_FAB2(SCH_1):PAGE82
   188 M_J_DQ<31> @BASEBOARD_FAB2_LIB.BASEBOARD_FAB2(SCH_1):M_J_DQ(31)   I187 @BASEBOARD_FAB2_LIB.BASEBOARD_FAB2(SCH_1):PAGE82
    43 M_J_DQ<30> @BASEBOARD_FAB2_LIB.BASEBOARD_FAB2(SCH_1):M_J_DQ(30)   I187 @BASEBOARD_FAB2_LIB.BASEBOARD_FAB2(SCH_1):PAGE82
   181 M_J_DQ<29> @BASEBOARD_FAB2_LIB.BASEBOARD_FAB2(SCH_1):M_J_DQ(29)   I187 @BASEBOARD_FAB2_LIB.BASEBOARD_FAB2(SCH_1):PAGE82
    36 M_J_DQ<28> @BASEBOARD_FAB2_LIB.BASEBOARD_FAB2(SCH_1):M_J_DQ(28)   I187 @BASEBOARD_FAB2_LIB.BASEBOARD_FAB2(SCH_1):PAGE82
   190 M_J_DQ<27> @BASEBOARD_FAB2_LIB.BASEBOARD_FAB2(SCH_1):M_J_DQ(27)   I187 @BASEBOARD_FAB2_LIB.BASEBOARD_FAB2(SCH_1):PAGE82
    45 M_J_DQ<26> @BASEBOARD_FAB2_LIB.BASEBOARD_FAB2(SCH_1):M_J_DQ(26)   I187 @BASEBOARD_FAB2_LIB.BASEBOARD_FAB2(SCH_1):PAGE82
   183 M_J_DQ<25> @BASEBOARD_FAB2_LIB.BASEBOARD_FAB2(SCH_1):M_J_DQ(25)   I187 @BASEBOARD_FAB2_LIB.BASEBOARD_FAB2(SCH_1):PAGE82
    38 M_J_DQ<24> @BASEBOARD_FAB2_LIB.BASEBOARD_FAB2(SCH_1):M_J_DQ(24)   I187 @BASEBOARD_FAB2_LIB.BASEBOARD_FAB2(SCH_1):PAGE82
   177 M_J_DQ<23> @BASEBOARD_FAB2_LIB.BASEBOARD_FAB2(SCH_1):M_J_DQ(23)   I187 @BASEBOARD_FAB2_LIB.BASEBOARD_FAB2(SCH_1):PAGE82
    32 M_J_DQ<22> @BASEBOARD_FAB2_LIB.BASEBOARD_FAB2(SCH_1):M_J_DQ(22)   I187 @BASEBOARD_FAB2_LIB.BASEBOARD_FAB2(SCH_1):PAGE82
   170 M_J_DQ<21> @BASEBOARD_FAB2_LIB.BASEBOARD_FAB2(SCH_1):M_J_DQ(21)   I187 @BASEBOARD_FAB2_LIB.BASEBOARD_FAB2(SCH_1):PAGE82
    25 M_J_DQ<20> @BASEBOARD_FAB2_LIB.BASEBOARD_FAB2(SCH_1):M_J_DQ(20)   I187 @BASEBOARD_FAB2_LIB.BASEBOARD_FAB2(SCH_1):PAGE82
   179 M_J_DQ<19> @BASEBOARD_FAB2_LIB.BASEBOARD_FAB2(SCH_1):M_J_DQ(19)   I187 @BASEBOARD_FAB2_LIB.BASEBOARD_FAB2(SCH_1):PAGE82
    34 M_J_DQ<18> @BASEBOARD_FAB2_LIB.BASEBOARD_FAB2(SCH_1):M_J_DQ(18)   I187 @BASEBOARD_FAB2_LIB.BASEBOARD_FAB2(SCH_1):PAGE82
   172 M_J_DQ<17> @BASEBOARD_FAB2_LIB.BASEBOARD_FAB2(SCH_1):M_J_DQ(17)   I187 @BASEBOARD_FAB2_LIB.BASEBOARD_FAB2(SCH_1):PAGE82
    27 M_J_DQ<16> @BASEBOARD_FAB2_LIB.BASEBOARD_FAB2(SCH_1):M_J_DQ(16)   I187 @BASEBOARD_FAB2_LIB.BASEBOARD_FAB2(SCH_1):PAGE82
   166 M_J_DQ<15> @BASEBOARD_FAB2_LIB.BASEBOARD_FAB2(SCH_1):M_J_DQ(15)   I187 @BASEBOARD_FAB2_LIB.BASEBOARD_FAB2(SCH_1):PAGE82
    21 M_J_DQ<14> @BASEBOARD_FAB2_LIB.BASEBOARD_FAB2(SCH_1):M_J_DQ(14)   I187 @BASEBOARD_FAB2_LIB.BASEBOARD_FAB2(SCH_1):PAGE82
   159 M_J_DQ<13> @BASEBOARD_FAB2_LIB.BASEBOARD_FAB2(SCH_1):M_J_DQ(13)   I187 @BASEBOARD_FAB2_LIB.BASEBOARD_FAB2(SCH_1):PAGE82
    14 M_J_DQ<12> @BASEBOARD_FAB2_LIB.BASEBOARD_FAB2(SCH_1):M_J_DQ(12)   I187 @BASEBOARD_FAB2_LIB.BASEBOARD_FAB2(SCH_1):PAGE82
   168 M_J_DQ<11> @BASEBOARD_FAB2_LIB.BASEBOARD_FAB2(SCH_1):M_J_DQ(11)   I187 @BASEBOARD_FAB2_LIB.BASEBOARD_FAB2(SCH_1):PAGE82
    23 M_J_DQ<10> @BASEBOARD_FAB2_LIB.BASEBOARD_FAB2(SCH_1):M_J_DQ(10)   I187 @BASEBOARD_FAB2_LIB.BASEBOARD_FAB2(SCH_1):PAGE82
   161 M_J_DQ<9> @BASEBOARD_FAB2_LIB.BASEBOARD_FAB2(SCH_1):M_J_DQ(9)   I187 @BASEBOARD_FAB2_LIB.BASEBOARD_FAB2(SCH_1):PAGE82
    16 M_J_DQ<8> @BASEBOARD_FAB2_LIB.BASEBOARD_FAB2(SCH_1):M_J_DQ(8)   I187 @BASEBOARD_FAB2_LIB.BASEBOARD_FAB2(SCH_1):PAGE82
   155 M_J_DQ<7> @BASEBOARD_FAB2_LIB.BASEBOARD_FAB2(SCH_1):M_J_DQ(7)   I187 @BASEBOARD_FAB2_LIB.BASEBOARD_FAB2(SCH_1):PAGE82
    10 M_J_DQ<6> @BASEBOARD_FAB2_LIB.BASEBOARD_FAB2(SCH_1):M_J_DQ(6)   I187 @BASEBOARD_FAB2_LIB.BASEBOARD_FAB2(SCH_1):PAGE82
   148 M_J_DQ<5> @BASEBOARD_FAB2_LIB.BASEBOARD_FAB2(SCH_1):M_J_DQ(5)   I187 @BASEBOARD_FAB2_LIB.BASEBOARD_FAB2(SCH_1):PAGE82
     3 M_J_DQ<4> @BASEBOARD_FAB2_LIB.BASEBOARD_FAB2(SCH_1):M_J_DQ(4)   I187 @BASEBOARD_FAB2_LIB.BASEBOARD_FAB2(SCH_1):PAGE82
   157 M_J_DQ<3> @BASEBOARD_FAB2_LIB.BASEBOARD_FAB2(SCH_1):M_J_DQ(3)   I187 @BASEBOARD_FAB2_LIB.BASEBOARD_FAB2(SCH_1):PAGE82
    12 M_J_DQ<2> @BASEBOARD_FAB2_LIB.BASEBOARD_FAB2(SCH_1):M_J_DQ(2)   I187 @BASEBOARD_FAB2_LIB.BASEBOARD_FAB2(SCH_1):PAGE82
   150 M_J_DQ<1> @BASEBOARD_FAB2_LIB.BASEBOARD_FAB2(SCH_1):M_J_DQ(1)   I187 @BASEBOARD_FAB2_LIB.BASEBOARD_FAB2(SCH_1):PAGE82
     5 M_J_DQ<0> @BASEBOARD_FAB2_LIB.BASEBOARD_FAB2(SCH_1):M_J_DQ(0)   I187 @BASEBOARD_FAB2_LIB.BASEBOARD_FAB2(SCH_1):PAGE82
    78 FM_DIMM_EVENT_COD_N @BASEBOARD_FAB2_LIB.BASEBOARD_FAB2(SCH_1):FM_DIMM_EVENT_COD_N   I187 @BASEBOARD_FAB2_LIB.BASEBOARD_FAB2(SCH_1):PAGE82
    91 M_J_ODT<3> @BASEBOARD_FAB2_LIB.BASEBOARD_FAB2(SCH_1):M_J_ODT(3)   I187 @BASEBOARD_FAB2_LIB.BASEBOARD_FAB2(SCH_1):PAGE82
    87 M_J_ODT<2> @BASEBOARD_FAB2_LIB.BASEBOARD_FAB2(SCH_1):M_J_ODT(2)   I187 @BASEBOARD_FAB2_LIB.BASEBOARD_FAB2(SCH_1):PAGE82
   222 M_J_PAR @BASEBOARD_FAB2_LIB.BASEBOARD_FAB2(SCH_1):M_J_PAR   I187 @BASEBOARD_FAB2_LIB.BASEBOARD_FAB2(SCH_1):PAGE82
    58 M_GHJ_RST_N @BASEBOARD_FAB2_LIB.BASEBOARD_FAB2(SCH_1):M_GHJ_RST_N   I187 @BASEBOARD_FAB2_LIB.BASEBOARD_FAB2(SCH_1):PAGE82
   144 TP_CH_J_DIMM_J1_RFU_2 @BASEBOARD_FAB2_LIB.BASEBOARD_FAB2(SCH_1):TP_CH_J_DIMM_J1_RFU_2   I187 @BASEBOARD_FAB2_LIB.BASEBOARD_FAB2(SCH_1):PAGE82
   227 TP_CH_J_DIMM_J1_RFU_1 @BASEBOARD_FAB2_LIB.BASEBOARD_FAB2(SCH_1):TP_CH_J_DIMM_J1_RFU_1   I187 @BASEBOARD_FAB2_LIB.BASEBOARD_FAB2(SCH_1):PAGE82
   205 TP_CH_J_DIMM_J1_RFU_0 @BASEBOARD_FAB2_LIB.BASEBOARD_FAB2(SCH_1):TP_CH_J_DIMM_J1_RFU_0   I187 @BASEBOARD_FAB2_LIB.BASEBOARD_FAB2(SCH_1):PAGE82
    84 M_J_CS_N<4> @BASEBOARD_FAB2_LIB.BASEBOARD_FAB2(SCH_1):M_J_CS_N(4)   I187 @BASEBOARD_FAB2_LIB.BASEBOARD_FAB2(SCH_1):PAGE82
    89 M_J_CS_N<5> @BASEBOARD_FAB2_LIB.BASEBOARD_FAB2(SCH_1):M_J_CS_N(5)   I187 @BASEBOARD_FAB2_LIB.BASEBOARD_FAB2(SCH_1):PAGE82
    93 M_J_CS_N<6> @BASEBOARD_FAB2_LIB.BASEBOARD_FAB2(SCH_1):M_J_CS_N(6)   I187 @BASEBOARD_FAB2_LIB.BASEBOARD_FAB2(SCH_1):PAGE82
   237 M_J_CS_N<7> @BASEBOARD_FAB2_LIB.BASEBOARD_FAB2(SCH_1):M_J_CS_N(7)   I187 @BASEBOARD_FAB2_LIB.BASEBOARD_FAB2(SCH_1):PAGE82
   238 PVPP_GHJ @BASEBOARD_FAB2_LIB.BASEBOARD_FAB2(SCH_1):PVPP_GHJ   I187 @BASEBOARD_FAB2_LIB.BASEBOARD_FAB2(SCH_1):PAGE82
   140    GND @BASEBOARD_FAB2_LIB.BASEBOARD_FAB2(SCH_1):GND   I187 @BASEBOARD_FAB2_LIB.BASEBOARD_FAB2(SCH_1):PAGE82
   139 PVPP_GHJ @BASEBOARD_FAB2_LIB.BASEBOARD_FAB2(SCH_1):PVPP_GHJ   I187 @BASEBOARD_FAB2_LIB.BASEBOARD_FAB2(SCH_1):PAGE82
   230 FM_ADR_COMPLETE_GHJ_N @BASEBOARD_FAB2_LIB.BASEBOARD_FAB2(SCH_1):FM_ADR_COMPLETE_GHJ_N   I187 @BASEBOARD_FAB2_LIB.BASEBOARD_FAB2(SCH_1):PAGE82
   141 SMB_DDR_GHJ_VPP_SCL @BASEBOARD_FAB2_LIB.BASEBOARD_FAB2(SCH_1):SMB_DDR_GHJ_VPP_SCL   I187 @BASEBOARD_FAB2_LIB.BASEBOARD_FAB2(SCH_1):PAGE82
   285 SMB_DDR_GHJ_VPP_SDA @BASEBOARD_FAB2_LIB.BASEBOARD_FAB2(SCH_1):SMB_DDR_GHJ_VPP_SDA   I187 @BASEBOARD_FAB2_LIB.BASEBOARD_FAB2(SCH_1):PAGE82
   284 PVPP_GHJ @BASEBOARD_FAB2_LIB.BASEBOARD_FAB2(SCH_1):PVPP_GHJ   I187 @BASEBOARD_FAB2_LIB.BASEBOARD_FAB2(SCH_1):PAGE82
   146 M_J_VREF @BASEBOARD_FAB2_LIB.BASEBOARD_FAB2(SCH_1):M_J_VREF   I187 @BASEBOARD_FAB2_LIB.BASEBOARD_FAB2(SCH_1):PAGE82
   152 M_J_DQS_DN<0> @BASEBOARD_FAB2_LIB.BASEBOARD_FAB2(SCH_1):M_J_DQS_DN(0)    I64 @BASEBOARD_FAB2_LIB.BASEBOARD_FAB2(SCH_1):PAGE82
   153 M_J_DQS_DP<0> @BASEBOARD_FAB2_LIB.BASEBOARD_FAB2(SCH_1):M_J_DQS_DP(0)    I64 @BASEBOARD_FAB2_LIB.BASEBOARD_FAB2(SCH_1):PAGE82
    19 M_J_DQS_DN<10> @BASEBOARD_FAB2_LIB.BASEBOARD_FAB2(SCH_1):M_J_DQS_DN(10)    I64 @BASEBOARD_FAB2_LIB.BASEBOARD_FAB2(SCH_1):PAGE82
    18 M_J_DQS_DP<10> @BASEBOARD_FAB2_LIB.BASEBOARD_FAB2(SCH_1):M_J_DQS_DP(10)    I64 @BASEBOARD_FAB2_LIB.BASEBOARD_FAB2(SCH_1):PAGE82
    30 M_J_DQS_DN<11> @BASEBOARD_FAB2_LIB.BASEBOARD_FAB2(SCH_1):M_J_DQS_DN(11)    I64 @BASEBOARD_FAB2_LIB.BASEBOARD_FAB2(SCH_1):PAGE82
    29 M_J_DQS_DP<11> @BASEBOARD_FAB2_LIB.BASEBOARD_FAB2(SCH_1):M_J_DQS_DP(11)    I64 @BASEBOARD_FAB2_LIB.BASEBOARD_FAB2(SCH_1):PAGE82
    41 M_J_DQS_DN<12> @BASEBOARD_FAB2_LIB.BASEBOARD_FAB2(SCH_1):M_J_DQS_DN(12)    I64 @BASEBOARD_FAB2_LIB.BASEBOARD_FAB2(SCH_1):PAGE82
    40 M_J_DQS_DP<12> @BASEBOARD_FAB2_LIB.BASEBOARD_FAB2(SCH_1):M_J_DQS_DP(12)    I64 @BASEBOARD_FAB2_LIB.BASEBOARD_FAB2(SCH_1):PAGE82
   100 M_J_DQS_DN<13> @BASEBOARD_FAB2_LIB.BASEBOARD_FAB2(SCH_1):M_J_DQS_DN(13)    I64 @BASEBOARD_FAB2_LIB.BASEBOARD_FAB2(SCH_1):PAGE82
    99 M_J_DQS_DP<13> @BASEBOARD_FAB2_LIB.BASEBOARD_FAB2(SCH_1):M_J_DQS_DP(13)    I64 @BASEBOARD_FAB2_LIB.BASEBOARD_FAB2(SCH_1):PAGE82
   111 M_J_DQS_DN<14> @BASEBOARD_FAB2_LIB.BASEBOARD_FAB2(SCH_1):M_J_DQS_DN(14)    I64 @BASEBOARD_FAB2_LIB.BASEBOARD_FAB2(SCH_1):PAGE82
   110 M_J_DQS_DP<14> @BASEBOARD_FAB2_LIB.BASEBOARD_FAB2(SCH_1):M_J_DQS_DP(14)    I64 @BASEBOARD_FAB2_LIB.BASEBOARD_FAB2(SCH_1):PAGE82
   122 M_J_DQS_DN<15> @BASEBOARD_FAB2_LIB.BASEBOARD_FAB2(SCH_1):M_J_DQS_DN(15)    I64 @BASEBOARD_FAB2_LIB.BASEBOARD_FAB2(SCH_1):PAGE82
   121 M_J_DQS_DP<15> @BASEBOARD_FAB2_LIB.BASEBOARD_FAB2(SCH_1):M_J_DQS_DP(15)    I64 @BASEBOARD_FAB2_LIB.BASEBOARD_FAB2(SCH_1):PAGE82
   133 M_J_DQS_DN<16> @BASEBOARD_FAB2_LIB.BASEBOARD_FAB2(SCH_1):M_J_DQS_DN(16)    I64 @BASEBOARD_FAB2_LIB.BASEBOARD_FAB2(SCH_1):PAGE82
   132 M_J_DQS_DP<16> @BASEBOARD_FAB2_LIB.BASEBOARD_FAB2(SCH_1):M_J_DQS_DP(16)    I64 @BASEBOARD_FAB2_LIB.BASEBOARD_FAB2(SCH_1):PAGE82
    52 M_J_DQS_DN<17> @BASEBOARD_FAB2_LIB.BASEBOARD_FAB2(SCH_1):M_J_DQS_DN(17)    I64 @BASEBOARD_FAB2_LIB.BASEBOARD_FAB2(SCH_1):PAGE82
    51 M_J_DQS_DP<17> @BASEBOARD_FAB2_LIB.BASEBOARD_FAB2(SCH_1):M_J_DQS_DP(17)    I64 @BASEBOARD_FAB2_LIB.BASEBOARD_FAB2(SCH_1):PAGE82
   163 M_J_DQS_DN<1> @BASEBOARD_FAB2_LIB.BASEBOARD_FAB2(SCH_1):M_J_DQS_DN(1)    I64 @BASEBOARD_FAB2_LIB.BASEBOARD_FAB2(SCH_1):PAGE82
   164 M_J_DQS_DP<1> @BASEBOARD_FAB2_LIB.BASEBOARD_FAB2(SCH_1):M_J_DQS_DP(1)    I64 @BASEBOARD_FAB2_LIB.BASEBOARD_FAB2(SCH_1):PAGE82
   174 M_J_DQS_DN<2> @BASEBOARD_FAB2_LIB.BASEBOARD_FAB2(SCH_1):M_J_DQS_DN(2)    I64 @BASEBOARD_FAB2_LIB.BASEBOARD_FAB2(SCH_1):PAGE82
   175 M_J_DQS_DP<2> @BASEBOARD_FAB2_LIB.BASEBOARD_FAB2(SCH_1):M_J_DQS_DP(2)    I64 @BASEBOARD_FAB2_LIB.BASEBOARD_FAB2(SCH_1):PAGE82
   185 M_J_DQS_DN<3> @BASEBOARD_FAB2_LIB.BASEBOARD_FAB2(SCH_1):M_J_DQS_DN(3)    I64 @BASEBOARD_FAB2_LIB.BASEBOARD_FAB2(SCH_1):PAGE82
   186 M_J_DQS_DP<3> @BASEBOARD_FAB2_LIB.BASEBOARD_FAB2(SCH_1):M_J_DQS_DP(3)    I64 @BASEBOARD_FAB2_LIB.BASEBOARD_FAB2(SCH_1):PAGE82
   244 M_J_DQS_DN<4> @BASEBOARD_FAB2_LIB.BASEBOARD_FAB2(SCH_1):M_J_DQS_DN(4)    I64 @BASEBOARD_FAB2_LIB.BASEBOARD_FAB2(SCH_1):PAGE82
   245 M_J_DQS_DP<4> @BASEBOARD_FAB2_LIB.BASEBOARD_FAB2(SCH_1):M_J_DQS_DP(4)    I64 @BASEBOARD_FAB2_LIB.BASEBOARD_FAB2(SCH_1):PAGE82
   255 M_J_DQS_DN<5> @BASEBOARD_FAB2_LIB.BASEBOARD_FAB2(SCH_1):M_J_DQS_DN(5)    I64 @BASEBOARD_FAB2_LIB.BASEBOARD_FAB2(SCH_1):PAGE82
   256 M_J_DQS_DP<5> @BASEBOARD_FAB2_LIB.BASEBOARD_FAB2(SCH_1):M_J_DQS_DP(5)    I64 @BASEBOARD_FAB2_LIB.BASEBOARD_FAB2(SCH_1):PAGE82
   266 M_J_DQS_DN<6> @BASEBOARD_FAB2_LIB.BASEBOARD_FAB2(SCH_1):M_J_DQS_DN(6)    I64 @BASEBOARD_FAB2_LIB.BASEBOARD_FAB2(SCH_1):PAGE82
   267 M_J_DQS_DP<6> @BASEBOARD_FAB2_LIB.BASEBOARD_FAB2(SCH_1):M_J_DQS_DP(6)    I64 @BASEBOARD_FAB2_LIB.BASEBOARD_FAB2(SCH_1):PAGE82
   277 M_J_DQS_DN<7> @BASEBOARD_FAB2_LIB.BASEBOARD_FAB2(SCH_1):M_J_DQS_DN(7)    I64 @BASEBOARD_FAB2_LIB.BASEBOARD_FAB2(SCH_1):PAGE82
   278 M_J_DQS_DP<7> @BASEBOARD_FAB2_LIB.BASEBOARD_FAB2(SCH_1):M_J_DQS_DP(7)    I64 @BASEBOARD_FAB2_LIB.BASEBOARD_FAB2(SCH_1):PAGE82
   196 M_J_DQS_DN<8> @BASEBOARD_FAB2_LIB.BASEBOARD_FAB2(SCH_1):M_J_DQS_DN(8)    I64 @BASEBOARD_FAB2_LIB.BASEBOARD_FAB2(SCH_1):PAGE82
   197 M_J_DQS_DP<8> @BASEBOARD_FAB2_LIB.BASEBOARD_FAB2(SCH_1):M_J_DQS_DP(8)    I64 @BASEBOARD_FAB2_LIB.BASEBOARD_FAB2(SCH_1):PAGE82
     8 M_J_DQS_DN<9> @BASEBOARD_FAB2_LIB.BASEBOARD_FAB2(SCH_1):M_J_DQS_DN(9)    I64 @BASEBOARD_FAB2_LIB.BASEBOARD_FAB2(SCH_1):PAGE82
     7 M_J_DQS_DP<9> @BASEBOARD_FAB2_LIB.BASEBOARD_FAB2(SCH_1):M_J_DQS_DP(9)    I64 @BASEBOARD_FAB2_LIB.BASEBOARD_FAB2(SCH_1):PAGE82
     2    GND @BASEBOARD_FAB2_LIB.BASEBOARD_FAB2(SCH_1):GND   I188 @BASEBOARD_FAB2_LIB.BASEBOARD_FAB2(SCH_1):PAGE82
     4    GND @BASEBOARD_FAB2_LIB.BASEBOARD_FAB2(SCH_1):GND   I188 @BASEBOARD_FAB2_LIB.BASEBOARD_FAB2(SCH_1):PAGE82
     6    GND @BASEBOARD_FAB2_LIB.BASEBOARD_FAB2(SCH_1):GND   I188 @BASEBOARD_FAB2_LIB.BASEBOARD_FAB2(SCH_1):PAGE82
     9    GND @BASEBOARD_FAB2_LIB.BASEBOARD_FAB2(SCH_1):GND   I188 @BASEBOARD_FAB2_LIB.BASEBOARD_FAB2(SCH_1):PAGE82
    11    GND @BASEBOARD_FAB2_LIB.BASEBOARD_FAB2(SCH_1):GND   I188 @BASEBOARD_FAB2_LIB.BASEBOARD_FAB2(SCH_1):PAGE82
    13    GND @BASEBOARD_FAB2_LIB.BASEBOARD_FAB2(SCH_1):GND   I188 @BASEBOARD_FAB2_LIB.BASEBOARD_FAB2(SCH_1):PAGE82
    15    GND @BASEBOARD_FAB2_LIB.BASEBOARD_FAB2(SCH_1):GND   I188 @BASEBOARD_FAB2_LIB.BASEBOARD_FAB2(SCH_1):PAGE82
    17    GND @BASEBOARD_FAB2_LIB.BASEBOARD_FAB2(SCH_1):GND   I188 @BASEBOARD_FAB2_LIB.BASEBOARD_FAB2(SCH_1):PAGE82
    20    GND @BASEBOARD_FAB2_LIB.BASEBOARD_FAB2(SCH_1):GND   I188 @BASEBOARD_FAB2_LIB.BASEBOARD_FAB2(SCH_1):PAGE82
    22    GND @BASEBOARD_FAB2_LIB.BASEBOARD_FAB2(SCH_1):GND   I188 @BASEBOARD_FAB2_LIB.BASEBOARD_FAB2(SCH_1):PAGE82
    24    GND @BASEBOARD_FAB2_LIB.BASEBOARD_FAB2(SCH_1):GND   I188 @BASEBOARD_FAB2_LIB.BASEBOARD_FAB2(SCH_1):PAGE82
    26    GND @BASEBOARD_FAB2_LIB.BASEBOARD_FAB2(SCH_1):GND   I188 @BASEBOARD_FAB2_LIB.BASEBOARD_FAB2(SCH_1):PAGE82
    28    GND @BASEBOARD_FAB2_LIB.BASEBOARD_FAB2(SCH_1):GND   I188 @BASEBOARD_FAB2_LIB.BASEBOARD_FAB2(SCH_1):PAGE82
    31    GND @BASEBOARD_FAB2_LIB.BASEBOARD_FAB2(SCH_1):GND   I188 @BASEBOARD_FAB2_LIB.BASEBOARD_FAB2(SCH_1):PAGE82
    33    GND @BASEBOARD_FAB2_LIB.BASEBOARD_FAB2(SCH_1):GND   I188 @BASEBOARD_FAB2_LIB.BASEBOARD_FAB2(SCH_1):PAGE82
    35    GND @BASEBOARD_FAB2_LIB.BASEBOARD_FAB2(SCH_1):GND   I188 @BASEBOARD_FAB2_LIB.BASEBOARD_FAB2(SCH_1):PAGE82
    37    GND @BASEBOARD_FAB2_LIB.BASEBOARD_FAB2(SCH_1):GND   I188 @BASEBOARD_FAB2_LIB.BASEBOARD_FAB2(SCH_1):PAGE82
    39    GND @BASEBOARD_FAB2_LIB.BASEBOARD_FAB2(SCH_1):GND   I188 @BASEBOARD_FAB2_LIB.BASEBOARD_FAB2(SCH_1):PAGE82
    42    GND @BASEBOARD_FAB2_LIB.BASEBOARD_FAB2(SCH_1):GND   I188 @BASEBOARD_FAB2_LIB.BASEBOARD_FAB2(SCH_1):PAGE82
    44    GND @BASEBOARD_FAB2_LIB.BASEBOARD_FAB2(SCH_1):GND   I188 @BASEBOARD_FAB2_LIB.BASEBOARD_FAB2(SCH_1):PAGE82
    46    GND @BASEBOARD_FAB2_LIB.BASEBOARD_FAB2(SCH_1):GND   I188 @BASEBOARD_FAB2_LIB.BASEBOARD_FAB2(SCH_1):PAGE82
    48    GND @BASEBOARD_FAB2_LIB.BASEBOARD_FAB2(SCH_1):GND   I188 @BASEBOARD_FAB2_LIB.BASEBOARD_FAB2(SCH_1):PAGE82
    50    GND @BASEBOARD_FAB2_LIB.BASEBOARD_FAB2(SCH_1):GND   I188 @BASEBOARD_FAB2_LIB.BASEBOARD_FAB2(SCH_1):PAGE82
    53    GND @BASEBOARD_FAB2_LIB.BASEBOARD_FAB2(SCH_1):GND   I188 @BASEBOARD_FAB2_LIB.BASEBOARD_FAB2(SCH_1):PAGE82
    55    GND @BASEBOARD_FAB2_LIB.BASEBOARD_FAB2(SCH_1):GND   I188 @BASEBOARD_FAB2_LIB.BASEBOARD_FAB2(SCH_1):PAGE82
    57    GND @BASEBOARD_FAB2_LIB.BASEBOARD_FAB2(SCH_1):GND   I188 @BASEBOARD_FAB2_LIB.BASEBOARD_FAB2(SCH_1):PAGE82
    94    GND @BASEBOARD_FAB2_LIB.BASEBOARD_FAB2(SCH_1):GND   I188 @BASEBOARD_FAB2_LIB.BASEBOARD_FAB2(SCH_1):PAGE82
    96    GND @BASEBOARD_FAB2_LIB.BASEBOARD_FAB2(SCH_1):GND   I188 @BASEBOARD_FAB2_LIB.BASEBOARD_FAB2(SCH_1):PAGE82
    98    GND @BASEBOARD_FAB2_LIB.BASEBOARD_FAB2(SCH_1):GND   I188 @BASEBOARD_FAB2_LIB.BASEBOARD_FAB2(SCH_1):PAGE82
   101    GND @BASEBOARD_FAB2_LIB.BASEBOARD_FAB2(SCH_1):GND   I188 @BASEBOARD_FAB2_LIB.BASEBOARD_FAB2(SCH_1):PAGE82
   103    GND @BASEBOARD_FAB2_LIB.BASEBOARD_FAB2(SCH_1):GND   I188 @BASEBOARD_FAB2_LIB.BASEBOARD_FAB2(SCH_1):PAGE82
   105    GND @BASEBOARD_FAB2_LIB.BASEBOARD_FAB2(SCH_1):GND   I188 @BASEBOARD_FAB2_LIB.BASEBOARD_FAB2(SCH_1):PAGE82
   107    GND @BASEBOARD_FAB2_LIB.BASEBOARD_FAB2(SCH_1):GND   I188 @BASEBOARD_FAB2_LIB.BASEBOARD_FAB2(SCH_1):PAGE82
   109    GND @BASEBOARD_FAB2_LIB.BASEBOARD_FAB2(SCH_1):GND   I188 @BASEBOARD_FAB2_LIB.BASEBOARD_FAB2(SCH_1):PAGE82
   112    GND @BASEBOARD_FAB2_LIB.BASEBOARD_FAB2(SCH_1):GND   I188 @BASEBOARD_FAB2_LIB.BASEBOARD_FAB2(SCH_1):PAGE82
   114    GND @BASEBOARD_FAB2_LIB.BASEBOARD_FAB2(SCH_1):GND   I188 @BASEBOARD_FAB2_LIB.BASEBOARD_FAB2(SCH_1):PAGE82
   116    GND @BASEBOARD_FAB2_LIB.BASEBOARD_FAB2(SCH_1):GND   I188 @BASEBOARD_FAB2_LIB.BASEBOARD_FAB2(SCH_1):PAGE82
   118    GND @BASEBOARD_FAB2_LIB.BASEBOARD_FAB2(SCH_1):GND   I188 @BASEBOARD_FAB2_LIB.BASEBOARD_FAB2(SCH_1):PAGE82
   120    GND @BASEBOARD_FAB2_LIB.BASEBOARD_FAB2(SCH_1):GND   I188 @BASEBOARD_FAB2_LIB.BASEBOARD_FAB2(SCH_1):PAGE82
   123    GND @BASEBOARD_FAB2_LIB.BASEBOARD_FAB2(SCH_1):GND   I188 @BASEBOARD_FAB2_LIB.BASEBOARD_FAB2(SCH_1):PAGE82
   125    GND @BASEBOARD_FAB2_LIB.BASEBOARD_FAB2(SCH_1):GND   I188 @BASEBOARD_FAB2_LIB.BASEBOARD_FAB2(SCH_1):PAGE82
   127    GND @BASEBOARD_FAB2_LIB.BASEBOARD_FAB2(SCH_1):GND   I188 @BASEBOARD_FAB2_LIB.BASEBOARD_FAB2(SCH_1):PAGE82
   129    GND @BASEBOARD_FAB2_LIB.BASEBOARD_FAB2(SCH_1):GND   I188 @BASEBOARD_FAB2_LIB.BASEBOARD_FAB2(SCH_1):PAGE82
   131    GND @BASEBOARD_FAB2_LIB.BASEBOARD_FAB2(SCH_1):GND   I188 @BASEBOARD_FAB2_LIB.BASEBOARD_FAB2(SCH_1):PAGE82
   134    GND @BASEBOARD_FAB2_LIB.BASEBOARD_FAB2(SCH_1):GND   I188 @BASEBOARD_FAB2_LIB.BASEBOARD_FAB2(SCH_1):PAGE82
   136    GND @BASEBOARD_FAB2_LIB.BASEBOARD_FAB2(SCH_1):GND   I188 @BASEBOARD_FAB2_LIB.BASEBOARD_FAB2(SCH_1):PAGE82
   138    GND @BASEBOARD_FAB2_LIB.BASEBOARD_FAB2(SCH_1):GND   I188 @BASEBOARD_FAB2_LIB.BASEBOARD_FAB2(SCH_1):PAGE82
   147    GND @BASEBOARD_FAB2_LIB.BASEBOARD_FAB2(SCH_1):GND   I188 @BASEBOARD_FAB2_LIB.BASEBOARD_FAB2(SCH_1):PAGE82
   149    GND @BASEBOARD_FAB2_LIB.BASEBOARD_FAB2(SCH_1):GND   I188 @BASEBOARD_FAB2_LIB.BASEBOARD_FAB2(SCH_1):PAGE82
   151    GND @BASEBOARD_FAB2_LIB.BASEBOARD_FAB2(SCH_1):GND   I188 @BASEBOARD_FAB2_LIB.BASEBOARD_FAB2(SCH_1):PAGE82
   154    GND @BASEBOARD_FAB2_LIB.BASEBOARD_FAB2(SCH_1):GND   I188 @BASEBOARD_FAB2_LIB.BASEBOARD_FAB2(SCH_1):PAGE82
   156    GND @BASEBOARD_FAB2_LIB.BASEBOARD_FAB2(SCH_1):GND   I188 @BASEBOARD_FAB2_LIB.BASEBOARD_FAB2(SCH_1):PAGE82
   158    GND @BASEBOARD_FAB2_LIB.BASEBOARD_FAB2(SCH_1):GND   I188 @BASEBOARD_FAB2_LIB.BASEBOARD_FAB2(SCH_1):PAGE82
   160    GND @BASEBOARD_FAB2_LIB.BASEBOARD_FAB2(SCH_1):GND   I188 @BASEBOARD_FAB2_LIB.BASEBOARD_FAB2(SCH_1):PAGE82
   162    GND @BASEBOARD_FAB2_LIB.BASEBOARD_FAB2(SCH_1):GND   I188 @BASEBOARD_FAB2_LIB.BASEBOARD_FAB2(SCH_1):PAGE82
   165    GND @BASEBOARD_FAB2_LIB.BASEBOARD_FAB2(SCH_1):GND   I188 @BASEBOARD_FAB2_LIB.BASEBOARD_FAB2(SCH_1):PAGE82
   167    GND @BASEBOARD_FAB2_LIB.BASEBOARD_FAB2(SCH_1):GND   I188 @BASEBOARD_FAB2_LIB.BASEBOARD_FAB2(SCH_1):PAGE82
   169    GND @BASEBOARD_FAB2_LIB.BASEBOARD_FAB2(SCH_1):GND   I188 @BASEBOARD_FAB2_LIB.BASEBOARD_FAB2(SCH_1):PAGE82
   171    GND @BASEBOARD_FAB2_LIB.BASEBOARD_FAB2(SCH_1):GND   I188 @BASEBOARD_FAB2_LIB.BASEBOARD_FAB2(SCH_1):PAGE82
   173    GND @BASEBOARD_FAB2_LIB.BASEBOARD_FAB2(SCH_1):GND   I188 @BASEBOARD_FAB2_LIB.BASEBOARD_FAB2(SCH_1):PAGE82
   176    GND @BASEBOARD_FAB2_LIB.BASEBOARD_FAB2(SCH_1):GND   I188 @BASEBOARD_FAB2_LIB.BASEBOARD_FAB2(SCH_1):PAGE82
   178    GND @BASEBOARD_FAB2_LIB.BASEBOARD_FAB2(SCH_1):GND   I188 @BASEBOARD_FAB2_LIB.BASEBOARD_FAB2(SCH_1):PAGE82
   180    GND @BASEBOARD_FAB2_LIB.BASEBOARD_FAB2(SCH_1):GND   I188 @BASEBOARD_FAB2_LIB.BASEBOARD_FAB2(SCH_1):PAGE82
   182    GND @BASEBOARD_FAB2_LIB.BASEBOARD_FAB2(SCH_1):GND   I188 @BASEBOARD_FAB2_LIB.BASEBOARD_FAB2(SCH_1):PAGE82
   184    GND @BASEBOARD_FAB2_LIB.BASEBOARD_FAB2(SCH_1):GND   I188 @BASEBOARD_FAB2_LIB.BASEBOARD_FAB2(SCH_1):PAGE82
   187    GND @BASEBOARD_FAB2_LIB.BASEBOARD_FAB2(SCH_1):GND   I188 @BASEBOARD_FAB2_LIB.BASEBOARD_FAB2(SCH_1):PAGE82
   189    GND @BASEBOARD_FAB2_LIB.BASEBOARD_FAB2(SCH_1):GND   I188 @BASEBOARD_FAB2_LIB.BASEBOARD_FAB2(SCH_1):PAGE82
   191    GND @BASEBOARD_FAB2_LIB.BASEBOARD_FAB2(SCH_1):GND   I188 @BASEBOARD_FAB2_LIB.BASEBOARD_FAB2(SCH_1):PAGE82
   193    GND @BASEBOARD_FAB2_LIB.BASEBOARD_FAB2(SCH_1):GND   I188 @BASEBOARD_FAB2_LIB.BASEBOARD_FAB2(SCH_1):PAGE82
   195    GND @BASEBOARD_FAB2_LIB.BASEBOARD_FAB2(SCH_1):GND   I188 @BASEBOARD_FAB2_LIB.BASEBOARD_FAB2(SCH_1):PAGE82
   198    GND @BASEBOARD_FAB2_LIB.BASEBOARD_FAB2(SCH_1):GND   I188 @BASEBOARD_FAB2_LIB.BASEBOARD_FAB2(SCH_1):PAGE82
   200    GND @BASEBOARD_FAB2_LIB.BASEBOARD_FAB2(SCH_1):GND   I188 @BASEBOARD_FAB2_LIB.BASEBOARD_FAB2(SCH_1):PAGE82
   202    GND @BASEBOARD_FAB2_LIB.BASEBOARD_FAB2(SCH_1):GND   I188 @BASEBOARD_FAB2_LIB.BASEBOARD_FAB2(SCH_1):PAGE82
   239    GND @BASEBOARD_FAB2_LIB.BASEBOARD_FAB2(SCH_1):GND   I188 @BASEBOARD_FAB2_LIB.BASEBOARD_FAB2(SCH_1):PAGE82
   241    GND @BASEBOARD_FAB2_LIB.BASEBOARD_FAB2(SCH_1):GND   I188 @BASEBOARD_FAB2_LIB.BASEBOARD_FAB2(SCH_1):PAGE82
   243    GND @BASEBOARD_FAB2_LIB.BASEBOARD_FAB2(SCH_1):GND   I188 @BASEBOARD_FAB2_LIB.BASEBOARD_FAB2(SCH_1):PAGE82
   246    GND @BASEBOARD_FAB2_LIB.BASEBOARD_FAB2(SCH_1):GND   I188 @BASEBOARD_FAB2_LIB.BASEBOARD_FAB2(SCH_1):PAGE82
   248    GND @BASEBOARD_FAB2_LIB.BASEBOARD_FAB2(SCH_1):GND   I188 @BASEBOARD_FAB2_LIB.BASEBOARD_FAB2(SCH_1):PAGE82
   250    GND @BASEBOARD_FAB2_LIB.BASEBOARD_FAB2(SCH_1):GND   I188 @BASEBOARD_FAB2_LIB.BASEBOARD_FAB2(SCH_1):PAGE82
   252    GND @BASEBOARD_FAB2_LIB.BASEBOARD_FAB2(SCH_1):GND   I188 @BASEBOARD_FAB2_LIB.BASEBOARD_FAB2(SCH_1):PAGE82
   254    GND @BASEBOARD_FAB2_LIB.BASEBOARD_FAB2(SCH_1):GND   I188 @BASEBOARD_FAB2_LIB.BASEBOARD_FAB2(SCH_1):PAGE82
   257    GND @BASEBOARD_FAB2_LIB.BASEBOARD_FAB2(SCH_1):GND   I188 @BASEBOARD_FAB2_LIB.BASEBOARD_FAB2(SCH_1):PAGE82
   259    GND @BASEBOARD_FAB2_LIB.BASEBOARD_FAB2(SCH_1):GND   I188 @BASEBOARD_FAB2_LIB.BASEBOARD_FAB2(SCH_1):PAGE82
   261    GND @BASEBOARD_FAB2_LIB.BASEBOARD_FAB2(SCH_1):GND   I188 @BASEBOARD_FAB2_LIB.BASEBOARD_FAB2(SCH_1):PAGE82
   263    GND @BASEBOARD_FAB2_LIB.BASEBOARD_FAB2(SCH_1):GND   I188 @BASEBOARD_FAB2_LIB.BASEBOARD_FAB2(SCH_1):PAGE82
   265    GND @BASEBOARD_FAB2_LIB.BASEBOARD_FAB2(SCH_1):GND   I188 @BASEBOARD_FAB2_LIB.BASEBOARD_FAB2(SCH_1):PAGE82
   268    GND @BASEBOARD_FAB2_LIB.BASEBOARD_FAB2(SCH_1):GND   I188 @BASEBOARD_FAB2_LIB.BASEBOARD_FAB2(SCH_1):PAGE82
   270    GND @BASEBOARD_FAB2_LIB.BASEBOARD_FAB2(SCH_1):GND   I188 @BASEBOARD_FAB2_LIB.BASEBOARD_FAB2(SCH_1):PAGE82
   272    GND @BASEBOARD_FAB2_LIB.BASEBOARD_FAB2(SCH_1):GND   I188 @BASEBOARD_FAB2_LIB.BASEBOARD_FAB2(SCH_1):PAGE82
   274    GND @BASEBOARD_FAB2_LIB.BASEBOARD_FAB2(SCH_1):GND   I188 @BASEBOARD_FAB2_LIB.BASEBOARD_FAB2(SCH_1):PAGE82
   276    GND @BASEBOARD_FAB2_LIB.BASEBOARD_FAB2(SCH_1):GND   I188 @BASEBOARD_FAB2_LIB.BASEBOARD_FAB2(SCH_1):PAGE82
   279    GND @BASEBOARD_FAB2_LIB.BASEBOARD_FAB2(SCH_1):GND   I188 @BASEBOARD_FAB2_LIB.BASEBOARD_FAB2(SCH_1):PAGE82
   281    GND @BASEBOARD_FAB2_LIB.BASEBOARD_FAB2(SCH_1):GND   I188 @BASEBOARD_FAB2_LIB.BASEBOARD_FAB2(SCH_1):PAGE82
   283    GND @BASEBOARD_FAB2_LIB.BASEBOARD_FAB2(SCH_1):GND   I188 @BASEBOARD_FAB2_LIB.BASEBOARD_FAB2(SCH_1):PAGE82
     1 P12V_NVDIMM_GHJ @BASEBOARD_FAB2_LIB.BASEBOARD_FAB2(SCH_1):P12V_NVDIMM_GHJ   I171 @BASEBOARD_FAB2_LIB.BASEBOARD_FAB2(SCH_1):PAGE82
   145 P12V_NVDIMM_GHJ @BASEBOARD_FAB2_LIB.BASEBOARD_FAB2(SCH_1):P12V_NVDIMM_GHJ   I171 @BASEBOARD_FAB2_LIB.BASEBOARD_FAB2(SCH_1):PAGE82
    59 PVDDQ_GHJ @BASEBOARD_FAB2_LIB.BASEBOARD_FAB2(SCH_1):PVDDQ_GHJ   I171 @BASEBOARD_FAB2_LIB.BASEBOARD_FAB2(SCH_1):PAGE82
    61 PVDDQ_GHJ @BASEBOARD_FAB2_LIB.BASEBOARD_FAB2(SCH_1):PVDDQ_GHJ   I171 @BASEBOARD_FAB2_LIB.BASEBOARD_FAB2(SCH_1):PAGE82
    64 PVDDQ_GHJ @BASEBOARD_FAB2_LIB.BASEBOARD_FAB2(SCH_1):PVDDQ_GHJ   I171 @BASEBOARD_FAB2_LIB.BASEBOARD_FAB2(SCH_1):PAGE82
    67 PVDDQ_GHJ @BASEBOARD_FAB2_LIB.BASEBOARD_FAB2(SCH_1):PVDDQ_GHJ   I171 @BASEBOARD_FAB2_LIB.BASEBOARD_FAB2(SCH_1):PAGE82
    70 PVDDQ_GHJ @BASEBOARD_FAB2_LIB.BASEBOARD_FAB2(SCH_1):PVDDQ_GHJ   I171 @BASEBOARD_FAB2_LIB.BASEBOARD_FAB2(SCH_1):PAGE82
    73 PVDDQ_GHJ @BASEBOARD_FAB2_LIB.BASEBOARD_FAB2(SCH_1):PVDDQ_GHJ   I171 @BASEBOARD_FAB2_LIB.BASEBOARD_FAB2(SCH_1):PAGE82
    76 PVDDQ_GHJ @BASEBOARD_FAB2_LIB.BASEBOARD_FAB2(SCH_1):PVDDQ_GHJ   I171 @BASEBOARD_FAB2_LIB.BASEBOARD_FAB2(SCH_1):PAGE82
    80 PVDDQ_GHJ @BASEBOARD_FAB2_LIB.BASEBOARD_FAB2(SCH_1):PVDDQ_GHJ   I171 @BASEBOARD_FAB2_LIB.BASEBOARD_FAB2(SCH_1):PAGE82
    83 PVDDQ_GHJ @BASEBOARD_FAB2_LIB.BASEBOARD_FAB2(SCH_1):PVDDQ_GHJ   I171 @BASEBOARD_FAB2_LIB.BASEBOARD_FAB2(SCH_1):PAGE82
    85 PVDDQ_GHJ @BASEBOARD_FAB2_LIB.BASEBOARD_FAB2(SCH_1):PVDDQ_GHJ   I171 @BASEBOARD_FAB2_LIB.BASEBOARD_FAB2(SCH_1):PAGE82
    88 PVDDQ_GHJ @BASEBOARD_FAB2_LIB.BASEBOARD_FAB2(SCH_1):PVDDQ_GHJ   I171 @BASEBOARD_FAB2_LIB.BASEBOARD_FAB2(SCH_1):PAGE82
    90 PVDDQ_GHJ @BASEBOARD_FAB2_LIB.BASEBOARD_FAB2(SCH_1):PVDDQ_GHJ   I171 @BASEBOARD_FAB2_LIB.BASEBOARD_FAB2(SCH_1):PAGE82
    92 PVDDQ_GHJ @BASEBOARD_FAB2_LIB.BASEBOARD_FAB2(SCH_1):PVDDQ_GHJ   I171 @BASEBOARD_FAB2_LIB.BASEBOARD_FAB2(SCH_1):PAGE82
   204 PVDDQ_GHJ @BASEBOARD_FAB2_LIB.BASEBOARD_FAB2(SCH_1):PVDDQ_GHJ   I171 @BASEBOARD_FAB2_LIB.BASEBOARD_FAB2(SCH_1):PAGE82
   206 PVDDQ_GHJ @BASEBOARD_FAB2_LIB.BASEBOARD_FAB2(SCH_1):PVDDQ_GHJ   I171 @BASEBOARD_FAB2_LIB.BASEBOARD_FAB2(SCH_1):PAGE82
   209 PVDDQ_GHJ @BASEBOARD_FAB2_LIB.BASEBOARD_FAB2(SCH_1):PVDDQ_GHJ   I171 @BASEBOARD_FAB2_LIB.BASEBOARD_FAB2(SCH_1):PAGE82
   212 PVDDQ_GHJ @BASEBOARD_FAB2_LIB.BASEBOARD_FAB2(SCH_1):PVDDQ_GHJ   I171 @BASEBOARD_FAB2_LIB.BASEBOARD_FAB2(SCH_1):PAGE82
   215 PVDDQ_GHJ @BASEBOARD_FAB2_LIB.BASEBOARD_FAB2(SCH_1):PVDDQ_GHJ   I171 @BASEBOARD_FAB2_LIB.BASEBOARD_FAB2(SCH_1):PAGE82
   217 PVDDQ_GHJ @BASEBOARD_FAB2_LIB.BASEBOARD_FAB2(SCH_1):PVDDQ_GHJ   I171 @BASEBOARD_FAB2_LIB.BASEBOARD_FAB2(SCH_1):PAGE82
   220 PVDDQ_GHJ @BASEBOARD_FAB2_LIB.BASEBOARD_FAB2(SCH_1):PVDDQ_GHJ   I171 @BASEBOARD_FAB2_LIB.BASEBOARD_FAB2(SCH_1):PAGE82
   223 PVDDQ_GHJ @BASEBOARD_FAB2_LIB.BASEBOARD_FAB2(SCH_1):PVDDQ_GHJ   I171 @BASEBOARD_FAB2_LIB.BASEBOARD_FAB2(SCH_1):PAGE82
   226 PVDDQ_GHJ @BASEBOARD_FAB2_LIB.BASEBOARD_FAB2(SCH_1):PVDDQ_GHJ   I171 @BASEBOARD_FAB2_LIB.BASEBOARD_FAB2(SCH_1):PAGE82
   229 PVDDQ_GHJ @BASEBOARD_FAB2_LIB.BASEBOARD_FAB2(SCH_1):PVDDQ_GHJ   I171 @BASEBOARD_FAB2_LIB.BASEBOARD_FAB2(SCH_1):PAGE82
   231 PVDDQ_GHJ @BASEBOARD_FAB2_LIB.BASEBOARD_FAB2(SCH_1):PVDDQ_GHJ   I171 @BASEBOARD_FAB2_LIB.BASEBOARD_FAB2(SCH_1):PAGE82
   233 PVDDQ_GHJ @BASEBOARD_FAB2_LIB.BASEBOARD_FAB2(SCH_1):PVDDQ_GHJ   I171 @BASEBOARD_FAB2_LIB.BASEBOARD_FAB2(SCH_1):PAGE82
   236 PVDDQ_GHJ @BASEBOARD_FAB2_LIB.BASEBOARD_FAB2(SCH_1):PVDDQ_GHJ   I171 @BASEBOARD_FAB2_LIB.BASEBOARD_FAB2(SCH_1):PAGE82
   142 PVPP_GHJ @BASEBOARD_FAB2_LIB.BASEBOARD_FAB2(SCH_1):PVPP_GHJ   I171 @BASEBOARD_FAB2_LIB.BASEBOARD_FAB2(SCH_1):PAGE82
   143 PVPP_GHJ @BASEBOARD_FAB2_LIB.BASEBOARD_FAB2(SCH_1):PVPP_GHJ   I171 @BASEBOARD_FAB2_LIB.BASEBOARD_FAB2(SCH_1):PAGE82
   288 PVPP_GHJ @BASEBOARD_FAB2_LIB.BASEBOARD_FAB2(SCH_1):PVPP_GHJ   I171 @BASEBOARD_FAB2_LIB.BASEBOARD_FAB2(SCH_1):PAGE82
   286 PVPP_GHJ @BASEBOARD_FAB2_LIB.BASEBOARD_FAB2(SCH_1):PVPP_GHJ   I171 @BASEBOARD_FAB2_LIB.BASEBOARD_FAB2(SCH_1):PAGE82
   287 PVPP_GHJ @BASEBOARD_FAB2_LIB.BASEBOARD_FAB2(SCH_1):PVPP_GHJ   I171 @BASEBOARD_FAB2_LIB.BASEBOARD_FAB2(SCH_1):PAGE82
    77 PVTT_GHJ @BASEBOARD_FAB2_LIB.BASEBOARD_FAB2(SCH_1):PVTT_GHJ   I171 @BASEBOARD_FAB2_LIB.BASEBOARD_FAB2(SCH_1):PAGE82
   221 PVTT_GHJ @BASEBOARD_FAB2_LIB.BASEBOARD_FAB2(SCH_1):PVTT_GHJ   I171 @BASEBOARD_FAB2_LIB.BASEBOARD_FAB2(SCH_1):PAGE82

JA9G1 CONN17_H71061002_PIP1-CONN,H71A
   MH2 GND_NIC @BASEBOARD_FAB2_LIB.BASEBOARD_FAB2(SCH_1):GND_NIC   I109 @BASEBOARD_FAB2_LIB.BASEBOARD_FAB2(SCH_1):PAGE141
   MH1 GND_NIC @BASEBOARD_FAB2_LIB.BASEBOARD_FAB2(SCH_1):GND_NIC   I109 @BASEBOARD_FAB2_LIB.BASEBOARD_FAB2(SCH_1):PAGE141
    R1 GND_LAN_TRCT1234_C @BASEBOARD_FAB2_LIB.BASEBOARD_FAB2(SCH_1):GND_LAN_TRCT1234_C   I109 @BASEBOARD_FAB2_LIB.BASEBOARD_FAB2(SCH_1):PAGE141
    R2 NIC_MDI_SPRV_RJ45_2_R_DN @BASEBOARD_FAB2_LIB.BASEBOARD_FAB2(SCH_1):NIC_MDI_SPRV_RJ45_2_R_DN   I109 @BASEBOARD_FAB2_LIB.BASEBOARD_FAB2(SCH_1):PAGE141
    R3 NIC_MDI_SPRV_RJ45_2_R_DP @BASEBOARD_FAB2_LIB.BASEBOARD_FAB2(SCH_1):NIC_MDI_SPRV_RJ45_2_R_DP   I109 @BASEBOARD_FAB2_LIB.BASEBOARD_FAB2(SCH_1):PAGE141
    R4 NIC_MDI_SPRV_RJ45_1_R_DP @BASEBOARD_FAB2_LIB.BASEBOARD_FAB2(SCH_1):NIC_MDI_SPRV_RJ45_1_R_DP   I109 @BASEBOARD_FAB2_LIB.BASEBOARD_FAB2(SCH_1):PAGE141
    R5 NIC_MDI_SPRV_RJ45_1_R_DN @BASEBOARD_FAB2_LIB.BASEBOARD_FAB2(SCH_1):NIC_MDI_SPRV_RJ45_1_R_DN   I109 @BASEBOARD_FAB2_LIB.BASEBOARD_FAB2(SCH_1):PAGE141
    R6 GND_LAN_TRCT1234_C @BASEBOARD_FAB2_LIB.BASEBOARD_FAB2(SCH_1):GND_LAN_TRCT1234_C   I109 @BASEBOARD_FAB2_LIB.BASEBOARD_FAB2(SCH_1):PAGE141
    R7 GND_LAN_TRCT1234_C @BASEBOARD_FAB2_LIB.BASEBOARD_FAB2(SCH_1):GND_LAN_TRCT1234_C   I109 @BASEBOARD_FAB2_LIB.BASEBOARD_FAB2(SCH_1):PAGE141
    R8 NIC_MDI_SPRV_RJ45_3_R_DP @BASEBOARD_FAB2_LIB.BASEBOARD_FAB2(SCH_1):NIC_MDI_SPRV_RJ45_3_R_DP   I109 @BASEBOARD_FAB2_LIB.BASEBOARD_FAB2(SCH_1):PAGE141
    R9 NIC_MDI_SPRV_RJ45_3_R_DN @BASEBOARD_FAB2_LIB.BASEBOARD_FAB2(SCH_1):NIC_MDI_SPRV_RJ45_3_R_DN   I109 @BASEBOARD_FAB2_LIB.BASEBOARD_FAB2(SCH_1):PAGE141
   R10 NIC_MDI_SPRV_RJ45_0_R_DN @BASEBOARD_FAB2_LIB.BASEBOARD_FAB2(SCH_1):NIC_MDI_SPRV_RJ45_0_R_DN   I109 @BASEBOARD_FAB2_LIB.BASEBOARD_FAB2(SCH_1):PAGE141
   R11 NIC_MDI_SPRV_RJ45_0_R_DP @BASEBOARD_FAB2_LIB.BASEBOARD_FAB2(SCH_1):NIC_MDI_SPRV_RJ45_0_R_DP   I109 @BASEBOARD_FAB2_LIB.BASEBOARD_FAB2(SCH_1):PAGE141
   R12 GND_LAN_TRCT1234_C @BASEBOARD_FAB2_LIB.BASEBOARD_FAB2(SCH_1):GND_LAN_TRCT1234_C   I109 @BASEBOARD_FAB2_LIB.BASEBOARD_FAB2(SCH_1):PAGE141
    L3 LED_LAN_2_R_N @BASEBOARD_FAB2_LIB.BASEBOARD_FAB2(SCH_1):LED_LAN_2_R_N   I109 @BASEBOARD_FAB2_LIB.BASEBOARD_FAB2(SCH_1):PAGE141
    L2 P3V3_STBY @BASEBOARD_FAB2_LIB.BASEBOARD_FAB2(SCH_1):P3V3_STBY   I109 @BASEBOARD_FAB2_LIB.BASEBOARD_FAB2(SCH_1):PAGE141
    L1 LED_LAN_0_R_N @BASEBOARD_FAB2_LIB.BASEBOARD_FAB2(SCH_1):LED_LAN_0_R_N   I109 @BASEBOARD_FAB2_LIB.BASEBOARD_FAB2(SCH_1):PAGE141
    L5 LED_LAN_1_R_N @BASEBOARD_FAB2_LIB.BASEBOARD_FAB2(SCH_1):LED_LAN_1_R_N   I109 @BASEBOARD_FAB2_LIB.BASEBOARD_FAB2(SCH_1):PAGE141
    L4 NIC_LED_ACT_ANODE_R @BASEBOARD_FAB2_LIB.BASEBOARD_FAB2(SCH_1):NIC_LED_ACT_ANODE_R   I109 @BASEBOARD_FAB2_LIB.BASEBOARD_FAB2(SCH_1):PAGE141

L1A1 INDUCTOR_SM-0.12UH,IND,D92183-A
     1 VR_PVDDQ_KLM_PH2_SW @BASEBOARD_FAB2_LIB.BASEBOARD_FAB2(SCH_1):VR_PVDDQ_KLM_PH2_SW    I65 @BASEBOARD_FAB2_LIB.BASEBOARD_FAB2(SCH_1):PAGE227
     2 PVDDQ_KLM @BASEBOARD_FAB2_LIB.BASEBOARD_FAB2(SCH_1):PVDDQ_KLM    I65 @BASEBOARD_FAB2_LIB.BASEBOARD_FAB2(SCH_1):PAGE227

L1A2 INDUCTOR_SM-0.12UH,IND,D92183-A
     1 VR_PVDDQ_KLM_PH1_SW @BASEBOARD_FAB2_LIB.BASEBOARD_FAB2(SCH_1):VR_PVDDQ_KLM_PH1_SW    I55 @BASEBOARD_FAB2_LIB.BASEBOARD_FAB2(SCH_1):PAGE227
     2 PVDDQ_KLM @BASEBOARD_FAB2_LIB.BASEBOARD_FAB2(SCH_1):PVDDQ_KLM    I55 @BASEBOARD_FAB2_LIB.BASEBOARD_FAB2(SCH_1):PAGE227

L1B1 INDUCTOR_SM-100NH,IND,D92183-0B
     1 P12V_STBY @BASEBOARD_FAB2_LIB.BASEBOARD_FAB2(SCH_1):P12V_STBY   I124 @BASEBOARD_FAB2_LIB.BASEBOARD_FAB2(SCH_1):PAGE228
     2 VR_FET_SW_P12V_STBY_PVDDQ_KLM @BASEBOARD_FAB2_LIB.BASEBOARD_FAB2(SCH_1):VR_FET_SW_P12V_STBY_PVDDQ_KLM   I124 @BASEBOARD_FAB2_LIB.BASEBOARD_FAB2(SCH_1):PAGE228

L1B2 INDUCTOR_SM-100NH,IND,D92183-0A
     1 P12V_STBY @BASEBOARD_FAB2_LIB.BASEBOARD_FAB2(SCH_1):P12V_STBY    I32 @BASEBOARD_FAB2_LIB.BASEBOARD_FAB2(SCH_1):PAGE209
     2 VR_FET_SW_P12V_PVCCIN_CPU1_R @BASEBOARD_FAB2_LIB.BASEBOARD_FAB2(SCH_1):VR_FET_SW_P12V_PVCCIN_CPU1_R    I32 @BASEBOARD_FAB2_LIB.BASEBOARD_FAB2(SCH_1):PAGE209

L1C1 INDUCTOR_SM-0.3UH,IND,D92183-0A
     1 VR_PVSA_CPU1_PHASE_SW @BASEBOARD_FAB2_LIB.BASEBOARD_FAB2(SCH_1):VR_PVSA_CPU1_PHASE_SW    I10 @BASEBOARD_FAB2_LIB.BASEBOARD_FAB2(SCH_1):PAGE210
     2 PVSA_CPU1 @BASEBOARD_FAB2_LIB.BASEBOARD_FAB2(SCH_1):PVSA_CPU1    I10 @BASEBOARD_FAB2_LIB.BASEBOARD_FAB2(SCH_1):PAGE210

L1C2 INDUCTOR_SM-0.12UH,IND,D92183-A
     1 VR_PVCCIN_CPU1_PHASE5 @BASEBOARD_FAB2_LIB.BASEBOARD_FAB2(SCH_1):VR_PVCCIN_CPU1_PHASE5    I40 @BASEBOARD_FAB2_LIB.BASEBOARD_FAB2(SCH_1):PAGE209
     2 PVCCIN_CPU1 @BASEBOARD_FAB2_LIB.BASEBOARD_FAB2(SCH_1):PVCCIN_CPU1    I40 @BASEBOARD_FAB2_LIB.BASEBOARD_FAB2(SCH_1):PAGE209

L1D1 INDUCTOR_SM-0.12UH,IND,D92183-A
     1 VR_PVCCIN_CPU1_PHASE4 @BASEBOARD_FAB2_LIB.BASEBOARD_FAB2(SCH_1):VR_PVCCIN_CPU1_PHASE4    I20 @BASEBOARD_FAB2_LIB.BASEBOARD_FAB2(SCH_1):PAGE208
     2 PVCCIN_CPU1 @BASEBOARD_FAB2_LIB.BASEBOARD_FAB2(SCH_1):PVCCIN_CPU1    I20 @BASEBOARD_FAB2_LIB.BASEBOARD_FAB2(SCH_1):PAGE208

L1D2 INDUCTOR_SM-0.12UH,IND,D92183-A
     1 VR_PVCCIN_CPU1_PHASE3 @BASEBOARD_FAB2_LIB.BASEBOARD_FAB2(SCH_1):VR_PVCCIN_CPU1_PHASE3    I11 @BASEBOARD_FAB2_LIB.BASEBOARD_FAB2(SCH_1):PAGE208
     2 PVCCIN_CPU1 @BASEBOARD_FAB2_LIB.BASEBOARD_FAB2(SCH_1):PVCCIN_CPU1    I11 @BASEBOARD_FAB2_LIB.BASEBOARD_FAB2(SCH_1):PAGE208

L1D3 INDUCTOR_SM-0.12UH,IND,D92183-A
     1 VR_PVCCIN_CPU1_PHASE2 @BASEBOARD_FAB2_LIB.BASEBOARD_FAB2(SCH_1):VR_PVCCIN_CPU1_PHASE2    I16 @BASEBOARD_FAB2_LIB.BASEBOARD_FAB2(SCH_1):PAGE207
     2 PVCCIN_CPU1 @BASEBOARD_FAB2_LIB.BASEBOARD_FAB2(SCH_1):PVCCIN_CPU1    I16 @BASEBOARD_FAB2_LIB.BASEBOARD_FAB2(SCH_1):PAGE207

L1E1 INDUCTOR_SM-0.12UH,IND,D92183-A
     1 VR_PVCCIN_CPU1_PHASE1 @BASEBOARD_FAB2_LIB.BASEBOARD_FAB2(SCH_1):VR_PVCCIN_CPU1_PHASE1    I10 @BASEBOARD_FAB2_LIB.BASEBOARD_FAB2(SCH_1):PAGE207
     2 PVCCIN_CPU1 @BASEBOARD_FAB2_LIB.BASEBOARD_FAB2(SCH_1):PVCCIN_CPU1    I10 @BASEBOARD_FAB2_LIB.BASEBOARD_FAB2(SCH_1):PAGE207

L1F1 INDUCTOR_SM-100NH,IND,D92183-0B
     1 P12V_STBY @BASEBOARD_FAB2_LIB.BASEBOARD_FAB2(SCH_1):P12V_STBY   I124 @BASEBOARD_FAB2_LIB.BASEBOARD_FAB2(SCH_1):PAGE225
     2 VR_FET_SW_P12V_STBY_PVDDQ_GHJ @BASEBOARD_FAB2_LIB.BASEBOARD_FAB2(SCH_1):VR_FET_SW_P12V_STBY_PVDDQ_GHJ   I124 @BASEBOARD_FAB2_LIB.BASEBOARD_FAB2(SCH_1):PAGE225

L1F2 INDUCTOR_SM-0.12UH,IND,D92183-A
     1 VR_PVDDQ_GHJ_PH2_SW @BASEBOARD_FAB2_LIB.BASEBOARD_FAB2(SCH_1):VR_PVDDQ_GHJ_PH2_SW    I65 @BASEBOARD_FAB2_LIB.BASEBOARD_FAB2(SCH_1):PAGE224
     2 PVDDQ_GHJ @BASEBOARD_FAB2_LIB.BASEBOARD_FAB2(SCH_1):PVDDQ_GHJ    I65 @BASEBOARD_FAB2_LIB.BASEBOARD_FAB2(SCH_1):PAGE224

L1G1 INDUCTOR_SM-0.12UH,IND,D92183-A
     1 VR_PVDDQ_GHJ_PH1_SW @BASEBOARD_FAB2_LIB.BASEBOARD_FAB2(SCH_1):VR_PVDDQ_GHJ_PH1_SW    I55 @BASEBOARD_FAB2_LIB.BASEBOARD_FAB2(SCH_1):PAGE224
     2 PVDDQ_GHJ @BASEBOARD_FAB2_LIB.BASEBOARD_FAB2(SCH_1):PVDDQ_GHJ    I55 @BASEBOARD_FAB2_LIB.BASEBOARD_FAB2(SCH_1):PAGE224

L1M2 CHOKE_4PIN_SMLF-90 OHM,EMPTY,7A
     1 USB2_P01_DN @BASEBOARD_FAB2_LIB.BASEBOARD_FAB2(SCH_1):USB2_P01_DN    I30 @BASEBOARD_FAB2_LIB.BASEBOARD_FAB2(SCH_1):PAGE176
     2 USB2_P01_DP @BASEBOARD_FAB2_LIB.BASEBOARD_FAB2(SCH_1):USB2_P01_DP    I30 @BASEBOARD_FAB2_LIB.BASEBOARD_FAB2(SCH_1):PAGE176
     3 USB2_P01_ESD_DP @BASEBOARD_FAB2_LIB.BASEBOARD_FAB2(SCH_1):USB2_P01_ESD_DP    I30 @BASEBOARD_FAB2_LIB.BASEBOARD_FAB2(SCH_1):PAGE176
     4 USB2_P01_ESD_DN @BASEBOARD_FAB2_LIB.BASEBOARD_FAB2(SCH_1):USB2_P01_ESD_DN    I30 @BASEBOARD_FAB2_LIB.BASEBOARD_FAB2(SCH_1):PAGE176

L2M1 INDUCTOR_SMT-0.022UH,IND,72189A
     1 P1V05_PCH_STBY @BASEBOARD_FAB2_LIB.BASEBOARD_FAB2(SCH_1):P1V05_PCH_STBY    I71 @BASEBOARD_FAB2_LIB.BASEBOARD_FAB2(SCH_1):PAGE127
     2 P1V05_PCH_STBY_KR_PLL @BASEBOARD_FAB2_LIB.BASEBOARD_FAB2(SCH_1):P1V05_PCH_STBY_KR_PLL    I71 @BASEBOARD_FAB2_LIB.BASEBOARD_FAB2(SCH_1):PAGE127

L4A1 INDUCTOR_SM-0.47UH,IND,E13358-A
     1 VR_PVPP_KLM_PHASE @BASEBOARD_FAB2_LIB.BASEBOARD_FAB2(SCH_1):VR_PVPP_KLM_PHASE   I164 @BASEBOARD_FAB2_LIB.BASEBOARD_FAB2(SCH_1):PAGE234
     2 PVPP_KLM @BASEBOARD_FAB2_LIB.BASEBOARD_FAB2(SCH_1):PVPP_KLM   I164 @BASEBOARD_FAB2_LIB.BASEBOARD_FAB2(SCH_1):PAGE234

L4C1 INDUCTOR_SM-100NH,IND,D92183-0A
     1 P12V_STBY @BASEBOARD_FAB2_LIB.BASEBOARD_FAB2(SCH_1):P12V_STBY    I46 @BASEBOARD_FAB2_LIB.BASEBOARD_FAB2(SCH_1):PAGE204
     2 VR_FET_SW_P12V_PVCCIN_CPU0_R @BASEBOARD_FAB2_LIB.BASEBOARD_FAB2(SCH_1):VR_FET_SW_P12V_PVCCIN_CPU0_R    I46 @BASEBOARD_FAB2_LIB.BASEBOARD_FAB2(SCH_1):PAGE204

L4C2 INDUCTOR_SM-0.3UH,IND,D92183-0A
     1 VR_PVSA_CPU0_PHASE_SW @BASEBOARD_FAB2_LIB.BASEBOARD_FAB2(SCH_1):VR_PVSA_CPU0_PHASE_SW     I7 @BASEBOARD_FAB2_LIB.BASEBOARD_FAB2(SCH_1):PAGE205
     2 PVSA_CPU0 @BASEBOARD_FAB2_LIB.BASEBOARD_FAB2(SCH_1):PVSA_CPU0     I7 @BASEBOARD_FAB2_LIB.BASEBOARD_FAB2(SCH_1):PAGE205

L4C3 INDUCTOR_SM-0.12UH,IND,D92183-A
     1 VR_PVCCIN_CPU0_PHASE5 @BASEBOARD_FAB2_LIB.BASEBOARD_FAB2(SCH_1):VR_PVCCIN_CPU0_PHASE5     I5 @BASEBOARD_FAB2_LIB.BASEBOARD_FAB2(SCH_1):PAGE204
     2 PVCCIN_CPU0 @BASEBOARD_FAB2_LIB.BASEBOARD_FAB2(SCH_1):PVCCIN_CPU0     I5 @BASEBOARD_FAB2_LIB.BASEBOARD_FAB2(SCH_1):PAGE204

L4D1 INDUCTOR_SM-0.12UH,IND,D92183-A
     1 VR_PVCCIN_CPU0_PHASE4 @BASEBOARD_FAB2_LIB.BASEBOARD_FAB2(SCH_1):VR_PVCCIN_CPU0_PHASE4    I24 @BASEBOARD_FAB2_LIB.BASEBOARD_FAB2(SCH_1):PAGE203
     2 PVCCIN_CPU0 @BASEBOARD_FAB2_LIB.BASEBOARD_FAB2(SCH_1):PVCCIN_CPU0    I24 @BASEBOARD_FAB2_LIB.BASEBOARD_FAB2(SCH_1):PAGE203

L4D2 INDUCTOR_SM-0.12UH,IND,D92183-A
     1 VR_PVCCIN_CPU0_PHASE3 @BASEBOARD_FAB2_LIB.BASEBOARD_FAB2(SCH_1):VR_PVCCIN_CPU0_PHASE3    I15 @BASEBOARD_FAB2_LIB.BASEBOARD_FAB2(SCH_1):PAGE203
     2 PVCCIN_CPU0 @BASEBOARD_FAB2_LIB.BASEBOARD_FAB2(SCH_1):PVCCIN_CPU0    I15 @BASEBOARD_FAB2_LIB.BASEBOARD_FAB2(SCH_1):PAGE203

L4D3 INDUCTOR_SM-0.12UH,IND,D92183-A
     1 VR_PVCCIN_CPU0_PHASE2 @BASEBOARD_FAB2_LIB.BASEBOARD_FAB2(SCH_1):VR_PVCCIN_CPU0_PHASE2    I29 @BASEBOARD_FAB2_LIB.BASEBOARD_FAB2(SCH_1):PAGE202
     2 PVCCIN_CPU0 @BASEBOARD_FAB2_LIB.BASEBOARD_FAB2(SCH_1):PVCCIN_CPU0    I29 @BASEBOARD_FAB2_LIB.BASEBOARD_FAB2(SCH_1):PAGE202

L4E1 INDUCTOR_SM-0.12UH,IND,D92183-A
     1 VR_PVCCIN_CPU0_PHASE1 @BASEBOARD_FAB2_LIB.BASEBOARD_FAB2(SCH_1):VR_PVCCIN_CPU0_PHASE1     I5 @BASEBOARD_FAB2_LIB.BASEBOARD_FAB2(SCH_1):PAGE202
     2 PVCCIN_CPU0 @BASEBOARD_FAB2_LIB.BASEBOARD_FAB2(SCH_1):PVCCIN_CPU0     I5 @BASEBOARD_FAB2_LIB.BASEBOARD_FAB2(SCH_1):PAGE202

L4E2 INDUCTOR_SM-150NH,IND,D92183-0A
     1 VR_PVCCIO_CPU1_PH1_SW @BASEBOARD_FAB2_LIB.BASEBOARD_FAB2(SCH_1):VR_PVCCIO_CPU1_PH1_SW    I67 @BASEBOARD_FAB2_LIB.BASEBOARD_FAB2(SCH_1):PAGE214
     2 PVCCIO_CPU1 @BASEBOARD_FAB2_LIB.BASEBOARD_FAB2(SCH_1):PVCCIO_CPU1    I67 @BASEBOARD_FAB2_LIB.BASEBOARD_FAB2(SCH_1):PAGE214

L4G1 INDUCTOR_SM-0.47UH,IND,E13358-A
     1 VR_PVPP_GHJ_PHASE @BASEBOARD_FAB2_LIB.BASEBOARD_FAB2(SCH_1):VR_PVPP_GHJ_PHASE   I277 @BASEBOARD_FAB2_LIB.BASEBOARD_FAB2(SCH_1):PAGE233
     2 PVPP_GHJ @BASEBOARD_FAB2_LIB.BASEBOARD_FAB2(SCH_1):PVPP_GHJ   I277 @BASEBOARD_FAB2_LIB.BASEBOARD_FAB2(SCH_1):PAGE233

L7A1 INDUCTOR_SM-0.12UH,IND,D92183-A
     1 VR_PVDDQ_DEF_PH1_SW @BASEBOARD_FAB2_LIB.BASEBOARD_FAB2(SCH_1):VR_PVDDQ_DEF_PH1_SW    I55 @BASEBOARD_FAB2_LIB.BASEBOARD_FAB2(SCH_1):PAGE219
     2 PVDDQ_DEF @BASEBOARD_FAB2_LIB.BASEBOARD_FAB2(SCH_1):PVDDQ_DEF    I55 @BASEBOARD_FAB2_LIB.BASEBOARD_FAB2(SCH_1):PAGE219

L7A2 INDUCTOR_SM-0.3UH,IND,D92183-0A
     1 VR_PVNN_PCH_PH1_PHASE_SW @BASEBOARD_FAB2_LIB.BASEBOARD_FAB2(SCH_1):VR_PVNN_PCH_PH1_PHASE_SW    I10 @BASEBOARD_FAB2_LIB.BASEBOARD_FAB2(SCH_1):PAGE236
     2 PVNN_PCH_STBY @BASEBOARD_FAB2_LIB.BASEBOARD_FAB2(SCH_1):PVNN_PCH_STBY    I10 @BASEBOARD_FAB2_LIB.BASEBOARD_FAB2(SCH_1):PAGE236

L7A3 INDUCTOR_SM-0.12UH,IND,D92183-A
     1 VR_PVDDQ_DEF_PH2_SW @BASEBOARD_FAB2_LIB.BASEBOARD_FAB2(SCH_1):VR_PVDDQ_DEF_PH2_SW    I65 @BASEBOARD_FAB2_LIB.BASEBOARD_FAB2(SCH_1):PAGE219
     2 PVDDQ_DEF @BASEBOARD_FAB2_LIB.BASEBOARD_FAB2(SCH_1):PVDDQ_DEF    I65 @BASEBOARD_FAB2_LIB.BASEBOARD_FAB2(SCH_1):PAGE219

L7A4 INDUCTOR_SM-0.3UH,IND,D92183-0A
     1 VR_P1V05_PCH_STBY_PH1_PHASE_SW @BASEBOARD_FAB2_LIB.BASEBOARD_FAB2(SCH_1):VR_P1V05_PCH_STBY_PH1_PHASE_SW    I45 @BASEBOARD_FAB2_LIB.BASEBOARD_FAB2(SCH_1):PAGE236
     2 P1V05_PCH_STBY @BASEBOARD_FAB2_LIB.BASEBOARD_FAB2(SCH_1):P1V05_PCH_STBY    I45 @BASEBOARD_FAB2_LIB.BASEBOARD_FAB2(SCH_1):PAGE236

L7A5 INDUCTOR_SM-100NH,IND,D92183-0B
     1 P12V_STBY @BASEBOARD_FAB2_LIB.BASEBOARD_FAB2(SCH_1):P12V_STBY   I124 @BASEBOARD_FAB2_LIB.BASEBOARD_FAB2(SCH_1):PAGE220
     2 VR_FET_SW_P12V_STBY_PVDDQ_DEF @BASEBOARD_FAB2_LIB.BASEBOARD_FAB2(SCH_1):VR_FET_SW_P12V_STBY_PVDDQ_DEF   I124 @BASEBOARD_FAB2_LIB.BASEBOARD_FAB2(SCH_1):PAGE220

L7B1 INDUCTOR_SM-0.47UH,IND,E13358-A
     1 VR_PVPP_DEF_PHASE @BASEBOARD_FAB2_LIB.BASEBOARD_FAB2(SCH_1):VR_PVPP_DEF_PHASE   I239 @BASEBOARD_FAB2_LIB.BASEBOARD_FAB2(SCH_1):PAGE232
     2 PVPP_DEF @BASEBOARD_FAB2_LIB.BASEBOARD_FAB2(SCH_1):PVPP_DEF   I239 @BASEBOARD_FAB2_LIB.BASEBOARD_FAB2(SCH_1):PAGE232

L7C1 INDUCTOR_SM-100NH,IND,D92183-0B
     1 P12V_STBY @BASEBOARD_FAB2_LIB.BASEBOARD_FAB2(SCH_1):P12V_STBY    I56 @BASEBOARD_FAB2_LIB.BASEBOARD_FAB2(SCH_1):PAGE212
     2 VR_FET_SW_P12V_STBY_PVCCIO_CPU0 @BASEBOARD_FAB2_LIB.BASEBOARD_FAB2(SCH_1):VR_FET_SW_P12V_STBY_PVCCIO_CPU0    I56 @BASEBOARD_FAB2_LIB.BASEBOARD_FAB2(SCH_1):PAGE212

L7C2 INDUCTOR_SM-150NH,IND,D92183-0A
     1 VR_PVCCIO_CPU0_PH1_SW @BASEBOARD_FAB2_LIB.BASEBOARD_FAB2(SCH_1):VR_PVCCIO_CPU0_PH1_SW    I25 @BASEBOARD_FAB2_LIB.BASEBOARD_FAB2(SCH_1):PAGE212
     2 PVCCIO_CPU0 @BASEBOARD_FAB2_LIB.BASEBOARD_FAB2(SCH_1):PVCCIO_CPU0    I25 @BASEBOARD_FAB2_LIB.BASEBOARD_FAB2(SCH_1):PAGE212

L7F1 INDUCTOR_SM-0.47UH,IND,E13358-A
     1 VR_PVPP_ABC_PHASE @BASEBOARD_FAB2_LIB.BASEBOARD_FAB2(SCH_1):VR_PVPP_ABC_PHASE   I178 @BASEBOARD_FAB2_LIB.BASEBOARD_FAB2(SCH_1):PAGE231
     2 PVPP_ABC @BASEBOARD_FAB2_LIB.BASEBOARD_FAB2(SCH_1):PVPP_ABC   I178 @BASEBOARD_FAB2_LIB.BASEBOARD_FAB2(SCH_1):PAGE231

L7F2 INDUCTOR_SM-100NH,IND,D92183-0B
     1 P12V_STBY @BASEBOARD_FAB2_LIB.BASEBOARD_FAB2(SCH_1):P12V_STBY   I124 @BASEBOARD_FAB2_LIB.BASEBOARD_FAB2(SCH_1):PAGE217
     2 VR_FET_SW_P12V_STBY_PVDDQ_ABC @BASEBOARD_FAB2_LIB.BASEBOARD_FAB2(SCH_1):VR_FET_SW_P12V_STBY_PVDDQ_ABC   I124 @BASEBOARD_FAB2_LIB.BASEBOARD_FAB2(SCH_1):PAGE217

L7G1 INDUCTOR_SM-0.12UH,IND,D92183-A
     1 VR_PVDDQ_ABC_PH1_SW @BASEBOARD_FAB2_LIB.BASEBOARD_FAB2(SCH_1):VR_PVDDQ_ABC_PH1_SW   I125 @BASEBOARD_FAB2_LIB.BASEBOARD_FAB2(SCH_1):PAGE216
     2 PVDDQ_ABC @BASEBOARD_FAB2_LIB.BASEBOARD_FAB2(SCH_1):PVDDQ_ABC   I125 @BASEBOARD_FAB2_LIB.BASEBOARD_FAB2(SCH_1):PAGE216

L7G2 INDUCTOR_SM-0.12UH,IND,D92183-A
     1 VR_PVDDQ_ABC_PH2_SW @BASEBOARD_FAB2_LIB.BASEBOARD_FAB2(SCH_1):VR_PVDDQ_ABC_PH2_SW    I65 @BASEBOARD_FAB2_LIB.BASEBOARD_FAB2(SCH_1):PAGE216
     2 PVDDQ_ABC @BASEBOARD_FAB2_LIB.BASEBOARD_FAB2(SCH_1):PVDDQ_ABC    I65 @BASEBOARD_FAB2_LIB.BASEBOARD_FAB2(SCH_1):PAGE216

L8E1 INDUCTOR_SM-2.2UH,IND,E98761-0A
     1 VR_P5V_STBY_PHASE @BASEBOARD_FAB2_LIB.BASEBOARD_FAB2(SCH_1):VR_P5V_STBY_PHASE    I90 @BASEBOARD_FAB2_LIB.BASEBOARD_FAB2(SCH_1):PAGE241
     2 P5V_STBY @BASEBOARD_FAB2_LIB.BASEBOARD_FAB2(SCH_1):P5V_STBY    I90 @BASEBOARD_FAB2_LIB.BASEBOARD_FAB2(SCH_1):PAGE241

L8F1 INDUCTOR_SM-1.00UH,IND,E98679-A
     1 VR_P3V3_STBY_PHASE @BASEBOARD_FAB2_LIB.BASEBOARD_FAB2(SCH_1):VR_P3V3_STBY_PHASE   I173 @BASEBOARD_FAB2_LIB.BASEBOARD_FAB2(SCH_1):PAGE240
     2 P3V3_STBY @BASEBOARD_FAB2_LIB.BASEBOARD_FAB2(SCH_1):P3V3_STBY   I173 @BASEBOARD_FAB2_LIB.BASEBOARD_FAB2(SCH_1):PAGE240

LB2B1 SNLABEL_A_LABEL-EMPTY,N_A

LB2F1 SNLABEL_A_LABEL-EMPTY,N_A

LB5B1 SNLABEL_A_LABEL-EMPTY,N_A

LB5F1 SNLABEL_A_LABEL-EMPTY,N_A

LB6T1 SNLABEL_A_LABEL-EMPTY,N_A

Q1B1 MOSFET_N_LCC3-BSZ019N03LS,NFETA
     4 P12V_FAN_SWITCH_G @BASEBOARD_FAB2_LIB.BASEBOARD_FAB2(SCH_1):P12V_FAN_SWITCH_G    I86 @BASEBOARD_FAB2_LIB.BASEBOARD_FAB2(SCH_1):PAGE198
     1 P12V_FAN @BASEBOARD_FAB2_LIB.BASEBOARD_FAB2(SCH_1):P12V_FAN    I86 @BASEBOARD_FAB2_LIB.BASEBOARD_FAB2(SCH_1):PAGE198
     5 P12V_STBY @BASEBOARD_FAB2_LIB.BASEBOARD_FAB2(SCH_1):P12V_STBY    I86 @BASEBOARD_FAB2_LIB.BASEBOARD_FAB2(SCH_1):PAGE198

Q1D1 FET_N_DUAL_SMLF-2N7002DW,FET,DA
     2 A_HSC_LOW_EN @BASEBOARD_FAB2_LIB.BASEBOARD_FAB2(SCH_1):A_HSC_LOW_EN    I86 @BASEBOARD_FAB2_LIB.BASEBOARD_FAB2(SCH_1):PAGE199
     1 AGND_HSC @BASEBOARD_FAB2_LIB.BASEBOARD_FAB2(SCH_1):AGND_HSC    I86 @BASEBOARD_FAB2_LIB.BASEBOARD_FAB2(SCH_1):PAGE199
     6 A_HSC_ISET_S2 @BASEBOARD_FAB2_LIB.BASEBOARD_FAB2(SCH_1):A_HSC_ISET_S2    I86 @BASEBOARD_FAB2_LIB.BASEBOARD_FAB2(SCH_1):PAGE199
     5 A_HSC_HIGH_EN @BASEBOARD_FAB2_LIB.BASEBOARD_FAB2(SCH_1):A_HSC_HIGH_EN    I82 @BASEBOARD_FAB2_LIB.BASEBOARD_FAB2(SCH_1):PAGE199
     4 AGND_HSC @BASEBOARD_FAB2_LIB.BASEBOARD_FAB2(SCH_1):AGND_HSC    I82 @BASEBOARD_FAB2_LIB.BASEBOARD_FAB2(SCH_1):PAGE199
     3 A_HSC_ISET_S @BASEBOARD_FAB2_LIB.BASEBOARD_FAB2(SCH_1):A_HSC_ISET_S    I82 @BASEBOARD_FAB2_LIB.BASEBOARD_FAB2(SCH_1):PAGE199

Q1D2 FET_N_SOT23LF-2N7002,FET,C7925A
     1 FM_OC_DETECT_EN_N @BASEBOARD_FAB2_LIB.BASEBOARD_FAB2(SCH_1):FM_OC_DETECT_EN_N   I203 @BASEBOARD_FAB2_LIB.BASEBOARD_FAB2(SCH_1):PAGE200
     2    GND @BASEBOARD_FAB2_LIB.BASEBOARD_FAB2(SCH_1):GND   I203 @BASEBOARD_FAB2_LIB.BASEBOARD_FAB2(SCH_1):PAGE200
     3 FM_OC_DETECT_EN @BASEBOARD_FAB2_LIB.BASEBOARD_FAB2(SCH_1):FM_OC_DETECT_EN   I203 @BASEBOARD_FAB2_LIB.BASEBOARD_FAB2(SCH_1):PAGE200

Q1D3 NPN_SM-MMBT3904,IC,C52245-001
     1 A_HSC_TEMP @BASEBOARD_FAB2_LIB.BASEBOARD_FAB2(SCH_1):A_HSC_TEMP    I58 @BASEBOARD_FAB2_LIB.BASEBOARD_FAB2(SCH_1):PAGE199
     3 A_HSC_TEMP @BASEBOARD_FAB2_LIB.BASEBOARD_FAB2(SCH_1):A_HSC_TEMP    I58 @BASEBOARD_FAB2_LIB.BASEBOARD_FAB2(SCH_1):PAGE199
     2    GND @BASEBOARD_FAB2_LIB.BASEBOARD_FAB2(SCH_1):GND    I58 @BASEBOARD_FAB2_LIB.BASEBOARD_FAB2(SCH_1):PAGE199

Q1E1 PNP_TO92-MPS2907,IC,G73554-001
     1 ISENSE_TMP421_2_BC @BASEBOARD_FAB2_LIB.BASEBOARD_FAB2(SCH_1):ISENSE_TMP421_2_BC    I27 @BASEBOARD_FAB2_LIB.BASEBOARD_FAB2(SCH_1):PAGE167
     3 ISENSE_TMP421_2_BC @BASEBOARD_FAB2_LIB.BASEBOARD_FAB2(SCH_1):ISENSE_TMP421_2_BC    I27 @BASEBOARD_FAB2_LIB.BASEBOARD_FAB2(SCH_1):PAGE167
     2 ISENSE_TMP421_2_E @BASEBOARD_FAB2_LIB.BASEBOARD_FAB2(SCH_1):ISENSE_TMP421_2_E    I27 @BASEBOARD_FAB2_LIB.BASEBOARD_FAB2(SCH_1):PAGE167

Q1L2 FET_N_DUAL_SMLF-NTJD4001N,FET,A
     2 FM_CPLD_DBG_PWR_EN @BASEBOARD_FAB2_LIB.BASEBOARD_FAB2(SCH_1):FM_CPLD_DBG_PWR_EN   I188 @BASEBOARD_FAB2_LIB.BASEBOARD_FAB2(SCH_1):PAGE155
     1 P5V_STBY_DBG @BASEBOARD_FAB2_LIB.BASEBOARD_FAB2(SCH_1):P5V_STBY_DBG   I188 @BASEBOARD_FAB2_LIB.BASEBOARD_FAB2(SCH_1):PAGE155
     6 P5V_STBY @BASEBOARD_FAB2_LIB.BASEBOARD_FAB2(SCH_1):P5V_STBY   I188 @BASEBOARD_FAB2_LIB.BASEBOARD_FAB2(SCH_1):PAGE155
     5 FM_CPLD_DBG_PWR_EN_R_N @BASEBOARD_FAB2_LIB.BASEBOARD_FAB2(SCH_1):FM_CPLD_DBG_PWR_EN_R_N   I187 @BASEBOARD_FAB2_LIB.BASEBOARD_FAB2(SCH_1):PAGE155
     4    GND @BASEBOARD_FAB2_LIB.BASEBOARD_FAB2(SCH_1):GND   I187 @BASEBOARD_FAB2_LIB.BASEBOARD_FAB2(SCH_1):PAGE155
     3 FM_CPLD_DBG_PWR_EN @BASEBOARD_FAB2_LIB.BASEBOARD_FAB2(SCH_1):FM_CPLD_DBG_PWR_EN   I187 @BASEBOARD_FAB2_LIB.BASEBOARD_FAB2(SCH_1):PAGE155

Q1L3 NPN_SM-MMBT3904,IC,C52245-001
     1 FM_DB_UART_SEL4_N @BASEBOARD_FAB2_LIB.BASEBOARD_FAB2(SCH_1):FM_DB_UART_SEL4_N     I8 @BASEBOARD_FAB2_LIB.BASEBOARD_FAB2(SCH_1):PAGE168
     3 FM_DB_PRESENT @BASEBOARD_FAB2_LIB.BASEBOARD_FAB2(SCH_1):FM_DB_PRESENT     I8 @BASEBOARD_FAB2_LIB.BASEBOARD_FAB2(SCH_1):PAGE168
     2    GND @BASEBOARD_FAB2_LIB.BASEBOARD_FAB2(SCH_1):GND     I8 @BASEBOARD_FAB2_LIB.BASEBOARD_FAB2(SCH_1):PAGE168

Q1L4 FET_N_DUAL_SMLF-2N7002DW,FET,DA
     2 FM_DB_PRESENT @BASEBOARD_FAB2_LIB.BASEBOARD_FAB2(SCH_1):FM_DB_PRESENT    I19 @BASEBOARD_FAB2_LIB.BASEBOARD_FAB2(SCH_1):PAGE168
     1    GND @BASEBOARD_FAB2_LIB.BASEBOARD_FAB2(SCH_1):GND    I19 @BASEBOARD_FAB2_LIB.BASEBOARD_FAB2(SCH_1):PAGE168
     6 FM_POST_CARD_PRES_BMC_N @BASEBOARD_FAB2_LIB.BASEBOARD_FAB2(SCH_1):FM_POST_CARD_PRES_BMC_N    I19 @BASEBOARD_FAB2_LIB.BASEBOARD_FAB2(SCH_1):PAGE168
     5 TP_FET_Q56_4 @BASEBOARD_FAB2_LIB.BASEBOARD_FAB2(SCH_1):TP_FET_Q56_4    I18 @BASEBOARD_FAB2_LIB.BASEBOARD_FAB2(SCH_1):PAGE168
     4 TP_FET_Q56_4 @BASEBOARD_FAB2_LIB.BASEBOARD_FAB2(SCH_1):TP_FET_Q56_4    I18 @BASEBOARD_FAB2_LIB.BASEBOARD_FAB2(SCH_1):PAGE168
     3 TP_FET_Q56_3 @BASEBOARD_FAB2_LIB.BASEBOARD_FAB2(SCH_1):TP_FET_Q56_3    I18 @BASEBOARD_FAB2_LIB.BASEBOARD_FAB2(SCH_1):PAGE168

Q2P1 FET_N_SOT23LF-2N7002,FET,C7925A
     1 FM_PMBUS_ALERT_BUF_EN_N @BASEBOARD_FAB2_LIB.BASEBOARD_FAB2(SCH_1):FM_PMBUS_ALERT_BUF_EN_N    I58 @BASEBOARD_FAB2_LIB.BASEBOARD_FAB2(SCH_1):PAGE170
     2    GND @BASEBOARD_FAB2_LIB.BASEBOARD_FAB2(SCH_1):GND    I58 @BASEBOARD_FAB2_LIB.BASEBOARD_FAB2(SCH_1):PAGE170
     3 FM_PMBUS_ALERT_BUF_EN @BASEBOARD_FAB2_LIB.BASEBOARD_FAB2(SCH_1):FM_PMBUS_ALERT_BUF_EN    I58 @BASEBOARD_FAB2_LIB.BASEBOARD_FAB2(SCH_1):PAGE170

Q2P2 FET_N_SOT23-2N7002,FET,C79254-A
     1 PWRGD_P5V_N @BASEBOARD_FAB2_LIB.BASEBOARD_FAB2(SCH_1):PWRGD_P5V_N   I124 @BASEBOARD_FAB2_LIB.BASEBOARD_FAB2(SCH_1):PAGE196
     2    GND @BASEBOARD_FAB2_LIB.BASEBOARD_FAB2(SCH_1):GND   I124 @BASEBOARD_FAB2_LIB.BASEBOARD_FAB2(SCH_1):PAGE196
     3 PWRGD_P5V_R @BASEBOARD_FAB2_LIB.BASEBOARD_FAB2(SCH_1):PWRGD_P5V_R   I124 @BASEBOARD_FAB2_LIB.BASEBOARD_FAB2(SCH_1):PAGE196

Q2T1 NPN_SM-MMBT3904,IC,C52245-001
     1 H_CPU0_FAST_WAKE_B_N @BASEBOARD_FAB2_LIB.BASEBOARD_FAB2(SCH_1):H_CPU0_FAST_WAKE_B_N   I330 @BASEBOARD_FAB2_LIB.BASEBOARD_FAB2(SCH_1):PAGE157
     3 H_CPU0_FAST_WAKE @BASEBOARD_FAB2_LIB.BASEBOARD_FAB2(SCH_1):H_CPU0_FAST_WAKE   I330 @BASEBOARD_FAB2_LIB.BASEBOARD_FAB2(SCH_1):PAGE157
     2    GND @BASEBOARD_FAB2_LIB.BASEBOARD_FAB2(SCH_1):GND   I330 @BASEBOARD_FAB2_LIB.BASEBOARD_FAB2(SCH_1):PAGE157

Q2T2 FET_N_SOT23LF-2N7002,FET,C7925A
     1 H_CPU0_FAST_WAKE @BASEBOARD_FAB2_LIB.BASEBOARD_FAB2(SCH_1):H_CPU0_FAST_WAKE   I340 @BASEBOARD_FAB2_LIB.BASEBOARD_FAB2(SCH_1):PAGE157
     2    GND @BASEBOARD_FAB2_LIB.BASEBOARD_FAB2(SCH_1):GND   I340 @BASEBOARD_FAB2_LIB.BASEBOARD_FAB2(SCH_1):PAGE157
     3 H_CPU0_FAST_WAKE_LVT3_N @BASEBOARD_FAB2_LIB.BASEBOARD_FAB2(SCH_1):H_CPU0_FAST_WAKE_LVT3_N   I340 @BASEBOARD_FAB2_LIB.BASEBOARD_FAB2(SCH_1):PAGE157

Q2U1 FET_N_DUAL_SMLF-NTJD4001N,FET,A
     2 FM_SYS_THROTTLE_LVC3 @BASEBOARD_FAB2_LIB.BASEBOARD_FAB2(SCH_1):FM_SYS_THROTTLE_LVC3    I28 @BASEBOARD_FAB2_LIB.BASEBOARD_FAB2(SCH_1):PAGE95
     1    GND @BASEBOARD_FAB2_LIB.BASEBOARD_FAB2(SCH_1):GND    I28 @BASEBOARD_FAB2_LIB.BASEBOARD_FAB2(SCH_1):PAGE95
     6 H_CPU0_MEMABC_MEMHOT_G_N @BASEBOARD_FAB2_LIB.BASEBOARD_FAB2(SCH_1):H_CPU0_MEMABC_MEMHOT_G_N    I28 @BASEBOARD_FAB2_LIB.BASEBOARD_FAB2(SCH_1):PAGE95
     5 FM_SYS_THROTTLE_LVC3 @BASEBOARD_FAB2_LIB.BASEBOARD_FAB2(SCH_1):FM_SYS_THROTTLE_LVC3   I113 @BASEBOARD_FAB2_LIB.BASEBOARD_FAB2(SCH_1):PAGE95
     4    GND @BASEBOARD_FAB2_LIB.BASEBOARD_FAB2(SCH_1):GND   I113 @BASEBOARD_FAB2_LIB.BASEBOARD_FAB2(SCH_1):PAGE95
     3 H_CPU0_MEMDEF_MEMHOT_G_N @BASEBOARD_FAB2_LIB.BASEBOARD_FAB2(SCH_1):H_CPU0_MEMDEF_MEMHOT_G_N   I113 @BASEBOARD_FAB2_LIB.BASEBOARD_FAB2(SCH_1):PAGE95

Q3U1 FET_N_DUAL_SMLF-NTJD4001N,FET,A
     2 IRQ_PVDDQ_ABC_VRHOT_LVT3_N @BASEBOARD_FAB2_LIB.BASEBOARD_FAB2(SCH_1):IRQ_PVDDQ_ABC_VRHOT_LVT3_N    I49 @BASEBOARD_FAB2_LIB.BASEBOARD_FAB2(SCH_1):PAGE94
     1    GND @BASEBOARD_FAB2_LIB.BASEBOARD_FAB2(SCH_1):GND    I49 @BASEBOARD_FAB2_LIB.BASEBOARD_FAB2(SCH_1):PAGE94
     6 H_CPU0_MEMABC_MEMHOT @BASEBOARD_FAB2_LIB.BASEBOARD_FAB2(SCH_1):H_CPU0_MEMABC_MEMHOT    I49 @BASEBOARD_FAB2_LIB.BASEBOARD_FAB2(SCH_1):PAGE94
     5 H_CPU0_MEMABC_MEMHOT @BASEBOARD_FAB2_LIB.BASEBOARD_FAB2(SCH_1):H_CPU0_MEMABC_MEMHOT    I89 @BASEBOARD_FAB2_LIB.BASEBOARD_FAB2(SCH_1):PAGE94
     4    GND @BASEBOARD_FAB2_LIB.BASEBOARD_FAB2(SCH_1):GND    I89 @BASEBOARD_FAB2_LIB.BASEBOARD_FAB2(SCH_1):PAGE94
     3 H_CPU0_MEMABC_MEMHOT_G_N @BASEBOARD_FAB2_LIB.BASEBOARD_FAB2(SCH_1):H_CPU0_MEMABC_MEMHOT_G_N    I89 @BASEBOARD_FAB2_LIB.BASEBOARD_FAB2(SCH_1):PAGE94

Q4B1 FET_N_DUAL_SMLF-NTJD4001N,FET,A
     2 IRQ_PVDDQ_KLM_VRHOT_LVT3_N @BASEBOARD_FAB2_LIB.BASEBOARD_FAB2(SCH_1):IRQ_PVDDQ_KLM_VRHOT_LVT3_N    I84 @BASEBOARD_FAB2_LIB.BASEBOARD_FAB2(SCH_1):PAGE94
     1    GND @BASEBOARD_FAB2_LIB.BASEBOARD_FAB2(SCH_1):GND    I84 @BASEBOARD_FAB2_LIB.BASEBOARD_FAB2(SCH_1):PAGE94
     6 H_CPU1_MEMKLM_MEMHOT @BASEBOARD_FAB2_LIB.BASEBOARD_FAB2(SCH_1):H_CPU1_MEMKLM_MEMHOT    I84 @BASEBOARD_FAB2_LIB.BASEBOARD_FAB2(SCH_1):PAGE94
     5 H_CPU1_MEMKLM_MEMHOT @BASEBOARD_FAB2_LIB.BASEBOARD_FAB2(SCH_1):H_CPU1_MEMKLM_MEMHOT    I77 @BASEBOARD_FAB2_LIB.BASEBOARD_FAB2(SCH_1):PAGE94
     4    GND @BASEBOARD_FAB2_LIB.BASEBOARD_FAB2(SCH_1):GND    I77 @BASEBOARD_FAB2_LIB.BASEBOARD_FAB2(SCH_1):PAGE94
     3 H_CPU1_MEMKLM_MEMHOT_G_N @BASEBOARD_FAB2_LIB.BASEBOARD_FAB2(SCH_1):H_CPU1_MEMKLM_MEMHOT_G_N    I77 @BASEBOARD_FAB2_LIB.BASEBOARD_FAB2(SCH_1):PAGE94

Q4B2 FET_N_DUAL_SMLF-NTJD4001N,FET,A
     2 FM_SYS_THROTTLE_LVC3 @BASEBOARD_FAB2_LIB.BASEBOARD_FAB2(SCH_1):FM_SYS_THROTTLE_LVC3    I32 @BASEBOARD_FAB2_LIB.BASEBOARD_FAB2(SCH_1):PAGE95
     1    GND @BASEBOARD_FAB2_LIB.BASEBOARD_FAB2(SCH_1):GND    I32 @BASEBOARD_FAB2_LIB.BASEBOARD_FAB2(SCH_1):PAGE95
     6 H_CPU1_MEMGHJ_MEMHOT_G_N @BASEBOARD_FAB2_LIB.BASEBOARD_FAB2(SCH_1):H_CPU1_MEMGHJ_MEMHOT_G_N    I32 @BASEBOARD_FAB2_LIB.BASEBOARD_FAB2(SCH_1):PAGE95
     5 FM_SYS_THROTTLE_LVC3 @BASEBOARD_FAB2_LIB.BASEBOARD_FAB2(SCH_1):FM_SYS_THROTTLE_LVC3    I33 @BASEBOARD_FAB2_LIB.BASEBOARD_FAB2(SCH_1):PAGE95
     4    GND @BASEBOARD_FAB2_LIB.BASEBOARD_FAB2(SCH_1):GND    I33 @BASEBOARD_FAB2_LIB.BASEBOARD_FAB2(SCH_1):PAGE95
     3 H_CPU1_MEMKLM_MEMHOT_G_N @BASEBOARD_FAB2_LIB.BASEBOARD_FAB2(SCH_1):H_CPU1_MEMKLM_MEMHOT_G_N    I33 @BASEBOARD_FAB2_LIB.BASEBOARD_FAB2(SCH_1):PAGE95

Q4U1 FET_N_DUAL_SMLF-NTJD4001N,FET,A
     2 FM_DIMM_EVENT_COD_N @BASEBOARD_FAB2_LIB.BASEBOARD_FAB2(SCH_1):FM_DIMM_EVENT_COD_N    I98 @BASEBOARD_FAB2_LIB.BASEBOARD_FAB2(SCH_1):PAGE94
     1    GND @BASEBOARD_FAB2_LIB.BASEBOARD_FAB2(SCH_1):GND    I98 @BASEBOARD_FAB2_LIB.BASEBOARD_FAB2(SCH_1):PAGE94
     6 FM_DIMM_EVENT_FET @BASEBOARD_FAB2_LIB.BASEBOARD_FAB2(SCH_1):FM_DIMM_EVENT_FET    I98 @BASEBOARD_FAB2_LIB.BASEBOARD_FAB2(SCH_1):PAGE94
     5 FM_DIMM_EVENT_FET @BASEBOARD_FAB2_LIB.BASEBOARD_FAB2(SCH_1):FM_DIMM_EVENT_FET   I102 @BASEBOARD_FAB2_LIB.BASEBOARD_FAB2(SCH_1):PAGE94
     4    GND @BASEBOARD_FAB2_LIB.BASEBOARD_FAB2(SCH_1):GND   I102 @BASEBOARD_FAB2_LIB.BASEBOARD_FAB2(SCH_1):PAGE94
     3 FM_MEM_THERM_EVENT_LVT3_N @BASEBOARD_FAB2_LIB.BASEBOARD_FAB2(SCH_1):FM_MEM_THERM_EVENT_LVT3_N   I102 @BASEBOARD_FAB2_LIB.BASEBOARD_FAB2(SCH_1):PAGE94

Q6F1 FET_N_SOT23-2N7002,FET,C79254-A
     1 FM_ADR_COMPLETE_R @BASEBOARD_FAB2_LIB.BASEBOARD_FAB2(SCH_1):FM_ADR_COMPLETE_R    I18 @BASEBOARD_FAB2_LIB.BASEBOARD_FAB2(SCH_1):PAGE89
     2    GND @BASEBOARD_FAB2_LIB.BASEBOARD_FAB2(SCH_1):GND    I18 @BASEBOARD_FAB2_LIB.BASEBOARD_FAB2(SCH_1):PAGE89
     3 IRQ_DIMM_SAVE_N @BASEBOARD_FAB2_LIB.BASEBOARD_FAB2(SCH_1):IRQ_DIMM_SAVE_N    I18 @BASEBOARD_FAB2_LIB.BASEBOARD_FAB2(SCH_1):PAGE89

Q6W1 FET_N_SOT23LF-2N7002,FET,C7925A
     1 BMC_UV_HIGH_SET @BASEBOARD_FAB2_LIB.BASEBOARD_FAB2(SCH_1):BMC_UV_HIGH_SET   I225 @BASEBOARD_FAB2_LIB.BASEBOARD_FAB2(SCH_1):PAGE200
     2    GND @BASEBOARD_FAB2_LIB.BASEBOARD_FAB2(SCH_1):GND   I225 @BASEBOARD_FAB2_LIB.BASEBOARD_FAB2(SCH_1):PAGE200
     3 UV_HIGH_SET_N @BASEBOARD_FAB2_LIB.BASEBOARD_FAB2(SCH_1):UV_HIGH_SET_N   I225 @BASEBOARD_FAB2_LIB.BASEBOARD_FAB2(SCH_1):PAGE200

Q6W2 FET_N_DUAL_SMLF-2N7002DW,FET,DA
     2 FM_UART_SEL_N @BASEBOARD_FAB2_LIB.BASEBOARD_FAB2(SCH_1):FM_UART_SEL_N    I30 @BASEBOARD_FAB2_LIB.BASEBOARD_FAB2(SCH_1):PAGE168
     1    GND @BASEBOARD_FAB2_LIB.BASEBOARD_FAB2(SCH_1):GND    I30 @BASEBOARD_FAB2_LIB.BASEBOARD_FAB2(SCH_1):PAGE168
     6 FM_SOL_UART_CH_SEL @BASEBOARD_FAB2_LIB.BASEBOARD_FAB2(SCH_1):FM_SOL_UART_CH_SEL    I30 @BASEBOARD_FAB2_LIB.BASEBOARD_FAB2(SCH_1):PAGE168

Q6W3 NPN_SM-MMBT3904,IC,C52245-001
     1 UART_SELECT_Q @BASEBOARD_FAB2_LIB.BASEBOARD_FAB2(SCH_1):UART_SELECT_Q    I37 @BASEBOARD_FAB2_LIB.BASEBOARD_FAB2(SCH_1):PAGE168
     3 FM_UART_SEL_N @BASEBOARD_FAB2_LIB.BASEBOARD_FAB2(SCH_1):FM_UART_SEL_N    I37 @BASEBOARD_FAB2_LIB.BASEBOARD_FAB2(SCH_1):PAGE168
     2 FM_UART_SWITCH_N @BASEBOARD_FAB2_LIB.BASEBOARD_FAB2(SCH_1):FM_UART_SWITCH_N    I37 @BASEBOARD_FAB2_LIB.BASEBOARD_FAB2(SCH_1):PAGE168

Q7D1 FET_N_SOT23-2N7002,FET,C79254-A
     1 FM_THERMTRIP_DLY_R @BASEBOARD_FAB2_LIB.BASEBOARD_FAB2(SCH_1):FM_THERMTRIP_DLY_R    I10 @BASEBOARD_FAB2_LIB.BASEBOARD_FAB2(SCH_1):PAGE134
     2    GND @BASEBOARD_FAB2_LIB.BASEBOARD_FAB2(SCH_1):GND    I10 @BASEBOARD_FAB2_LIB.BASEBOARD_FAB2(SCH_1):PAGE134
     3 FM_PCH_LVC1_THERMTRIP_N @BASEBOARD_FAB2_LIB.BASEBOARD_FAB2(SCH_1):FM_PCH_LVC1_THERMTRIP_N    I10 @BASEBOARD_FAB2_LIB.BASEBOARD_FAB2(SCH_1):PAGE134

Q7E1 FET_N_DUAL_SMLF-NTJD4001N,FET,A
     2 IRQ_PVDDQ_DEF_VRHOT_LVT3_N @BASEBOARD_FAB2_LIB.BASEBOARD_FAB2(SCH_1):IRQ_PVDDQ_DEF_VRHOT_LVT3_N    I60 @BASEBOARD_FAB2_LIB.BASEBOARD_FAB2(SCH_1):PAGE94
     1    GND @BASEBOARD_FAB2_LIB.BASEBOARD_FAB2(SCH_1):GND    I60 @BASEBOARD_FAB2_LIB.BASEBOARD_FAB2(SCH_1):PAGE94
     6 H_CPU0_MEMDEF_MEMHOT @BASEBOARD_FAB2_LIB.BASEBOARD_FAB2(SCH_1):H_CPU0_MEMDEF_MEMHOT    I60 @BASEBOARD_FAB2_LIB.BASEBOARD_FAB2(SCH_1):PAGE94
     5 H_CPU0_MEMDEF_MEMHOT @BASEBOARD_FAB2_LIB.BASEBOARD_FAB2(SCH_1):H_CPU0_MEMDEF_MEMHOT    I64 @BASEBOARD_FAB2_LIB.BASEBOARD_FAB2(SCH_1):PAGE94
     4    GND @BASEBOARD_FAB2_LIB.BASEBOARD_FAB2(SCH_1):GND    I64 @BASEBOARD_FAB2_LIB.BASEBOARD_FAB2(SCH_1):PAGE94
     3 H_CPU0_MEMDEF_MEMHOT_G_N @BASEBOARD_FAB2_LIB.BASEBOARD_FAB2(SCH_1):H_CPU0_MEMDEF_MEMHOT_G_N    I64 @BASEBOARD_FAB2_LIB.BASEBOARD_FAB2(SCH_1):PAGE94

Q7E2 FET_N_DUAL_SMLF-NTJD4001N,FET,A
     2 IRQ_PVDDQ_GHJ_VRHOT_LVT3_N @BASEBOARD_FAB2_LIB.BASEBOARD_FAB2(SCH_1):IRQ_PVDDQ_GHJ_VRHOT_LVT3_N    I69 @BASEBOARD_FAB2_LIB.BASEBOARD_FAB2(SCH_1):PAGE94
     1    GND @BASEBOARD_FAB2_LIB.BASEBOARD_FAB2(SCH_1):GND    I69 @BASEBOARD_FAB2_LIB.BASEBOARD_FAB2(SCH_1):PAGE94
     6 H_CPU1_MEMGHJ_MEMHOT @BASEBOARD_FAB2_LIB.BASEBOARD_FAB2(SCH_1):H_CPU1_MEMGHJ_MEMHOT    I69 @BASEBOARD_FAB2_LIB.BASEBOARD_FAB2(SCH_1):PAGE94
     5 H_CPU1_MEMGHJ_MEMHOT @BASEBOARD_FAB2_LIB.BASEBOARD_FAB2(SCH_1):H_CPU1_MEMGHJ_MEMHOT    I75 @BASEBOARD_FAB2_LIB.BASEBOARD_FAB2(SCH_1):PAGE94
     4    GND @BASEBOARD_FAB2_LIB.BASEBOARD_FAB2(SCH_1):GND    I75 @BASEBOARD_FAB2_LIB.BASEBOARD_FAB2(SCH_1):PAGE94
     3 H_CPU1_MEMGHJ_MEMHOT_G_N @BASEBOARD_FAB2_LIB.BASEBOARD_FAB2(SCH_1):H_CPU1_MEMGHJ_MEMHOT_G_N    I75 @BASEBOARD_FAB2_LIB.BASEBOARD_FAB2(SCH_1):PAGE94

Q7E3 FET_N_DUAL_SMLF-NTJD4001N,FET,A
     2 FM_SYS_THROTTLE_LVC3 @BASEBOARD_FAB2_LIB.BASEBOARD_FAB2(SCH_1):FM_SYS_THROTTLE_LVC3    I52 @BASEBOARD_FAB2_LIB.BASEBOARD_FAB2(SCH_1):PAGE95
     1    GND @BASEBOARD_FAB2_LIB.BASEBOARD_FAB2(SCH_1):GND    I52 @BASEBOARD_FAB2_LIB.BASEBOARD_FAB2(SCH_1):PAGE95
     6 H_CPU0_PROCHOT_G_N @BASEBOARD_FAB2_LIB.BASEBOARD_FAB2(SCH_1):H_CPU0_PROCHOT_G_N    I52 @BASEBOARD_FAB2_LIB.BASEBOARD_FAB2(SCH_1):PAGE95
     5 FM_SYS_THROTTLE_LVC3 @BASEBOARD_FAB2_LIB.BASEBOARD_FAB2(SCH_1):FM_SYS_THROTTLE_LVC3    I51 @BASEBOARD_FAB2_LIB.BASEBOARD_FAB2(SCH_1):PAGE95
     4    GND @BASEBOARD_FAB2_LIB.BASEBOARD_FAB2(SCH_1):GND    I51 @BASEBOARD_FAB2_LIB.BASEBOARD_FAB2(SCH_1):PAGE95
     3 H_CPU1_PROCHOT_G_N @BASEBOARD_FAB2_LIB.BASEBOARD_FAB2(SCH_1):H_CPU1_PROCHOT_G_N    I51 @BASEBOARD_FAB2_LIB.BASEBOARD_FAB2(SCH_1):PAGE95

Q7E4 FET_N_SOT23-2N7002,FET,C79254-A
     1 FM_THROTTLE_R_N @BASEBOARD_FAB2_LIB.BASEBOARD_FAB2(SCH_1):FM_THROTTLE_R_N   I104 @BASEBOARD_FAB2_LIB.BASEBOARD_FAB2(SCH_1):PAGE95
     2    GND @BASEBOARD_FAB2_LIB.BASEBOARD_FAB2(SCH_1):GND   I104 @BASEBOARD_FAB2_LIB.BASEBOARD_FAB2(SCH_1):PAGE95
     3 FM_SYS_THROTTLE_LVC3 @BASEBOARD_FAB2_LIB.BASEBOARD_FAB2(SCH_1):FM_SYS_THROTTLE_LVC3   I104 @BASEBOARD_FAB2_LIB.BASEBOARD_FAB2(SCH_1):PAGE95

Q7E5 FET_N_DUAL_SMLF-NTJD4001N,FET,A
     2 IRQ_CPU0_PROCHOT_G_N @BASEBOARD_FAB2_LIB.BASEBOARD_FAB2(SCH_1):IRQ_CPU0_PROCHOT_G_N   I111 @BASEBOARD_FAB2_LIB.BASEBOARD_FAB2(SCH_1):PAGE95
     1    GND @BASEBOARD_FAB2_LIB.BASEBOARD_FAB2(SCH_1):GND   I111 @BASEBOARD_FAB2_LIB.BASEBOARD_FAB2(SCH_1):PAGE95
     6 IRQ_CPU0_VRHOT @BASEBOARD_FAB2_LIB.BASEBOARD_FAB2(SCH_1):IRQ_CPU0_VRHOT   I111 @BASEBOARD_FAB2_LIB.BASEBOARD_FAB2(SCH_1):PAGE95
     5 IRQ_CPU0_VRHOT @BASEBOARD_FAB2_LIB.BASEBOARD_FAB2(SCH_1):IRQ_CPU0_VRHOT    I59 @BASEBOARD_FAB2_LIB.BASEBOARD_FAB2(SCH_1):PAGE95
     4    GND @BASEBOARD_FAB2_LIB.BASEBOARD_FAB2(SCH_1):GND    I59 @BASEBOARD_FAB2_LIB.BASEBOARD_FAB2(SCH_1):PAGE95
     3 H_CPU0_PROCHOT_G_N @BASEBOARD_FAB2_LIB.BASEBOARD_FAB2(SCH_1):H_CPU0_PROCHOT_G_N    I59 @BASEBOARD_FAB2_LIB.BASEBOARD_FAB2(SCH_1):PAGE95

Q7E6 FET_N_DUAL_SMLF-NTJD4001N,FET,A
     2 IRQ_CPU1_PROCHOT_G_N @BASEBOARD_FAB2_LIB.BASEBOARD_FAB2(SCH_1):IRQ_CPU1_PROCHOT_G_N   I112 @BASEBOARD_FAB2_LIB.BASEBOARD_FAB2(SCH_1):PAGE95
     1    GND @BASEBOARD_FAB2_LIB.BASEBOARD_FAB2(SCH_1):GND   I112 @BASEBOARD_FAB2_LIB.BASEBOARD_FAB2(SCH_1):PAGE95
     6 IRQ_CPU1_VRHOT @BASEBOARD_FAB2_LIB.BASEBOARD_FAB2(SCH_1):IRQ_CPU1_VRHOT   I112 @BASEBOARD_FAB2_LIB.BASEBOARD_FAB2(SCH_1):PAGE95
     5 IRQ_CPU1_VRHOT @BASEBOARD_FAB2_LIB.BASEBOARD_FAB2(SCH_1):IRQ_CPU1_VRHOT    I69 @BASEBOARD_FAB2_LIB.BASEBOARD_FAB2(SCH_1):PAGE95
     4    GND @BASEBOARD_FAB2_LIB.BASEBOARD_FAB2(SCH_1):GND    I69 @BASEBOARD_FAB2_LIB.BASEBOARD_FAB2(SCH_1):PAGE95
     3 H_CPU1_PROCHOT_G_N @BASEBOARD_FAB2_LIB.BASEBOARD_FAB2(SCH_1):H_CPU1_PROCHOT_G_N    I69 @BASEBOARD_FAB2_LIB.BASEBOARD_FAB2(SCH_1):PAGE95

Q7E7 MOSFET_N_LCC3-BSZ019N03LS,NFETA
     4 P12V_SWITCH_G @BASEBOARD_FAB2_LIB.BASEBOARD_FAB2(SCH_1):P12V_SWITCH_G    I88 @BASEBOARD_FAB2_LIB.BASEBOARD_FAB2(SCH_1):PAGE198
     1   P12V @BASEBOARD_FAB2_LIB.BASEBOARD_FAB2(SCH_1):P12V    I88 @BASEBOARD_FAB2_LIB.BASEBOARD_FAB2(SCH_1):PAGE198
     5 P12V_STBY @BASEBOARD_FAB2_LIB.BASEBOARD_FAB2(SCH_1):P12V_STBY    I88 @BASEBOARD_FAB2_LIB.BASEBOARD_FAB2(SCH_1):PAGE198

Q7E8 FET_N_SOT23-2N7002,FET,C79254-A
     1 FM_SYS_THROTTLE_LVC3 @BASEBOARD_FAB2_LIB.BASEBOARD_FAB2(SCH_1):FM_SYS_THROTTLE_LVC3   I119 @BASEBOARD_FAB2_LIB.BASEBOARD_FAB2(SCH_1):PAGE95
     2    GND @BASEBOARD_FAB2_LIB.BASEBOARD_FAB2(SCH_1):GND   I119 @BASEBOARD_FAB2_LIB.BASEBOARD_FAB2(SCH_1):PAGE95
     3 FM_PWRBRK_N @BASEBOARD_FAB2_LIB.BASEBOARD_FAB2(SCH_1):FM_PWRBRK_N   I119 @BASEBOARD_FAB2_LIB.BASEBOARD_FAB2(SCH_1):PAGE95

Q8B1 MOSFET_N_LCC3-BSZ019N03LS,NFETA
     4 P5V_SWITCH_G @BASEBOARD_FAB2_LIB.BASEBOARD_FAB2(SCH_1):P5V_SWITCH_G    I87 @BASEBOARD_FAB2_LIB.BASEBOARD_FAB2(SCH_1):PAGE198
     1    P5V @BASEBOARD_FAB2_LIB.BASEBOARD_FAB2(SCH_1):P5V    I87 @BASEBOARD_FAB2_LIB.BASEBOARD_FAB2(SCH_1):PAGE198
     5 P5V_STBY @BASEBOARD_FAB2_LIB.BASEBOARD_FAB2(SCH_1):P5V_STBY    I87 @BASEBOARD_FAB2_LIB.BASEBOARD_FAB2(SCH_1):PAGE198

Q8D1 NPN_DUAL_SSOPLF-MBT3904,XSTR,CA
     5 IRQ_DIMM_SAVE_R_N @BASEBOARD_FAB2_LIB.BASEBOARD_FAB2(SCH_1):IRQ_DIMM_SAVE_R_N    I35 @BASEBOARD_FAB2_LIB.BASEBOARD_FAB2(SCH_1):PAGE89
     3 IRQ_DIMM_SAVE_LVT3 @BASEBOARD_FAB2_LIB.BASEBOARD_FAB2(SCH_1):IRQ_DIMM_SAVE_LVT3    I35 @BASEBOARD_FAB2_LIB.BASEBOARD_FAB2(SCH_1):PAGE89
     4    GND @BASEBOARD_FAB2_LIB.BASEBOARD_FAB2(SCH_1):GND    I35 @BASEBOARD_FAB2_LIB.BASEBOARD_FAB2(SCH_1):PAGE89
     2 IRQ_DIMM_SAVE_LVT3 @BASEBOARD_FAB2_LIB.BASEBOARD_FAB2(SCH_1):IRQ_DIMM_SAVE_LVT3    I36 @BASEBOARD_FAB2_LIB.BASEBOARD_FAB2(SCH_1):PAGE89
     6 IRQ_DIMM_SAVE_LVT3_N @BASEBOARD_FAB2_LIB.BASEBOARD_FAB2(SCH_1):IRQ_DIMM_SAVE_LVT3_N    I36 @BASEBOARD_FAB2_LIB.BASEBOARD_FAB2(SCH_1):PAGE89
     1    GND @BASEBOARD_FAB2_LIB.BASEBOARD_FAB2(SCH_1):GND    I36 @BASEBOARD_FAB2_LIB.BASEBOARD_FAB2(SCH_1):PAGE89

Q8D2 FET_N_SOT23-2N7002,FET,C79254-A
     1 RST_PLTRST_BUF_N @BASEBOARD_FAB2_LIB.BASEBOARD_FAB2(SCH_1):RST_PLTRST_BUF_N     I4 @BASEBOARD_FAB2_LIB.BASEBOARD_FAB2(SCH_1):PAGE134
     2 FM_PCH_BMC_THERMTRIP_EXI_STRAP_ @BASEBOARD_FAB2_LIB.BASEBOARD_FAB2(SCH_1):FM_PCH_BMC_THERMTRIP_EXI_STRAP_N     I4 @BASEBOARD_FAB2_LIB.BASEBOARD_FAB2(SCH_1):PAGE134
     3 FM_PCH_BMC_THERMTRIP_N @BASEBOARD_FAB2_LIB.BASEBOARD_FAB2(SCH_1):FM_PCH_BMC_THERMTRIP_N     I4 @BASEBOARD_FAB2_LIB.BASEBOARD_FAB2(SCH_1):PAGE134

Q8E1 FET_N_SOT23LF-2N7002,FET,C7925A
     1 RST_PLTRST_N @BASEBOARD_FAB2_LIB.BASEBOARD_FAB2(SCH_1):RST_PLTRST_N   I134 @BASEBOARD_FAB2_LIB.BASEBOARD_FAB2(SCH_1):PAGE136
     2    GND @BASEBOARD_FAB2_LIB.BASEBOARD_FAB2(SCH_1):GND   I134 @BASEBOARD_FAB2_LIB.BASEBOARD_FAB2(SCH_1):PAGE136
     3 RST_PLTRST_TOP_SWAP @BASEBOARD_FAB2_LIB.BASEBOARD_FAB2(SCH_1):RST_PLTRST_TOP_SWAP   I134 @BASEBOARD_FAB2_LIB.BASEBOARD_FAB2(SCH_1):PAGE136

Q8E2 FET_N_SOT23LF-2N7002,FET,C7925A
     1 RST_RSMRST_DLY @BASEBOARD_FAB2_LIB.BASEBOARD_FAB2(SCH_1):RST_RSMRST_DLY    I13 @BASEBOARD_FAB2_LIB.BASEBOARD_FAB2(SCH_1):PAGE126
     2    GND @BASEBOARD_FAB2_LIB.BASEBOARD_FAB2(SCH_1):GND    I13 @BASEBOARD_FAB2_LIB.BASEBOARD_FAB2(SCH_1):PAGE126
     3 IRQ_SML0_ALERT_N @BASEBOARD_FAB2_LIB.BASEBOARD_FAB2(SCH_1):IRQ_SML0_ALERT_N    I13 @BASEBOARD_FAB2_LIB.BASEBOARD_FAB2(SCH_1):PAGE126

Q8F1 FET_N_SOT23LF-2N7002,FET,C7925A
     1 FM_BACKUP_BIOS_SEL_N @BASEBOARD_FAB2_LIB.BASEBOARD_FAB2(SCH_1):FM_BACKUP_BIOS_SEL_N   I126 @BASEBOARD_FAB2_LIB.BASEBOARD_FAB2(SCH_1):PAGE154
     2    GND @BASEBOARD_FAB2_LIB.BASEBOARD_FAB2(SCH_1):GND   I126 @BASEBOARD_FAB2_LIB.BASEBOARD_FAB2(SCH_1):PAGE154
     3 FM_DUAL_BIOS_SEL_N @BASEBOARD_FAB2_LIB.BASEBOARD_FAB2(SCH_1):FM_DUAL_BIOS_SEL_N   I126 @BASEBOARD_FAB2_LIB.BASEBOARD_FAB2(SCH_1):PAGE154

Q8F2 FET_N_SOT23LF-2N7002,FET,C7925A
     1 FM_FAST_PROCHOT_EN_N @BASEBOARD_FAB2_LIB.BASEBOARD_FAB2(SCH_1):FM_FAST_PROCHOT_EN_N    I67 @BASEBOARD_FAB2_LIB.BASEBOARD_FAB2(SCH_1):PAGE170
     2    GND @BASEBOARD_FAB2_LIB.BASEBOARD_FAB2(SCH_1):GND    I67 @BASEBOARD_FAB2_LIB.BASEBOARD_FAB2(SCH_1):PAGE170
     3 FM_FAST_PROCHOT_EN @BASEBOARD_FAB2_LIB.BASEBOARD_FAB2(SCH_1):FM_FAST_PROCHOT_EN    I67 @BASEBOARD_FAB2_LIB.BASEBOARD_FAB2(SCH_1):PAGE170

Q8G1 MOSFET_N_LCC3-BSZ019N03LS,NFETA
     4 P3V3_SWITCH_G @BASEBOARD_FAB2_LIB.BASEBOARD_FAB2(SCH_1):P3V3_SWITCH_G    I85 @BASEBOARD_FAB2_LIB.BASEBOARD_FAB2(SCH_1):PAGE198
     1   P3V3 @BASEBOARD_FAB2_LIB.BASEBOARD_FAB2(SCH_1):P3V3    I85 @BASEBOARD_FAB2_LIB.BASEBOARD_FAB2(SCH_1):PAGE198
     5 P3V3_STBY @BASEBOARD_FAB2_LIB.BASEBOARD_FAB2(SCH_1):P3V3_STBY    I85 @BASEBOARD_FAB2_LIB.BASEBOARD_FAB2(SCH_1):PAGE198

Q9A1 NPN_DUAL_SSOPLF-MBT3904,EMPTY,A
     5 XDP_CPU_TCK_BUF @BASEBOARD_FAB2_LIB.BASEBOARD_FAB2(SCH_1):XDP_CPU_TCK_BUF    I94 @BASEBOARD_FAB2_LIB.BASEBOARD_FAB2(SCH_1):PAGE111
     3   P3V3 @BASEBOARD_FAB2_LIB.BASEBOARD_FAB2(SCH_1):P3V3    I94 @BASEBOARD_FAB2_LIB.BASEBOARD_FAB2(SCH_1):PAGE111
     4 XDP_CPU_TCK0 @BASEBOARD_FAB2_LIB.BASEBOARD_FAB2(SCH_1):XDP_CPU_TCK0    I94 @BASEBOARD_FAB2_LIB.BASEBOARD_FAB2(SCH_1):PAGE111
     2 XDP_CPU_TCK_BUF @BASEBOARD_FAB2_LIB.BASEBOARD_FAB2(SCH_1):XDP_CPU_TCK_BUF    I93 @BASEBOARD_FAB2_LIB.BASEBOARD_FAB2(SCH_1):PAGE111
     6 XDP_CPU_TCK_BUF @BASEBOARD_FAB2_LIB.BASEBOARD_FAB2(SCH_1):XDP_CPU_TCK_BUF    I93 @BASEBOARD_FAB2_LIB.BASEBOARD_FAB2(SCH_1):PAGE111
     1 XDP_CPU_GTL_TCK_R2 @BASEBOARD_FAB2_LIB.BASEBOARD_FAB2(SCH_1):XDP_CPU_GTL_TCK_R2    I93 @BASEBOARD_FAB2_LIB.BASEBOARD_FAB2(SCH_1):PAGE111

Q9A2 FET_N_DUAL_SMLF-NTJD4001N,FET,A
     2 FM_PWR_LED_N @BASEBOARD_FAB2_LIB.BASEBOARD_FAB2(SCH_1):FM_PWR_LED_N   I175 @BASEBOARD_FAB2_LIB.BASEBOARD_FAB2(SCH_1):PAGE119
     1    GND @BASEBOARD_FAB2_LIB.BASEBOARD_FAB2(SCH_1):GND   I175 @BASEBOARD_FAB2_LIB.BASEBOARD_FAB2(SCH_1):PAGE119
     6 FM_PWR_LED @BASEBOARD_FAB2_LIB.BASEBOARD_FAB2(SCH_1):FM_PWR_LED   I175 @BASEBOARD_FAB2_LIB.BASEBOARD_FAB2(SCH_1):PAGE119
     5 FM_PWR_LED @BASEBOARD_FAB2_LIB.BASEBOARD_FAB2(SCH_1):FM_PWR_LED   I180 @BASEBOARD_FAB2_LIB.BASEBOARD_FAB2(SCH_1):PAGE119
     4    GND @BASEBOARD_FAB2_LIB.BASEBOARD_FAB2(SCH_1):GND   I180 @BASEBOARD_FAB2_LIB.BASEBOARD_FAB2(SCH_1):PAGE119
     3 FM_PWR_LED_K @BASEBOARD_FAB2_LIB.BASEBOARD_FAB2(SCH_1):FM_PWR_LED_K   I180 @BASEBOARD_FAB2_LIB.BASEBOARD_FAB2(SCH_1):PAGE119

Q9A3 FET_N_SOT23LF-2N7002,FET,C7925A
     1 FM_BIOS_TOP_SWAP_SPKR @BASEBOARD_FAB2_LIB.BASEBOARD_FAB2(SCH_1):FM_BIOS_TOP_SWAP_SPKR    I49 @BASEBOARD_FAB2_LIB.BASEBOARD_FAB2(SCH_1):PAGE175
     2    GND @BASEBOARD_FAB2_LIB.BASEBOARD_FAB2(SCH_1):GND    I49 @BASEBOARD_FAB2_LIB.BASEBOARD_FAB2(SCH_1):PAGE175
     3 FM_SPEAKER_PCH_N_R @BASEBOARD_FAB2_LIB.BASEBOARD_FAB2(SCH_1):FM_SPEAKER_PCH_N_R    I49 @BASEBOARD_FAB2_LIB.BASEBOARD_FAB2(SCH_1):PAGE175

Q9B1 PNP_TO92-MPS2907,IC,G73554-001
     1 ISENSE_TMP421_1_BC @BASEBOARD_FAB2_LIB.BASEBOARD_FAB2(SCH_1):ISENSE_TMP421_1_BC     I3 @BASEBOARD_FAB2_LIB.BASEBOARD_FAB2(SCH_1):PAGE167
     3 ISENSE_TMP421_1_BC @BASEBOARD_FAB2_LIB.BASEBOARD_FAB2(SCH_1):ISENSE_TMP421_1_BC     I3 @BASEBOARD_FAB2_LIB.BASEBOARD_FAB2(SCH_1):PAGE167
     2 ISENSE_TMP421_1_E @BASEBOARD_FAB2_LIB.BASEBOARD_FAB2(SCH_1):ISENSE_TMP421_1_E     I3 @BASEBOARD_FAB2_LIB.BASEBOARD_FAB2(SCH_1):PAGE167

Q9E1 FET_N_DUAL_SMLF-NTJD4001N,FET,A
     2 FM_BMC_HEARTBEAT_N @BASEBOARD_FAB2_LIB.BASEBOARD_FAB2(SCH_1):FM_BMC_HEARTBEAT_N   I113 @BASEBOARD_FAB2_LIB.BASEBOARD_FAB2(SCH_1):PAGE149
     1    GND @BASEBOARD_FAB2_LIB.BASEBOARD_FAB2(SCH_1):GND   I113 @BASEBOARD_FAB2_LIB.BASEBOARD_FAB2(SCH_1):PAGE149
     6 FM_HEARTBEAT_LED @BASEBOARD_FAB2_LIB.BASEBOARD_FAB2(SCH_1):FM_HEARTBEAT_LED   I113 @BASEBOARD_FAB2_LIB.BASEBOARD_FAB2(SCH_1):PAGE149
     5 FM_HEARTBEAT_LED @BASEBOARD_FAB2_LIB.BASEBOARD_FAB2(SCH_1):FM_HEARTBEAT_LED   I109 @BASEBOARD_FAB2_LIB.BASEBOARD_FAB2(SCH_1):PAGE149
     4    GND @BASEBOARD_FAB2_LIB.BASEBOARD_FAB2(SCH_1):GND   I109 @BASEBOARD_FAB2_LIB.BASEBOARD_FAB2(SCH_1):PAGE149
     3 FM_HEARTBEAT_LED_K @BASEBOARD_FAB2_LIB.BASEBOARD_FAB2(SCH_1):FM_HEARTBEAT_LED_K   I109 @BASEBOARD_FAB2_LIB.BASEBOARD_FAB2(SCH_1):PAGE149

Q9F1 FET_N_DUAL_SMLF-NTJD4001N,FET,A
     2 FM_BMC_FAULT_LED_N @BASEBOARD_FAB2_LIB.BASEBOARD_FAB2(SCH_1):FM_BMC_FAULT_LED_N    I80 @BASEBOARD_FAB2_LIB.BASEBOARD_FAB2(SCH_1):PAGE177
     1    GND @BASEBOARD_FAB2_LIB.BASEBOARD_FAB2(SCH_1):GND    I80 @BASEBOARD_FAB2_LIB.BASEBOARD_FAB2(SCH_1):PAGE177
     6 FM_BMC_FAULT_LED @BASEBOARD_FAB2_LIB.BASEBOARD_FAB2(SCH_1):FM_BMC_FAULT_LED    I80 @BASEBOARD_FAB2_LIB.BASEBOARD_FAB2(SCH_1):PAGE177
     5 FM_BMC_FAULT_LED @BASEBOARD_FAB2_LIB.BASEBOARD_FAB2(SCH_1):FM_BMC_FAULT_LED    I79 @BASEBOARD_FAB2_LIB.BASEBOARD_FAB2(SCH_1):PAGE177
     4    GND @BASEBOARD_FAB2_LIB.BASEBOARD_FAB2(SCH_1):GND    I79 @BASEBOARD_FAB2_LIB.BASEBOARD_FAB2(SCH_1):PAGE177
     3 FM_RED_LED_CATHODE @BASEBOARD_FAB2_LIB.BASEBOARD_FAB2(SCH_1):FM_RED_LED_CATHODE    I79 @BASEBOARD_FAB2_LIB.BASEBOARD_FAB2(SCH_1):PAGE177

Q9G1 FET_N_DUAL_SMLF-NTJD4001N,FET,A
     2 FM_BATTERY_SENSE_EN_N @BASEBOARD_FAB2_LIB.BASEBOARD_FAB2(SCH_1):FM_BATTERY_SENSE_EN_N   I162 @BASEBOARD_FAB2_LIB.BASEBOARD_FAB2(SCH_1):PAGE169
     1    GND @BASEBOARD_FAB2_LIB.BASEBOARD_FAB2(SCH_1):GND   I162 @BASEBOARD_FAB2_LIB.BASEBOARD_FAB2(SCH_1):PAGE169
     6 FM_BATTERY_SENSE_EN @BASEBOARD_FAB2_LIB.BASEBOARD_FAB2(SCH_1):FM_BATTERY_SENSE_EN   I162 @BASEBOARD_FAB2_LIB.BASEBOARD_FAB2(SCH_1):PAGE169
     5 FM_BATTERY_SENSE_EN @BASEBOARD_FAB2_LIB.BASEBOARD_FAB2(SCH_1):FM_BATTERY_SENSE_EN   I157 @BASEBOARD_FAB2_LIB.BASEBOARD_FAB2(SCH_1):PAGE169
     4 A_P3V_BAT_SCALED @BASEBOARD_FAB2_LIB.BASEBOARD_FAB2(SCH_1):A_P3V_BAT_SCALED   I157 @BASEBOARD_FAB2_LIB.BASEBOARD_FAB2(SCH_1):PAGE169
     3 P3V_BAT_SOURCE_R @BASEBOARD_FAB2_LIB.BASEBOARD_FAB2(SCH_1):P3V_BAT_SOURCE_R   I157 @BASEBOARD_FAB2_LIB.BASEBOARD_FAB2(SCH_1):PAGE169

Q9P1 FET_N_DUAL_SMLF-2N7002DW,FET,DA
     2 A_HSC_LOW_GATE @BASEBOARD_FAB2_LIB.BASEBOARD_FAB2(SCH_1):A_HSC_LOW_GATE   I196 @BASEBOARD_FAB2_LIB.BASEBOARD_FAB2(SCH_1):PAGE200
     1    GND @BASEBOARD_FAB2_LIB.BASEBOARD_FAB2(SCH_1):GND   I196 @BASEBOARD_FAB2_LIB.BASEBOARD_FAB2(SCH_1):PAGE200
     6 A_HSC_LOW_DRAIN @BASEBOARD_FAB2_LIB.BASEBOARD_FAB2(SCH_1):A_HSC_LOW_DRAIN   I196 @BASEBOARD_FAB2_LIB.BASEBOARD_FAB2(SCH_1):PAGE200
     5 A_P12V_STBY_FPH_GATE @BASEBOARD_FAB2_LIB.BASEBOARD_FAB2(SCH_1):A_P12V_STBY_FPH_GATE   I199 @BASEBOARD_FAB2_LIB.BASEBOARD_FAB2(SCH_1):PAGE200
     4    GND @BASEBOARD_FAB2_LIB.BASEBOARD_FAB2(SCH_1):GND   I199 @BASEBOARD_FAB2_LIB.BASEBOARD_FAB2(SCH_1):PAGE200
     3 IRQ_UV_DETECT_N @BASEBOARD_FAB2_LIB.BASEBOARD_FAB2(SCH_1):IRQ_UV_DETECT_N   I199 @BASEBOARD_FAB2_LIB.BASEBOARD_FAB2(SCH_1):PAGE200

Q9T1 NPN_SM-MMBT3904,IC,C52245-001
     1 FM_MATED_IN_D2_N @BASEBOARD_FAB2_LIB.BASEBOARD_FAB2(SCH_1):FM_MATED_IN_D2_N   I181 @BASEBOARD_FAB2_LIB.BASEBOARD_FAB2(SCH_1):PAGE181
     3 FM_P12V_HOTSWAP0_EN @BASEBOARD_FAB2_LIB.BASEBOARD_FAB2(SCH_1):FM_P12V_HOTSWAP0_EN   I181 @BASEBOARD_FAB2_LIB.BASEBOARD_FAB2(SCH_1):PAGE181
     2    GND @BASEBOARD_FAB2_LIB.BASEBOARD_FAB2(SCH_1):GND   I181 @BASEBOARD_FAB2_LIB.BASEBOARD_FAB2(SCH_1):PAGE181

Q9W1 FET_N_SOT23LF-2N7002,FET,C7925A
     1 BMC_TPM_HW_C_RST @BASEBOARD_FAB2_LIB.BASEBOARD_FAB2(SCH_1):BMC_TPM_HW_C_RST    I30 @BASEBOARD_FAB2_LIB.BASEBOARD_FAB2(SCH_1):PAGE249
     2    GND @BASEBOARD_FAB2_LIB.BASEBOARD_FAB2(SCH_1):GND    I30 @BASEBOARD_FAB2_LIB.BASEBOARD_FAB2(SCH_1):PAGE249
     3 FM_TPM_PRES_RST_N @BASEBOARD_FAB2_LIB.BASEBOARD_FAB2(SCH_1):FM_TPM_PRES_RST_N    I30 @BASEBOARD_FAB2_LIB.BASEBOARD_FAB2(SCH_1):PAGE249

Q9W2 NPN_SM-MMBT3904,IC,C52245-001
     1 FM_TPM_PRES_RST_N_R @BASEBOARD_FAB2_LIB.BASEBOARD_FAB2(SCH_1):FM_TPM_PRES_RST_N_R    I29 @BASEBOARD_FAB2_LIB.BASEBOARD_FAB2(SCH_1):PAGE249
     3 FM_TPM_PRES_RST @BASEBOARD_FAB2_LIB.BASEBOARD_FAB2(SCH_1):FM_TPM_PRES_RST    I29 @BASEBOARD_FAB2_LIB.BASEBOARD_FAB2(SCH_1):PAGE249
     2    GND @BASEBOARD_FAB2_LIB.BASEBOARD_FAB2(SCH_1):GND    I29 @BASEBOARD_FAB2_LIB.BASEBOARD_FAB2(SCH_1):PAGE249

Q9W3 NPN_SM-MMBT3904,IC,C52245-001
     1 FM_TPM_PRES_RST @BASEBOARD_FAB2_LIB.BASEBOARD_FAB2(SCH_1):FM_TPM_PRES_RST    I26 @BASEBOARD_FAB2_LIB.BASEBOARD_FAB2(SCH_1):PAGE249
     3 RST_BMC_SRST_N @BASEBOARD_FAB2_LIB.BASEBOARD_FAB2(SCH_1):RST_BMC_SRST_N    I26 @BASEBOARD_FAB2_LIB.BASEBOARD_FAB2(SCH_1):PAGE249
     2    GND @BASEBOARD_FAB2_LIB.BASEBOARD_FAB2(SCH_1):GND    I26 @BASEBOARD_FAB2_LIB.BASEBOARD_FAB2(SCH_1):PAGE249

Q9W4 LMV331IDCKRG4-GP_DISCRET-G-LMVA
     1 FM_TPM_PRES_RST_N @BASEBOARD_FAB2_LIB.BASEBOARD_FAB2(SCH_1):FM_TPM_PRES_RST_N    I15 @BASEBOARD_FAB2_LIB.BASEBOARD_FAB2(SCH_1):PAGE249
     3 VREF_2V2 @BASEBOARD_FAB2_LIB.BASEBOARD_FAB2(SCH_1):VREF_2V2    I15 @BASEBOARD_FAB2_LIB.BASEBOARD_FAB2(SCH_1):PAGE249
     4 FM_TPM_PRES_N @BASEBOARD_FAB2_LIB.BASEBOARD_FAB2(SCH_1):FM_TPM_PRES_N    I15 @BASEBOARD_FAB2_LIB.BASEBOARD_FAB2(SCH_1):PAGE249
     5 P3V3_STBY @BASEBOARD_FAB2_LIB.BASEBOARD_FAB2(SCH_1):P3V3_STBY    I15 @BASEBOARD_FAB2_LIB.BASEBOARD_FAB2(SCH_1):PAGE249
     2    GND @BASEBOARD_FAB2_LIB.BASEBOARD_FAB2(SCH_1):GND    I15 @BASEBOARD_FAB2_LIB.BASEBOARD_FAB2(SCH_1):PAGE249

R1A1 RES_0603-120.0,1%,1/10W,CHIP,GA
     1 PVDDQ_KLM @BASEBOARD_FAB2_LIB.BASEBOARD_FAB2(SCH_1):PVDDQ_KLM    I58 @BASEBOARD_FAB2_LIB.BASEBOARD_FAB2(SCH_1):PAGE228
     2    GND @BASEBOARD_FAB2_LIB.BASEBOARD_FAB2(SCH_1):GND    I58 @BASEBOARD_FAB2_LIB.BASEBOARD_FAB2(SCH_1):PAGE228

R1A2 RES_0402-68.1K,1%,1/16W,EMPTY,A
     1 VR_PVDDQ_KLM_PH2_OCSET @BASEBOARD_FAB2_LIB.BASEBOARD_FAB2(SCH_1):VR_PVDDQ_KLM_PH2_OCSET   I105 @BASEBOARD_FAB2_LIB.BASEBOARD_FAB2(SCH_1):PAGE227
     2    GND @BASEBOARD_FAB2_LIB.BASEBOARD_FAB2(SCH_1):GND   I105 @BASEBOARD_FAB2_LIB.BASEBOARD_FAB2(SCH_1):PAGE227

R1A3 RES_0402-68.1K,1%,1/16W,EMPTY,A
     1 VR_PVDDQ_KLM_PH1_OCSET @BASEBOARD_FAB2_LIB.BASEBOARD_FAB2(SCH_1):VR_PVDDQ_KLM_PH1_OCSET   I103 @BASEBOARD_FAB2_LIB.BASEBOARD_FAB2(SCH_1):PAGE227
     2    GND @BASEBOARD_FAB2_LIB.BASEBOARD_FAB2(SCH_1):GND   I103 @BASEBOARD_FAB2_LIB.BASEBOARD_FAB2(SCH_1):PAGE227

R1B1 RES_0402-1.00K,1%,1/16W,CHIP,GA
     1 P3V3_STBY @BASEBOARD_FAB2_LIB.BASEBOARD_FAB2(SCH_1):P3V3_STBY    I79 @BASEBOARD_FAB2_LIB.BASEBOARD_FAB2(SCH_1):PAGE226
     2 IRQ_PVDDQ_KLM_VRHOT_LVT3_R_N @BASEBOARD_FAB2_LIB.BASEBOARD_FAB2(SCH_1):IRQ_PVDDQ_KLM_VRHOT_LVT3_R_N    I79 @BASEBOARD_FAB2_LIB.BASEBOARD_FAB2(SCH_1):PAGE226

R1B2 RES_0402-1.00K,1%,1/16W,CHIP,GA
     1 P3V3_STBY @BASEBOARD_FAB2_LIB.BASEBOARD_FAB2(SCH_1):P3V3_STBY    I17 @BASEBOARD_FAB2_LIB.BASEBOARD_FAB2(SCH_1):PAGE226
     2 PWRGD_PVDDQ_KLM_R @BASEBOARD_FAB2_LIB.BASEBOARD_FAB2(SCH_1):PWRGD_PVDDQ_KLM_R    I17 @BASEBOARD_FAB2_LIB.BASEBOARD_FAB2(SCH_1):PAGE226

R1B4 RES_0402-33.2,1%,1/16W,CHIP,G2A
     1 IRQ_PVDDQ_KLM_VRHOT_LVT3_R_N @BASEBOARD_FAB2_LIB.BASEBOARD_FAB2(SCH_1):IRQ_PVDDQ_KLM_VRHOT_LVT3_R_N    I82 @BASEBOARD_FAB2_LIB.BASEBOARD_FAB2(SCH_1):PAGE226
     2 IRQ_PVDDQ_KLM_VRHOT_LVT3_N @BASEBOARD_FAB2_LIB.BASEBOARD_FAB2(SCH_1):IRQ_PVDDQ_KLM_VRHOT_LVT3_N    I82 @BASEBOARD_FAB2_LIB.BASEBOARD_FAB2(SCH_1):PAGE226

R1B5 RES_0402-22.1,1.0%,1/16W,CHIP,A
     1 PWRGD_PVDDQ_KLM_R @BASEBOARD_FAB2_LIB.BASEBOARD_FAB2(SCH_1):PWRGD_PVDDQ_KLM_R    I14 @BASEBOARD_FAB2_LIB.BASEBOARD_FAB2(SCH_1):PAGE226
     2 PWRGD_PVDDQ_KLM @BASEBOARD_FAB2_LIB.BASEBOARD_FAB2(SCH_1):PWRGD_PVDDQ_KLM    I14 @BASEBOARD_FAB2_LIB.BASEBOARD_FAB2(SCH_1):PAGE226

R1B6 RES_0402-20.0,1%,1/16W,CHIP,G2A
     1 SMB_VR_SCL_VDDQ_KLM @BASEBOARD_FAB2_LIB.BASEBOARD_FAB2(SCH_1):SMB_VR_SCL_VDDQ_KLM    I21 @BASEBOARD_FAB2_LIB.BASEBOARD_FAB2(SCH_1):PAGE226
     2 SMB_VR_STBY_LVC3_SCL @BASEBOARD_FAB2_LIB.BASEBOARD_FAB2(SCH_1):SMB_VR_STBY_LVC3_SCL    I21 @BASEBOARD_FAB2_LIB.BASEBOARD_FAB2(SCH_1):PAGE226

R1B7 RES_0402-20.0,1%,1/16W,CHIP,G2A
     1 SMB_VR_SDA_VDDQ_KLM @BASEBOARD_FAB2_LIB.BASEBOARD_FAB2(SCH_1):SMB_VR_SDA_VDDQ_KLM    I22 @BASEBOARD_FAB2_LIB.BASEBOARD_FAB2(SCH_1):PAGE226
     2 SMB_VR_STBY_LVC3_SDA @BASEBOARD_FAB2_LIB.BASEBOARD_FAB2(SCH_1):SMB_VR_STBY_LVC3_SDA    I22 @BASEBOARD_FAB2_LIB.BASEBOARD_FAB2(SCH_1):PAGE226

R1B8 RES_0402-150.0,1%,1/16W,CHIP,GA
     1 SVID_CLK1_CPU1_R @BASEBOARD_FAB2_LIB.BASEBOARD_FAB2(SCH_1):SVID_CLK1_CPU1_R    I53 @BASEBOARD_FAB2_LIB.BASEBOARD_FAB2(SCH_1):PAGE226
     2 SVID_CLK_PVDDQ_KLM @BASEBOARD_FAB2_LIB.BASEBOARD_FAB2(SCH_1):SVID_CLK_PVDDQ_KLM    I53 @BASEBOARD_FAB2_LIB.BASEBOARD_FAB2(SCH_1):PAGE226

R1B9 RES_0402-1.5K,1%,1/16W,CHIP,G2A
     1 VR_PVDDQ_KLM_VINSEN @BASEBOARD_FAB2_LIB.BASEBOARD_FAB2(SCH_1):VR_PVDDQ_KLM_VINSEN    I58 @BASEBOARD_FAB2_LIB.BASEBOARD_FAB2(SCH_1):PAGE226
     2    GND @BASEBOARD_FAB2_LIB.BASEBOARD_FAB2(SCH_1):GND    I58 @BASEBOARD_FAB2_LIB.BASEBOARD_FAB2(SCH_1):PAGE226

R1B10 RES_0402-0.0,5%,1/16W,CHIP,G21A
     1 SVID_VDIO_PVDDQ_KLM @BASEBOARD_FAB2_LIB.BASEBOARD_FAB2(SCH_1):SVID_VDIO_PVDDQ_KLM    I23 @BASEBOARD_FAB2_LIB.BASEBOARD_FAB2(SCH_1):PAGE226
     2 SVID_DIO1_CPU1_R @BASEBOARD_FAB2_LIB.BASEBOARD_FAB2(SCH_1):SVID_DIO1_CPU1_R    I23 @BASEBOARD_FAB2_LIB.BASEBOARD_FAB2(SCH_1):PAGE226

R1B11 RES_0402-0.0,5%,1/16W,CHIP,G21A
     1 SVID_ALERT_PVDDQ_KLM @BASEBOARD_FAB2_LIB.BASEBOARD_FAB2(SCH_1):SVID_ALERT_PVDDQ_KLM    I16 @BASEBOARD_FAB2_LIB.BASEBOARD_FAB2(SCH_1):PAGE226
     2 SVID_ALERT1_CPU1_R_N @BASEBOARD_FAB2_LIB.BASEBOARD_FAB2(SCH_1):SVID_ALERT1_CPU1_R_N    I16 @BASEBOARD_FAB2_LIB.BASEBOARD_FAB2(SCH_1):PAGE226

R1B12 RES_0402-3.16K,1%,1/16W,CHIP,GA
     1 VR_PVDDQ_KLM_XADDR1 @BASEBOARD_FAB2_LIB.BASEBOARD_FAB2(SCH_1):VR_PVDDQ_KLM_XADDR1    I78 @BASEBOARD_FAB2_LIB.BASEBOARD_FAB2(SCH_1):PAGE226
     2    GND @BASEBOARD_FAB2_LIB.BASEBOARD_FAB2(SCH_1):GND    I78 @BASEBOARD_FAB2_LIB.BASEBOARD_FAB2(SCH_1):PAGE226

R1B13 RES_0402-2.26K,1.0%,1/16W,EMPTA
     1 P3V3_STBY @BASEBOARD_FAB2_LIB.BASEBOARD_FAB2(SCH_1):P3V3_STBY    I13 @BASEBOARD_FAB2_LIB.BASEBOARD_FAB2(SCH_1):PAGE226
     2 PU_VR_PVDDQ_KLM_FAULT1 @BASEBOARD_FAB2_LIB.BASEBOARD_FAB2(SCH_1):PU_VR_PVDDQ_KLM_FAULT1    I13 @BASEBOARD_FAB2_LIB.BASEBOARD_FAB2(SCH_1):PAGE226

R1B14 RES_0402-0.0,5%,1/16W,CHIP,G21A
     1 VR_PVDDQ_KLM_AIINSEN_R @BASEBOARD_FAB2_LIB.BASEBOARD_FAB2(SCH_1):VR_PVDDQ_KLM_AIINSEN_R   I137 @BASEBOARD_FAB2_LIB.BASEBOARD_FAB2(SCH_1):PAGE197
     2 VR_PVDDQ_KLM_AIINSEN @BASEBOARD_FAB2_LIB.BASEBOARD_FAB2(SCH_1):VR_PVDDQ_KLM_AIINSEN   I137 @BASEBOARD_FAB2_LIB.BASEBOARD_FAB2(SCH_1):PAGE197

R1B15 RES_0402-5.36K,1.0%,1/16W,CHIPA
     1 VR_PVDDQ_KLM_XADDR2 @BASEBOARD_FAB2_LIB.BASEBOARD_FAB2(SCH_1):VR_PVDDQ_KLM_XADDR2    I77 @BASEBOARD_FAB2_LIB.BASEBOARD_FAB2(SCH_1):PAGE226
     2    GND @BASEBOARD_FAB2_LIB.BASEBOARD_FAB2(SCH_1):GND    I77 @BASEBOARD_FAB2_LIB.BASEBOARD_FAB2(SCH_1):PAGE226

R1B16 RES_0402-10.0,1%,1/16W,CHIP,G2A
     1 VSENSE_PVDDQ_KLM_P @BASEBOARD_FAB2_LIB.BASEBOARD_FAB2(SCH_1):VSENSE_PVDDQ_KLM_P    I32 @BASEBOARD_FAB2_LIB.BASEBOARD_FAB2(SCH_1):PAGE226
     2 VR_PVDDQ_KLM_AVSP @BASEBOARD_FAB2_LIB.BASEBOARD_FAB2(SCH_1):VR_PVDDQ_KLM_AVSP    I32 @BASEBOARD_FAB2_LIB.BASEBOARD_FAB2(SCH_1):PAGE226

R1B20 RES_2010-0.001,1%,1W,CHIP,E309A
     1 VR_FET_SW_P12V_PVCCIN_CPU1_R @BASEBOARD_FAB2_LIB.BASEBOARD_FAB2(SCH_1):VR_FET_SW_P12V_PVCCIN_CPU1_R    I39 @BASEBOARD_FAB2_LIB.BASEBOARD_FAB2(SCH_1):PAGE209
     2 VR_FET_SW_P12V_STBY_PVCCIN_CPU1 @BASEBOARD_FAB2_LIB.BASEBOARD_FAB2(SCH_1):VR_FET_SW_P12V_STBY_PVCCIN_CPU1    I39 @BASEBOARD_FAB2_LIB.BASEBOARD_FAB2(SCH_1):PAGE209

R1B21 RES_0402-4.75K,1%,1/16W,CHIP,GA
     1 P3V3_STBY @BASEBOARD_FAB2_LIB.BASEBOARD_FAB2(SCH_1):P3V3_STBY    I70 @BASEBOARD_FAB2_LIB.BASEBOARD_FAB2(SCH_1):PAGE161
     2 FAN_TACH2 @BASEBOARD_FAB2_LIB.BASEBOARD_FAB2(SCH_1):FAN_TACH2    I70 @BASEBOARD_FAB2_LIB.BASEBOARD_FAB2(SCH_1):PAGE161

R1B22 RES_0402-100.0,1%,1/16W,CHIP,GA
     1 FAN_TACH2 @BASEBOARD_FAB2_LIB.BASEBOARD_FAB2(SCH_1):FAN_TACH2    I67 @BASEBOARD_FAB2_LIB.BASEBOARD_FAB2(SCH_1):PAGE161
     2 FAN_TACH2_CPU1_D2 @BASEBOARD_FAB2_LIB.BASEBOARD_FAB2(SCH_1):FAN_TACH2_CPU1_D2    I67 @BASEBOARD_FAB2_LIB.BASEBOARD_FAB2(SCH_1):PAGE161

R1B23 RES_0402-100.0,1%,1/16W,CHIP,GA
     1 FAN_TACH3 @BASEBOARD_FAB2_LIB.BASEBOARD_FAB2(SCH_1):FAN_TACH3   I124 @BASEBOARD_FAB2_LIB.BASEBOARD_FAB2(SCH_1):PAGE161
     2 FAN_TACH3_CPU1_D2 @BASEBOARD_FAB2_LIB.BASEBOARD_FAB2(SCH_1):FAN_TACH3_CPU1_D2   I124 @BASEBOARD_FAB2_LIB.BASEBOARD_FAB2(SCH_1):PAGE161

R1B24 RES_0402-4.75K,1%,1/16W,CHIP,GA
     1 P3V3_STBY @BASEBOARD_FAB2_LIB.BASEBOARD_FAB2(SCH_1):P3V3_STBY   I126 @BASEBOARD_FAB2_LIB.BASEBOARD_FAB2(SCH_1):PAGE161
     2 FAN_TACH3 @BASEBOARD_FAB2_LIB.BASEBOARD_FAB2(SCH_1):FAN_TACH3   I126 @BASEBOARD_FAB2_LIB.BASEBOARD_FAB2(SCH_1):PAGE161

R1C1 RES_0402-221,1.0%,1/16W,CHIP,GA
     1 SVID_ALERT1_CPU1_N @BASEBOARD_FAB2_LIB.BASEBOARD_FAB2(SCH_1):SVID_ALERT1_CPU1_N    I26 @BASEBOARD_FAB2_LIB.BASEBOARD_FAB2(SCH_1):PAGE55
     2 SVID_ALERT1_CPU1_R_N @BASEBOARD_FAB2_LIB.BASEBOARD_FAB2(SCH_1):SVID_ALERT1_CPU1_R_N    I26 @BASEBOARD_FAB2_LIB.BASEBOARD_FAB2(SCH_1):PAGE55

R1C2 RES_0402-0.0,5%,1/16W,CHIP,G21A
     1 SVID_DIO1_CPU1 @BASEBOARD_FAB2_LIB.BASEBOARD_FAB2(SCH_1):SVID_DIO1_CPU1    I24 @BASEBOARD_FAB2_LIB.BASEBOARD_FAB2(SCH_1):PAGE55
     2 SVID_DIO1_CPU1_R @BASEBOARD_FAB2_LIB.BASEBOARD_FAB2(SCH_1):SVID_DIO1_CPU1_R    I24 @BASEBOARD_FAB2_LIB.BASEBOARD_FAB2(SCH_1):PAGE55

R1C3 RES_0402-0.0,5%,1/16W,CHIP,G21A
     1 SVID_CLK1_CPU1 @BASEBOARD_FAB2_LIB.BASEBOARD_FAB2(SCH_1):SVID_CLK1_CPU1    I25 @BASEBOARD_FAB2_LIB.BASEBOARD_FAB2(SCH_1):PAGE55
     2 SVID_CLK1_CPU1_R @BASEBOARD_FAB2_LIB.BASEBOARD_FAB2(SCH_1):SVID_CLK1_CPU1_R    I25 @BASEBOARD_FAB2_LIB.BASEBOARD_FAB2(SCH_1):PAGE55

R1C4 RES_0402-100.0,1%,1/16W,CHIP,GA
     1 VSENSE_PVSA_CPU1_N @BASEBOARD_FAB2_LIB.BASEBOARD_FAB2(SCH_1):VSENSE_PVSA_CPU1_N    I33 @BASEBOARD_FAB2_LIB.BASEBOARD_FAB2(SCH_1):PAGE210
     2    GND @BASEBOARD_FAB2_LIB.BASEBOARD_FAB2(SCH_1):GND    I33 @BASEBOARD_FAB2_LIB.BASEBOARD_FAB2(SCH_1):PAGE210

R1C5 RES_0402-0.0,5%,1/16W,CHIP,G21A
     1 VSENSE_PVSA_CPU1_N @BASEBOARD_FAB2_LIB.BASEBOARD_FAB2(SCH_1):VSENSE_PVSA_CPU1_N    I32 @BASEBOARD_FAB2_LIB.BASEBOARD_FAB2(SCH_1):PAGE210
     2 VSENSE_PVSA_CPU1_SKT_VRTN @BASEBOARD_FAB2_LIB.BASEBOARD_FAB2(SCH_1):VSENSE_PVSA_CPU1_SKT_VRTN    I32 @BASEBOARD_FAB2_LIB.BASEBOARD_FAB2(SCH_1):PAGE210

R1C6 RES_0402-1.00K,1%,1/16W,EMPTY,A
     1 VSENSE_PVSA_CPU1_P @BASEBOARD_FAB2_LIB.BASEBOARD_FAB2(SCH_1):VSENSE_PVSA_CPU1_P    I34 @BASEBOARD_FAB2_LIB.BASEBOARD_FAB2(SCH_1):PAGE210
     2 VSENSE_PVSA_CPU1_N @BASEBOARD_FAB2_LIB.BASEBOARD_FAB2(SCH_1):VSENSE_PVSA_CPU1_N    I34 @BASEBOARD_FAB2_LIB.BASEBOARD_FAB2(SCH_1):PAGE210

R1C7 RES_0402-0.0,5%,1/16W,CHIP,G21A
     1 VSENSE_PVSA_CPU1_P @BASEBOARD_FAB2_LIB.BASEBOARD_FAB2(SCH_1):VSENSE_PVSA_CPU1_P    I31 @BASEBOARD_FAB2_LIB.BASEBOARD_FAB2(SCH_1):PAGE210
     2 VSENSE_PVSA_CPU1_SKT_VSEN @BASEBOARD_FAB2_LIB.BASEBOARD_FAB2(SCH_1):VSENSE_PVSA_CPU1_SKT_VSEN    I31 @BASEBOARD_FAB2_LIB.BASEBOARD_FAB2(SCH_1):PAGE210

R1C9 RES_0402-0.0,5%,1/16W,EMPTY,G2A
     1 IRQ_BOARD_BMC_ALERT_N @BASEBOARD_FAB2_LIB.BASEBOARD_FAB2(SCH_1):IRQ_BOARD_BMC_ALERT_N   I104 @BASEBOARD_FAB2_LIB.BASEBOARD_FAB2(SCH_1):PAGE182
     2 FAN_TACH2_R @BASEBOARD_FAB2_LIB.BASEBOARD_FAB2(SCH_1):FAN_TACH2_R   I104 @BASEBOARD_FAB2_LIB.BASEBOARD_FAB2(SCH_1):PAGE182

R1C10 RES_0402-0.0,5%,1/16W,EMPTY,G2A
     1 SMB_LAN_STBY_LVC3_SDA @BASEBOARD_FAB2_LIB.BASEBOARD_FAB2(SCH_1):SMB_LAN_STBY_LVC3_SDA   I101 @BASEBOARD_FAB2_LIB.BASEBOARD_FAB2(SCH_1):PAGE182
     2 FAN_TACH3_R @BASEBOARD_FAB2_LIB.BASEBOARD_FAB2(SCH_1):FAN_TACH3_R   I101 @BASEBOARD_FAB2_LIB.BASEBOARD_FAB2(SCH_1):PAGE182

R1C11 RES_0402-0.0,5%,1/16W,EMPTY,G2A
     1 SMB_LAN_STBY_LVC3_SCL @BASEBOARD_FAB2_LIB.BASEBOARD_FAB2(SCH_1):SMB_LAN_STBY_LVC3_SCL    I97 @BASEBOARD_FAB2_LIB.BASEBOARD_FAB2(SCH_1):PAGE182
     2 FAN_TACH1_R @BASEBOARD_FAB2_LIB.BASEBOARD_FAB2(SCH_1):FAN_TACH1_R    I97 @BASEBOARD_FAB2_LIB.BASEBOARD_FAB2(SCH_1):PAGE182

R1C12 RES_0402-100.0,1%,1/16W,CHIP,GA
     1 VSENSE_PVSA_CPU1_P @BASEBOARD_FAB2_LIB.BASEBOARD_FAB2(SCH_1):VSENSE_PVSA_CPU1_P    I29 @BASEBOARD_FAB2_LIB.BASEBOARD_FAB2(SCH_1):PAGE210
     2 PVSA_CPU1 @BASEBOARD_FAB2_LIB.BASEBOARD_FAB2(SCH_1):PVSA_CPU1    I29 @BASEBOARD_FAB2_LIB.BASEBOARD_FAB2(SCH_1):PAGE210

R1C13 RES_0402-100.0K,1%,1/16W,CHIP,B
     1 VR_FET_SW_P12V_STBY_PVCCIN_CPU1 @BASEBOARD_FAB2_LIB.BASEBOARD_FAB2(SCH_1):VR_FET_SW_P12V_STBY_PVCCIN_CPU1    I49 @BASEBOARD_FAB2_LIB.BASEBOARD_FAB2(SCH_1):PAGE206
     2 VR_PVCCIN_CPU1_AVINSEN @BASEBOARD_FAB2_LIB.BASEBOARD_FAB2(SCH_1):VR_PVCCIN_CPU1_AVINSEN    I49 @BASEBOARD_FAB2_LIB.BASEBOARD_FAB2(SCH_1):PAGE206

R1C14 RES_0402-0.0,5%,1/16W,CHIP,G21A
     1 P3V3_STBY @BASEBOARD_FAB2_LIB.BASEBOARD_FAB2(SCH_1):P3V3_STBY    I46 @BASEBOARD_FAB2_LIB.BASEBOARD_FAB2(SCH_1):PAGE206
     2 VR_PVCCIN_CPU1_VDD @BASEBOARD_FAB2_LIB.BASEBOARD_FAB2(SCH_1):VR_PVCCIN_CPU1_VDD    I46 @BASEBOARD_FAB2_LIB.BASEBOARD_FAB2(SCH_1):PAGE206

R1C16 RES_0402-1.5K,1%,1/16W,CHIP,G2A
     1 VR_PVCCIN_CPU1_AVINSEN @BASEBOARD_FAB2_LIB.BASEBOARD_FAB2(SCH_1):VR_PVCCIN_CPU1_AVINSEN    I56 @BASEBOARD_FAB2_LIB.BASEBOARD_FAB2(SCH_1):PAGE206
     2    GND @BASEBOARD_FAB2_LIB.BASEBOARD_FAB2(SCH_1):GND    I56 @BASEBOARD_FAB2_LIB.BASEBOARD_FAB2(SCH_1):PAGE206

R1C18 RES_0402-2.26K,1.0%,1/16W,EMPTA
     1 P3V3_STBY @BASEBOARD_FAB2_LIB.BASEBOARD_FAB2(SCH_1):P3V3_STBY    I34 @BASEBOARD_FAB2_LIB.BASEBOARD_FAB2(SCH_1):PAGE206
     2 PU_VR_PVCCIN_CPU1_IMON @BASEBOARD_FAB2_LIB.BASEBOARD_FAB2(SCH_1):PU_VR_PVCCIN_CPU1_IMON    I34 @BASEBOARD_FAB2_LIB.BASEBOARD_FAB2(SCH_1):PAGE206

R1C21 RES_0402-10.0,1%,1/16W,CHIP,G2A
     1 VSENSE_PVSA_CPU1_P @BASEBOARD_FAB2_LIB.BASEBOARD_FAB2(SCH_1):VSENSE_PVSA_CPU1_P    I77 @BASEBOARD_FAB2_LIB.BASEBOARD_FAB2(SCH_1):PAGE206
     2 VSENSE_PVSA_CPU1_BVSP @BASEBOARD_FAB2_LIB.BASEBOARD_FAB2(SCH_1):VSENSE_PVSA_CPU1_BVSP    I77 @BASEBOARD_FAB2_LIB.BASEBOARD_FAB2(SCH_1):PAGE206

R1C23 RES_0402-0.0,5%,1/16W,CHIP,G21A
     1 SMB_VR_SDA_R1 @BASEBOARD_FAB2_LIB.BASEBOARD_FAB2(SCH_1):SMB_VR_SDA_R1    I27 @BASEBOARD_FAB2_LIB.BASEBOARD_FAB2(SCH_1):PAGE206
     2 SMB_VR_STBY_LVC3_SDA @BASEBOARD_FAB2_LIB.BASEBOARD_FAB2(SCH_1):SMB_VR_STBY_LVC3_SDA    I27 @BASEBOARD_FAB2_LIB.BASEBOARD_FAB2(SCH_1):PAGE206

R1C25 RES_0402-0.0,5%,1/16W,CHIP,G21A
     1 SMB_VR_SCL_R1 @BASEBOARD_FAB2_LIB.BASEBOARD_FAB2(SCH_1):SMB_VR_SCL_R1    I28 @BASEBOARD_FAB2_LIB.BASEBOARD_FAB2(SCH_1):PAGE206
     2 SMB_VR_STBY_LVC3_SCL @BASEBOARD_FAB2_LIB.BASEBOARD_FAB2(SCH_1):SMB_VR_STBY_LVC3_SCL    I28 @BASEBOARD_FAB2_LIB.BASEBOARD_FAB2(SCH_1):PAGE206

R1C28 RES_0402-1.00K,1%,1/16W,CHIP,GA
     1 P3V3_STBY @BASEBOARD_FAB2_LIB.BASEBOARD_FAB2(SCH_1):P3V3_STBY    I35 @BASEBOARD_FAB2_LIB.BASEBOARD_FAB2(SCH_1):PAGE206
     2 VR_VRRDY_PVCCIN_CPU1 @BASEBOARD_FAB2_LIB.BASEBOARD_FAB2(SCH_1):VR_VRRDY_PVCCIN_CPU1    I35 @BASEBOARD_FAB2_LIB.BASEBOARD_FAB2(SCH_1):PAGE206

R1C30 RES_0402-22.1,1.0%,1/16W,CHIP,A
     1 VR_VRRDY_PVCCIN_CPU1 @BASEBOARD_FAB2_LIB.BASEBOARD_FAB2(SCH_1):VR_VRRDY_PVCCIN_CPU1   I113 @BASEBOARD_FAB2_LIB.BASEBOARD_FAB2(SCH_1):PAGE206
     2 PWRGD_PVCCIN_CPU1 @BASEBOARD_FAB2_LIB.BASEBOARD_FAB2(SCH_1):PWRGD_PVCCIN_CPU1   I113 @BASEBOARD_FAB2_LIB.BASEBOARD_FAB2(SCH_1):PAGE206

R1C31 RES_0402-0.0,5%,1/16W,EMPTY,G2A
     1 FM_XRC_READY_N @BASEBOARD_FAB2_LIB.BASEBOARD_FAB2(SCH_1):FM_XRC_READY_N   I110 @BASEBOARD_FAB2_LIB.BASEBOARD_FAB2(SCH_1):PAGE182
     2 FAN_TACH0_R @BASEBOARD_FAB2_LIB.BASEBOARD_FAB2(SCH_1):FAN_TACH0_R   I110 @BASEBOARD_FAB2_LIB.BASEBOARD_FAB2(SCH_1):PAGE182

R1C32 RES_0402-1.00K,1%,1/16W,CHIP,GA
     1    GND @BASEBOARD_FAB2_LIB.BASEBOARD_FAB2(SCH_1):GND   I312 @BASEBOARD_FAB2_LIB.BASEBOARD_FAB2(SCH_1):PAGE156
     2 PD_PIROM_CPU1_ADDR2 @BASEBOARD_FAB2_LIB.BASEBOARD_FAB2(SCH_1):PD_PIROM_CPU1_ADDR2   I312 @BASEBOARD_FAB2_LIB.BASEBOARD_FAB2(SCH_1):PAGE156

R1C33 RES_0402-1.00K,1%,1/16W,CHIP,GA
     1    GND @BASEBOARD_FAB2_LIB.BASEBOARD_FAB2(SCH_1):GND   I313 @BASEBOARD_FAB2_LIB.BASEBOARD_FAB2(SCH_1):PAGE156
     2 PD_PIROM_CPU1_ADDR1 @BASEBOARD_FAB2_LIB.BASEBOARD_FAB2(SCH_1):PD_PIROM_CPU1_ADDR1   I313 @BASEBOARD_FAB2_LIB.BASEBOARD_FAB2(SCH_1):PAGE156

R1C34 RES_0402-10.0K,1%,1/16W,CHIP,GA
     1 P3V3_STBY @BASEBOARD_FAB2_LIB.BASEBOARD_FAB2(SCH_1):P3V3_STBY   I320 @BASEBOARD_FAB2_LIB.BASEBOARD_FAB2(SCH_1):PAGE156
     2 PU_PIROM_CPU1_ADDR0 @BASEBOARD_FAB2_LIB.BASEBOARD_FAB2(SCH_1):PU_PIROM_CPU1_ADDR0   I320 @BASEBOARD_FAB2_LIB.BASEBOARD_FAB2(SCH_1):PAGE156

R1C35 RES_0402-3.32K,1%,1/16W,EMPTY,A
     1 P3V3_STBY @BASEBOARD_FAB2_LIB.BASEBOARD_FAB2(SCH_1):P3V3_STBY   I336 @BASEBOARD_FAB2_LIB.BASEBOARD_FAB2(SCH_1):PAGE156
     2 FM_CPU1_SM_WP @BASEBOARD_FAB2_LIB.BASEBOARD_FAB2(SCH_1):FM_CPU1_SM_WP   I336 @BASEBOARD_FAB2_LIB.BASEBOARD_FAB2(SCH_1):PAGE156

R1C36 RES_0402-1.00K,1%,1/16W,CHIP,GA
     1 FM_CPU1_SM_WP @BASEBOARD_FAB2_LIB.BASEBOARD_FAB2(SCH_1):FM_CPU1_SM_WP   I337 @BASEBOARD_FAB2_LIB.BASEBOARD_FAB2(SCH_1):PAGE156
     2    GND @BASEBOARD_FAB2_LIB.BASEBOARD_FAB2(SCH_1):GND   I337 @BASEBOARD_FAB2_LIB.BASEBOARD_FAB2(SCH_1):PAGE156

R1C37 RES_0402-68.1K,1%,1/16W,EMPTY,A
     1 VR_PVSA_CPU1_OCSET @BASEBOARD_FAB2_LIB.BASEBOARD_FAB2(SCH_1):VR_PVSA_CPU1_OCSET    I52 @BASEBOARD_FAB2_LIB.BASEBOARD_FAB2(SCH_1):PAGE210
     2    GND @BASEBOARD_FAB2_LIB.BASEBOARD_FAB2(SCH_1):GND    I52 @BASEBOARD_FAB2_LIB.BASEBOARD_FAB2(SCH_1):PAGE210

R1D1 RES_0402-33.2,1%,1/16W,CHIP,G2A
     1 PWRGD_PVSA_CPU1_R @BASEBOARD_FAB2_LIB.BASEBOARD_FAB2(SCH_1):PWRGD_PVSA_CPU1_R   I116 @BASEBOARD_FAB2_LIB.BASEBOARD_FAB2(SCH_1):PAGE206
     2 PWRGD_PVSA_CPU1 @BASEBOARD_FAB2_LIB.BASEBOARD_FAB2(SCH_1):PWRGD_PVSA_CPU1   I116 @BASEBOARD_FAB2_LIB.BASEBOARD_FAB2(SCH_1):PAGE206

R1D2 RES_0402-0.0,5%,1/16W,CHIP,G21A
     1 SVID_VDIO_PVCCIN_CPU1 @BASEBOARD_FAB2_LIB.BASEBOARD_FAB2(SCH_1):SVID_VDIO_PVCCIN_CPU1    I38 @BASEBOARD_FAB2_LIB.BASEBOARD_FAB2(SCH_1):PAGE206
     2 SVID_DIO0_CPU1_R @BASEBOARD_FAB2_LIB.BASEBOARD_FAB2(SCH_1):SVID_DIO0_CPU1_R    I38 @BASEBOARD_FAB2_LIB.BASEBOARD_FAB2(SCH_1):PAGE206

R1D3 RES_0402-0.0,5%,1/16W,CHIP,G21A
     1 SVID_VALERT_VCCIN_CPU1 @BASEBOARD_FAB2_LIB.BASEBOARD_FAB2(SCH_1):SVID_VALERT_VCCIN_CPU1    I37 @BASEBOARD_FAB2_LIB.BASEBOARD_FAB2(SCH_1):PAGE206
     2 SVID_ALERT0_CPU1_R_N @BASEBOARD_FAB2_LIB.BASEBOARD_FAB2(SCH_1):SVID_ALERT0_CPU1_R_N    I37 @BASEBOARD_FAB2_LIB.BASEBOARD_FAB2(SCH_1):PAGE206

R1D4 RES_0402-10.0,1%,1/16W,CHIP,G2A
     1 VSENSE_PVCCIN_CPU1_P @BASEBOARD_FAB2_LIB.BASEBOARD_FAB2(SCH_1):VSENSE_PVCCIN_CPU1_P    I79 @BASEBOARD_FAB2_LIB.BASEBOARD_FAB2(SCH_1):PAGE206
     2 VSENSE_PVCCIN_CPU1_AVSP @BASEBOARD_FAB2_LIB.BASEBOARD_FAB2(SCH_1):VSENSE_PVCCIN_CPU1_AVSP    I79 @BASEBOARD_FAB2_LIB.BASEBOARD_FAB2(SCH_1):PAGE206

R1D6 RES_0402-1.00K,1%,1/16W,CHIP,GA
     1 P3V3_STBY @BASEBOARD_FAB2_LIB.BASEBOARD_FAB2(SCH_1):P3V3_STBY     I6 @BASEBOARD_FAB2_LIB.BASEBOARD_FAB2(SCH_1):PAGE206
     2 IRQ_PVCCIN_CPU1_VRHOT_LVC3_R_N @BASEBOARD_FAB2_LIB.BASEBOARD_FAB2(SCH_1):IRQ_PVCCIN_CPU1_VRHOT_LVC3_R_N     I6 @BASEBOARD_FAB2_LIB.BASEBOARD_FAB2(SCH_1):PAGE206

R1D7 RES_0402-2.26K,1.0%,1/16W,CHIPA
     1 P3V3_STBY @BASEBOARD_FAB2_LIB.BASEBOARD_FAB2(SCH_1):P3V3_STBY     I7 @BASEBOARD_FAB2_LIB.BASEBOARD_FAB2(SCH_1):PAGE206
     2 FM_PVCCIN_CPU1_PWR_IN_ALERT_N @BASEBOARD_FAB2_LIB.BASEBOARD_FAB2(SCH_1):FM_PVCCIN_CPU1_PWR_IN_ALERT_N     I7 @BASEBOARD_FAB2_LIB.BASEBOARD_FAB2(SCH_1):PAGE206

R1D8 RES_0402-1.00K,1%,1/16W,CHIP,GA
     1 P3V3_STBY @BASEBOARD_FAB2_LIB.BASEBOARD_FAB2(SCH_1):P3V3_STBY    I36 @BASEBOARD_FAB2_LIB.BASEBOARD_FAB2(SCH_1):PAGE206
     2 PWRGD_PVSA_CPU1_R @BASEBOARD_FAB2_LIB.BASEBOARD_FAB2(SCH_1):PWRGD_PVSA_CPU1_R    I36 @BASEBOARD_FAB2_LIB.BASEBOARD_FAB2(SCH_1):PAGE206

R1D9 RES_0402-150.0,1%,1/16W,CHIP,GA
     1 SVID_CLK0_CPU1_R @BASEBOARD_FAB2_LIB.BASEBOARD_FAB2(SCH_1):SVID_CLK0_CPU1_R    I54 @BASEBOARD_FAB2_LIB.BASEBOARD_FAB2(SCH_1):PAGE206
     2 SVID_VCLK_PVCCIN_CPU1 @BASEBOARD_FAB2_LIB.BASEBOARD_FAB2(SCH_1):SVID_VCLK_PVCCIN_CPU1    I54 @BASEBOARD_FAB2_LIB.BASEBOARD_FAB2(SCH_1):PAGE206

R1D10 RES_0402-10.0K,1%,1/16W,CHIP,GA
     1 P3V3_STBY @BASEBOARD_FAB2_LIB.BASEBOARD_FAB2(SCH_1):P3V3_STBY   I189 @BASEBOARD_FAB2_LIB.BASEBOARD_FAB2(SCH_1):PAGE200
     2 A_HSC_LOW_GATE @BASEBOARD_FAB2_LIB.BASEBOARD_FAB2(SCH_1):A_HSC_LOW_GATE   I189 @BASEBOARD_FAB2_LIB.BASEBOARD_FAB2(SCH_1):PAGE200

R1D11 RES_0402-100.0K,1%,1/16W,CHIP,A
     1 A_HSC_LOW_EN @BASEBOARD_FAB2_LIB.BASEBOARD_FAB2(SCH_1):A_HSC_LOW_EN    I88 @BASEBOARD_FAB2_LIB.BASEBOARD_FAB2(SCH_1):PAGE199
     2 AGND_HSC @BASEBOARD_FAB2_LIB.BASEBOARD_FAB2(SCH_1):AGND_HSC    I88 @BASEBOARD_FAB2_LIB.BASEBOARD_FAB2(SCH_1):PAGE199

R1D12 RES_0402-10.0K,1%,1/16W,CHIP,GA
     1 A_HSC_LOW @BASEBOARD_FAB2_LIB.BASEBOARD_FAB2(SCH_1):A_HSC_LOW   I174 @BASEBOARD_FAB2_LIB.BASEBOARD_FAB2(SCH_1):PAGE200
     2 AGND_HSC @BASEBOARD_FAB2_LIB.BASEBOARD_FAB2(SCH_1):AGND_HSC   I174 @BASEBOARD_FAB2_LIB.BASEBOARD_FAB2(SCH_1):PAGE200

R1D13 RES_0402-90.9K,1%,1/16W,CHIP,GA
     1 A_HSC_ISET_S @BASEBOARD_FAB2_LIB.BASEBOARD_FAB2(SCH_1):A_HSC_ISET_S    I84 @BASEBOARD_FAB2_LIB.BASEBOARD_FAB2(SCH_1):PAGE199
     2 A_HSC_ISET @BASEBOARD_FAB2_LIB.BASEBOARD_FAB2(SCH_1):A_HSC_ISET    I84 @BASEBOARD_FAB2_LIB.BASEBOARD_FAB2(SCH_1):PAGE199

R1D14 RES_0402-105.0K,1%,1/16W,CHIP,A
     1 A_HSC_CSOUT @BASEBOARD_FAB2_LIB.BASEBOARD_FAB2(SCH_1):A_HSC_CSOUT   I173 @BASEBOARD_FAB2_LIB.BASEBOARD_FAB2(SCH_1):PAGE200
     2 A_HSC_LOW @BASEBOARD_FAB2_LIB.BASEBOARD_FAB2(SCH_1):A_HSC_LOW   I173 @BASEBOARD_FAB2_LIB.BASEBOARD_FAB2(SCH_1):PAGE200

R1D15 RES_0402-100.0K,1%,1/16W,CHIP,A
     1 P12V_PSU @BASEBOARD_FAB2_LIB.BASEBOARD_FAB2(SCH_1):P12V_PSU    I92 @BASEBOARD_FAB2_LIB.BASEBOARD_FAB2(SCH_1):PAGE199
     2 A_HSC_OCP_SEL @BASEBOARD_FAB2_LIB.BASEBOARD_FAB2(SCH_1):A_HSC_OCP_SEL    I92 @BASEBOARD_FAB2_LIB.BASEBOARD_FAB2(SCH_1):PAGE199

R1D16 RES_0402-69.8K,1%,1/16W,CHIP,GA
     1 A_HSC_ISET @BASEBOARD_FAB2_LIB.BASEBOARD_FAB2(SCH_1):A_HSC_ISET    I85 @BASEBOARD_FAB2_LIB.BASEBOARD_FAB2(SCH_1):PAGE199
     2 A_HSC_ISET_S2 @BASEBOARD_FAB2_LIB.BASEBOARD_FAB2(SCH_1):A_HSC_ISET_S2    I85 @BASEBOARD_FAB2_LIB.BASEBOARD_FAB2(SCH_1):PAGE199

R1D18 RES_0402-100.0K,1%,1/16W,CHIP,A
     1 A_HSC_HIGH_EN @BASEBOARD_FAB2_LIB.BASEBOARD_FAB2(SCH_1):A_HSC_HIGH_EN    I87 @BASEBOARD_FAB2_LIB.BASEBOARD_FAB2(SCH_1):PAGE199
     2 AGND_HSC @BASEBOARD_FAB2_LIB.BASEBOARD_FAB2(SCH_1):AGND_HSC    I87 @BASEBOARD_FAB2_LIB.BASEBOARD_FAB2(SCH_1):PAGE199

R1D19 RES_0402-10.0K,1%,1/16W,CHIP,GA
     1 A_HSC_HIGH @BASEBOARD_FAB2_LIB.BASEBOARD_FAB2(SCH_1):A_HSC_HIGH   I175 @BASEBOARD_FAB2_LIB.BASEBOARD_FAB2(SCH_1):PAGE200
     2 AGND_HSC @BASEBOARD_FAB2_LIB.BASEBOARD_FAB2(SCH_1):AGND_HSC   I175 @BASEBOARD_FAB2_LIB.BASEBOARD_FAB2(SCH_1):PAGE200

R1D20 RES_0402-150.0K,1%,1/16W,CHIP,A
     1 A_HSC_CSOUT @BASEBOARD_FAB2_LIB.BASEBOARD_FAB2(SCH_1):A_HSC_CSOUT   I172 @BASEBOARD_FAB2_LIB.BASEBOARD_FAB2(SCH_1):PAGE200
     2 A_HSC_HIGH @BASEBOARD_FAB2_LIB.BASEBOARD_FAB2(SCH_1):A_HSC_HIGH   I172 @BASEBOARD_FAB2_LIB.BASEBOARD_FAB2(SCH_1):PAGE200

R1D21 RES_0402-4.75K,1%,1/16W,CHIP,GA
     1 P3V3_STBY @BASEBOARD_FAB2_LIB.BASEBOARD_FAB2(SCH_1):P3V3_STBY   I204 @BASEBOARD_FAB2_LIB.BASEBOARD_FAB2(SCH_1):PAGE200
     2 FM_OC_DETECT_EN @BASEBOARD_FAB2_LIB.BASEBOARD_FAB2(SCH_1):FM_OC_DETECT_EN   I204 @BASEBOARD_FAB2_LIB.BASEBOARD_FAB2(SCH_1):PAGE200

R1D22 RES_0402-10.0K,1%,1/16W,CHIP,GA
     1 P3V3_STBY @BASEBOARD_FAB2_LIB.BASEBOARD_FAB2(SCH_1):P3V3_STBY   I158 @BASEBOARD_FAB2_LIB.BASEBOARD_FAB2(SCH_1):PAGE200
     2 FM_OC_DETECT_N @BASEBOARD_FAB2_LIB.BASEBOARD_FAB2(SCH_1):FM_OC_DETECT_N   I158 @BASEBOARD_FAB2_LIB.BASEBOARD_FAB2(SCH_1):PAGE200

R1D23 RES_0402-10.0K,1%,1/16W,CHIP,GA
     1 P3V3_STBY @BASEBOARD_FAB2_LIB.BASEBOARD_FAB2(SCH_1):P3V3_STBY   I191 @BASEBOARD_FAB2_LIB.BASEBOARD_FAB2(SCH_1):PAGE200
     2 IRQ_OC_DETECT_N @BASEBOARD_FAB2_LIB.BASEBOARD_FAB2(SCH_1):IRQ_OC_DETECT_N   I191 @BASEBOARD_FAB2_LIB.BASEBOARD_FAB2(SCH_1):PAGE200

R1D24 RES_0402-0.0,5%,1/16W,CHIP,G21A
     1 SMB_BMC_PMBUS_STBY_LVC3_SCL @BASEBOARD_FAB2_LIB.BASEBOARD_FAB2(SCH_1):SMB_BMC_PMBUS_STBY_LVC3_SCL    I27 @BASEBOARD_FAB2_LIB.BASEBOARD_FAB2(SCH_1):PAGE199
     2 SMB_3V3SB_HSC_SCL_R @BASEBOARD_FAB2_LIB.BASEBOARD_FAB2(SCH_1):SMB_3V3SB_HSC_SCL_R    I27 @BASEBOARD_FAB2_LIB.BASEBOARD_FAB2(SCH_1):PAGE199

R1D25 RES_0402-0.0,5%,1/16W,CHIP,G21A
     1 SMB_BMC_PMBUS_STBY_LVC3_SDA @BASEBOARD_FAB2_LIB.BASEBOARD_FAB2(SCH_1):SMB_BMC_PMBUS_STBY_LVC3_SDA    I28 @BASEBOARD_FAB2_LIB.BASEBOARD_FAB2(SCH_1):PAGE199
     2 SMB_3V3SB_HSC_SDA_R @BASEBOARD_FAB2_LIB.BASEBOARD_FAB2(SCH_1):SMB_3V3SB_HSC_SDA_R    I28 @BASEBOARD_FAB2_LIB.BASEBOARD_FAB2(SCH_1):PAGE199

R1D26 RES_0402-33.2,1%,1/16W,CHIP,G2A
     1 IRQ_SML1_PMBUS_ALERT_R_N @BASEBOARD_FAB2_LIB.BASEBOARD_FAB2(SCH_1):IRQ_SML1_PMBUS_ALERT_R_N   I109 @BASEBOARD_FAB2_LIB.BASEBOARD_FAB2(SCH_1):PAGE199
     2 IRQ_SML1_PMBUS_ALERT_N @BASEBOARD_FAB2_LIB.BASEBOARD_FAB2(SCH_1):IRQ_SML1_PMBUS_ALERT_N   I109 @BASEBOARD_FAB2_LIB.BASEBOARD_FAB2(SCH_1):PAGE199

R1D27 RES_0402-4.75K,1%,1/16W,EMPTY,A
     1 A_HSC_VCAP @BASEBOARD_FAB2_LIB.BASEBOARD_FAB2(SCH_1):A_HSC_VCAP    I38 @BASEBOARD_FAB2_LIB.BASEBOARD_FAB2(SCH_1):PAGE199
     2 FM_P12V_HSC_ADR2 @BASEBOARD_FAB2_LIB.BASEBOARD_FAB2(SCH_1):FM_P12V_HSC_ADR2    I38 @BASEBOARD_FAB2_LIB.BASEBOARD_FAB2(SCH_1):PAGE199

R1D28 RES_0402-100.0,1%,1/16W,EMPTY,A
     1 PD_HSC_RETRY_N @BASEBOARD_FAB2_LIB.BASEBOARD_FAB2(SCH_1):PD_HSC_RETRY_N    I26 @BASEBOARD_FAB2_LIB.BASEBOARD_FAB2(SCH_1):PAGE199
     2 AGND_HSC @BASEBOARD_FAB2_LIB.BASEBOARD_FAB2(SCH_1):AGND_HSC    I26 @BASEBOARD_FAB2_LIB.BASEBOARD_FAB2(SCH_1):PAGE199

R1D29 RES_0402-4.75K,1%,1/16W,EMPTY,A
     1 A_HSC_VCAP @BASEBOARD_FAB2_LIB.BASEBOARD_FAB2(SCH_1):A_HSC_VCAP    I37 @BASEBOARD_FAB2_LIB.BASEBOARD_FAB2(SCH_1):PAGE199
     2 FM_P12V_HSC_ADR1 @BASEBOARD_FAB2_LIB.BASEBOARD_FAB2(SCH_1):FM_P12V_HSC_ADR1    I37 @BASEBOARD_FAB2_LIB.BASEBOARD_FAB2(SCH_1):PAGE199

R1D30 RES_0402-33.2,1%,1/16W,CHIP,G2A
     1 IRQ_HSC_FAULT_R_N @BASEBOARD_FAB2_LIB.BASEBOARD_FAB2(SCH_1):IRQ_HSC_FAULT_R_N   I110 @BASEBOARD_FAB2_LIB.BASEBOARD_FAB2(SCH_1):PAGE199
     2 IRQ_HSC_FAULT_N @BASEBOARD_FAB2_LIB.BASEBOARD_FAB2(SCH_1):IRQ_HSC_FAULT_N   I110 @BASEBOARD_FAB2_LIB.BASEBOARD_FAB2(SCH_1):PAGE199

R1D31 RES_0402-6.19K,1%,1/16W,CHIP,GA
     1 PWRGD_P12V_R @BASEBOARD_FAB2_LIB.BASEBOARD_FAB2(SCH_1):PWRGD_P12V_R    I43 @BASEBOARD_FAB2_LIB.BASEBOARD_FAB2(SCH_1):PAGE199
     2    GND @BASEBOARD_FAB2_LIB.BASEBOARD_FAB2(SCH_1):GND    I43 @BASEBOARD_FAB2_LIB.BASEBOARD_FAB2(SCH_1):PAGE199

R1D32 RES_0402-100.0K,1%,1/16W,CHIP,A
     1 A_HSC_VCAP @BASEBOARD_FAB2_LIB.BASEBOARD_FAB2(SCH_1):A_HSC_VCAP    I17 @BASEBOARD_FAB2_LIB.BASEBOARD_FAB2(SCH_1):PAGE199
     2 A_HSC_ISTART @BASEBOARD_FAB2_LIB.BASEBOARD_FAB2(SCH_1):A_HSC_ISTART    I17 @BASEBOARD_FAB2_LIB.BASEBOARD_FAB2(SCH_1):PAGE199

R1D33 RES_0402-33.2,1%,1/16W,CHIP,G2A
     1 PWRGD_P12V_R @BASEBOARD_FAB2_LIB.BASEBOARD_FAB2(SCH_1):PWRGD_P12V_R   I108 @BASEBOARD_FAB2_LIB.BASEBOARD_FAB2(SCH_1):PAGE199
     2 PWRGD_P12V_HSC @BASEBOARD_FAB2_LIB.BASEBOARD_FAB2(SCH_1):PWRGD_P12V_HSC   I108 @BASEBOARD_FAB2_LIB.BASEBOARD_FAB2(SCH_1):PAGE199

R1D34 RES_0402-16K,1.0%,1/16W,CHIP,GA
     1 A_HSC_ISTART @BASEBOARD_FAB2_LIB.BASEBOARD_FAB2(SCH_1):A_HSC_ISTART   I102 @BASEBOARD_FAB2_LIB.BASEBOARD_FAB2(SCH_1):PAGE199
     2 AGND_HSC @BASEBOARD_FAB2_LIB.BASEBOARD_FAB2(SCH_1):AGND_HSC   I102 @BASEBOARD_FAB2_LIB.BASEBOARD_FAB2(SCH_1):PAGE199

R1D35 RES_0402-4.75K,1%,1/16W,CHIP,GA
     1 P3V3_STBY @BASEBOARD_FAB2_LIB.BASEBOARD_FAB2(SCH_1):P3V3_STBY    I12 @BASEBOARD_FAB2_LIB.BASEBOARD_FAB2(SCH_1):PAGE126
     2 FM_OC_DETECT_EN_N @BASEBOARD_FAB2_LIB.BASEBOARD_FAB2(SCH_1):FM_OC_DETECT_EN_N    I12 @BASEBOARD_FAB2_LIB.BASEBOARD_FAB2(SCH_1):PAGE126

R1D36 RES_0402-1.00K,1%,1/16W,CHIP,GA
     1 P12V_STBY @BASEBOARD_FAB2_LIB.BASEBOARD_FAB2(SCH_1):P12V_STBY    I65 @BASEBOARD_FAB2_LIB.BASEBOARD_FAB2(SCH_1):PAGE199
     2 A_HSC_VOUT @BASEBOARD_FAB2_LIB.BASEBOARD_FAB2(SCH_1):A_HSC_VOUT    I65 @BASEBOARD_FAB2_LIB.BASEBOARD_FAB2(SCH_1):PAGE199

R1D37 RES_0402-100.0K,1%,1/16W,CHIP,A
     1 A_HSC_VCAP @BASEBOARD_FAB2_LIB.BASEBOARD_FAB2(SCH_1):A_HSC_VCAP    I15 @BASEBOARD_FAB2_LIB.BASEBOARD_FAB2(SCH_1):PAGE199
     2 A_HSC_ISET @BASEBOARD_FAB2_LIB.BASEBOARD_FAB2(SCH_1):A_HSC_ISET    I15 @BASEBOARD_FAB2_LIB.BASEBOARD_FAB2(SCH_1):PAGE199

R1D39 RES_0402-100.0K,1%,1/16W,CHIP,A
     1 A_HSC_VCAP @BASEBOARD_FAB2_LIB.BASEBOARD_FAB2(SCH_1):A_HSC_VCAP    I16 @BASEBOARD_FAB2_LIB.BASEBOARD_FAB2(SCH_1):PAGE199
     2 A_HSC_PSET @BASEBOARD_FAB2_LIB.BASEBOARD_FAB2(SCH_1):A_HSC_PSET    I16 @BASEBOARD_FAB2_LIB.BASEBOARD_FAB2(SCH_1):PAGE199

R1D40 RES_0402-40.2K,1%,1/16W,CHIP,GA
     1 A_HSC_PSET @BASEBOARD_FAB2_LIB.BASEBOARD_FAB2(SCH_1):A_HSC_PSET   I100 @BASEBOARD_FAB2_LIB.BASEBOARD_FAB2(SCH_1):PAGE199
     2 AGND_HSC @BASEBOARD_FAB2_LIB.BASEBOARD_FAB2(SCH_1):AGND_HSC   I100 @BASEBOARD_FAB2_LIB.BASEBOARD_FAB2(SCH_1):PAGE199

R1D41 RES_0805-0.0,5%,1/8W,CHIP,G221A
     1    GND @BASEBOARD_FAB2_LIB.BASEBOARD_FAB2(SCH_1):GND    I19 @BASEBOARD_FAB2_LIB.BASEBOARD_FAB2(SCH_1):PAGE199
     2 AGND_HSC @BASEBOARD_FAB2_LIB.BASEBOARD_FAB2(SCH_1):AGND_HSC    I19 @BASEBOARD_FAB2_LIB.BASEBOARD_FAB2(SCH_1):PAGE199

R1D42 RES_0402-11K,1%,1/16W,CHIP,G21A
     1 A_HSC_UV @BASEBOARD_FAB2_LIB.BASEBOARD_FAB2(SCH_1):A_HSC_UV    I13 @BASEBOARD_FAB2_LIB.BASEBOARD_FAB2(SCH_1):PAGE199
     2 AGND_HSC @BASEBOARD_FAB2_LIB.BASEBOARD_FAB2(SCH_1):AGND_HSC    I13 @BASEBOARD_FAB2_LIB.BASEBOARD_FAB2(SCH_1):PAGE199

R1D43 RES_0402-7.5K,1%,1/16W,CHIP,G2A
     1 A_HSC_OV @BASEBOARD_FAB2_LIB.BASEBOARD_FAB2(SCH_1):A_HSC_OV     I9 @BASEBOARD_FAB2_LIB.BASEBOARD_FAB2(SCH_1):PAGE199
     2 AGND_HSC @BASEBOARD_FAB2_LIB.BASEBOARD_FAB2(SCH_1):AGND_HSC     I9 @BASEBOARD_FAB2_LIB.BASEBOARD_FAB2(SCH_1):PAGE199

R1D44 RES_0402-0.0,5%,1/16W,CHIP,G21A
     1 A_HSC_MOP @BASEBOARD_FAB2_LIB.BASEBOARD_FAB2(SCH_1):A_HSC_MOP    I44 @BASEBOARD_FAB2_LIB.BASEBOARD_FAB2(SCH_1):PAGE200
     2 A_HSC_HSP @BASEBOARD_FAB2_LIB.BASEBOARD_FAB2(SCH_1):A_HSC_HSP    I44 @BASEBOARD_FAB2_LIB.BASEBOARD_FAB2(SCH_1):PAGE200

R1D45 RES_0402-0.0,5%,1/16W,CHIP,G21A
     1 A_HSC_MON @BASEBOARD_FAB2_LIB.BASEBOARD_FAB2(SCH_1):A_HSC_MON    I43 @BASEBOARD_FAB2_LIB.BASEBOARD_FAB2(SCH_1):PAGE200
     2 A_HSC_HSN @BASEBOARD_FAB2_LIB.BASEBOARD_FAB2(SCH_1):A_HSC_HSN    I43 @BASEBOARD_FAB2_LIB.BASEBOARD_FAB2(SCH_1):PAGE200

R1D46 RES_0402-10.0,1%,1/16W,CHIP,G2A
     1 P12V_HSC_SENP0 @BASEBOARD_FAB2_LIB.BASEBOARD_FAB2(SCH_1):P12V_HSC_SENP0    I48 @BASEBOARD_FAB2_LIB.BASEBOARD_FAB2(SCH_1):PAGE200
     2 A_HSC_HSP @BASEBOARD_FAB2_LIB.BASEBOARD_FAB2(SCH_1):A_HSC_HSP    I48 @BASEBOARD_FAB2_LIB.BASEBOARD_FAB2(SCH_1):PAGE200

R1D47 RES_0402-10.0,1%,1/16W,CHIP,G2A
     1 P12V_HSC_SENN0 @BASEBOARD_FAB2_LIB.BASEBOARD_FAB2(SCH_1):P12V_HSC_SENN0    I52 @BASEBOARD_FAB2_LIB.BASEBOARD_FAB2(SCH_1):PAGE200
     2 A_HSC_HSN @BASEBOARD_FAB2_LIB.BASEBOARD_FAB2(SCH_1):A_HSC_HSN    I52 @BASEBOARD_FAB2_LIB.BASEBOARD_FAB2(SCH_1):PAGE200

R1D48 RES_0402-10.0,1%,1/16W,CHIP,G2A
     1 A_HSC_GATE @BASEBOARD_FAB2_LIB.BASEBOARD_FAB2(SCH_1):A_HSC_GATE    I60 @BASEBOARD_FAB2_LIB.BASEBOARD_FAB2(SCH_1):PAGE200
     2 A_HSC_GATE3_R @BASEBOARD_FAB2_LIB.BASEBOARD_FAB2(SCH_1):A_HSC_GATE3_R    I60 @BASEBOARD_FAB2_LIB.BASEBOARD_FAB2(SCH_1):PAGE200

R1D49 RES_PWR_6PAD-0.001,1%,3W,CHIP,A
     1 P12V_PSU @BASEBOARD_FAB2_LIB.BASEBOARD_FAB2(SCH_1):P12V_PSU    I50 @BASEBOARD_FAB2_LIB.BASEBOARD_FAB2(SCH_1):PAGE200
     2 P12V_MB0_SW @BASEBOARD_FAB2_LIB.BASEBOARD_FAB2(SCH_1):P12V_MB0_SW    I50 @BASEBOARD_FAB2_LIB.BASEBOARD_FAB2(SCH_1):PAGE200
     3 P12V_HSC_SENP0 @BASEBOARD_FAB2_LIB.BASEBOARD_FAB2(SCH_1):P12V_HSC_SENP0    I50 @BASEBOARD_FAB2_LIB.BASEBOARD_FAB2(SCH_1):PAGE200
     4 P12V_HSC_SENN0 @BASEBOARD_FAB2_LIB.BASEBOARD_FAB2(SCH_1):P12V_HSC_SENN0    I50 @BASEBOARD_FAB2_LIB.BASEBOARD_FAB2(SCH_1):PAGE200
     5 P12V_PSU @BASEBOARD_FAB2_LIB.BASEBOARD_FAB2(SCH_1):P12V_PSU    I50 @BASEBOARD_FAB2_LIB.BASEBOARD_FAB2(SCH_1):PAGE200
     6 P12V_MB0_SW @BASEBOARD_FAB2_LIB.BASEBOARD_FAB2(SCH_1):P12V_MB0_SW    I50 @BASEBOARD_FAB2_LIB.BASEBOARD_FAB2(SCH_1):PAGE200

R1D51 RES_0402-10.0,1%,1/16W,CHIP,G2A
     1 A_HSC_C @BASEBOARD_FAB2_LIB.BASEBOARD_FAB2(SCH_1):A_HSC_C   I154 @BASEBOARD_FAB2_LIB.BASEBOARD_FAB2(SCH_1):PAGE200
     2 A_HSC_GATE @BASEBOARD_FAB2_LIB.BASEBOARD_FAB2(SCH_1):A_HSC_GATE   I154 @BASEBOARD_FAB2_LIB.BASEBOARD_FAB2(SCH_1):PAGE200

R1D52 RES_0402-68.1K,1%,1/16W,EMPTY,A
     1 VR_PVCCIN_CPU1_PH5_OCSET @BASEBOARD_FAB2_LIB.BASEBOARD_FAB2(SCH_1):VR_PVCCIN_CPU1_PH5_OCSET    I59 @BASEBOARD_FAB2_LIB.BASEBOARD_FAB2(SCH_1):PAGE209
     2    GND @BASEBOARD_FAB2_LIB.BASEBOARD_FAB2(SCH_1):GND    I59 @BASEBOARD_FAB2_LIB.BASEBOARD_FAB2(SCH_1):PAGE209

R1D53 RES_0402-2.26K,1.0%,1/16W,EMPTA
     1 P3V3_STBY @BASEBOARD_FAB2_LIB.BASEBOARD_FAB2(SCH_1):P3V3_STBY    I33 @BASEBOARD_FAB2_LIB.BASEBOARD_FAB2(SCH_1):PAGE206
     2 PU_VR_PVCCIN_CPU1_FLT1_SMBALT_N @BASEBOARD_FAB2_LIB.BASEBOARD_FAB2(SCH_1):PU_VR_PVCCIN_CPU1_FLT1_SMBALT_N_IMON    I33 @BASEBOARD_FAB2_LIB.BASEBOARD_FAB2(SCH_1):PAGE206

R1D54 RES_0402-68.1K,1%,1/16W,EMPTY,A
     1 VR_PVCCIN_CPU1_PH4_OCSET @BASEBOARD_FAB2_LIB.BASEBOARD_FAB2(SCH_1):VR_PVCCIN_CPU1_PH4_OCSET    I75 @BASEBOARD_FAB2_LIB.BASEBOARD_FAB2(SCH_1):PAGE208
     2    GND @BASEBOARD_FAB2_LIB.BASEBOARD_FAB2(SCH_1):GND    I75 @BASEBOARD_FAB2_LIB.BASEBOARD_FAB2(SCH_1):PAGE208

R1D55 RES_0402-68.1K,1%,1/16W,EMPTY,A
     1 VR_PVCCIN_CPU1_PH3_OCSET @BASEBOARD_FAB2_LIB.BASEBOARD_FAB2(SCH_1):VR_PVCCIN_CPU1_PH3_OCSET    I76 @BASEBOARD_FAB2_LIB.BASEBOARD_FAB2(SCH_1):PAGE208
     2    GND @BASEBOARD_FAB2_LIB.BASEBOARD_FAB2(SCH_1):GND    I76 @BASEBOARD_FAB2_LIB.BASEBOARD_FAB2(SCH_1):PAGE208

R1E1 RES_0402-10.0,1%,1/16W,CHIP,G2A
     1 A_HSC_GATE @BASEBOARD_FAB2_LIB.BASEBOARD_FAB2(SCH_1):A_HSC_GATE    I56 @BASEBOARD_FAB2_LIB.BASEBOARD_FAB2(SCH_1):PAGE200
     2 A_HSC_GATE1_R @BASEBOARD_FAB2_LIB.BASEBOARD_FAB2(SCH_1):A_HSC_GATE1_R    I56 @BASEBOARD_FAB2_LIB.BASEBOARD_FAB2(SCH_1):PAGE200

R1E3 RES_0603-100.0,1%,1/10W,CHIP,GA
     1 PVCCIN_CPU1 @BASEBOARD_FAB2_LIB.BASEBOARD_FAB2(SCH_1):PVCCIN_CPU1     I7 @BASEBOARD_FAB2_LIB.BASEBOARD_FAB2(SCH_1):PAGE208
     2    GND @BASEBOARD_FAB2_LIB.BASEBOARD_FAB2(SCH_1):GND     I7 @BASEBOARD_FAB2_LIB.BASEBOARD_FAB2(SCH_1):PAGE208

R1E4 RES_0402-100.0,1%,1/16W,CHIP,GA
     1 VSENSE_PVCCIN_CPU1_P @BASEBOARD_FAB2_LIB.BASEBOARD_FAB2(SCH_1):VSENSE_PVCCIN_CPU1_P    I15 @BASEBOARD_FAB2_LIB.BASEBOARD_FAB2(SCH_1):PAGE209
     2 PVCCIN_CPU1 @BASEBOARD_FAB2_LIB.BASEBOARD_FAB2(SCH_1):PVCCIN_CPU1    I15 @BASEBOARD_FAB2_LIB.BASEBOARD_FAB2(SCH_1):PAGE209

R1E5 RES_0402-1.00K,1%,1/16W,EMPTY,A
     1 VSENSE_PVCCIN_CPU1_P @BASEBOARD_FAB2_LIB.BASEBOARD_FAB2(SCH_1):VSENSE_PVCCIN_CPU1_P     I3 @BASEBOARD_FAB2_LIB.BASEBOARD_FAB2(SCH_1):PAGE209
     2 VSENSE_PVCCIN_CPU1_N @BASEBOARD_FAB2_LIB.BASEBOARD_FAB2(SCH_1):VSENSE_PVCCIN_CPU1_N     I3 @BASEBOARD_FAB2_LIB.BASEBOARD_FAB2(SCH_1):PAGE209

R1E6 RES_0402-0.0,5%,1/16W,CHIP,G21A
     1 VSENSE_PVCCIN_CPU1_P @BASEBOARD_FAB2_LIB.BASEBOARD_FAB2(SCH_1):VSENSE_PVCCIN_CPU1_P    I11 @BASEBOARD_FAB2_LIB.BASEBOARD_FAB2(SCH_1):PAGE209
     2 VSENSE_PVCCIN_CPU1_SKT_VSEN @BASEBOARD_FAB2_LIB.BASEBOARD_FAB2(SCH_1):VSENSE_PVCCIN_CPU1_SKT_VSEN    I11 @BASEBOARD_FAB2_LIB.BASEBOARD_FAB2(SCH_1):PAGE209

R1E7 RES_0402-0.0,5%,1/16W,CHIP,G21A
     1 VSENSE_PVCCIN_CPU1_N @BASEBOARD_FAB2_LIB.BASEBOARD_FAB2(SCH_1):VSENSE_PVCCIN_CPU1_N    I10 @BASEBOARD_FAB2_LIB.BASEBOARD_FAB2(SCH_1):PAGE209
     2 VSENSE_PVCCIN_CPU1_SKT_VRTN @BASEBOARD_FAB2_LIB.BASEBOARD_FAB2(SCH_1):VSENSE_PVCCIN_CPU1_SKT_VRTN    I10 @BASEBOARD_FAB2_LIB.BASEBOARD_FAB2(SCH_1):PAGE209

R1E8 RES_0402-100.0,1%,1/16W,CHIP,GA
     1 VSENSE_PVCCIN_CPU1_N @BASEBOARD_FAB2_LIB.BASEBOARD_FAB2(SCH_1):VSENSE_PVCCIN_CPU1_N     I9 @BASEBOARD_FAB2_LIB.BASEBOARD_FAB2(SCH_1):PAGE209
     2    GND @BASEBOARD_FAB2_LIB.BASEBOARD_FAB2(SCH_1):GND     I9 @BASEBOARD_FAB2_LIB.BASEBOARD_FAB2(SCH_1):PAGE209

R1E9 RES_0402-1.00K,1%,1/16W,CHIP,GA
     1 P3V3_STBY @BASEBOARD_FAB2_LIB.BASEBOARD_FAB2(SCH_1):P3V3_STBY    I34 @BASEBOARD_FAB2_LIB.BASEBOARD_FAB2(SCH_1):PAGE167
     2 PU_TMP421_2_A0 @BASEBOARD_FAB2_LIB.BASEBOARD_FAB2(SCH_1):PU_TMP421_2_A0    I34 @BASEBOARD_FAB2_LIB.BASEBOARD_FAB2(SCH_1):PAGE167

R1E10 RES_0402-1.00K,1%,1/16W,CHIP,GA
     1 P3V3_STBY @BASEBOARD_FAB2_LIB.BASEBOARD_FAB2(SCH_1):P3V3_STBY    I38 @BASEBOARD_FAB2_LIB.BASEBOARD_FAB2(SCH_1):PAGE167
     2 PD_TMP421_2_A1 @BASEBOARD_FAB2_LIB.BASEBOARD_FAB2(SCH_1):PD_TMP421_2_A1    I38 @BASEBOARD_FAB2_LIB.BASEBOARD_FAB2(SCH_1):PAGE167

R1E11 RES_0402-10.0K,1%,1/16W,EMPTY,A
     1 P3V3_STBY @BASEBOARD_FAB2_LIB.BASEBOARD_FAB2(SCH_1):P3V3_STBY   I120 @BASEBOARD_FAB2_LIB.BASEBOARD_FAB2(SCH_1):PAGE161
     2 FM_ENABLE_FAN_POWER @BASEBOARD_FAB2_LIB.BASEBOARD_FAB2(SCH_1):FM_ENABLE_FAN_POWER   I120 @BASEBOARD_FAB2_LIB.BASEBOARD_FAB2(SCH_1):PAGE161

R1E12 RES_0402-4.75K,1%,1/16W,CHIP,GA
     1 P5V_STBY @BASEBOARD_FAB2_LIB.BASEBOARD_FAB2(SCH_1):P5V_STBY    I51 @BASEBOARD_FAB2_LIB.BASEBOARD_FAB2(SCH_1):PAGE161
     2 FAN_PWM_OUT_SYS0_R @BASEBOARD_FAB2_LIB.BASEBOARD_FAB2(SCH_1):FAN_PWM_OUT_SYS0_R    I51 @BASEBOARD_FAB2_LIB.BASEBOARD_FAB2(SCH_1):PAGE161

R1E13 RES_0402-68.1K,1%,1/16W,EMPTY,A
     1 VR_PVCCIN_CPU1_PH2_OCSET @BASEBOARD_FAB2_LIB.BASEBOARD_FAB2(SCH_1):VR_PVCCIN_CPU1_PH2_OCSET    I67 @BASEBOARD_FAB2_LIB.BASEBOARD_FAB2(SCH_1):PAGE207
     2    GND @BASEBOARD_FAB2_LIB.BASEBOARD_FAB2(SCH_1):GND    I67 @BASEBOARD_FAB2_LIB.BASEBOARD_FAB2(SCH_1):PAGE207

R1E14 RES_0402-68.1K,1%,1/16W,EMPTY,A
     1 VR_PVCCIN_CPU1_PH1_OCSET @BASEBOARD_FAB2_LIB.BASEBOARD_FAB2(SCH_1):VR_PVCCIN_CPU1_PH1_OCSET    I68 @BASEBOARD_FAB2_LIB.BASEBOARD_FAB2(SCH_1):PAGE207
     2    GND @BASEBOARD_FAB2_LIB.BASEBOARD_FAB2(SCH_1):GND    I68 @BASEBOARD_FAB2_LIB.BASEBOARD_FAB2(SCH_1):PAGE207

R1F1 RES_0402-4.75K,1%,1/16W,CHIP,GA
     1 P3V3_STBY @BASEBOARD_FAB2_LIB.BASEBOARD_FAB2(SCH_1):P3V3_STBY    I45 @BASEBOARD_FAB2_LIB.BASEBOARD_FAB2(SCH_1):PAGE161
     2 FAN_TACH0 @BASEBOARD_FAB2_LIB.BASEBOARD_FAB2(SCH_1):FAN_TACH0    I45 @BASEBOARD_FAB2_LIB.BASEBOARD_FAB2(SCH_1):PAGE161

R1F2 RES_0402-100.0,1%,1/16W,CHIP,GA
     1 FAN_TACH0 @BASEBOARD_FAB2_LIB.BASEBOARD_FAB2(SCH_1):FAN_TACH0    I43 @BASEBOARD_FAB2_LIB.BASEBOARD_FAB2(SCH_1):PAGE161
     2 FAN_TACH0_CPU0_D2 @BASEBOARD_FAB2_LIB.BASEBOARD_FAB2(SCH_1):FAN_TACH0_CPU0_D2    I43 @BASEBOARD_FAB2_LIB.BASEBOARD_FAB2(SCH_1):PAGE161

R1F3 RES_1206-0.002,1%,1W,CHIP,G521A
     1 P12V_NVDIMM_GHJ @BASEBOARD_FAB2_LIB.BASEBOARD_FAB2(SCH_1):P12V_NVDIMM_GHJ   I131 @BASEBOARD_FAB2_LIB.BASEBOARD_FAB2(SCH_1):PAGE197
     2 P12V_STBY @BASEBOARD_FAB2_LIB.BASEBOARD_FAB2(SCH_1):P12V_STBY   I131 @BASEBOARD_FAB2_LIB.BASEBOARD_FAB2(SCH_1):PAGE197

R1F4 RES_0402-2,1.0%,1/16W,CHIP,G21A
     1 M_G_CPU_VREF @BASEBOARD_FAB2_LIB.BASEBOARD_FAB2(SCH_1):M_G_CPU_VREF     I7 @BASEBOARD_FAB2_LIB.BASEBOARD_FAB2(SCH_1):PAGE100
     2 M_G_VREF @BASEBOARD_FAB2_LIB.BASEBOARD_FAB2(SCH_1):M_G_VREF     I7 @BASEBOARD_FAB2_LIB.BASEBOARD_FAB2(SCH_1):PAGE100

R1F5 RES_0402-1.00K,1%,1/16W,CHIP,GA
     1 PVDDQ_GHJ @BASEBOARD_FAB2_LIB.BASEBOARD_FAB2(SCH_1):PVDDQ_GHJ     I6 @BASEBOARD_FAB2_LIB.BASEBOARD_FAB2(SCH_1):PAGE100
     2 M_G_VREF @BASEBOARD_FAB2_LIB.BASEBOARD_FAB2(SCH_1):M_G_VREF     I6 @BASEBOARD_FAB2_LIB.BASEBOARD_FAB2(SCH_1):PAGE100

R1F6 RES_0402-1.00K,1%,1/16W,CHIP,GA
     1 M_G_VREF @BASEBOARD_FAB2_LIB.BASEBOARD_FAB2(SCH_1):M_G_VREF     I2 @BASEBOARD_FAB2_LIB.BASEBOARD_FAB2(SCH_1):PAGE100
     2    GND @BASEBOARD_FAB2_LIB.BASEBOARD_FAB2(SCH_1):GND     I2 @BASEBOARD_FAB2_LIB.BASEBOARD_FAB2(SCH_1):PAGE100

R1F8 RES_0402-0.0,5%,1/16W,CHIP,G21A
     1 FAN_TACH0 @BASEBOARD_FAB2_LIB.BASEBOARD_FAB2(SCH_1):FAN_TACH0   I268 @BASEBOARD_FAB2_LIB.BASEBOARD_FAB2(SCH_1):PAGE181
     2 FAN_TACH0_R @BASEBOARD_FAB2_LIB.BASEBOARD_FAB2(SCH_1):FAN_TACH0_R   I268 @BASEBOARD_FAB2_LIB.BASEBOARD_FAB2(SCH_1):PAGE181

R1F9 RES_0402-0.0,5%,1/16W,EMPTY,G2A
     1 FM_BMC_READY_N @BASEBOARD_FAB2_LIB.BASEBOARD_FAB2(SCH_1):FM_BMC_READY_N   I107 @BASEBOARD_FAB2_LIB.BASEBOARD_FAB2(SCH_1):PAGE182
     2 FAN_PWM_OUT_SYS0_R1 @BASEBOARD_FAB2_LIB.BASEBOARD_FAB2(SCH_1):FAN_PWM_OUT_SYS0_R1   I107 @BASEBOARD_FAB2_LIB.BASEBOARD_FAB2(SCH_1):PAGE182

R1G1 RES_0402-2,1.0%,1/16W,CHIP,G21A
     1 M_H_CPU_VREF @BASEBOARD_FAB2_LIB.BASEBOARD_FAB2(SCH_1):M_H_CPU_VREF    I25 @BASEBOARD_FAB2_LIB.BASEBOARD_FAB2(SCH_1):PAGE100
     2 M_H_VREF @BASEBOARD_FAB2_LIB.BASEBOARD_FAB2(SCH_1):M_H_VREF    I25 @BASEBOARD_FAB2_LIB.BASEBOARD_FAB2(SCH_1):PAGE100

R1G2 RES_0402-1.00K,1%,1/16W,CHIP,GA
     1 PVDDQ_GHJ @BASEBOARD_FAB2_LIB.BASEBOARD_FAB2(SCH_1):PVDDQ_GHJ    I19 @BASEBOARD_FAB2_LIB.BASEBOARD_FAB2(SCH_1):PAGE100
     2 M_H_VREF @BASEBOARD_FAB2_LIB.BASEBOARD_FAB2(SCH_1):M_H_VREF    I19 @BASEBOARD_FAB2_LIB.BASEBOARD_FAB2(SCH_1):PAGE100

R1G3 RES_0402-1.00K,1%,1/16W,CHIP,GA
     1 M_H_VREF @BASEBOARD_FAB2_LIB.BASEBOARD_FAB2(SCH_1):M_H_VREF    I20 @BASEBOARD_FAB2_LIB.BASEBOARD_FAB2(SCH_1):PAGE100
     2    GND @BASEBOARD_FAB2_LIB.BASEBOARD_FAB2(SCH_1):GND    I20 @BASEBOARD_FAB2_LIB.BASEBOARD_FAB2(SCH_1):PAGE100

R1G5 RES_0402-10.0,1%,1/16W,CHIP,G2A
     1 VSENSE_PVDDQ_GHJ_P @BASEBOARD_FAB2_LIB.BASEBOARD_FAB2(SCH_1):VSENSE_PVDDQ_GHJ_P    I32 @BASEBOARD_FAB2_LIB.BASEBOARD_FAB2(SCH_1):PAGE223
     2 VR_PVDDQ_GHJ_AVSP @BASEBOARD_FAB2_LIB.BASEBOARD_FAB2(SCH_1):VR_PVDDQ_GHJ_AVSP    I32 @BASEBOARD_FAB2_LIB.BASEBOARD_FAB2(SCH_1):PAGE223

R1G6 RES_0402-2.26K,1.0%,1/16W,EMPTA
     1 P3V3_STBY @BASEBOARD_FAB2_LIB.BASEBOARD_FAB2(SCH_1):P3V3_STBY    I13 @BASEBOARD_FAB2_LIB.BASEBOARD_FAB2(SCH_1):PAGE223
     2 PU_VR_PVDDQ_GHJ_FAULT1 @BASEBOARD_FAB2_LIB.BASEBOARD_FAB2(SCH_1):PU_VR_PVDDQ_GHJ_FAULT1    I13 @BASEBOARD_FAB2_LIB.BASEBOARD_FAB2(SCH_1):PAGE223

R1G7 RES_0402-150.0,1%,1/16W,CHIP,GA
     1 SVID_CLK1_CPU1_R @BASEBOARD_FAB2_LIB.BASEBOARD_FAB2(SCH_1):SVID_CLK1_CPU1_R    I53 @BASEBOARD_FAB2_LIB.BASEBOARD_FAB2(SCH_1):PAGE223
     2 SVID_CLK_PVDDQ_GHJ @BASEBOARD_FAB2_LIB.BASEBOARD_FAB2(SCH_1):SVID_CLK_PVDDQ_GHJ    I53 @BASEBOARD_FAB2_LIB.BASEBOARD_FAB2(SCH_1):PAGE223

R1G8 RES_0402-33.2,1%,1/16W,CHIP,G2A
     1 IRQ_PVDDQ_GHJ_VRHOT_LVT3_R_N @BASEBOARD_FAB2_LIB.BASEBOARD_FAB2(SCH_1):IRQ_PVDDQ_GHJ_VRHOT_LVT3_R_N    I82 @BASEBOARD_FAB2_LIB.BASEBOARD_FAB2(SCH_1):PAGE223
     2 IRQ_PVDDQ_GHJ_VRHOT_LVT3_N @BASEBOARD_FAB2_LIB.BASEBOARD_FAB2(SCH_1):IRQ_PVDDQ_GHJ_VRHOT_LVT3_N    I82 @BASEBOARD_FAB2_LIB.BASEBOARD_FAB2(SCH_1):PAGE223

R1G9 RES_0402-0.0,5%,1/16W,CHIP,G21A
     1 SVID_ALERT_PVDDQ_GHJ @BASEBOARD_FAB2_LIB.BASEBOARD_FAB2(SCH_1):SVID_ALERT_PVDDQ_GHJ    I16 @BASEBOARD_FAB2_LIB.BASEBOARD_FAB2(SCH_1):PAGE223
     2 SVID_ALERT1_CPU1_R_N @BASEBOARD_FAB2_LIB.BASEBOARD_FAB2(SCH_1):SVID_ALERT1_CPU1_R_N    I16 @BASEBOARD_FAB2_LIB.BASEBOARD_FAB2(SCH_1):PAGE223

R1G10 RES_0402-0.0,5%,1/16W,CHIP,G21A
     1 SVID_VDIO_PVDDQ_GHJ @BASEBOARD_FAB2_LIB.BASEBOARD_FAB2(SCH_1):SVID_VDIO_PVDDQ_GHJ    I23 @BASEBOARD_FAB2_LIB.BASEBOARD_FAB2(SCH_1):PAGE223
     2 SVID_DIO1_CPU1_R @BASEBOARD_FAB2_LIB.BASEBOARD_FAB2(SCH_1):SVID_DIO1_CPU1_R    I23 @BASEBOARD_FAB2_LIB.BASEBOARD_FAB2(SCH_1):PAGE223

R1G11 RES_0402-1.00K,1%,1/16W,CHIP,GA
     1 P3V3_STBY @BASEBOARD_FAB2_LIB.BASEBOARD_FAB2(SCH_1):P3V3_STBY    I79 @BASEBOARD_FAB2_LIB.BASEBOARD_FAB2(SCH_1):PAGE223
     2 IRQ_PVDDQ_GHJ_VRHOT_LVT3_R_N @BASEBOARD_FAB2_LIB.BASEBOARD_FAB2(SCH_1):IRQ_PVDDQ_GHJ_VRHOT_LVT3_R_N    I79 @BASEBOARD_FAB2_LIB.BASEBOARD_FAB2(SCH_1):PAGE223

R1G12 RES_0402-22.1,1.0%,1/16W,CHIP,A
     1 PWRGD_PVDDQ_GHJ_R @BASEBOARD_FAB2_LIB.BASEBOARD_FAB2(SCH_1):PWRGD_PVDDQ_GHJ_R    I14 @BASEBOARD_FAB2_LIB.BASEBOARD_FAB2(SCH_1):PAGE223
     2 PWRGD_PVDDQ_GHJ @BASEBOARD_FAB2_LIB.BASEBOARD_FAB2(SCH_1):PWRGD_PVDDQ_GHJ    I14 @BASEBOARD_FAB2_LIB.BASEBOARD_FAB2(SCH_1):PAGE223

R1G14 RES_0402-2,1.0%,1/16W,CHIP,G21A
     1 M_J_CPU_VREF @BASEBOARD_FAB2_LIB.BASEBOARD_FAB2(SCH_1):M_J_CPU_VREF    I41 @BASEBOARD_FAB2_LIB.BASEBOARD_FAB2(SCH_1):PAGE100
     2 M_J_VREF @BASEBOARD_FAB2_LIB.BASEBOARD_FAB2(SCH_1):M_J_VREF    I41 @BASEBOARD_FAB2_LIB.BASEBOARD_FAB2(SCH_1):PAGE100

R1G15 RES_0402-1.00K,1%,1/16W,CHIP,GA
     1 PVDDQ_GHJ @BASEBOARD_FAB2_LIB.BASEBOARD_FAB2(SCH_1):PVDDQ_GHJ    I35 @BASEBOARD_FAB2_LIB.BASEBOARD_FAB2(SCH_1):PAGE100
     2 M_J_VREF @BASEBOARD_FAB2_LIB.BASEBOARD_FAB2(SCH_1):M_J_VREF    I35 @BASEBOARD_FAB2_LIB.BASEBOARD_FAB2(SCH_1):PAGE100

R1G16 RES_0402-1.00K,1%,1/16W,CHIP,GA
     1 P3V3_STBY @BASEBOARD_FAB2_LIB.BASEBOARD_FAB2(SCH_1):P3V3_STBY    I17 @BASEBOARD_FAB2_LIB.BASEBOARD_FAB2(SCH_1):PAGE223
     2 PWRGD_PVDDQ_GHJ_R @BASEBOARD_FAB2_LIB.BASEBOARD_FAB2(SCH_1):PWRGD_PVDDQ_GHJ_R    I17 @BASEBOARD_FAB2_LIB.BASEBOARD_FAB2(SCH_1):PAGE223

R1G17 RES_0402-1.00K,1%,1/16W,CHIP,GA
     1 M_J_VREF @BASEBOARD_FAB2_LIB.BASEBOARD_FAB2(SCH_1):M_J_VREF    I36 @BASEBOARD_FAB2_LIB.BASEBOARD_FAB2(SCH_1):PAGE100
     2    GND @BASEBOARD_FAB2_LIB.BASEBOARD_FAB2(SCH_1):GND    I36 @BASEBOARD_FAB2_LIB.BASEBOARD_FAB2(SCH_1):PAGE100

R1G19 RES_0402-0.0,5%,1/16W,CHIP,G21A
     1 SMB_VR_SCL_VDDQ_GHJ @BASEBOARD_FAB2_LIB.BASEBOARD_FAB2(SCH_1):SMB_VR_SCL_VDDQ_GHJ    I21 @BASEBOARD_FAB2_LIB.BASEBOARD_FAB2(SCH_1):PAGE223
     2 SMB_VR_STBY_LVC3_SCL @BASEBOARD_FAB2_LIB.BASEBOARD_FAB2(SCH_1):SMB_VR_STBY_LVC3_SCL    I21 @BASEBOARD_FAB2_LIB.BASEBOARD_FAB2(SCH_1):PAGE223

R1G20 RES_0603-120.0,1%,1/10W,CHIP,GA
     1 PVDDQ_GHJ @BASEBOARD_FAB2_LIB.BASEBOARD_FAB2(SCH_1):PVDDQ_GHJ    I58 @BASEBOARD_FAB2_LIB.BASEBOARD_FAB2(SCH_1):PAGE225
     2    GND @BASEBOARD_FAB2_LIB.BASEBOARD_FAB2(SCH_1):GND    I58 @BASEBOARD_FAB2_LIB.BASEBOARD_FAB2(SCH_1):PAGE225

R1G21 RES_0402-0.0,5%,1/16W,CHIP,G21A
     1 SMB_VR_SDA_VDDQ_GHJ @BASEBOARD_FAB2_LIB.BASEBOARD_FAB2(SCH_1):SMB_VR_SDA_VDDQ_GHJ    I22 @BASEBOARD_FAB2_LIB.BASEBOARD_FAB2(SCH_1):PAGE223
     2 SMB_VR_STBY_LVC3_SDA @BASEBOARD_FAB2_LIB.BASEBOARD_FAB2(SCH_1):SMB_VR_STBY_LVC3_SDA    I22 @BASEBOARD_FAB2_LIB.BASEBOARD_FAB2(SCH_1):PAGE223

R1G22 RES_0402-5.36K,1.0%,1/16W,CHIPA
     1 VR_PVDDQ_GHJ_XADDR2 @BASEBOARD_FAB2_LIB.BASEBOARD_FAB2(SCH_1):VR_PVDDQ_GHJ_XADDR2    I78 @BASEBOARD_FAB2_LIB.BASEBOARD_FAB2(SCH_1):PAGE223
     2    GND @BASEBOARD_FAB2_LIB.BASEBOARD_FAB2(SCH_1):GND    I78 @BASEBOARD_FAB2_LIB.BASEBOARD_FAB2(SCH_1):PAGE223

R1G23 RES_0402-4.02K,1%,1/16W,CHIP,GA
     1 VR_PVDDQ_GHJ_XADDR1 @BASEBOARD_FAB2_LIB.BASEBOARD_FAB2(SCH_1):VR_PVDDQ_GHJ_XADDR1    I77 @BASEBOARD_FAB2_LIB.BASEBOARD_FAB2(SCH_1):PAGE223
     2    GND @BASEBOARD_FAB2_LIB.BASEBOARD_FAB2(SCH_1):GND    I77 @BASEBOARD_FAB2_LIB.BASEBOARD_FAB2(SCH_1):PAGE223

R1G24 RES_0402-1.5K,1%,1/16W,CHIP,G2A
     1 VR_PVDDQ_GHJ_VINSEN @BASEBOARD_FAB2_LIB.BASEBOARD_FAB2(SCH_1):VR_PVDDQ_GHJ_VINSEN    I58 @BASEBOARD_FAB2_LIB.BASEBOARD_FAB2(SCH_1):PAGE223
     2    GND @BASEBOARD_FAB2_LIB.BASEBOARD_FAB2(SCH_1):GND    I58 @BASEBOARD_FAB2_LIB.BASEBOARD_FAB2(SCH_1):PAGE223

R1G25 RES_0402-68.1K,1%,1/16W,EMPTY,A
     1 VR_PVDDQ_GHJ_PH2_OCSET @BASEBOARD_FAB2_LIB.BASEBOARD_FAB2(SCH_1):VR_PVDDQ_GHJ_PH2_OCSET   I114 @BASEBOARD_FAB2_LIB.BASEBOARD_FAB2(SCH_1):PAGE224
     2    GND @BASEBOARD_FAB2_LIB.BASEBOARD_FAB2(SCH_1):GND   I114 @BASEBOARD_FAB2_LIB.BASEBOARD_FAB2(SCH_1):PAGE224

R1G26 RES_0402-68.1K,1%,1/16W,EMPTY,A
     1 VR_PVDDQ_GHJ_PH1_OCSET @BASEBOARD_FAB2_LIB.BASEBOARD_FAB2(SCH_1):VR_PVDDQ_GHJ_PH1_OCSET   I112 @BASEBOARD_FAB2_LIB.BASEBOARD_FAB2(SCH_1):PAGE224
     2    GND @BASEBOARD_FAB2_LIB.BASEBOARD_FAB2(SCH_1):GND   I112 @BASEBOARD_FAB2_LIB.BASEBOARD_FAB2(SCH_1):PAGE224

R1G27 RES_0402-0.0,5%,1/16W,CHIP,G21A
     1 VR_PVDDQ_GHJ_VD12 @BASEBOARD_FAB2_LIB.BASEBOARD_FAB2(SCH_1):VR_PVDDQ_GHJ_VD12    I88 @BASEBOARD_FAB2_LIB.BASEBOARD_FAB2(SCH_1):PAGE223
     2 VR_PVDDQ_GHJ_AIREF2 @BASEBOARD_FAB2_LIB.BASEBOARD_FAB2(SCH_1):VR_PVDDQ_GHJ_AIREF2    I88 @BASEBOARD_FAB2_LIB.BASEBOARD_FAB2(SCH_1):PAGE223

R1G28 RES_0402-0.0,5%,1/16W,CHIP,G21A
     1 VR_PVDDQ_GHJ_VD12 @BASEBOARD_FAB2_LIB.BASEBOARD_FAB2(SCH_1):VR_PVDDQ_GHJ_VD12    I87 @BASEBOARD_FAB2_LIB.BASEBOARD_FAB2(SCH_1):PAGE223
     2 VR_PVDDQ_GHJ_AIREF1 @BASEBOARD_FAB2_LIB.BASEBOARD_FAB2(SCH_1):VR_PVDDQ_GHJ_AIREF1    I87 @BASEBOARD_FAB2_LIB.BASEBOARD_FAB2(SCH_1):PAGE223

R1L1 RES_0402-2.0K,1%,1/16W,CHIP,G2A
     1   P3V3 @BASEBOARD_FAB2_LIB.BASEBOARD_FAB2(SCH_1):P3V3    I25 @BASEBOARD_FAB2_LIB.BASEBOARD_FAB2(SCH_1):PAGE174
     2 PU_DATAIN1_SATA_2 @BASEBOARD_FAB2_LIB.BASEBOARD_FAB2(SCH_1):PU_DATAIN1_SATA_2    I25 @BASEBOARD_FAB2_LIB.BASEBOARD_FAB2(SCH_1):PAGE174

R1L2 RES_0402-10.0,1%,1/16W,CHIP,G2A
     1 FM_CPLD_DBG_PWR_EN_N @BASEBOARD_FAB2_LIB.BASEBOARD_FAB2(SCH_1):FM_CPLD_DBG_PWR_EN_N   I186 @BASEBOARD_FAB2_LIB.BASEBOARD_FAB2(SCH_1):PAGE155
     2 FM_CPLD_DBG_PWR_EN_R_N @BASEBOARD_FAB2_LIB.BASEBOARD_FAB2(SCH_1):FM_CPLD_DBG_PWR_EN_R_N   I186 @BASEBOARD_FAB2_LIB.BASEBOARD_FAB2(SCH_1):PAGE155

R1L3 RES_0402-1.00K,1%,1/16W,CHIP,GA
     1 PD_SATA2_CONTROLLER_TYPE @BASEBOARD_FAB2_LIB.BASEBOARD_FAB2(SCH_1):PD_SATA2_CONTROLLER_TYPE     I5 @BASEBOARD_FAB2_LIB.BASEBOARD_FAB2(SCH_1):PAGE174
     2    GND @BASEBOARD_FAB2_LIB.BASEBOARD_FAB2(SCH_1):GND     I5 @BASEBOARD_FAB2_LIB.BASEBOARD_FAB2(SCH_1):PAGE174

R1L6 RES_0402-0.0,5%,1/16W,CHIP,G21A
     1 FM_UART_SWITCH_N @BASEBOARD_FAB2_LIB.BASEBOARD_FAB2(SCH_1):FM_UART_SWITCH_N     I6 @BASEBOARD_FAB2_LIB.BASEBOARD_FAB2(SCH_1):PAGE168
     2 FM_DB_UART_SEL0_N @BASEBOARD_FAB2_LIB.BASEBOARD_FAB2(SCH_1):FM_DB_UART_SEL0_N     I6 @BASEBOARD_FAB2_LIB.BASEBOARD_FAB2(SCH_1):PAGE168

R1L7 RES_0402-4.75K,1%,1/16W,CHIP,GA
     1 P3V3_STBY @BASEBOARD_FAB2_LIB.BASEBOARD_FAB2(SCH_1):P3V3_STBY   I382 @BASEBOARD_FAB2_LIB.BASEBOARD_FAB2(SCH_1):PAGE157
     2 FM_BMC_CPLD_MP_RST_N @BASEBOARD_FAB2_LIB.BASEBOARD_FAB2(SCH_1):FM_BMC_CPLD_MP_RST_N   I382 @BASEBOARD_FAB2_LIB.BASEBOARD_FAB2(SCH_1):PAGE157

R1L8 RES_0402-470.0,5%,1/16W,CHIP,GA
     1 P5V_STBY @BASEBOARD_FAB2_LIB.BASEBOARD_FAB2(SCH_1):P5V_STBY    I58 @BASEBOARD_FAB2_LIB.BASEBOARD_FAB2(SCH_1):PAGE175
     2 FP_ID_LED_XOR_R @BASEBOARD_FAB2_LIB.BASEBOARD_FAB2(SCH_1):FP_ID_LED_XOR_R    I58 @BASEBOARD_FAB2_LIB.BASEBOARD_FAB2(SCH_1):PAGE175

R1L9 RES_0402-100.0K,1%,1/16W,CHIP,A
     1 P12V_STBY @BASEBOARD_FAB2_LIB.BASEBOARD_FAB2(SCH_1):P12V_STBY   I130 @BASEBOARD_FAB2_LIB.BASEBOARD_FAB2(SCH_1):PAGE155
     2 FM_CPLD_DBG_PWR_EN @BASEBOARD_FAB2_LIB.BASEBOARD_FAB2(SCH_1):FM_CPLD_DBG_PWR_EN   I130 @BASEBOARD_FAB2_LIB.BASEBOARD_FAB2(SCH_1):PAGE155

R1L11 RES_0402-10.0,1%,1/16W,CHIP,G2A
     1 LED_POSTCODE_7 @BASEBOARD_FAB2_LIB.BASEBOARD_FAB2(SCH_1):LED_POSTCODE_7    I76 @BASEBOARD_FAB2_LIB.BASEBOARD_FAB2(SCH_1):PAGE155
     2 LED_POSTCODE_7_R @BASEBOARD_FAB2_LIB.BASEBOARD_FAB2(SCH_1):LED_POSTCODE_7_R    I76 @BASEBOARD_FAB2_LIB.BASEBOARD_FAB2(SCH_1):PAGE155

R1L12 RES_0402-0.0,5%,1/16W,CHIP,G21A
     1 PWRGD_P3V3 @BASEBOARD_FAB2_LIB.BASEBOARD_FAB2(SCH_1):PWRGD_P3V3    I63 @BASEBOARD_FAB2_LIB.BASEBOARD_FAB2(SCH_1):PAGE175
     2 PWRGD_P3V3_R @BASEBOARD_FAB2_LIB.BASEBOARD_FAB2(SCH_1):PWRGD_P3V3_R    I63 @BASEBOARD_FAB2_LIB.BASEBOARD_FAB2(SCH_1):PAGE175

R1L13 RES_0402-1.00K,1%,1/16W,CHIP,GA
     1 XDP_SYSPWROK @BASEBOARD_FAB2_LIB.BASEBOARD_FAB2(SCH_1):XDP_SYSPWROK     I6 @BASEBOARD_FAB2_LIB.BASEBOARD_FAB2(SCH_1):PAGE111
     2 P3V3_STBY @BASEBOARD_FAB2_LIB.BASEBOARD_FAB2(SCH_1):P3V3_STBY     I6 @BASEBOARD_FAB2_LIB.BASEBOARD_FAB2(SCH_1):PAGE111

R1L14 RES_0402-10.0,1%,1/16W,CHIP,G2A
     1 LED_POSTCODE_6 @BASEBOARD_FAB2_LIB.BASEBOARD_FAB2(SCH_1):LED_POSTCODE_6    I75 @BASEBOARD_FAB2_LIB.BASEBOARD_FAB2(SCH_1):PAGE155
     2 LED_POSTCODE_6_R @BASEBOARD_FAB2_LIB.BASEBOARD_FAB2(SCH_1):LED_POSTCODE_6_R    I75 @BASEBOARD_FAB2_LIB.BASEBOARD_FAB2(SCH_1):PAGE155

R1L15 RES_0402-150.0,1%,1/16W,CHIP,GA
     1 PVCCIO_CPU0 @BASEBOARD_FAB2_LIB.BASEBOARD_FAB2(SCH_1):PVCCIO_CPU0    I60 @BASEBOARD_FAB2_LIB.BASEBOARD_FAB2(SCH_1):PAGE112
     2 XDP_CPU_TMS @BASEBOARD_FAB2_LIB.BASEBOARD_FAB2(SCH_1):XDP_CPU_TMS    I60 @BASEBOARD_FAB2_LIB.BASEBOARD_FAB2(SCH_1):PAGE112

R1L16 RES_0402-49.9,1%,1/16W,CHIP,G2A
     1 PWRGD_P3V3_R1 @BASEBOARD_FAB2_LIB.BASEBOARD_FAB2(SCH_1):PWRGD_P3V3_R1    I68 @BASEBOARD_FAB2_LIB.BASEBOARD_FAB2(SCH_1):PAGE196
     2 PWRGD_P3V3 @BASEBOARD_FAB2_LIB.BASEBOARD_FAB2(SCH_1):PWRGD_P3V3    I68 @BASEBOARD_FAB2_LIB.BASEBOARD_FAB2(SCH_1):PAGE196

R1L17 RES_0402-150.0,1%,1/16W,CHIP,GA
     1 XDP_CPU_PWR_DEBUG_N @BASEBOARD_FAB2_LIB.BASEBOARD_FAB2(SCH_1):XDP_CPU_PWR_DEBUG_N    I56 @BASEBOARD_FAB2_LIB.BASEBOARD_FAB2(SCH_1):PAGE111
     2 PVCCIO_CPU0 @BASEBOARD_FAB2_LIB.BASEBOARD_FAB2(SCH_1):PVCCIO_CPU0    I56 @BASEBOARD_FAB2_LIB.BASEBOARD_FAB2(SCH_1):PAGE111

R1L18 RES_0402-10.0,1%,1/16W,CHIP,G2A
     1 LED_POSTCODE_5 @BASEBOARD_FAB2_LIB.BASEBOARD_FAB2(SCH_1):LED_POSTCODE_5    I74 @BASEBOARD_FAB2_LIB.BASEBOARD_FAB2(SCH_1):PAGE155
     2 LED_POSTCODE_5_R @BASEBOARD_FAB2_LIB.BASEBOARD_FAB2(SCH_1):LED_POSTCODE_5_R    I74 @BASEBOARD_FAB2_LIB.BASEBOARD_FAB2(SCH_1):PAGE155

R1L19 RES_0402-4.75K,1%,1/16W,EMPTY,A
     1 P3V3_STBY @BASEBOARD_FAB2_LIB.BASEBOARD_FAB2(SCH_1):P3V3_STBY    I24 @BASEBOARD_FAB2_LIB.BASEBOARD_FAB2(SCH_1):PAGE175
     2 FM_DEBUG_RST_BTN_N @BASEBOARD_FAB2_LIB.BASEBOARD_FAB2(SCH_1):FM_DEBUG_RST_BTN_N    I24 @BASEBOARD_FAB2_LIB.BASEBOARD_FAB2(SCH_1):PAGE175

R1L20 RES_0402-10.0,1%,1/16W,CHIP,G2A
     1 LED_POSTCODE_4 @BASEBOARD_FAB2_LIB.BASEBOARD_FAB2(SCH_1):LED_POSTCODE_4    I73 @BASEBOARD_FAB2_LIB.BASEBOARD_FAB2(SCH_1):PAGE155
     2 LED_POSTCODE_4_R @BASEBOARD_FAB2_LIB.BASEBOARD_FAB2(SCH_1):LED_POSTCODE_4_R    I73 @BASEBOARD_FAB2_LIB.BASEBOARD_FAB2(SCH_1):PAGE155

R1L21 RES_0402-64.9,1.0%,1/16W,CHIP,A
     1   P3V3 @BASEBOARD_FAB2_LIB.BASEBOARD_FAB2(SCH_1):P3V3    I43 @BASEBOARD_FAB2_LIB.BASEBOARD_FAB2(SCH_1):PAGE177
     2 FP_LED_HDD_ACTIVITY_AND_R_N @BASEBOARD_FAB2_LIB.BASEBOARD_FAB2(SCH_1):FP_LED_HDD_ACTIVITY_AND_R_N    I43 @BASEBOARD_FAB2_LIB.BASEBOARD_FAB2(SCH_1):PAGE177

R1L22 RES_0402-200.0,1%,1/16W,CHIP,GA
     1 FM_DEBUG_RST_BTN_N @BASEBOARD_FAB2_LIB.BASEBOARD_FAB2(SCH_1):FM_DEBUG_RST_BTN_N    I22 @BASEBOARD_FAB2_LIB.BASEBOARD_FAB2(SCH_1):PAGE175
     2 FP_RST_BTN_R_N @BASEBOARD_FAB2_LIB.BASEBOARD_FAB2(SCH_1):FP_RST_BTN_R_N    I22 @BASEBOARD_FAB2_LIB.BASEBOARD_FAB2(SCH_1):PAGE175

R1L23 RES_0402-1.00K,1%,1/16W,CHIP,GA
     1 XDP_PWRGD_RST_N @BASEBOARD_FAB2_LIB.BASEBOARD_FAB2(SCH_1):XDP_PWRGD_RST_N    I13 @BASEBOARD_FAB2_LIB.BASEBOARD_FAB2(SCH_1):PAGE111
     2 P3V3_STBY @BASEBOARD_FAB2_LIB.BASEBOARD_FAB2(SCH_1):P3V3_STBY    I13 @BASEBOARD_FAB2_LIB.BASEBOARD_FAB2(SCH_1):PAGE111

R1L24 RES_0402-10.0,1%,1/16W,CHIP,G2A
     1 LED_POSTCODE_3 @BASEBOARD_FAB2_LIB.BASEBOARD_FAB2(SCH_1):LED_POSTCODE_3    I68 @BASEBOARD_FAB2_LIB.BASEBOARD_FAB2(SCH_1):PAGE155
     2 LED_POSTCODE_3_R @BASEBOARD_FAB2_LIB.BASEBOARD_FAB2(SCH_1):LED_POSTCODE_3_R    I68 @BASEBOARD_FAB2_LIB.BASEBOARD_FAB2(SCH_1):PAGE155

R1L25 RES_0402-10.0,1%,1/16W,CHIP,G2A
     1 LED_POSTCODE_2 @BASEBOARD_FAB2_LIB.BASEBOARD_FAB2(SCH_1):LED_POSTCODE_2    I67 @BASEBOARD_FAB2_LIB.BASEBOARD_FAB2(SCH_1):PAGE155
     2 LED_POSTCODE_2_R @BASEBOARD_FAB2_LIB.BASEBOARD_FAB2(SCH_1):LED_POSTCODE_2_R    I67 @BASEBOARD_FAB2_LIB.BASEBOARD_FAB2(SCH_1):PAGE155

R1L26 RES_0402-33.2,1%,1/16W,CHIP,G2A
     1 FM_PWR_BTN_R_N @BASEBOARD_FAB2_LIB.BASEBOARD_FAB2(SCH_1):FM_PWR_BTN_R_N    I13 @BASEBOARD_FAB2_LIB.BASEBOARD_FAB2(SCH_1):PAGE175
     2 FM_PWR_BTN_N @BASEBOARD_FAB2_LIB.BASEBOARD_FAB2(SCH_1):FM_PWR_BTN_N    I13 @BASEBOARD_FAB2_LIB.BASEBOARD_FAB2(SCH_1):PAGE175

R1L27 RES_0402-4.75K,1%,1/16W,CHIP,GA
     1 P3V3_STBY @BASEBOARD_FAB2_LIB.BASEBOARD_FAB2(SCH_1):P3V3_STBY     I5 @BASEBOARD_FAB2_LIB.BASEBOARD_FAB2(SCH_1):PAGE175
     2 FP_PWR_BTN_R_N @BASEBOARD_FAB2_LIB.BASEBOARD_FAB2(SCH_1):FP_PWR_BTN_R_N     I5 @BASEBOARD_FAB2_LIB.BASEBOARD_FAB2(SCH_1):PAGE175

R1L28 RES_0402-4.75K,1%,1/16W,CHIP,GA
     1 P3V3_STBY @BASEBOARD_FAB2_LIB.BASEBOARD_FAB2(SCH_1):P3V3_STBY    I66 @BASEBOARD_FAB2_LIB.BASEBOARD_FAB2(SCH_1):PAGE111
     2 FM_DEBUG_RST_BTN_R1_N @BASEBOARD_FAB2_LIB.BASEBOARD_FAB2(SCH_1):FM_DEBUG_RST_BTN_R1_N    I66 @BASEBOARD_FAB2_LIB.BASEBOARD_FAB2(SCH_1):PAGE111

R1L29 RES_0402-33.2,1%,1/16W,CHIP,G2A
     1 FM_DEBUG_RST_BTN_R1_N @BASEBOARD_FAB2_LIB.BASEBOARD_FAB2(SCH_1):FM_DEBUG_RST_BTN_R1_N    I68 @BASEBOARD_FAB2_LIB.BASEBOARD_FAB2(SCH_1):PAGE111
     2 FM_DEBUG_RST_BTN_N @BASEBOARD_FAB2_LIB.BASEBOARD_FAB2(SCH_1):FM_DEBUG_RST_BTN_N    I68 @BASEBOARD_FAB2_LIB.BASEBOARD_FAB2(SCH_1):PAGE111

R1L30 RES_0402-10.0,1%,1/16W,CHIP,G2A
     1 LED_POSTCODE_1 @BASEBOARD_FAB2_LIB.BASEBOARD_FAB2(SCH_1):LED_POSTCODE_1    I66 @BASEBOARD_FAB2_LIB.BASEBOARD_FAB2(SCH_1):PAGE155
     2 LED_POSTCODE_1_R @BASEBOARD_FAB2_LIB.BASEBOARD_FAB2(SCH_1):LED_POSTCODE_1_R    I66 @BASEBOARD_FAB2_LIB.BASEBOARD_FAB2(SCH_1):PAGE155

R1L31 RES_0402-200.0,1%,1/16W,CHIP,GA
     1 FP_PWR_BTN_R_N @BASEBOARD_FAB2_LIB.BASEBOARD_FAB2(SCH_1):FP_PWR_BTN_R_N     I4 @BASEBOARD_FAB2_LIB.BASEBOARD_FAB2(SCH_1):PAGE175
     2 FP_PWR_BTN_R1_N @BASEBOARD_FAB2_LIB.BASEBOARD_FAB2(SCH_1):FP_PWR_BTN_R1_N     I4 @BASEBOARD_FAB2_LIB.BASEBOARD_FAB2(SCH_1):PAGE175

R1L32 RES_0402-10.0,1%,1/16W,CHIP,G2A
     1 LED_POSTCODE_0 @BASEBOARD_FAB2_LIB.BASEBOARD_FAB2(SCH_1):LED_POSTCODE_0    I65 @BASEBOARD_FAB2_LIB.BASEBOARD_FAB2(SCH_1):PAGE155
     2 LED_POSTCODE_0_R @BASEBOARD_FAB2_LIB.BASEBOARD_FAB2(SCH_1):LED_POSTCODE_0_R    I65 @BASEBOARD_FAB2_LIB.BASEBOARD_FAB2(SCH_1):PAGE155

R1L33 RES_0402-221,1.0%,1/16W,CHIP,GA
     1 FM_BEEP_LED_P @BASEBOARD_FAB2_LIB.BASEBOARD_FAB2(SCH_1):FM_BEEP_LED_P    I45 @BASEBOARD_FAB2_LIB.BASEBOARD_FAB2(SCH_1):PAGE175
     2 P3V3_STBY @BASEBOARD_FAB2_LIB.BASEBOARD_FAB2(SCH_1):P3V3_STBY    I45 @BASEBOARD_FAB2_LIB.BASEBOARD_FAB2(SCH_1):PAGE175

R1L36 RES_0402-1.00K,1%,1/16W,CHIP,GA
     1 P3V3_STBY @BASEBOARD_FAB2_LIB.BASEBOARD_FAB2(SCH_1):P3V3_STBY    I11 @BASEBOARD_FAB2_LIB.BASEBOARD_FAB2(SCH_1):PAGE168
     2 FM_DB_PRESENT @BASEBOARD_FAB2_LIB.BASEBOARD_FAB2(SCH_1):FM_DB_PRESENT    I11 @BASEBOARD_FAB2_LIB.BASEBOARD_FAB2(SCH_1):PAGE168

R1L37 RES_0402-301.0,1%,1/16W,CHIP,GA
     1 P5V_STBY @BASEBOARD_FAB2_LIB.BASEBOARD_FAB2(SCH_1):P5V_STBY    I33 @BASEBOARD_FAB2_LIB.BASEBOARD_FAB2(SCH_1):PAGE177
     2 LED_P5V_STBY @BASEBOARD_FAB2_LIB.BASEBOARD_FAB2(SCH_1):LED_P5V_STBY    I33 @BASEBOARD_FAB2_LIB.BASEBOARD_FAB2(SCH_1):PAGE177

R1L38 RES_0402-1.00K,1%,1/16W,CHIP,GA
     1 P3V3_STBY @BASEBOARD_FAB2_LIB.BASEBOARD_FAB2(SCH_1):P3V3_STBY    I22 @BASEBOARD_FAB2_LIB.BASEBOARD_FAB2(SCH_1):PAGE168
     2 FM_POST_CARD_PRES_BMC_N @BASEBOARD_FAB2_LIB.BASEBOARD_FAB2(SCH_1):FM_POST_CARD_PRES_BMC_N    I22 @BASEBOARD_FAB2_LIB.BASEBOARD_FAB2(SCH_1):PAGE168

R1L39 RES_0402-100.0,1%,1/16W,CHIP,GA
     1 P1V05_PCH_STBY @BASEBOARD_FAB2_LIB.BASEBOARD_FAB2(SCH_1):P1V05_PCH_STBY    I76 @BASEBOARD_FAB2_LIB.BASEBOARD_FAB2(SCH_1):PAGE112
     2 XDP_PRDY_N @BASEBOARD_FAB2_LIB.BASEBOARD_FAB2(SCH_1):XDP_PRDY_N    I76 @BASEBOARD_FAB2_LIB.BASEBOARD_FAB2(SCH_1):PAGE112

R1L41 RES_0402-100.0,1%,1/16W,CHIP,GA
     1 P1V05_PCH_STBY @BASEBOARD_FAB2_LIB.BASEBOARD_FAB2(SCH_1):P1V05_PCH_STBY    I77 @BASEBOARD_FAB2_LIB.BASEBOARD_FAB2(SCH_1):PAGE112
     2 XDP_PREQ_N @BASEBOARD_FAB2_LIB.BASEBOARD_FAB2(SCH_1):XDP_PREQ_N    I77 @BASEBOARD_FAB2_LIB.BASEBOARD_FAB2(SCH_1):PAGE112

R1L43 RES_0402-330,5%,1/16W,CHIP,G21A
     1 FM_UARTSW_LSB_R_N @BASEBOARD_FAB2_LIB.BASEBOARD_FAB2(SCH_1):FM_UARTSW_LSB_R_N   I131 @BASEBOARD_FAB2_LIB.BASEBOARD_FAB2(SCH_1):PAGE158
     2 P3V3_STBY @BASEBOARD_FAB2_LIB.BASEBOARD_FAB2(SCH_1):P3V3_STBY   I131 @BASEBOARD_FAB2_LIB.BASEBOARD_FAB2(SCH_1):PAGE158

R1L44 RES_0402-330,5%,1/16W,CHIP,G21A
     1 FM_UARTSW_MSB_R_N @BASEBOARD_FAB2_LIB.BASEBOARD_FAB2(SCH_1):FM_UARTSW_MSB_R_N   I136 @BASEBOARD_FAB2_LIB.BASEBOARD_FAB2(SCH_1):PAGE158
     2 P3V3_STBY @BASEBOARD_FAB2_LIB.BASEBOARD_FAB2(SCH_1):P3V3_STBY   I136 @BASEBOARD_FAB2_LIB.BASEBOARD_FAB2(SCH_1):PAGE158

R1L45 0R2J-L-GP_SMD-RG5-0R2J-L-GP,63A
     1 FM_SPEAKER_PCH_N @BASEBOARD_FAB2_LIB.BASEBOARD_FAB2(SCH_1):FM_SPEAKER_PCH_N    I89 @BASEBOARD_FAB2_LIB.BASEBOARD_FAB2(SCH_1):PAGE175
     2 FM_SPEAKER_PCH_N_R @BASEBOARD_FAB2_LIB.BASEBOARD_FAB2(SCH_1):FM_SPEAKER_PCH_N_R    I89 @BASEBOARD_FAB2_LIB.BASEBOARD_FAB2(SCH_1):PAGE175

R1M3 RES_0402-100.0,1%,1/16W,CHIP,GA
     1 PVCCIO_CPU0 @BASEBOARD_FAB2_LIB.BASEBOARD_FAB2(SCH_1):PVCCIO_CPU0    I51 @BASEBOARD_FAB2_LIB.BASEBOARD_FAB2(SCH_1):PAGE112
     2 XDP_CPU_PRDY_N @BASEBOARD_FAB2_LIB.BASEBOARD_FAB2(SCH_1):XDP_CPU_PRDY_N    I51 @BASEBOARD_FAB2_LIB.BASEBOARD_FAB2(SCH_1):PAGE112

R1M4 RES_0402-100.0,1%,1/16W,CHIP,GA
     1 PVCCIO_CPU0 @BASEBOARD_FAB2_LIB.BASEBOARD_FAB2(SCH_1):PVCCIO_CPU0    I54 @BASEBOARD_FAB2_LIB.BASEBOARD_FAB2(SCH_1):PAGE112
     2 XDP_CPU_PREQ_N @BASEBOARD_FAB2_LIB.BASEBOARD_FAB2(SCH_1):XDP_CPU_PREQ_N    I54 @BASEBOARD_FAB2_LIB.BASEBOARD_FAB2(SCH_1):PAGE112

R1M5 RES_0402-0.0,5%,1/16W,CHIP,G21A
     1 USB2_P01_DP @BASEBOARD_FAB2_LIB.BASEBOARD_FAB2(SCH_1):USB2_P01_DP    I16 @BASEBOARD_FAB2_LIB.BASEBOARD_FAB2(SCH_1):PAGE176
     2 USB2_P01_ESD_DP @BASEBOARD_FAB2_LIB.BASEBOARD_FAB2(SCH_1):USB2_P01_ESD_DP    I16 @BASEBOARD_FAB2_LIB.BASEBOARD_FAB2(SCH_1):PAGE176

R1M6 RES_0402-0.0,5%,1/16W,CHIP,G21A
     1 USB2_P01_DN @BASEBOARD_FAB2_LIB.BASEBOARD_FAB2(SCH_1):USB2_P01_DN    I31 @BASEBOARD_FAB2_LIB.BASEBOARD_FAB2(SCH_1):PAGE176
     2 USB2_P01_ESD_DN @BASEBOARD_FAB2_LIB.BASEBOARD_FAB2(SCH_1):USB2_P01_ESD_DN    I31 @BASEBOARD_FAB2_LIB.BASEBOARD_FAB2(SCH_1):PAGE176

R1M8 RES_0402-20.0,1%,1/16W,CHIP,G2A
     1 SMB_SENSOR_TMP421_1_SCL @BASEBOARD_FAB2_LIB.BASEBOARD_FAB2(SCH_1):SMB_SENSOR_TMP421_1_SCL    I74 @BASEBOARD_FAB2_LIB.BASEBOARD_FAB2(SCH_1):PAGE167
     2 SMB_SENSOR_STBY_LVC3_SCL @BASEBOARD_FAB2_LIB.BASEBOARD_FAB2(SCH_1):SMB_SENSOR_STBY_LVC3_SCL    I74 @BASEBOARD_FAB2_LIB.BASEBOARD_FAB2(SCH_1):PAGE167

R1M9 RES_0402-20.0,1%,1/16W,CHIP,G2A
     1 SMB_SENSOR_TMP421_1_SDA @BASEBOARD_FAB2_LIB.BASEBOARD_FAB2(SCH_1):SMB_SENSOR_TMP421_1_SDA     I8 @BASEBOARD_FAB2_LIB.BASEBOARD_FAB2(SCH_1):PAGE167
     2 SMB_SENSOR_STBY_LVC3_SDA @BASEBOARD_FAB2_LIB.BASEBOARD_FAB2(SCH_1):SMB_SENSOR_STBY_LVC3_SDA     I8 @BASEBOARD_FAB2_LIB.BASEBOARD_FAB2(SCH_1):PAGE167

R1M10 RES_0402-0.0,5%,1/16W,CHIP,G21A
     1 LED_PCH_SATA_HDD_N @BASEBOARD_FAB2_LIB.BASEBOARD_FAB2(SCH_1):LED_PCH_SATA_HDD_N     I6 @BASEBOARD_FAB2_LIB.BASEBOARD_FAB2(SCH_1):PAGE177
     2 LED_SATA_ACT_R_N @BASEBOARD_FAB2_LIB.BASEBOARD_FAB2(SCH_1):LED_SATA_ACT_R_N     I6 @BASEBOARD_FAB2_LIB.BASEBOARD_FAB2(SCH_1):PAGE177

R1M11 RES_0402-10.0K,1%,1/16W,CHIP,GA
     1   P3V3 @BASEBOARD_FAB2_LIB.BASEBOARD_FAB2(SCH_1):P3V3     I9 @BASEBOARD_FAB2_LIB.BASEBOARD_FAB2(SCH_1):PAGE177
     2 LED_SATA_ACT_R_N @BASEBOARD_FAB2_LIB.BASEBOARD_FAB2(SCH_1):LED_SATA_ACT_R_N     I9 @BASEBOARD_FAB2_LIB.BASEBOARD_FAB2(SCH_1):PAGE177

R1M12 RES_0402-10.0K,1%,1/16W,CHIP,GA
     1   P3V3 @BASEBOARD_FAB2_LIB.BASEBOARD_FAB2(SCH_1):P3V3     I8 @BASEBOARD_FAB2_LIB.BASEBOARD_FAB2(SCH_1):PAGE177
     2 LED_SAS_ACT_R_N @BASEBOARD_FAB2_LIB.BASEBOARD_FAB2(SCH_1):LED_SAS_ACT_R_N     I8 @BASEBOARD_FAB2_LIB.BASEBOARD_FAB2(SCH_1):PAGE177

R1M13 RES_0402-0.0,5%,1/16W,CHIP,G21A
     1 LED_PCH_SSATA_HDD_N @BASEBOARD_FAB2_LIB.BASEBOARD_FAB2(SCH_1):LED_PCH_SSATA_HDD_N     I3 @BASEBOARD_FAB2_LIB.BASEBOARD_FAB2(SCH_1):PAGE177
     2 LED_SAS_ACT_R_N @BASEBOARD_FAB2_LIB.BASEBOARD_FAB2(SCH_1):LED_SAS_ACT_R_N     I3 @BASEBOARD_FAB2_LIB.BASEBOARD_FAB2(SCH_1):PAGE177

R1M14 RES_0402-200.0,1%,1/16W,CHIP,GA
     1 RST_PCIE_CPU_DEV0_N @BASEBOARD_FAB2_LIB.BASEBOARD_FAB2(SCH_1):RST_PCIE_CPU_DEV0_N   I220 @BASEBOARD_FAB2_LIB.BASEBOARD_FAB2(SCH_1):PAGE186
     2 RST_PCIE_CPU_DEV0_R_N @BASEBOARD_FAB2_LIB.BASEBOARD_FAB2(SCH_1):RST_PCIE_CPU_DEV0_R_N   I220 @BASEBOARD_FAB2_LIB.BASEBOARD_FAB2(SCH_1):PAGE186

R1M15 RES_0402-0.0,5%,1/16W,CHIP,G21A
     1 RMII_BMC_OCP_CRSDV @BASEBOARD_FAB2_LIB.BASEBOARD_FAB2(SCH_1):RMII_BMC_OCP_CRSDV   I339 @BASEBOARD_FAB2_LIB.BASEBOARD_FAB2(SCH_1):PAGE186
     2 RMII_BMC_OCP_CRSDV_R @BASEBOARD_FAB2_LIB.BASEBOARD_FAB2(SCH_1):RMII_BMC_OCP_CRSDV_R   I339 @BASEBOARD_FAB2_LIB.BASEBOARD_FAB2(SCH_1):PAGE186

R1M16 RES_0402-0.0,5%,1/16W,CHIP,G21A
     1 RMII_BMC_OCP_RXD1 @BASEBOARD_FAB2_LIB.BASEBOARD_FAB2(SCH_1):RMII_BMC_OCP_RXD1   I337 @BASEBOARD_FAB2_LIB.BASEBOARD_FAB2(SCH_1):PAGE186
     2 RMII_BMC_OCP_RXD1_R @BASEBOARD_FAB2_LIB.BASEBOARD_FAB2(SCH_1):RMII_BMC_OCP_RXD1_R   I337 @BASEBOARD_FAB2_LIB.BASEBOARD_FAB2(SCH_1):PAGE186

R1M17 RES_0402-0.0,5%,1/16W,CHIP,G21A
     1 RMII_BMC_OCP_RXD0 @BASEBOARD_FAB2_LIB.BASEBOARD_FAB2(SCH_1):RMII_BMC_OCP_RXD0   I338 @BASEBOARD_FAB2_LIB.BASEBOARD_FAB2(SCH_1):PAGE186
     2 RMII_BMC_OCP_RXD0_R @BASEBOARD_FAB2_LIB.BASEBOARD_FAB2(SCH_1):RMII_BMC_OCP_RXD0_R   I338 @BASEBOARD_FAB2_LIB.BASEBOARD_FAB2(SCH_1):PAGE186

R1M18 RES_0402-0.0,5%,1/16W,CHIP,G21A
     1 RMII_BMC_OCP_RXER_R @BASEBOARD_FAB2_LIB.BASEBOARD_FAB2(SCH_1):RMII_BMC_OCP_RXER_R   I340 @BASEBOARD_FAB2_LIB.BASEBOARD_FAB2(SCH_1):PAGE186
     2 RMII_BMC_OCP_RXER @BASEBOARD_FAB2_LIB.BASEBOARD_FAB2(SCH_1):RMII_BMC_OCP_RXER   I340 @BASEBOARD_FAB2_LIB.BASEBOARD_FAB2(SCH_1):PAGE186

R1M19 RES_0402-1.00K,1%,1/16W,CHIP,GA
     1 P1V8_MCP_CPU0 @BASEBOARD_FAB2_LIB.BASEBOARD_FAB2(SCH_1):P1V8_MCP_CPU0   I202 @BASEBOARD_FAB2_LIB.BASEBOARD_FAB2(SCH_1):PAGE113
     2 JTAG_MCP_TMS @BASEBOARD_FAB2_LIB.BASEBOARD_FAB2(SCH_1):JTAG_MCP_TMS   I202 @BASEBOARD_FAB2_LIB.BASEBOARD_FAB2(SCH_1):PAGE113

R1M20 RES_0402-1.00K,1%,1/16W,CHIP,GA
     1 P1V8_MCP_CPU0 @BASEBOARD_FAB2_LIB.BASEBOARD_FAB2(SCH_1):P1V8_MCP_CPU0   I204 @BASEBOARD_FAB2_LIB.BASEBOARD_FAB2(SCH_1):PAGE113
     2 JTAG_MCP_MUX_TDI @BASEBOARD_FAB2_LIB.BASEBOARD_FAB2(SCH_1):JTAG_MCP_MUX_TDI   I204 @BASEBOARD_FAB2_LIB.BASEBOARD_FAB2(SCH_1):PAGE113

R1M21 RES_0402-1.00K,1%,1/16W,CHIP,GA
     1 P1V8_MCP_CPU0 @BASEBOARD_FAB2_LIB.BASEBOARD_FAB2(SCH_1):P1V8_MCP_CPU0   I205 @BASEBOARD_FAB2_LIB.BASEBOARD_FAB2(SCH_1):PAGE113
     2 JTAG_MCP_TRST_N @BASEBOARD_FAB2_LIB.BASEBOARD_FAB2(SCH_1):JTAG_MCP_TRST_N   I205 @BASEBOARD_FAB2_LIB.BASEBOARD_FAB2(SCH_1):PAGE113

R1M22 RES_0402-49.9,1%,1/16W,CHIP,G2A
     1 JTAG_MCP_TMS_R1 @BASEBOARD_FAB2_LIB.BASEBOARD_FAB2(SCH_1):JTAG_MCP_TMS_R1   I195 @BASEBOARD_FAB2_LIB.BASEBOARD_FAB2(SCH_1):PAGE113
     2 JTAG_MCP_TMS @BASEBOARD_FAB2_LIB.BASEBOARD_FAB2(SCH_1):JTAG_MCP_TMS   I195 @BASEBOARD_FAB2_LIB.BASEBOARD_FAB2(SCH_1):PAGE113

R1M23 RES_0402-1.00K,1%,1/16W,EMPTY,A
     1 JTAG_MCP_TRST_N @BASEBOARD_FAB2_LIB.BASEBOARD_FAB2(SCH_1):JTAG_MCP_TRST_N   I199 @BASEBOARD_FAB2_LIB.BASEBOARD_FAB2(SCH_1):PAGE113
     2    GND @BASEBOARD_FAB2_LIB.BASEBOARD_FAB2(SCH_1):GND   I199 @BASEBOARD_FAB2_LIB.BASEBOARD_FAB2(SCH_1):PAGE113

R1M24 RES_0402-10.0K,1%,1/16W,CHIP,GA
     1 P3V3_STBY @BASEBOARD_FAB2_LIB.BASEBOARD_FAB2(SCH_1):P3V3_STBY   I105 @BASEBOARD_FAB2_LIB.BASEBOARD_FAB2(SCH_1):PAGE176
     2 FM_OC0_USB_N @BASEBOARD_FAB2_LIB.BASEBOARD_FAB2(SCH_1):FM_OC0_USB_N   I105 @BASEBOARD_FAB2_LIB.BASEBOARD_FAB2(SCH_1):PAGE176

R1M25 RES_0402-10.0K,1%,1/16W,CHIP,GA
     1 FM_USB_P0_EN_BOOT_BIOS_STRAP_N @BASEBOARD_FAB2_LIB.BASEBOARD_FAB2(SCH_1):FM_USB_P0_EN_BOOT_BIOS_STRAP_N   I111 @BASEBOARD_FAB2_LIB.BASEBOARD_FAB2(SCH_1):PAGE176
     2    GND @BASEBOARD_FAB2_LIB.BASEBOARD_FAB2(SCH_1):GND   I111 @BASEBOARD_FAB2_LIB.BASEBOARD_FAB2(SCH_1):PAGE176

R1R1 RES_0402-0.0,5%,1/16W,CHIP,G21A
     1 RST_PLTRST_N @BASEBOARD_FAB2_LIB.BASEBOARD_FAB2(SCH_1):RST_PLTRST_N   I195 @BASEBOARD_FAB2_LIB.BASEBOARD_FAB2(SCH_1):PAGE139
     2 RST_PLTRST_SPRV_R_N @BASEBOARD_FAB2_LIB.BASEBOARD_FAB2(SCH_1):RST_PLTRST_SPRV_R_N   I195 @BASEBOARD_FAB2_LIB.BASEBOARD_FAB2(SCH_1):PAGE139

R1R3 RES_0402-3.32K,1%,1/16W,CHIP,GA
     1 P3V3_STBY @BASEBOARD_FAB2_LIB.BASEBOARD_FAB2(SCH_1):P3V3_STBY    I11 @BASEBOARD_FAB2_LIB.BASEBOARD_FAB2(SCH_1):PAGE140
     2 PU_NV_WP_N @BASEBOARD_FAB2_LIB.BASEBOARD_FAB2(SCH_1):PU_NV_WP_N    I11 @BASEBOARD_FAB2_LIB.BASEBOARD_FAB2(SCH_1):PAGE140

R1R5 RES_0402-4.75K,1%,1/16W,CHIP,GA
     1 P3V3_STBY @BASEBOARD_FAB2_LIB.BASEBOARD_FAB2(SCH_1):P3V3_STBY    I73 @BASEBOARD_FAB2_LIB.BASEBOARD_FAB2(SCH_1):PAGE170
     2 FM_FAST_PROCHOT_THROTTLE_DLY_BU @BASEBOARD_FAB2_LIB.BASEBOARD_FAB2(SCH_1):FM_FAST_PROCHOT_THROTTLE_DLY_BUF_N    I73 @BASEBOARD_FAB2_LIB.BASEBOARD_FAB2(SCH_1):PAGE170

R1R6 RES_0402-3.32K,1%,1/16W,EMPTY,A
     1 SPI_NIC_MOSI @BASEBOARD_FAB2_LIB.BASEBOARD_FAB2(SCH_1):SPI_NIC_MOSI    I14 @BASEBOARD_FAB2_LIB.BASEBOARD_FAB2(SCH_1):PAGE140
     2    GND @BASEBOARD_FAB2_LIB.BASEBOARD_FAB2(SCH_1):GND    I14 @BASEBOARD_FAB2_LIB.BASEBOARD_FAB2(SCH_1):PAGE140

R1R7 RES_0402-20.0K,1%,1/16W,CHIP,GA
     1 P3V3_STBY @BASEBOARD_FAB2_LIB.BASEBOARD_FAB2(SCH_1):P3V3_STBY    I12 @BASEBOARD_FAB2_LIB.BASEBOARD_FAB2(SCH_1):PAGE140
     2 SPI_NIC_MOSI @BASEBOARD_FAB2_LIB.BASEBOARD_FAB2(SCH_1):SPI_NIC_MOSI    I12 @BASEBOARD_FAB2_LIB.BASEBOARD_FAB2(SCH_1):PAGE140

R1R8 RES_0402-0.0,5%,1/16W,CHIP,G21A
     1 FM_THROTTLE_R1_N @BASEBOARD_FAB2_LIB.BASEBOARD_FAB2(SCH_1):FM_THROTTLE_R1_N    I51 @BASEBOARD_FAB2_LIB.BASEBOARD_FAB2(SCH_1):PAGE170
     2 FM_THROTTLE_N @BASEBOARD_FAB2_LIB.BASEBOARD_FAB2(SCH_1):FM_THROTTLE_N    I51 @BASEBOARD_FAB2_LIB.BASEBOARD_FAB2(SCH_1):PAGE170

R1R9 RES_0402-3.32K,1%,1/16W,CHIP,GA
     1 P3V3_STBY @BASEBOARD_FAB2_LIB.BASEBOARD_FAB2(SCH_1):P3V3_STBY    I10 @BASEBOARD_FAB2_LIB.BASEBOARD_FAB2(SCH_1):PAGE140
     2 PU_NV_HOLD_N @BASEBOARD_FAB2_LIB.BASEBOARD_FAB2(SCH_1):PU_NV_HOLD_N    I10 @BASEBOARD_FAB2_LIB.BASEBOARD_FAB2(SCH_1):PAGE140

R1R12 RES_0402-10.0K,1%,1/16W,CHIP,GA
     1 CLK_50M_CKMNG_SPRVLLE @BASEBOARD_FAB2_LIB.BASEBOARD_FAB2(SCH_1):CLK_50M_CKMNG_SPRVLLE   I213 @BASEBOARD_FAB2_LIB.BASEBOARD_FAB2(SCH_1):PAGE139
     2    GND @BASEBOARD_FAB2_LIB.BASEBOARD_FAB2(SCH_1):GND   I213 @BASEBOARD_FAB2_LIB.BASEBOARD_FAB2(SCH_1):PAGE139

R1R15 RES_0603-0,5.0%,1/10W,CHIP,G22A
     1 P0V9_LAN @BASEBOARD_FAB2_LIB.BASEBOARD_FAB2(SCH_1):P0V9_LAN   I237 @BASEBOARD_FAB2_LIB.BASEBOARD_FAB2(SCH_1):PAGE139
     2 P0V9_LAN_I210 @BASEBOARD_FAB2_LIB.BASEBOARD_FAB2(SCH_1):P0V9_LAN_I210   I237 @BASEBOARD_FAB2_LIB.BASEBOARD_FAB2(SCH_1):PAGE139

R1R16 RES_0402-2.21K,1%,1/16W,CHIP,GA
     1 P3V3_STBY @BASEBOARD_FAB2_LIB.BASEBOARD_FAB2(SCH_1):P3V3_STBY    I93 @BASEBOARD_FAB2_LIB.BASEBOARD_FAB2(SCH_1):PAGE188
     2 SMB_PCH_MEZZ_LOM2_SCL @BASEBOARD_FAB2_LIB.BASEBOARD_FAB2(SCH_1):SMB_PCH_MEZZ_LOM2_SCL    I93 @BASEBOARD_FAB2_LIB.BASEBOARD_FAB2(SCH_1):PAGE188

R1R17 RES_0402-2.21K,1%,1/16W,CHIP,GA
     1 P3V3_STBY @BASEBOARD_FAB2_LIB.BASEBOARD_FAB2(SCH_1):P3V3_STBY    I94 @BASEBOARD_FAB2_LIB.BASEBOARD_FAB2(SCH_1):PAGE188
     2 SMB_PCH_MEZZ_LOM2_SDA @BASEBOARD_FAB2_LIB.BASEBOARD_FAB2(SCH_1):SMB_PCH_MEZZ_LOM2_SDA    I94 @BASEBOARD_FAB2_LIB.BASEBOARD_FAB2(SCH_1):PAGE188

R1R18 RES_0402-2.21K,1%,1/16W,CHIP,GA
     1 P3V3_STBY @BASEBOARD_FAB2_LIB.BASEBOARD_FAB2(SCH_1):P3V3_STBY    I88 @BASEBOARD_FAB2_LIB.BASEBOARD_FAB2(SCH_1):PAGE188
     2 SMB_PCH_MEZZ_LOM0_SCL @BASEBOARD_FAB2_LIB.BASEBOARD_FAB2(SCH_1):SMB_PCH_MEZZ_LOM0_SCL    I88 @BASEBOARD_FAB2_LIB.BASEBOARD_FAB2(SCH_1):PAGE188

R1R19 RES_0402-2.21K,1%,1/16W,CHIP,GA
     1 P3V3_STBY @BASEBOARD_FAB2_LIB.BASEBOARD_FAB2(SCH_1):P3V3_STBY    I89 @BASEBOARD_FAB2_LIB.BASEBOARD_FAB2(SCH_1):PAGE188
     2 SMB_PCH_MEZZ_LOM0_SDA @BASEBOARD_FAB2_LIB.BASEBOARD_FAB2(SCH_1):SMB_PCH_MEZZ_LOM0_SDA    I89 @BASEBOARD_FAB2_LIB.BASEBOARD_FAB2(SCH_1):PAGE188

R1R20 RES_0402-2.21K,1%,1/16W,CHIP,GA
     1 P3V3_STBY @BASEBOARD_FAB2_LIB.BASEBOARD_FAB2(SCH_1):P3V3_STBY    I91 @BASEBOARD_FAB2_LIB.BASEBOARD_FAB2(SCH_1):PAGE188
     2 SMB_PCH_MEZZ_LOM1_SCL @BASEBOARD_FAB2_LIB.BASEBOARD_FAB2(SCH_1):SMB_PCH_MEZZ_LOM1_SCL    I91 @BASEBOARD_FAB2_LIB.BASEBOARD_FAB2(SCH_1):PAGE188

R1R21 RES_0402-2.21K,1%,1/16W,CHIP,GA
     1 P3V3_STBY @BASEBOARD_FAB2_LIB.BASEBOARD_FAB2(SCH_1):P3V3_STBY    I90 @BASEBOARD_FAB2_LIB.BASEBOARD_FAB2(SCH_1):PAGE188
     2 SMB_PCH_MEZZ_LOM1_SDA @BASEBOARD_FAB2_LIB.BASEBOARD_FAB2(SCH_1):SMB_PCH_MEZZ_LOM1_SDA    I90 @BASEBOARD_FAB2_LIB.BASEBOARD_FAB2(SCH_1):PAGE188

R1R22 RES_0402-2.21K,1%,1/16W,CHIP,GA
     1 P3V3_STBY @BASEBOARD_FAB2_LIB.BASEBOARD_FAB2(SCH_1):P3V3_STBY    I92 @BASEBOARD_FAB2_LIB.BASEBOARD_FAB2(SCH_1):PAGE188
     2 SMB_PCH_MEZZ_LOM3_SDA @BASEBOARD_FAB2_LIB.BASEBOARD_FAB2(SCH_1):SMB_PCH_MEZZ_LOM3_SDA    I92 @BASEBOARD_FAB2_LIB.BASEBOARD_FAB2(SCH_1):PAGE188

R1R23 RES_0402-2.21K,1%,1/16W,CHIP,GA
     1 P3V3_STBY @BASEBOARD_FAB2_LIB.BASEBOARD_FAB2(SCH_1):P3V3_STBY    I95 @BASEBOARD_FAB2_LIB.BASEBOARD_FAB2(SCH_1):PAGE188
     2 SMB_PCH_MEZZ_LOM3_SCL @BASEBOARD_FAB2_LIB.BASEBOARD_FAB2(SCH_1):SMB_PCH_MEZZ_LOM3_SCL    I95 @BASEBOARD_FAB2_LIB.BASEBOARD_FAB2(SCH_1):PAGE188

R1T1 RES_0402-10.0K,1%,1/16W,CHIP,GA
     1 RMII_BMC_PCH_SPRNGVLLE_CRSDV @BASEBOARD_FAB2_LIB.BASEBOARD_FAB2(SCH_1):RMII_BMC_PCH_SPRNGVLLE_CRSDV   I214 @BASEBOARD_FAB2_LIB.BASEBOARD_FAB2(SCH_1):PAGE139
     2    GND @BASEBOARD_FAB2_LIB.BASEBOARD_FAB2(SCH_1):GND   I214 @BASEBOARD_FAB2_LIB.BASEBOARD_FAB2(SCH_1):PAGE139

R1T2 RES_0402-665,1.0%,1/16W,CHIP,GA
     1 P3V3_STBY @BASEBOARD_FAB2_LIB.BASEBOARD_FAB2(SCH_1):P3V3_STBY    I49 @BASEBOARD_FAB2_LIB.BASEBOARD_FAB2(SCH_1):PAGE160
     2 SMB_SLOTX24_STBY_LVC3_SCL_R @BASEBOARD_FAB2_LIB.BASEBOARD_FAB2(SCH_1):SMB_SLOTX24_STBY_LVC3_SCL_R    I49 @BASEBOARD_FAB2_LIB.BASEBOARD_FAB2(SCH_1):PAGE160

R1T3 RES_0402-665,1.0%,1/16W,CHIP,GA
     1 P3V3_STBY @BASEBOARD_FAB2_LIB.BASEBOARD_FAB2(SCH_1):P3V3_STBY    I46 @BASEBOARD_FAB2_LIB.BASEBOARD_FAB2(SCH_1):PAGE160
     2 SMB_SLOTX24_STBY_LVC3_SDA_R @BASEBOARD_FAB2_LIB.BASEBOARD_FAB2(SCH_1):SMB_SLOTX24_STBY_LVC3_SDA_R    I46 @BASEBOARD_FAB2_LIB.BASEBOARD_FAB2(SCH_1):PAGE160

R1T4 RES_0402-2.7K,1%,1/16W,CHIP,G2A
     1 P3V3_STBY @BASEBOARD_FAB2_LIB.BASEBOARD_FAB2(SCH_1):P3V3_STBY    I14 @BASEBOARD_FAB2_LIB.BASEBOARD_FAB2(SCH_1):PAGE164
     2 FM_BOARD_REV_ID0 @BASEBOARD_FAB2_LIB.BASEBOARD_FAB2(SCH_1):FM_BOARD_REV_ID0    I14 @BASEBOARD_FAB2_LIB.BASEBOARD_FAB2(SCH_1):PAGE164

R1T5 RES_0402-2.7K,1%,1/16W,EMPTY,GA
     1 P3V3_STBY @BASEBOARD_FAB2_LIB.BASEBOARD_FAB2(SCH_1):P3V3_STBY    I11 @BASEBOARD_FAB2_LIB.BASEBOARD_FAB2(SCH_1):PAGE164
     2 FM_BOARD_REV_ID2 @BASEBOARD_FAB2_LIB.BASEBOARD_FAB2(SCH_1):FM_BOARD_REV_ID2    I11 @BASEBOARD_FAB2_LIB.BASEBOARD_FAB2(SCH_1):PAGE164

R1T6 RES_0402-2.7K,1%,1/16W,EMPTY,GA
     1 P3V3_STBY @BASEBOARD_FAB2_LIB.BASEBOARD_FAB2(SCH_1):P3V3_STBY    I13 @BASEBOARD_FAB2_LIB.BASEBOARD_FAB2(SCH_1):PAGE164
     2 FM_BOARD_REV_ID1 @BASEBOARD_FAB2_LIB.BASEBOARD_FAB2(SCH_1):FM_BOARD_REV_ID1    I13 @BASEBOARD_FAB2_LIB.BASEBOARD_FAB2(SCH_1):PAGE164

R1T7 RES_0402-20.0,1%,1/16W,CHIP,G2A
     1 SMB_SLOTX24_STBY_LVC3_SCL_R @BASEBOARD_FAB2_LIB.BASEBOARD_FAB2(SCH_1):SMB_SLOTX24_STBY_LVC3_SCL_R    I50 @BASEBOARD_FAB2_LIB.BASEBOARD_FAB2(SCH_1):PAGE160
     2 SMB_SLOTX24_BMC_STBY_LVC3_SCL @BASEBOARD_FAB2_LIB.BASEBOARD_FAB2(SCH_1):SMB_SLOTX24_BMC_STBY_LVC3_SCL    I50 @BASEBOARD_FAB2_LIB.BASEBOARD_FAB2(SCH_1):PAGE160

R1T8 RES_0402-20.0,1%,1/16W,CHIP,G2A
     1 SMB_SLOTX24_STBY_LVC3_SDA_R @BASEBOARD_FAB2_LIB.BASEBOARD_FAB2(SCH_1):SMB_SLOTX24_STBY_LVC3_SDA_R     I4 @BASEBOARD_FAB2_LIB.BASEBOARD_FAB2(SCH_1):PAGE160
     2 SMB_SLOTX24_BMC_STBY_LVC3_SDA @BASEBOARD_FAB2_LIB.BASEBOARD_FAB2(SCH_1):SMB_SLOTX24_BMC_STBY_LVC3_SDA     I4 @BASEBOARD_FAB2_LIB.BASEBOARD_FAB2(SCH_1):PAGE160

R1T9 RES_0402-22.1,1.0%,1/16W,CHIP,A
     1 PWRGD_P1V538_BMC_STBY_R @BASEBOARD_FAB2_LIB.BASEBOARD_FAB2(SCH_1):PWRGD_P1V538_BMC_STBY_R    I72 @BASEBOARD_FAB2_LIB.BASEBOARD_FAB2(SCH_1):PAGE239
     2 PWRGD_P1V538_BMC_STBY @BASEBOARD_FAB2_LIB.BASEBOARD_FAB2(SCH_1):PWRGD_P1V538_BMC_STBY    I72 @BASEBOARD_FAB2_LIB.BASEBOARD_FAB2(SCH_1):PAGE239

R1T10 RES_0402-1.00K,1%,1/16W,EMPTY,A
     1 FM_BOARD_REV_ID0 @BASEBOARD_FAB2_LIB.BASEBOARD_FAB2(SCH_1):FM_BOARD_REV_ID0     I5 @BASEBOARD_FAB2_LIB.BASEBOARD_FAB2(SCH_1):PAGE164
     2    GND @BASEBOARD_FAB2_LIB.BASEBOARD_FAB2(SCH_1):GND     I5 @BASEBOARD_FAB2_LIB.BASEBOARD_FAB2(SCH_1):PAGE164

R1T11 RES_0402-1.00K,1%,1/16W,CHIP,GA
     1 FM_BOARD_REV_ID2 @BASEBOARD_FAB2_LIB.BASEBOARD_FAB2(SCH_1):FM_BOARD_REV_ID2     I7 @BASEBOARD_FAB2_LIB.BASEBOARD_FAB2(SCH_1):PAGE164
     2    GND @BASEBOARD_FAB2_LIB.BASEBOARD_FAB2(SCH_1):GND     I7 @BASEBOARD_FAB2_LIB.BASEBOARD_FAB2(SCH_1):PAGE164

R1T12 RES_0402-1.00K,1%,1/16W,CHIP,GA
     1 FM_BOARD_REV_ID1 @BASEBOARD_FAB2_LIB.BASEBOARD_FAB2(SCH_1):FM_BOARD_REV_ID1     I6 @BASEBOARD_FAB2_LIB.BASEBOARD_FAB2(SCH_1):PAGE164
     2    GND @BASEBOARD_FAB2_LIB.BASEBOARD_FAB2(SCH_1):GND     I6 @BASEBOARD_FAB2_LIB.BASEBOARD_FAB2(SCH_1):PAGE164

R1T15 RES_0402-0.0,5%,1/16W,EMPTY,G2A
     1 FM_BMC_ONCTL_N @BASEBOARD_FAB2_LIB.BASEBOARD_FAB2(SCH_1):FM_BMC_ONCTL_N   I100 @BASEBOARD_FAB2_LIB.BASEBOARD_FAB2(SCH_1):PAGE145
     2 FM_BMC_ONCTL_R_N @BASEBOARD_FAB2_LIB.BASEBOARD_FAB2(SCH_1):FM_BMC_ONCTL_R_N   I100 @BASEBOARD_FAB2_LIB.BASEBOARD_FAB2(SCH_1):PAGE145

R1T23 RES_0402-0.0,5%,1/16W,EMPTY,G2A
     1 FM_BMC_ONCTL_R_N @BASEBOARD_FAB2_LIB.BASEBOARD_FAB2(SCH_1):FM_BMC_ONCTL_R_N   I101 @BASEBOARD_FAB2_LIB.BASEBOARD_FAB2(SCH_1):PAGE145
     2    GND @BASEBOARD_FAB2_LIB.BASEBOARD_FAB2(SCH_1):GND   I101 @BASEBOARD_FAB2_LIB.BASEBOARD_FAB2(SCH_1):PAGE145

R1T24 RES_0402-0.0,5%,1/16W,EMPTY,G2A
     1 FM_FLASH_DESC_OVERRIDE_R @BASEBOARD_FAB2_LIB.BASEBOARD_FAB2(SCH_1):FM_FLASH_DESC_OVERRIDE_R    I82 @BASEBOARD_FAB2_LIB.BASEBOARD_FAB2(SCH_1):PAGE144
     2 FM_FLASH_DESC_OVERRIDE @BASEBOARD_FAB2_LIB.BASEBOARD_FAB2(SCH_1):FM_FLASH_DESC_OVERRIDE    I82 @BASEBOARD_FAB2_LIB.BASEBOARD_FAB2(SCH_1):PAGE144

R1T25 RES_0402-8.2K,1%,1/16W,CHIP,G2A
     1 A_USB2BVRES @BASEBOARD_FAB2_LIB.BASEBOARD_FAB2(SCH_1):A_USB2BVRES    I35 @BASEBOARD_FAB2_LIB.BASEBOARD_FAB2(SCH_1):PAGE146
     2    GND @BASEBOARD_FAB2_LIB.BASEBOARD_FAB2(SCH_1):GND    I35 @BASEBOARD_FAB2_LIB.BASEBOARD_FAB2(SCH_1):PAGE146

R1T26 RES_0402-8.2K,1%,1/16W,CHIP,G2A
     1 A_USB2AVRES @BASEBOARD_FAB2_LIB.BASEBOARD_FAB2(SCH_1):A_USB2AVRES    I37 @BASEBOARD_FAB2_LIB.BASEBOARD_FAB2(SCH_1):PAGE146
     2    GND @BASEBOARD_FAB2_LIB.BASEBOARD_FAB2(SCH_1):GND    I37 @BASEBOARD_FAB2_LIB.BASEBOARD_FAB2(SCH_1):PAGE146

R1T27 RES_0402-240,1.0%,1/16W,CHIP,GA
     1    GND @BASEBOARD_FAB2_LIB.BASEBOARD_FAB2(SCH_1):GND    I58 @BASEBOARD_FAB2_LIB.BASEBOARD_FAB2(SCH_1):PAGE143
     2 BMC_MIOZ @BASEBOARD_FAB2_LIB.BASEBOARD_FAB2(SCH_1):BMC_MIOZ    I58 @BASEBOARD_FAB2_LIB.BASEBOARD_FAB2(SCH_1):PAGE143

R1T28 120R2F-GP_RCL_GP-120R2F-GP,64.A
     1 BMC_M_CLK_DN @BASEBOARD_FAB2_LIB.BASEBOARD_FAB2(SCH_1):BMC_M_CLK_DN   I212 @BASEBOARD_FAB2_LIB.BASEBOARD_FAB2(SCH_1):PAGE149
     2 BMC_M_CLK_DP @BASEBOARD_FAB2_LIB.BASEBOARD_FAB2(SCH_1):BMC_M_CLK_DP   I212 @BASEBOARD_FAB2_LIB.BASEBOARD_FAB2(SCH_1):PAGE149

R1T29 RES_0402-1.00K,1%,1/16W,CHIP,GA
     1 BMC_M_VREFCA @BASEBOARD_FAB2_LIB.BASEBOARD_FAB2(SCH_1):BMC_M_VREFCA   I125 @BASEBOARD_FAB2_LIB.BASEBOARD_FAB2(SCH_1):PAGE149
     2    GND @BASEBOARD_FAB2_LIB.BASEBOARD_FAB2(SCH_1):GND   I125 @BASEBOARD_FAB2_LIB.BASEBOARD_FAB2(SCH_1):PAGE149

R1T30 RES_0402-1.00K,1%,1/16W,CHIP,GA
     1 P1V2_AUX_BMC @BASEBOARD_FAB2_LIB.BASEBOARD_FAB2(SCH_1):P1V2_AUX_BMC   I124 @BASEBOARD_FAB2_LIB.BASEBOARD_FAB2(SCH_1):PAGE149
     2 BMC_M_VREFCA @BASEBOARD_FAB2_LIB.BASEBOARD_FAB2(SCH_1):BMC_M_VREFCA   I124 @BASEBOARD_FAB2_LIB.BASEBOARD_FAB2(SCH_1):PAGE149

R1T32 RES_0603-0,5.0%,1/10W,CHIP,G22A
     1 P1V5_LAN @BASEBOARD_FAB2_LIB.BASEBOARD_FAB2(SCH_1):P1V5_LAN   I238 @BASEBOARD_FAB2_LIB.BASEBOARD_FAB2(SCH_1):PAGE139
     2 P1V5_LAN_I210 @BASEBOARD_FAB2_LIB.BASEBOARD_FAB2(SCH_1):P1V5_LAN_I210   I238 @BASEBOARD_FAB2_LIB.BASEBOARD_FAB2(SCH_1):PAGE139

R1T33 RES_0603-0,5.0%,1/10W,EMPTY,G2A
     1 P1V5_LAN @BASEBOARD_FAB2_LIB.BASEBOARD_FAB2(SCH_1):P1V5_LAN   I240 @BASEBOARD_FAB2_LIB.BASEBOARD_FAB2(SCH_1):PAGE139
     2 P3V3_STBY_P1V5_LAN_I210 @BASEBOARD_FAB2_LIB.BASEBOARD_FAB2(SCH_1):P3V3_STBY_P1V5_LAN_I210   I240 @BASEBOARD_FAB2_LIB.BASEBOARD_FAB2(SCH_1):PAGE139

R1T34 RES_0603-0,5.0%,1/10W,CHIP,G22A
     1 P3V3_STBY @BASEBOARD_FAB2_LIB.BASEBOARD_FAB2(SCH_1):P3V3_STBY   I239 @BASEBOARD_FAB2_LIB.BASEBOARD_FAB2(SCH_1):PAGE139
     2 P3V3_STBY_P1V5_LAN_I210 @BASEBOARD_FAB2_LIB.BASEBOARD_FAB2(SCH_1):P3V3_STBY_P1V5_LAN_I210   I239 @BASEBOARD_FAB2_LIB.BASEBOARD_FAB2(SCH_1):PAGE139

R1T35 RES_0402-0.0,5%,1/16W,EMPTY,G2A
     1 FM_CPU0_PROCHOT_LVT3_N @BASEBOARD_FAB2_LIB.BASEBOARD_FAB2(SCH_1):FM_CPU0_PROCHOT_LVT3_N   I135 @BASEBOARD_FAB2_LIB.BASEBOARD_FAB2(SCH_1):PAGE93
     2 FM_CPU0_PROCHOT_PCH_N @BASEBOARD_FAB2_LIB.BASEBOARD_FAB2(SCH_1):FM_CPU0_PROCHOT_PCH_N   I135 @BASEBOARD_FAB2_LIB.BASEBOARD_FAB2(SCH_1):PAGE93

R1T36 RES_0402-0.0,5%,1/16W,CHIP,G21A
     1 FM_CPU0_PROCHOT_LVT3_N @BASEBOARD_FAB2_LIB.BASEBOARD_FAB2(SCH_1):FM_CPU0_PROCHOT_LVT3_N   I122 @BASEBOARD_FAB2_LIB.BASEBOARD_FAB2(SCH_1):PAGE93
     2 FM_CPU0_PROCHOT_LVT3_BMC_N @BASEBOARD_FAB2_LIB.BASEBOARD_FAB2(SCH_1):FM_CPU0_PROCHOT_LVT3_BMC_N   I122 @BASEBOARD_FAB2_LIB.BASEBOARD_FAB2(SCH_1):PAGE93

R1T37 RES_0402-0.0,5%,1/16W,CHIP,G21A
     1 FM_CPU1_PROCHOT_LVT3_N @BASEBOARD_FAB2_LIB.BASEBOARD_FAB2(SCH_1):FM_CPU1_PROCHOT_LVT3_N   I123 @BASEBOARD_FAB2_LIB.BASEBOARD_FAB2(SCH_1):PAGE93
     2 FM_CPU1_PROCHOT_LVT3_BMC_N @BASEBOARD_FAB2_LIB.BASEBOARD_FAB2(SCH_1):FM_CPU1_PROCHOT_LVT3_BMC_N   I123 @BASEBOARD_FAB2_LIB.BASEBOARD_FAB2(SCH_1):PAGE93

R1T38 RES_0402-0.0,5%,1/16W,EMPTY,G2A
     1 FM_CPU1_PROCHOT_LVT3_N @BASEBOARD_FAB2_LIB.BASEBOARD_FAB2(SCH_1):FM_CPU1_PROCHOT_LVT3_N   I137 @BASEBOARD_FAB2_LIB.BASEBOARD_FAB2(SCH_1):PAGE93
     2 FM_CPU1_PROCHOT_PCH_N @BASEBOARD_FAB2_LIB.BASEBOARD_FAB2(SCH_1):FM_CPU1_PROCHOT_PCH_N   I137 @BASEBOARD_FAB2_LIB.BASEBOARD_FAB2(SCH_1):PAGE93

R1U1 RES_0402-100.0K,1%,1/16W,CHIP,A
     1 FAN_TACH3 @BASEBOARD_FAB2_LIB.BASEBOARD_FAB2(SCH_1):FAN_TACH3    I61 @BASEBOARD_FAB2_LIB.BASEBOARD_FAB2(SCH_1):PAGE147
     2    GND @BASEBOARD_FAB2_LIB.BASEBOARD_FAB2(SCH_1):GND    I61 @BASEBOARD_FAB2_LIB.BASEBOARD_FAB2(SCH_1):PAGE147

R1U2 RES_0402-100.0K,1%,1/16W,CHIP,A
     1 FAN_TACH2 @BASEBOARD_FAB2_LIB.BASEBOARD_FAB2(SCH_1):FAN_TACH2    I62 @BASEBOARD_FAB2_LIB.BASEBOARD_FAB2(SCH_1):PAGE147
     2    GND @BASEBOARD_FAB2_LIB.BASEBOARD_FAB2(SCH_1):GND    I62 @BASEBOARD_FAB2_LIB.BASEBOARD_FAB2(SCH_1):PAGE147

R1U3 RES_0402-0.0,5%,1/16W,CHIP,G21A
     1    GND @BASEBOARD_FAB2_LIB.BASEBOARD_FAB2(SCH_1):GND   I114 @BASEBOARD_FAB2_LIB.BASEBOARD_FAB2(SCH_1):PAGE141
     2 GND_NIC @BASEBOARD_FAB2_LIB.BASEBOARD_FAB2(SCH_1):GND_NIC   I114 @BASEBOARD_FAB2_LIB.BASEBOARD_FAB2(SCH_1):PAGE141

R1U4 RES_0402-100.0K,1%,1/16W,CHIP,A
     1 FAN_TACH1 @BASEBOARD_FAB2_LIB.BASEBOARD_FAB2(SCH_1):FAN_TACH1    I65 @BASEBOARD_FAB2_LIB.BASEBOARD_FAB2(SCH_1):PAGE147
     2    GND @BASEBOARD_FAB2_LIB.BASEBOARD_FAB2(SCH_1):GND    I65 @BASEBOARD_FAB2_LIB.BASEBOARD_FAB2(SCH_1):PAGE147

R1U5 RES_0402-100.0K,1%,1/16W,CHIP,A
     1 FAN_TACH0 @BASEBOARD_FAB2_LIB.BASEBOARD_FAB2(SCH_1):FAN_TACH0    I66 @BASEBOARD_FAB2_LIB.BASEBOARD_FAB2(SCH_1):PAGE147
     2    GND @BASEBOARD_FAB2_LIB.BASEBOARD_FAB2(SCH_1):GND    I66 @BASEBOARD_FAB2_LIB.BASEBOARD_FAB2(SCH_1):PAGE147

R1U6 RES_0402-10.0K,1%,1/16W,CHIP,GA
     1 FM_BIOS_SPI_BMC_CTRL @BASEBOARD_FAB2_LIB.BASEBOARD_FAB2(SCH_1):FM_BIOS_SPI_BMC_CTRL   I128 @BASEBOARD_FAB2_LIB.BASEBOARD_FAB2(SCH_1):PAGE154
     2    GND @BASEBOARD_FAB2_LIB.BASEBOARD_FAB2(SCH_1):GND   I128 @BASEBOARD_FAB2_LIB.BASEBOARD_FAB2(SCH_1):PAGE154

R1U7 RES_0402-10.0K,1%,1/16W,CHIP,GA
     1    GND @BASEBOARD_FAB2_LIB.BASEBOARD_FAB2(SCH_1):GND    I78 @BASEBOARD_FAB2_LIB.BASEBOARD_FAB2(SCH_1):PAGE146
     2 PD_SP_ENTEST @BASEBOARD_FAB2_LIB.BASEBOARD_FAB2(SCH_1):PD_SP_ENTEST    I78 @BASEBOARD_FAB2_LIB.BASEBOARD_FAB2(SCH_1):PAGE146

R1U8 RES_0402-0.0,5%,1/16W,CHIP,G21A
     1 SMB_VR_STBY_LVC3_SDA_R @BASEBOARD_FAB2_LIB.BASEBOARD_FAB2(SCH_1):SMB_VR_STBY_LVC3_SDA_R   I223 @BASEBOARD_FAB2_LIB.BASEBOARD_FAB2(SCH_1):PAGE159
     2 SMB_VR_STBY_LVC3_SDA @BASEBOARD_FAB2_LIB.BASEBOARD_FAB2(SCH_1):SMB_VR_STBY_LVC3_SDA   I223 @BASEBOARD_FAB2_LIB.BASEBOARD_FAB2(SCH_1):PAGE159

R1U9 RES_0402-20.0,1%,1/16W,CHIP,G2A
     1 SMB_SMLINK0_STBY_LVC3_SCL_R @BASEBOARD_FAB2_LIB.BASEBOARD_FAB2(SCH_1):SMB_SMLINK0_STBY_LVC3_SCL_R   I232 @BASEBOARD_FAB2_LIB.BASEBOARD_FAB2(SCH_1):PAGE159
     2 SMB_SMLINK0_STBY_LVC3_SCL @BASEBOARD_FAB2_LIB.BASEBOARD_FAB2(SCH_1):SMB_SMLINK0_STBY_LVC3_SCL   I232 @BASEBOARD_FAB2_LIB.BASEBOARD_FAB2(SCH_1):PAGE159

R1U10 RES_0402-20.0,1%,1/16W,CHIP,G2A
     1 SMB_SMLINK0_STBY_LVC3_SDA_R @BASEBOARD_FAB2_LIB.BASEBOARD_FAB2(SCH_1):SMB_SMLINK0_STBY_LVC3_SDA_R   I233 @BASEBOARD_FAB2_LIB.BASEBOARD_FAB2(SCH_1):PAGE159
     2 SMB_SMLINK0_STBY_LVC3_SDA @BASEBOARD_FAB2_LIB.BASEBOARD_FAB2(SCH_1):SMB_SMLINK0_STBY_LVC3_SDA   I233 @BASEBOARD_FAB2_LIB.BASEBOARD_FAB2(SCH_1):PAGE159

R1U11 RES_0402-0.0,5%,1/16W,CHIP,G21A
     1 SMB_VR_STBY_LVC3_SCL_R @BASEBOARD_FAB2_LIB.BASEBOARD_FAB2(SCH_1):SMB_VR_STBY_LVC3_SCL_R   I222 @BASEBOARD_FAB2_LIB.BASEBOARD_FAB2(SCH_1):PAGE159
     2 SMB_VR_STBY_LVC3_SCL @BASEBOARD_FAB2_LIB.BASEBOARD_FAB2(SCH_1):SMB_VR_STBY_LVC3_SCL   I222 @BASEBOARD_FAB2_LIB.BASEBOARD_FAB2(SCH_1):PAGE159

R1U12 RES_0402-51,5.0%,1/16W,CHIP,G2A
     1 SGPIO_BMC_LD_R_N @BASEBOARD_FAB2_LIB.BASEBOARD_FAB2(SCH_1):SGPIO_BMC_LD_R_N    I59 @BASEBOARD_FAB2_LIB.BASEBOARD_FAB2(SCH_1):PAGE144
     2 SGPIO_BMC_LD_N @BASEBOARD_FAB2_LIB.BASEBOARD_FAB2(SCH_1):SGPIO_BMC_LD_N    I59 @BASEBOARD_FAB2_LIB.BASEBOARD_FAB2(SCH_1):PAGE144

R1U13 RES_0402-51,5.0%,1/16W,CHIP,G2A
     1 SGPIO_BMC_DOUT_R @BASEBOARD_FAB2_LIB.BASEBOARD_FAB2(SCH_1):SGPIO_BMC_DOUT_R    I58 @BASEBOARD_FAB2_LIB.BASEBOARD_FAB2(SCH_1):PAGE144
     2 SGPIO_BMC_DOUT @BASEBOARD_FAB2_LIB.BASEBOARD_FAB2(SCH_1):SGPIO_BMC_DOUT    I58 @BASEBOARD_FAB2_LIB.BASEBOARD_FAB2(SCH_1):PAGE144

R1U14 RES_0402-51,5.0%,1/16W,CHIP,G2A
     1 SGPIO_BMC_CLK_R @BASEBOARD_FAB2_LIB.BASEBOARD_FAB2(SCH_1):SGPIO_BMC_CLK_R    I57 @BASEBOARD_FAB2_LIB.BASEBOARD_FAB2(SCH_1):PAGE144
     2 SGPIO_BMC_CLK @BASEBOARD_FAB2_LIB.BASEBOARD_FAB2(SCH_1):SGPIO_BMC_CLK    I57 @BASEBOARD_FAB2_LIB.BASEBOARD_FAB2(SCH_1):PAGE144

R1U15 RES_0402-1.00K,1%,1/16W,EMPTY,A
     1 FM_BOARD_SKU_ID3 @BASEBOARD_FAB2_LIB.BASEBOARD_FAB2(SCH_1):FM_BOARD_SKU_ID3    I22 @BASEBOARD_FAB2_LIB.BASEBOARD_FAB2(SCH_1):PAGE164
     2    GND @BASEBOARD_FAB2_LIB.BASEBOARD_FAB2(SCH_1):GND    I22 @BASEBOARD_FAB2_LIB.BASEBOARD_FAB2(SCH_1):PAGE164

R1U16 RES_0402-1.00K,1%,1/16W,EMPTY,A
     1 FM_BOARD_SKU_ID1 @BASEBOARD_FAB2_LIB.BASEBOARD_FAB2(SCH_1):FM_BOARD_SKU_ID1    I20 @BASEBOARD_FAB2_LIB.BASEBOARD_FAB2(SCH_1):PAGE164
     2    GND @BASEBOARD_FAB2_LIB.BASEBOARD_FAB2(SCH_1):GND    I20 @BASEBOARD_FAB2_LIB.BASEBOARD_FAB2(SCH_1):PAGE164

R1U17 RES_0402-1.00K,1%,1/16W,CHIP,GA
     1 FM_BOARD_SKU_ID2 @BASEBOARD_FAB2_LIB.BASEBOARD_FAB2(SCH_1):FM_BOARD_SKU_ID2    I21 @BASEBOARD_FAB2_LIB.BASEBOARD_FAB2(SCH_1):PAGE164
     2    GND @BASEBOARD_FAB2_LIB.BASEBOARD_FAB2(SCH_1):GND    I21 @BASEBOARD_FAB2_LIB.BASEBOARD_FAB2(SCH_1):PAGE164

R1U18 RES_0402-1.00K,1%,1/16W,CHIP,GA
     1 FM_BOARD_SKU_ID0 @BASEBOARD_FAB2_LIB.BASEBOARD_FAB2(SCH_1):FM_BOARD_SKU_ID0    I19 @BASEBOARD_FAB2_LIB.BASEBOARD_FAB2(SCH_1):PAGE164
     2    GND @BASEBOARD_FAB2_LIB.BASEBOARD_FAB2(SCH_1):GND    I19 @BASEBOARD_FAB2_LIB.BASEBOARD_FAB2(SCH_1):PAGE164

R1U19 RES_0402-20.0,1%,1/16W,CHIP,G2A
     1 SMB_SMLINK0_STBY_LVC3_SCL @BASEBOARD_FAB2_LIB.BASEBOARD_FAB2(SCH_1):SMB_SMLINK0_STBY_LVC3_SCL   I226 @BASEBOARD_FAB2_LIB.BASEBOARD_FAB2(SCH_1):PAGE159
     2 SMB_SPRINGVILLE_STBY_LVC3_SCL @BASEBOARD_FAB2_LIB.BASEBOARD_FAB2(SCH_1):SMB_SPRINGVILLE_STBY_LVC3_SCL   I226 @BASEBOARD_FAB2_LIB.BASEBOARD_FAB2(SCH_1):PAGE159

R1U20 RES_0402-20.0,1%,1/16W,CHIP,G2A
     1 SMB_SMLINK0_STBY_LVC3_SDA @BASEBOARD_FAB2_LIB.BASEBOARD_FAB2(SCH_1):SMB_SMLINK0_STBY_LVC3_SDA   I225 @BASEBOARD_FAB2_LIB.BASEBOARD_FAB2(SCH_1):PAGE159
     2 SMB_SPRINGVILLE_STBY_LVC3_SDA @BASEBOARD_FAB2_LIB.BASEBOARD_FAB2(SCH_1):SMB_SPRINGVILLE_STBY_LVC3_SDA   I225 @BASEBOARD_FAB2_LIB.BASEBOARD_FAB2(SCH_1):PAGE159

R1U21 RES_0402-2.7K,1%,1/16W,CHIP,G2A
     1 P3V3_STBY @BASEBOARD_FAB2_LIB.BASEBOARD_FAB2(SCH_1):P3V3_STBY    I24 @BASEBOARD_FAB2_LIB.BASEBOARD_FAB2(SCH_1):PAGE164
     2 FM_BOARD_SKU_ID3 @BASEBOARD_FAB2_LIB.BASEBOARD_FAB2(SCH_1):FM_BOARD_SKU_ID3    I24 @BASEBOARD_FAB2_LIB.BASEBOARD_FAB2(SCH_1):PAGE164

R1U22 RES_0402-2.7K,1%,1/16W,CHIP,G2A
     1 P3V3_STBY @BASEBOARD_FAB2_LIB.BASEBOARD_FAB2(SCH_1):P3V3_STBY    I27 @BASEBOARD_FAB2_LIB.BASEBOARD_FAB2(SCH_1):PAGE164
     2 FM_BOARD_SKU_ID1 @BASEBOARD_FAB2_LIB.BASEBOARD_FAB2(SCH_1):FM_BOARD_SKU_ID1    I27 @BASEBOARD_FAB2_LIB.BASEBOARD_FAB2(SCH_1):PAGE164

R1U23 RES_0402-2.7K,1%,1/16W,EMPTY,GA
     1 P3V3_STBY @BASEBOARD_FAB2_LIB.BASEBOARD_FAB2(SCH_1):P3V3_STBY    I28 @BASEBOARD_FAB2_LIB.BASEBOARD_FAB2(SCH_1):PAGE164
     2 FM_BOARD_SKU_ID0 @BASEBOARD_FAB2_LIB.BASEBOARD_FAB2(SCH_1):FM_BOARD_SKU_ID0    I28 @BASEBOARD_FAB2_LIB.BASEBOARD_FAB2(SCH_1):PAGE164

R1U24 RES_0402-2.7K,1%,1/16W,EMPTY,GA
     1 P3V3_STBY @BASEBOARD_FAB2_LIB.BASEBOARD_FAB2(SCH_1):P3V3_STBY    I25 @BASEBOARD_FAB2_LIB.BASEBOARD_FAB2(SCH_1):PAGE164
     2 FM_BOARD_SKU_ID2 @BASEBOARD_FAB2_LIB.BASEBOARD_FAB2(SCH_1):FM_BOARD_SKU_ID2    I25 @BASEBOARD_FAB2_LIB.BASEBOARD_FAB2(SCH_1):PAGE164

R1U25 RES_0402-20.0,1%,1/16W,CHIP,G2A
     1 SMB_SENSOR_PCH_STBY_LVC3_SCL @BASEBOARD_FAB2_LIB.BASEBOARD_FAB2(SCH_1):SMB_SENSOR_PCH_STBY_LVC3_SCL    I79 @BASEBOARD_FAB2_LIB.BASEBOARD_FAB2(SCH_1):PAGE167
     2 SMB_SENSOR_STBY_LVC3_SCL @BASEBOARD_FAB2_LIB.BASEBOARD_FAB2(SCH_1):SMB_SENSOR_STBY_LVC3_SCL    I79 @BASEBOARD_FAB2_LIB.BASEBOARD_FAB2(SCH_1):PAGE167

R1U26 RES_0402-5.11K,1%,1/16W,CHIP,GA
     1   P3V3 @BASEBOARD_FAB2_LIB.BASEBOARD_FAB2(SCH_1):P3V3   I148 @BASEBOARD_FAB2_LIB.BASEBOARD_FAB2(SCH_1):PAGE169
     2 A_P3V3_SCALED @BASEBOARD_FAB2_LIB.BASEBOARD_FAB2(SCH_1):A_P3V3_SCALED   I148 @BASEBOARD_FAB2_LIB.BASEBOARD_FAB2(SCH_1):PAGE169

R1U27 RES_0402-8.2K,1%,1/16W,CHIP,G2A
     1 A_P3V3_SCALED @BASEBOARD_FAB2_LIB.BASEBOARD_FAB2(SCH_1):A_P3V3_SCALED   I149 @BASEBOARD_FAB2_LIB.BASEBOARD_FAB2(SCH_1):PAGE169
     2    GND @BASEBOARD_FAB2_LIB.BASEBOARD_FAB2(SCH_1):GND   I149 @BASEBOARD_FAB2_LIB.BASEBOARD_FAB2(SCH_1):PAGE169

R1U28 RES_0402-3.48K,1.0%,1/16W,CHIPA
     1 A_P5V_SCALED @BASEBOARD_FAB2_LIB.BASEBOARD_FAB2(SCH_1):A_P5V_SCALED   I142 @BASEBOARD_FAB2_LIB.BASEBOARD_FAB2(SCH_1):PAGE169
     2    GND @BASEBOARD_FAB2_LIB.BASEBOARD_FAB2(SCH_1):GND   I142 @BASEBOARD_FAB2_LIB.BASEBOARD_FAB2(SCH_1):PAGE169

R1U29 RES_0402-5.11K,1%,1/16W,CHIP,GA
     1    P5V @BASEBOARD_FAB2_LIB.BASEBOARD_FAB2(SCH_1):P5V   I141 @BASEBOARD_FAB2_LIB.BASEBOARD_FAB2(SCH_1):PAGE169
     2 A_P5V_SCALED @BASEBOARD_FAB2_LIB.BASEBOARD_FAB2(SCH_1):A_P5V_SCALED   I141 @BASEBOARD_FAB2_LIB.BASEBOARD_FAB2(SCH_1):PAGE169

R1U30 RES_0402-1.00K,1%,1/16W,CHIP,GA
     1 PD_DIR_2 @BASEBOARD_FAB2_LIB.BASEBOARD_FAB2(SCH_1):PD_DIR_2     I2 @BASEBOARD_FAB2_LIB.BASEBOARD_FAB2(SCH_1):PAGE152
     2    GND @BASEBOARD_FAB2_LIB.BASEBOARD_FAB2(SCH_1):GND     I2 @BASEBOARD_FAB2_LIB.BASEBOARD_FAB2(SCH_1):PAGE152

R1U31 RES_0402-20.0,1%,1/16W,CHIP,G2A
     1 SMB_SENSOR_PCH_STBY_LVC3_SDA @BASEBOARD_FAB2_LIB.BASEBOARD_FAB2(SCH_1):SMB_SENSOR_PCH_STBY_LVC3_SDA    I78 @BASEBOARD_FAB2_LIB.BASEBOARD_FAB2(SCH_1):PAGE167
     2 SMB_SENSOR_STBY_LVC3_SDA @BASEBOARD_FAB2_LIB.BASEBOARD_FAB2(SCH_1):SMB_SENSOR_STBY_LVC3_SDA    I78 @BASEBOARD_FAB2_LIB.BASEBOARD_FAB2(SCH_1):PAGE167

R1U32 RES_0402-5.11K,1%,1/16W,CHIP,GA
     1 P12V_STBY @BASEBOARD_FAB2_LIB.BASEBOARD_FAB2(SCH_1):P12V_STBY    I82 @BASEBOARD_FAB2_LIB.BASEBOARD_FAB2(SCH_1):PAGE169
     2 A_P12V_STBY_SCALED @BASEBOARD_FAB2_LIB.BASEBOARD_FAB2(SCH_1):A_P12V_STBY_SCALED    I82 @BASEBOARD_FAB2_LIB.BASEBOARD_FAB2(SCH_1):PAGE169

R1U33 RES_0402-1.00K,1%,1/16W,CHIP,GA
     1 A_P12V_STBY_SCALED @BASEBOARD_FAB2_LIB.BASEBOARD_FAB2(SCH_1):A_P12V_STBY_SCALED    I83 @BASEBOARD_FAB2_LIB.BASEBOARD_FAB2(SCH_1):PAGE169
     2    GND @BASEBOARD_FAB2_LIB.BASEBOARD_FAB2(SCH_1):GND    I83 @BASEBOARD_FAB2_LIB.BASEBOARD_FAB2(SCH_1):PAGE169

R1U34 RES_0402-33.2,1%,1/16W,CHIP,G2A
     1 H_CPU1_MEMKLM_MEMHOT_LVT3_K_N @BASEBOARD_FAB2_LIB.BASEBOARD_FAB2(SCH_1):H_CPU1_MEMKLM_MEMHOT_LVT3_K_N    I16 @BASEBOARD_FAB2_LIB.BASEBOARD_FAB2(SCH_1):PAGE152
     2 H_CPU1_MEMKLM_MEMHOT_LVT3_N @BASEBOARD_FAB2_LIB.BASEBOARD_FAB2(SCH_1):H_CPU1_MEMKLM_MEMHOT_LVT3_N    I16 @BASEBOARD_FAB2_LIB.BASEBOARD_FAB2(SCH_1):PAGE152

R1U35 RES_0402-150.0,1%,1/16W,CHIP,GA
     1 PVCCIO_CPU1 @BASEBOARD_FAB2_LIB.BASEBOARD_FAB2(SCH_1):PVCCIO_CPU1    I57 @BASEBOARD_FAB2_LIB.BASEBOARD_FAB2(SCH_1):PAGE152
     2 H_CPU1_MEMKLM_MEMHOT_G_N @BASEBOARD_FAB2_LIB.BASEBOARD_FAB2(SCH_1):H_CPU1_MEMKLM_MEMHOT_G_N    I57 @BASEBOARD_FAB2_LIB.BASEBOARD_FAB2(SCH_1):PAGE152

R1U36 RES_0402-33.2,1%,1/16W,CHIP,G2A
     1 H_CPU1_MEMGHJ_MEMHOT_LVT3_K_N @BASEBOARD_FAB2_LIB.BASEBOARD_FAB2(SCH_1):H_CPU1_MEMGHJ_MEMHOT_LVT3_K_N    I15 @BASEBOARD_FAB2_LIB.BASEBOARD_FAB2(SCH_1):PAGE152
     2 H_CPU1_MEMGHJ_MEMHOT_LVT3_N @BASEBOARD_FAB2_LIB.BASEBOARD_FAB2(SCH_1):H_CPU1_MEMGHJ_MEMHOT_LVT3_N    I15 @BASEBOARD_FAB2_LIB.BASEBOARD_FAB2(SCH_1):PAGE152

R1U37 RES_0402-100.0,1%,1/16W,CHIP,GA
     1 P0V7_GTL2014_2 @BASEBOARD_FAB2_LIB.BASEBOARD_FAB2(SCH_1):P0V7_GTL2014_2    I26 @BASEBOARD_FAB2_LIB.BASEBOARD_FAB2(SCH_1):PAGE152
     2    GND @BASEBOARD_FAB2_LIB.BASEBOARD_FAB2(SCH_1):GND    I26 @BASEBOARD_FAB2_LIB.BASEBOARD_FAB2(SCH_1):PAGE152

R1U38 RES_0402-8.2K,1%,1/16W,CHIP,G2A
     1 A_P3V3_STBY_SCALED @BASEBOARD_FAB2_LIB.BASEBOARD_FAB2(SCH_1):A_P3V3_STBY_SCALED   I114 @BASEBOARD_FAB2_LIB.BASEBOARD_FAB2(SCH_1):PAGE169
     2    GND @BASEBOARD_FAB2_LIB.BASEBOARD_FAB2(SCH_1):GND   I114 @BASEBOARD_FAB2_LIB.BASEBOARD_FAB2(SCH_1):PAGE169

R1U39 RES_0402-5.11K,1%,1/16W,CHIP,GA
     1 P3V3_STBY @BASEBOARD_FAB2_LIB.BASEBOARD_FAB2(SCH_1):P3V3_STBY    I88 @BASEBOARD_FAB2_LIB.BASEBOARD_FAB2(SCH_1):PAGE169
     2 A_P3V3_STBY_SCALED @BASEBOARD_FAB2_LIB.BASEBOARD_FAB2(SCH_1):A_P3V3_STBY_SCALED    I88 @BASEBOARD_FAB2_LIB.BASEBOARD_FAB2(SCH_1):PAGE169

R1U40 RES_0402-33.2,1%,1/16W,CHIP,G2A
     1 IRQ_VM_INT_R_N @BASEBOARD_FAB2_LIB.BASEBOARD_FAB2(SCH_1):IRQ_VM_INT_R_N    I81 @BASEBOARD_FAB2_LIB.BASEBOARD_FAB2(SCH_1):PAGE165
     2 IRQ_VM_INT_N @BASEBOARD_FAB2_LIB.BASEBOARD_FAB2(SCH_1):IRQ_VM_INT_N    I81 @BASEBOARD_FAB2_LIB.BASEBOARD_FAB2(SCH_1):PAGE165

R1U41 RES_0402-150.0,1%,1/16W,CHIP,GA
     1 PVCCIO_CPU1 @BASEBOARD_FAB2_LIB.BASEBOARD_FAB2(SCH_1):PVCCIO_CPU1    I56 @BASEBOARD_FAB2_LIB.BASEBOARD_FAB2(SCH_1):PAGE152
     2 H_CPU1_MEMGHJ_MEMHOT_G_N @BASEBOARD_FAB2_LIB.BASEBOARD_FAB2(SCH_1):H_CPU1_MEMGHJ_MEMHOT_G_N    I56 @BASEBOARD_FAB2_LIB.BASEBOARD_FAB2(SCH_1):PAGE152

R1U43 RES_0402-49.9,1%,1/16W,CHIP,G2A
     1 PVCCIO_CPU0 @BASEBOARD_FAB2_LIB.BASEBOARD_FAB2(SCH_1):PVCCIO_CPU0    I25 @BASEBOARD_FAB2_LIB.BASEBOARD_FAB2(SCH_1):PAGE152
     2 P0V7_GTL2014_2 @BASEBOARD_FAB2_LIB.BASEBOARD_FAB2(SCH_1):P0V7_GTL2014_2    I25 @BASEBOARD_FAB2_LIB.BASEBOARD_FAB2(SCH_1):PAGE152

R1U44 RES_0402-3.48K,1.0%,1/16W,CHIPA
     1 A_P5V_STBY_SCALED @BASEBOARD_FAB2_LIB.BASEBOARD_FAB2(SCH_1):A_P5V_STBY_SCALED   I116 @BASEBOARD_FAB2_LIB.BASEBOARD_FAB2(SCH_1):PAGE169
     2    GND @BASEBOARD_FAB2_LIB.BASEBOARD_FAB2(SCH_1):GND   I116 @BASEBOARD_FAB2_LIB.BASEBOARD_FAB2(SCH_1):PAGE169

R1U45 RES_0402-4.75K,1%,1/16W,CHIP,GA
     1 FM_ADC128_A0 @BASEBOARD_FAB2_LIB.BASEBOARD_FAB2(SCH_1):FM_ADC128_A0    I55 @BASEBOARD_FAB2_LIB.BASEBOARD_FAB2(SCH_1):PAGE165
     2    GND @BASEBOARD_FAB2_LIB.BASEBOARD_FAB2(SCH_1):GND    I55 @BASEBOARD_FAB2_LIB.BASEBOARD_FAB2(SCH_1):PAGE165

R1U46 RES_0402-33.2,1%,1/16W,CHIP,G2A
     1 H_CPU0_MEMABC_MEMHOT_LVT3_K_N @BASEBOARD_FAB2_LIB.BASEBOARD_FAB2(SCH_1):H_CPU0_MEMABC_MEMHOT_LVT3_K_N     I6 @BASEBOARD_FAB2_LIB.BASEBOARD_FAB2(SCH_1):PAGE152
     2 H_CPU0_MEMABC_MEMHOT_LVT3_N @BASEBOARD_FAB2_LIB.BASEBOARD_FAB2(SCH_1):H_CPU0_MEMABC_MEMHOT_LVT3_N     I6 @BASEBOARD_FAB2_LIB.BASEBOARD_FAB2(SCH_1):PAGE152

R1U47 RES_0402-5.11K,1%,1/16W,CHIP,GA
     1 P5V_STBY @BASEBOARD_FAB2_LIB.BASEBOARD_FAB2(SCH_1):P5V_STBY   I115 @BASEBOARD_FAB2_LIB.BASEBOARD_FAB2(SCH_1):PAGE169
     2 A_P5V_STBY_SCALED @BASEBOARD_FAB2_LIB.BASEBOARD_FAB2(SCH_1):A_P5V_STBY_SCALED   I115 @BASEBOARD_FAB2_LIB.BASEBOARD_FAB2(SCH_1):PAGE169

R1U48 RES_0402-4.75K,1%,1/16W,CHIP,GA
     1 FM_ADC128_A1 @BASEBOARD_FAB2_LIB.BASEBOARD_FAB2(SCH_1):FM_ADC128_A1    I56 @BASEBOARD_FAB2_LIB.BASEBOARD_FAB2(SCH_1):PAGE165
     2    GND @BASEBOARD_FAB2_LIB.BASEBOARD_FAB2(SCH_1):GND    I56 @BASEBOARD_FAB2_LIB.BASEBOARD_FAB2(SCH_1):PAGE165

R1U49 RES_0402-2.7K,1%,1/16W,CHIP,G2A
     1 P3V3_STBY @BASEBOARD_FAB2_LIB.BASEBOARD_FAB2(SCH_1):P3V3_STBY   I163 @BASEBOARD_FAB2_LIB.BASEBOARD_FAB2(SCH_1):PAGE169
     2 FM_BATTERY_SENSE_EN @BASEBOARD_FAB2_LIB.BASEBOARD_FAB2(SCH_1):FM_BATTERY_SENSE_EN   I163 @BASEBOARD_FAB2_LIB.BASEBOARD_FAB2(SCH_1):PAGE169

R1U50 RES_0402-200.0K,1%,1/16W,CHIP,A
     1 A_P3V_BAT_R @BASEBOARD_FAB2_LIB.BASEBOARD_FAB2(SCH_1):A_P3V_BAT_R   I126 @BASEBOARD_FAB2_LIB.BASEBOARD_FAB2(SCH_1):PAGE169
     2 P3V_BAT_SOURCE_R @BASEBOARD_FAB2_LIB.BASEBOARD_FAB2(SCH_1):P3V_BAT_SOURCE_R   I126 @BASEBOARD_FAB2_LIB.BASEBOARD_FAB2(SCH_1):PAGE169

R1U51 RES_0402-0.0,5%,1/16W,CHIP,G21A
     1    GND @BASEBOARD_FAB2_LIB.BASEBOARD_FAB2(SCH_1):GND   I112 @BASEBOARD_FAB2_LIB.BASEBOARD_FAB2(SCH_1):PAGE141
     2 GND_NIC @BASEBOARD_FAB2_LIB.BASEBOARD_FAB2(SCH_1):GND_NIC   I112 @BASEBOARD_FAB2_LIB.BASEBOARD_FAB2(SCH_1):PAGE141

R1U52 RES_0402-1.5K,1%,1/16W,CHIP,G2A
     1 P3V3_STBY @BASEBOARD_FAB2_LIB.BASEBOARD_FAB2(SCH_1):P3V3_STBY    I51 @BASEBOARD_FAB2_LIB.BASEBOARD_FAB2(SCH_1):PAGE146
     2 USB_PCH_BMC_P4_DP @BASEBOARD_FAB2_LIB.BASEBOARD_FAB2(SCH_1):USB_PCH_BMC_P4_DP    I51 @BASEBOARD_FAB2_LIB.BASEBOARD_FAB2(SCH_1):PAGE146

R1U53 RES_0402-0.0,5%,1/16W,CHIP,G21A
     1 H_CPU1_MEMGHJ_MEMHOT_G_N @BASEBOARD_FAB2_LIB.BASEBOARD_FAB2(SCH_1):H_CPU1_MEMGHJ_MEMHOT_G_N    I64 @BASEBOARD_FAB2_LIB.BASEBOARD_FAB2(SCH_1):PAGE152
     2 H_CPU1_MEMGHJ_MEMHOT_G_R_N @BASEBOARD_FAB2_LIB.BASEBOARD_FAB2(SCH_1):H_CPU1_MEMGHJ_MEMHOT_G_R_N    I64 @BASEBOARD_FAB2_LIB.BASEBOARD_FAB2(SCH_1):PAGE152

R1U54 RES_0402-0.0,5%,1/16W,CHIP,G21A
     1 H_CPU1_MEMGHJ_MEMHOT_LVT3_N @BASEBOARD_FAB2_LIB.BASEBOARD_FAB2(SCH_1):H_CPU1_MEMGHJ_MEMHOT_LVT3_N    I93 @BASEBOARD_FAB2_LIB.BASEBOARD_FAB2(SCH_1):PAGE152
     2 H_CPU1_MEMGHJ_MEMHOT_LVT3_BMC_N @BASEBOARD_FAB2_LIB.BASEBOARD_FAB2(SCH_1):H_CPU1_MEMGHJ_MEMHOT_LVT3_BMC_N    I93 @BASEBOARD_FAB2_LIB.BASEBOARD_FAB2(SCH_1):PAGE152

R1U55 RES_0402-0.0,5%,1/16W,EMPTY,G2A
     1 H_CPU1_MEMGHJ_MEMHOT_G_N @BASEBOARD_FAB2_LIB.BASEBOARD_FAB2(SCH_1):H_CPU1_MEMGHJ_MEMHOT_G_N    I67 @BASEBOARD_FAB2_LIB.BASEBOARD_FAB2(SCH_1):PAGE152
     2 H_CPU1_MEMGHJ_MEMHOT_G_PCH_N @BASEBOARD_FAB2_LIB.BASEBOARD_FAB2(SCH_1):H_CPU1_MEMGHJ_MEMHOT_G_PCH_N    I67 @BASEBOARD_FAB2_LIB.BASEBOARD_FAB2(SCH_1):PAGE152

R1U56 RES_0402-0.0,5%,1/16W,EMPTY,G2A
     1 H_CPU0_MEMDEF_MEMHOT_G_PCH_N @BASEBOARD_FAB2_LIB.BASEBOARD_FAB2(SCH_1):H_CPU0_MEMDEF_MEMHOT_G_PCH_N    I50 @BASEBOARD_FAB2_LIB.BASEBOARD_FAB2(SCH_1):PAGE152
     2 H_CPU0_MEMDEF_MEMHOT_G_N @BASEBOARD_FAB2_LIB.BASEBOARD_FAB2(SCH_1):H_CPU0_MEMDEF_MEMHOT_G_N    I50 @BASEBOARD_FAB2_LIB.BASEBOARD_FAB2(SCH_1):PAGE152

R1U57 RES_0402-0.0,5%,1/16W,EMPTY,G2A
     1 H_CPU1_MEMGHJ_MEMHOT_LVT3_K_N @BASEBOARD_FAB2_LIB.BASEBOARD_FAB2(SCH_1):H_CPU1_MEMGHJ_MEMHOT_LVT3_K_N    I69 @BASEBOARD_FAB2_LIB.BASEBOARD_FAB2(SCH_1):PAGE152
     2 H_CPU1_MEMGHJ_MEMHOT_G_PCH_N @BASEBOARD_FAB2_LIB.BASEBOARD_FAB2(SCH_1):H_CPU1_MEMGHJ_MEMHOT_G_PCH_N    I69 @BASEBOARD_FAB2_LIB.BASEBOARD_FAB2(SCH_1):PAGE152

R1U58 RES_0402-0.0,5%,1/16W,CHIP,G21A
     1 H_CPU0_MEMDEF_MEMHOT_G_N @BASEBOARD_FAB2_LIB.BASEBOARD_FAB2(SCH_1):H_CPU0_MEMDEF_MEMHOT_G_N    I49 @BASEBOARD_FAB2_LIB.BASEBOARD_FAB2(SCH_1):PAGE152
     2 H_CPU0_MEMDEF_MEMHOT_G_R_N @BASEBOARD_FAB2_LIB.BASEBOARD_FAB2(SCH_1):H_CPU0_MEMDEF_MEMHOT_G_R_N    I49 @BASEBOARD_FAB2_LIB.BASEBOARD_FAB2(SCH_1):PAGE152

R1U59 RES_0402-0.0,5%,1/16W,CHIP,G21A
     1 H_CPU0_ABC_MEMHOT_LVT3_R_N @BASEBOARD_FAB2_LIB.BASEBOARD_FAB2(SCH_1):H_CPU0_ABC_MEMHOT_LVT3_R_N    I74 @BASEBOARD_FAB2_LIB.BASEBOARD_FAB2(SCH_1):PAGE152
     2 H_CPU0_MEMABC_MEMHOT_LVT3_K_N @BASEBOARD_FAB2_LIB.BASEBOARD_FAB2(SCH_1):H_CPU0_MEMABC_MEMHOT_LVT3_K_N    I74 @BASEBOARD_FAB2_LIB.BASEBOARD_FAB2(SCH_1):PAGE152

R1U60 RES_0402-0.0,5%,1/16W,CHIP,G21A
     1 H_CPU1_MEMKLM_MEMHOT_G_N @BASEBOARD_FAB2_LIB.BASEBOARD_FAB2(SCH_1):H_CPU1_MEMKLM_MEMHOT_G_N    I65 @BASEBOARD_FAB2_LIB.BASEBOARD_FAB2(SCH_1):PAGE152
     2 H_CPU1_MEMKLM_MEMHOT_G_R_N @BASEBOARD_FAB2_LIB.BASEBOARD_FAB2(SCH_1):H_CPU1_MEMKLM_MEMHOT_G_R_N    I65 @BASEBOARD_FAB2_LIB.BASEBOARD_FAB2(SCH_1):PAGE152

R1U61 RES_0402-0.0,5%,1/16W,EMPTY,G2A
     1 H_CPU1_MEMKLM_MEMHOT_LVT3_K_N @BASEBOARD_FAB2_LIB.BASEBOARD_FAB2(SCH_1):H_CPU1_MEMKLM_MEMHOT_LVT3_K_N    I70 @BASEBOARD_FAB2_LIB.BASEBOARD_FAB2(SCH_1):PAGE152
     2 H_CPU1_MEMKLM_MEMHOT_G_PCH_N @BASEBOARD_FAB2_LIB.BASEBOARD_FAB2(SCH_1):H_CPU1_MEMKLM_MEMHOT_G_PCH_N    I70 @BASEBOARD_FAB2_LIB.BASEBOARD_FAB2(SCH_1):PAGE152

R1U62 RES_0402-0.0,5%,1/16W,EMPTY,G2A
     1 H_CPU1_MEMKLM_MEMHOT_G_N @BASEBOARD_FAB2_LIB.BASEBOARD_FAB2(SCH_1):H_CPU1_MEMKLM_MEMHOT_G_N    I68 @BASEBOARD_FAB2_LIB.BASEBOARD_FAB2(SCH_1):PAGE152
     2 H_CPU1_MEMKLM_MEMHOT_G_PCH_N @BASEBOARD_FAB2_LIB.BASEBOARD_FAB2(SCH_1):H_CPU1_MEMKLM_MEMHOT_G_PCH_N    I68 @BASEBOARD_FAB2_LIB.BASEBOARD_FAB2(SCH_1):PAGE152

R1U63 RES_0402-1.00K,1%,1/16W,CHIP,GA
     1 PD_RST_RTCRST_N @BASEBOARD_FAB2_LIB.BASEBOARD_FAB2(SCH_1):PD_RST_RTCRST_N    I15 @BASEBOARD_FAB2_LIB.BASEBOARD_FAB2(SCH_1):PAGE137
     2    GND @BASEBOARD_FAB2_LIB.BASEBOARD_FAB2(SCH_1):GND    I15 @BASEBOARD_FAB2_LIB.BASEBOARD_FAB2(SCH_1):PAGE137

R1U64 RES_0402-1.00K,1%,1/16W,CHIP,GA
     1 PD_IE_DEBUG_MODE @BASEBOARD_FAB2_LIB.BASEBOARD_FAB2(SCH_1):PD_IE_DEBUG_MODE    I69 @BASEBOARD_FAB2_LIB.BASEBOARD_FAB2(SCH_1):PAGE137
     2    GND @BASEBOARD_FAB2_LIB.BASEBOARD_FAB2(SCH_1):GND    I69 @BASEBOARD_FAB2_LIB.BASEBOARD_FAB2(SCH_1):PAGE137

R1W9 RES_0402-22.1,1.0%,1/16W,CHIP,A
     1 UNNAMED_239_CAP_I84_A @BASEBOARD_FAB2_LIB.BASEBOARD_FAB2(SCH_1):UNNAMED_239_CAP_I84_A    I77 @BASEBOARD_FAB2_LIB.BASEBOARD_FAB2(SCH_1):PAGE239
     2 UNNAMED_239_OFFPAGE_I76_A @BASEBOARD_FAB2_LIB.BASEBOARD_FAB2(SCH_1):UNNAMED_239_OFFPAGE_I76_A    I77 @BASEBOARD_FAB2_LIB.BASEBOARD_FAB2(SCH_1):PAGE239

R2L1 RES_0402-0.0,5%,1/16W,CHIP,G21A
     1 VR_PVNN_P1V05_PCH_VD12 @BASEBOARD_FAB2_LIB.BASEBOARD_FAB2(SCH_1):VR_PVNN_P1V05_PCH_VD12   I224 @BASEBOARD_FAB2_LIB.BASEBOARD_FAB2(SCH_1):PAGE235
     2 VR_PVNN_PCH_AIREF1 @BASEBOARD_FAB2_LIB.BASEBOARD_FAB2(SCH_1):VR_PVNN_PCH_AIREF1   I224 @BASEBOARD_FAB2_LIB.BASEBOARD_FAB2(SCH_1):PAGE235

R2L4 RES_0402-2.0K,1%,1/16W,CHIP,G2A
     1 P3V3_STBY @BASEBOARD_FAB2_LIB.BASEBOARD_FAB2(SCH_1):P3V3_STBY    I18 @BASEBOARD_FAB2_LIB.BASEBOARD_FAB2(SCH_1):PAGE178
     2 SGPIO_PCH_SSATA_DOUT0_R @BASEBOARD_FAB2_LIB.BASEBOARD_FAB2(SCH_1):SGPIO_PCH_SSATA_DOUT0_R    I18 @BASEBOARD_FAB2_LIB.BASEBOARD_FAB2(SCH_1):PAGE178

R2L5 RES_0402-2.0K,1%,1/16W,CHIP,G2A
     1 P3V3_STBY @BASEBOARD_FAB2_LIB.BASEBOARD_FAB2(SCH_1):P3V3_STBY    I20 @BASEBOARD_FAB2_LIB.BASEBOARD_FAB2(SCH_1):PAGE178
     2 SGPIO_PCH_SSATA_LOAD_R @BASEBOARD_FAB2_LIB.BASEBOARD_FAB2(SCH_1):SGPIO_PCH_SSATA_LOAD_R    I20 @BASEBOARD_FAB2_LIB.BASEBOARD_FAB2(SCH_1):PAGE178

R2L6 RES_0402-2.0K,1%,1/16W,CHIP,G2A
     1 P3V3_STBY @BASEBOARD_FAB2_LIB.BASEBOARD_FAB2(SCH_1):P3V3_STBY    I17 @BASEBOARD_FAB2_LIB.BASEBOARD_FAB2(SCH_1):PAGE178
     2 SGPIO_PCH_SSATA_CLOCK_R @BASEBOARD_FAB2_LIB.BASEBOARD_FAB2(SCH_1):SGPIO_PCH_SSATA_CLOCK_R    I17 @BASEBOARD_FAB2_LIB.BASEBOARD_FAB2(SCH_1):PAGE178

R2L7 RES_0402-0.0,5%,1/16W,CHIP,G21A
     1 VR_PVNN_P1V05_PCH_VD12 @BASEBOARD_FAB2_LIB.BASEBOARD_FAB2(SCH_1):VR_PVNN_P1V05_PCH_VD12   I225 @BASEBOARD_FAB2_LIB.BASEBOARD_FAB2(SCH_1):PAGE235
     2 VR_P1V05_PCH_BIREF1 @BASEBOARD_FAB2_LIB.BASEBOARD_FAB2(SCH_1):VR_P1V05_PCH_BIREF1   I225 @BASEBOARD_FAB2_LIB.BASEBOARD_FAB2(SCH_1):PAGE235

R2L8 RES_0603-10.0,1%,1/10W,CHIP,G2A
     1 VSENSE_P1V05_PCH_STBY_AVSP @BASEBOARD_FAB2_LIB.BASEBOARD_FAB2(SCH_1):VSENSE_P1V05_PCH_STBY_AVSP   I154 @BASEBOARD_FAB2_LIB.BASEBOARD_FAB2(SCH_1):PAGE235
     2 VR_P1V05_PCH_STBY_AVSP @BASEBOARD_FAB2_LIB.BASEBOARD_FAB2(SCH_1):VR_P1V05_PCH_STBY_AVSP   I154 @BASEBOARD_FAB2_LIB.BASEBOARD_FAB2(SCH_1):PAGE235

R2L9 RES_0402-4.02K,1%,1/16W,CHIP,GA
     1 VR_PVNN_PCH_XADDR1 @BASEBOARD_FAB2_LIB.BASEBOARD_FAB2(SCH_1):VR_PVNN_PCH_XADDR1   I176 @BASEBOARD_FAB2_LIB.BASEBOARD_FAB2(SCH_1):PAGE235
     2    GND @BASEBOARD_FAB2_LIB.BASEBOARD_FAB2(SCH_1):GND   I176 @BASEBOARD_FAB2_LIB.BASEBOARD_FAB2(SCH_1):PAGE235

R2L10 RES_0402-1.5K,1%,1/16W,CHIP,G2A
     1 VR_PVNN_PCH_VINSEN @BASEBOARD_FAB2_LIB.BASEBOARD_FAB2(SCH_1):VR_PVNN_PCH_VINSEN   I166 @BASEBOARD_FAB2_LIB.BASEBOARD_FAB2(SCH_1):PAGE235
     2    GND @BASEBOARD_FAB2_LIB.BASEBOARD_FAB2(SCH_1):GND   I166 @BASEBOARD_FAB2_LIB.BASEBOARD_FAB2(SCH_1):PAGE235

R2L11 RES_0402-2.0K,1%,1/16W,CHIP,G2A
     1 P3V3_STBY @BASEBOARD_FAB2_LIB.BASEBOARD_FAB2(SCH_1):P3V3_STBY    I13 @BASEBOARD_FAB2_LIB.BASEBOARD_FAB2(SCH_1):PAGE178
     2 SGPIO_PCH_SATA_CLOCK_R @BASEBOARD_FAB2_LIB.BASEBOARD_FAB2(SCH_1):SGPIO_PCH_SATA_CLOCK_R    I13 @BASEBOARD_FAB2_LIB.BASEBOARD_FAB2(SCH_1):PAGE178

R2L12 RES_0402-2.0K,1%,1/16W,CHIP,G2A
     1 P3V3_STBY @BASEBOARD_FAB2_LIB.BASEBOARD_FAB2(SCH_1):P3V3_STBY     I2 @BASEBOARD_FAB2_LIB.BASEBOARD_FAB2(SCH_1):PAGE178
     2 SGPIO_PCH_SATA_LOAD_R @BASEBOARD_FAB2_LIB.BASEBOARD_FAB2(SCH_1):SGPIO_PCH_SATA_LOAD_R     I2 @BASEBOARD_FAB2_LIB.BASEBOARD_FAB2(SCH_1):PAGE178

R2L14 RES_0402-0.0,5%,1/16W,CHIP,G21A
     1 P3V3_STBY @BASEBOARD_FAB2_LIB.BASEBOARD_FAB2(SCH_1):P3V3_STBY   I159 @BASEBOARD_FAB2_LIB.BASEBOARD_FAB2(SCH_1):PAGE235
     2 VR_PVNN_PCH_VDD @BASEBOARD_FAB2_LIB.BASEBOARD_FAB2(SCH_1):VR_PVNN_PCH_VDD   I159 @BASEBOARD_FAB2_LIB.BASEBOARD_FAB2(SCH_1):PAGE235

R2L15 RES_0402-2.0K,1%,1/16W,CHIP,G2A
     1 P3V3_STBY @BASEBOARD_FAB2_LIB.BASEBOARD_FAB2(SCH_1):P3V3_STBY    I12 @BASEBOARD_FAB2_LIB.BASEBOARD_FAB2(SCH_1):PAGE178
     2 SGPIO_PCH_SATA_DOUT0_R @BASEBOARD_FAB2_LIB.BASEBOARD_FAB2(SCH_1):SGPIO_PCH_SATA_DOUT0_R    I12 @BASEBOARD_FAB2_LIB.BASEBOARD_FAB2(SCH_1):PAGE178

R2L16 RES_0402-22.1,1.0%,1/16W,CHIP,A
     1 PWRGD_PVNN_PCH_R @BASEBOARD_FAB2_LIB.BASEBOARD_FAB2(SCH_1):PWRGD_PVNN_PCH_R   I147 @BASEBOARD_FAB2_LIB.BASEBOARD_FAB2(SCH_1):PAGE235
     2 PWRGD_PVNN_P1V05_PCH @BASEBOARD_FAB2_LIB.BASEBOARD_FAB2(SCH_1):PWRGD_PVNN_P1V05_PCH   I147 @BASEBOARD_FAB2_LIB.BASEBOARD_FAB2(SCH_1):PAGE235

R2L17 RES_0402-0.0,5%,1/16W,CHIP,G21A
     1 PWRGD_P1V8_PCH_STBY @BASEBOARD_FAB2_LIB.BASEBOARD_FAB2(SCH_1):PWRGD_P1V8_PCH_STBY   I221 @BASEBOARD_FAB2_LIB.BASEBOARD_FAB2(SCH_1):PAGE235
     2 VR_PVNN_PCH_VREN @BASEBOARD_FAB2_LIB.BASEBOARD_FAB2(SCH_1):VR_PVNN_PCH_VREN   I221 @BASEBOARD_FAB2_LIB.BASEBOARD_FAB2(SCH_1):PAGE235

R2L18 RES_0402-1.00K,1%,1/16W,CHIP,GA
     1 PD_SATA0_CONTROLLER_TYPE_R @BASEBOARD_FAB2_LIB.BASEBOARD_FAB2(SCH_1):PD_SATA0_CONTROLLER_TYPE_R   I266 @BASEBOARD_FAB2_LIB.BASEBOARD_FAB2(SCH_1):PAGE173
     2    GND @BASEBOARD_FAB2_LIB.BASEBOARD_FAB2(SCH_1):GND   I266 @BASEBOARD_FAB2_LIB.BASEBOARD_FAB2(SCH_1):PAGE173

R2L19 RES_0402-49.9K,1%,1/16W,CHIP,GA
     1 VR_P1V8_PCH_STBY_FB @BASEBOARD_FAB2_LIB.BASEBOARD_FAB2(SCH_1):VR_P1V8_PCH_STBY_FB    I80 @BASEBOARD_FAB2_LIB.BASEBOARD_FAB2(SCH_1):PAGE237
     2    GND @BASEBOARD_FAB2_LIB.BASEBOARD_FAB2(SCH_1):GND    I80 @BASEBOARD_FAB2_LIB.BASEBOARD_FAB2(SCH_1):PAGE237

R2L20 RES_0402-63.4K,1.0%,1/16W,CHIPA
     1 P1V8_PCH_STBY @BASEBOARD_FAB2_LIB.BASEBOARD_FAB2(SCH_1):P1V8_PCH_STBY    I81 @BASEBOARD_FAB2_LIB.BASEBOARD_FAB2(SCH_1):PAGE237
     2 VR_P1V8_PCH_STBY_FB @BASEBOARD_FAB2_LIB.BASEBOARD_FAB2(SCH_1):VR_P1V8_PCH_STBY_FB    I81 @BASEBOARD_FAB2_LIB.BASEBOARD_FAB2(SCH_1):PAGE237

R2L21 RES_0402-2.0K,1%,1/16W,CHIP,G2A
     1   P3V3 @BASEBOARD_FAB2_LIB.BASEBOARD_FAB2(SCH_1):P3V3   I263 @BASEBOARD_FAB2_LIB.BASEBOARD_FAB2(SCH_1):PAGE173
     2 PU_DATAIN1_SATA_0_R @BASEBOARD_FAB2_LIB.BASEBOARD_FAB2(SCH_1):PU_DATAIN1_SATA_0_R   I263 @BASEBOARD_FAB2_LIB.BASEBOARD_FAB2(SCH_1):PAGE173

R2L22 RES_0402-1.00K,1%,1/16W,CHIP,GA
     1 PD_SATA1_CONTROLLER_TYPE_R @BASEBOARD_FAB2_LIB.BASEBOARD_FAB2(SCH_1):PD_SATA1_CONTROLLER_TYPE_R   I264 @BASEBOARD_FAB2_LIB.BASEBOARD_FAB2(SCH_1):PAGE173
     2    GND @BASEBOARD_FAB2_LIB.BASEBOARD_FAB2(SCH_1):GND   I264 @BASEBOARD_FAB2_LIB.BASEBOARD_FAB2(SCH_1):PAGE173

R2L23 RES_0402-2.0K,1%,1/16W,CHIP,G2A
     1   P3V3 @BASEBOARD_FAB2_LIB.BASEBOARD_FAB2(SCH_1):P3V3   I261 @BASEBOARD_FAB2_LIB.BASEBOARD_FAB2(SCH_1):PAGE173
     2 PU_DATAIN1_SATA_1_R @BASEBOARD_FAB2_LIB.BASEBOARD_FAB2(SCH_1):PU_DATAIN1_SATA_1_R   I261 @BASEBOARD_FAB2_LIB.BASEBOARD_FAB2(SCH_1):PAGE173

R2L24 RES_0402-2.26K,1.0%,1/16W,EMPTA
     1 P3V3_STBY @BASEBOARD_FAB2_LIB.BASEBOARD_FAB2(SCH_1):P3V3_STBY   I148 @BASEBOARD_FAB2_LIB.BASEBOARD_FAB2(SCH_1):PAGE235
     2 PU_VR_PVNN_PCH_FAULT1 @BASEBOARD_FAB2_LIB.BASEBOARD_FAB2(SCH_1):PU_VR_PVNN_PCH_FAULT1   I148 @BASEBOARD_FAB2_LIB.BASEBOARD_FAB2(SCH_1):PAGE235

R2L25 RES_0402-100.0K,1%,1/16W,EMPTYA
     1 P3V3_STBY @BASEBOARD_FAB2_LIB.BASEBOARD_FAB2(SCH_1):P3V3_STBY   I235 @BASEBOARD_FAB2_LIB.BASEBOARD_FAB2(SCH_1):PAGE235
     2 VID_PCH_CORE_PVNN_AUX_VID_1 @BASEBOARD_FAB2_LIB.BASEBOARD_FAB2(SCH_1):VID_PCH_CORE_PVNN_AUX_VID_1   I235 @BASEBOARD_FAB2_LIB.BASEBOARD_FAB2(SCH_1):PAGE235

R2L26 RES_0402-100.0K,1%,1/16W,EMPTYA
     1 P3V3_STBY @BASEBOARD_FAB2_LIB.BASEBOARD_FAB2(SCH_1):P3V3_STBY   I236 @BASEBOARD_FAB2_LIB.BASEBOARD_FAB2(SCH_1):PAGE235
     2 VID_PCH_CORE_PVNN_AUX_VID_0 @BASEBOARD_FAB2_LIB.BASEBOARD_FAB2(SCH_1):VID_PCH_CORE_PVNN_AUX_VID_0   I236 @BASEBOARD_FAB2_LIB.BASEBOARD_FAB2(SCH_1):PAGE235

R2M1 RES_0402-33.2,1%,1/16W,CHIP,G2A
     1 FM_CPLD_ADR_TRIGGER_N @BASEBOARD_FAB2_LIB.BASEBOARD_FAB2(SCH_1):FM_CPLD_ADR_TRIGGER_N   I218 @BASEBOARD_FAB2_LIB.BASEBOARD_FAB2(SCH_1):PAGE120
     2 FM_CPLD_ADR_TRIGGER_R_N @BASEBOARD_FAB2_LIB.BASEBOARD_FAB2(SCH_1):FM_CPLD_ADR_TRIGGER_R_N   I218 @BASEBOARD_FAB2_LIB.BASEBOARD_FAB2(SCH_1):PAGE120

R2M2 RES_0402-4.75K,1%,1/16W,CHIP,GA
     1 P3V3_STBY @BASEBOARD_FAB2_LIB.BASEBOARD_FAB2(SCH_1):P3V3_STBY   I346 @BASEBOARD_FAB2_LIB.BASEBOARD_FAB2(SCH_1):PAGE157
     2 FM_ADR_SMI_GPIO_N @BASEBOARD_FAB2_LIB.BASEBOARD_FAB2(SCH_1):FM_ADR_SMI_GPIO_N   I346 @BASEBOARD_FAB2_LIB.BASEBOARD_FAB2(SCH_1):PAGE157

R2M3 RES_0402-33.2,1%,1/16W,CHIP,G2A
     1 FM_PCH_PLD_DATA_R @BASEBOARD_FAB2_LIB.BASEBOARD_FAB2(SCH_1):FM_PCH_PLD_DATA_R   I172 @BASEBOARD_FAB2_LIB.BASEBOARD_FAB2(SCH_1):PAGE119
     2 FM_PCH_PLD_DATA @BASEBOARD_FAB2_LIB.BASEBOARD_FAB2(SCH_1):FM_PCH_PLD_DATA   I172 @BASEBOARD_FAB2_LIB.BASEBOARD_FAB2(SCH_1):PAGE119

R2M4 RES_0402-1.00K,1%,1/16W,CHIP,GA
     1 P3V3_STBY @BASEBOARD_FAB2_LIB.BASEBOARD_FAB2(SCH_1):P3V3_STBY   I284 @BASEBOARD_FAB2_LIB.BASEBOARD_FAB2(SCH_1):PAGE133
     2 IRQ_HSC_FAULT_N @BASEBOARD_FAB2_LIB.BASEBOARD_FAB2(SCH_1):IRQ_HSC_FAULT_N   I284 @BASEBOARD_FAB2_LIB.BASEBOARD_FAB2(SCH_1):PAGE133

R2M5 RES_0402-4.75K,1%,1/16W,CHIP,GA
     1 P3V3_STBY @BASEBOARD_FAB2_LIB.BASEBOARD_FAB2(SCH_1):P3V3_STBY   I348 @BASEBOARD_FAB2_LIB.BASEBOARD_FAB2(SCH_1):PAGE157
     2 FM_BMC_CPLD_GPO @BASEBOARD_FAB2_LIB.BASEBOARD_FAB2(SCH_1):FM_BMC_CPLD_GPO   I348 @BASEBOARD_FAB2_LIB.BASEBOARD_FAB2(SCH_1):PAGE157

R2M6 RES_0402-1.0K,0.1%,1/16W,CHIP,A
     1 A_KR1_RBIAS @BASEBOARD_FAB2_LIB.BASEBOARD_FAB2(SCH_1):A_KR1_RBIAS    I99 @BASEBOARD_FAB2_LIB.BASEBOARD_FAB2(SCH_1):PAGE118
     2 P1V05_PCH_STBY_KR_PLL @BASEBOARD_FAB2_LIB.BASEBOARD_FAB2(SCH_1):P1V05_PCH_STBY_KR_PLL    I99 @BASEBOARD_FAB2_LIB.BASEBOARD_FAB2(SCH_1):PAGE118

R2M7 RES_0402-33.2,1%,1/16W,CHIP,G2A
     1 FM_ADR_MODE_SEL_R @BASEBOARD_FAB2_LIB.BASEBOARD_FAB2(SCH_1):FM_ADR_MODE_SEL_R   I174 @BASEBOARD_FAB2_LIB.BASEBOARD_FAB2(SCH_1):PAGE119
     2 FM_ADR_MODE_SEL @BASEBOARD_FAB2_LIB.BASEBOARD_FAB2(SCH_1):FM_ADR_MODE_SEL   I174 @BASEBOARD_FAB2_LIB.BASEBOARD_FAB2(SCH_1):PAGE119

R2M8 RES_0402-1.5K,1%,1/16W,CHIP,G2A
     1 P3V3_STBY @BASEBOARD_FAB2_LIB.BASEBOARD_FAB2(SCH_1):P3V3_STBY   I349 @BASEBOARD_FAB2_LIB.BASEBOARD_FAB2(SCH_1):PAGE133
     2 FM_CPU0_RC_ERROR_N @BASEBOARD_FAB2_LIB.BASEBOARD_FAB2(SCH_1):FM_CPU0_RC_ERROR_N   I349 @BASEBOARD_FAB2_LIB.BASEBOARD_FAB2(SCH_1):PAGE133

R2N1 RES_0402-33.2,1%,1/16W,CHIP,G2A
     1 FM_CPU_CATERR_DLY_LVT3_R_N @BASEBOARD_FAB2_LIB.BASEBOARD_FAB2(SCH_1):FM_CPU_CATERR_DLY_LVT3_R_N   I173 @BASEBOARD_FAB2_LIB.BASEBOARD_FAB2(SCH_1):PAGE119
     2 FM_CPU_CATERR_DLY_LVT3_N @BASEBOARD_FAB2_LIB.BASEBOARD_FAB2(SCH_1):FM_CPU_CATERR_DLY_LVT3_N   I173 @BASEBOARD_FAB2_LIB.BASEBOARD_FAB2(SCH_1):PAGE119

R2N4 RES_0402-1.0K,0.1%,1/16W,CHIP,A
     1 P1V05_PCH_STBY_KR_PLL @BASEBOARD_FAB2_LIB.BASEBOARD_FAB2(SCH_1):P1V05_PCH_STBY_KR_PLL    I96 @BASEBOARD_FAB2_LIB.BASEBOARD_FAB2(SCH_1):PAGE118
     2 A_KR0_RBIAS @BASEBOARD_FAB2_LIB.BASEBOARD_FAB2(SCH_1):A_KR0_RBIAS    I96 @BASEBOARD_FAB2_LIB.BASEBOARD_FAB2(SCH_1):PAGE118

R2N5 RES_0402-665,1.0%,1/16W,CHIP,GA
     1 P3V3_STBY @BASEBOARD_FAB2_LIB.BASEBOARD_FAB2(SCH_1):P3V3_STBY    I90 @BASEBOARD_FAB2_LIB.BASEBOARD_FAB2(SCH_1):PAGE138
     2 SMB_SMLINK0_STBY_LVC3_SCL @BASEBOARD_FAB2_LIB.BASEBOARD_FAB2(SCH_1):SMB_SMLINK0_STBY_LVC3_SCL    I90 @BASEBOARD_FAB2_LIB.BASEBOARD_FAB2(SCH_1):PAGE138

R2N6 RES_0402-10.0K,1%,1/16W,CHIP,GA
     1 P3V3_STBY @BASEBOARD_FAB2_LIB.BASEBOARD_FAB2(SCH_1):P3V3_STBY   I128 @BASEBOARD_FAB2_LIB.BASEBOARD_FAB2(SCH_1):PAGE118
     2 FM_GBE_LOM_DISABLE_N @BASEBOARD_FAB2_LIB.BASEBOARD_FAB2(SCH_1):FM_GBE_LOM_DISABLE_N   I128 @BASEBOARD_FAB2_LIB.BASEBOARD_FAB2(SCH_1):PAGE118

R2N7 RES_0402-4.75K,1%,1/16W,CHIP,GA
     1 P3V3_STBY @BASEBOARD_FAB2_LIB.BASEBOARD_FAB2(SCH_1):P3V3_STBY   I309 @BASEBOARD_FAB2_LIB.BASEBOARD_FAB2(SCH_1):PAGE133
     2 IRQ_BOARD_BMC_ALERT_N @BASEBOARD_FAB2_LIB.BASEBOARD_FAB2(SCH_1):IRQ_BOARD_BMC_ALERT_N   I309 @BASEBOARD_FAB2_LIB.BASEBOARD_FAB2(SCH_1):PAGE133

R2N8 RES_0402-665,1.0%,1/16W,CHIP,GA
     1 P3V3_STBY @BASEBOARD_FAB2_LIB.BASEBOARD_FAB2(SCH_1):P3V3_STBY    I89 @BASEBOARD_FAB2_LIB.BASEBOARD_FAB2(SCH_1):PAGE138
     2 SMB_SMLINK0_STBY_LVC3_SDA @BASEBOARD_FAB2_LIB.BASEBOARD_FAB2(SCH_1):SMB_SMLINK0_STBY_LVC3_SDA    I89 @BASEBOARD_FAB2_LIB.BASEBOARD_FAB2(SCH_1):PAGE138

R2N9 RES_0402-10.0K,1%,1/16W,CHIP,GA
     1 P3V3_STBY @BASEBOARD_FAB2_LIB.BASEBOARD_FAB2(SCH_1):P3V3_STBY   I267 @BASEBOARD_FAB2_LIB.BASEBOARD_FAB2(SCH_1):PAGE133
     2 PU_10GBE_LOM_PCI_DISABLE_N @BASEBOARD_FAB2_LIB.BASEBOARD_FAB2(SCH_1):PU_10GBE_LOM_PCI_DISABLE_N   I267 @BASEBOARD_FAB2_LIB.BASEBOARD_FAB2(SCH_1):PAGE133

R2N10 RES_0402-4.75K,1%,1/16W,CHIP,GA
     1 P3V3_STBY @BASEBOARD_FAB2_LIB.BASEBOARD_FAB2(SCH_1):P3V3_STBY    I10 @BASEBOARD_FAB2_LIB.BASEBOARD_FAB2(SCH_1):PAGE126
     2 FM_PCH_BMC_THERMTRIP_EXI_STRAP_ @BASEBOARD_FAB2_LIB.BASEBOARD_FAB2(SCH_1):FM_PCH_BMC_THERMTRIP_EXI_STRAP_N    I10 @BASEBOARD_FAB2_LIB.BASEBOARD_FAB2(SCH_1):PAGE126

R2N12 RES_0402-10.0K,1%,1/16W,EMPTY,A
     1    GND @BASEBOARD_FAB2_LIB.BASEBOARD_FAB2(SCH_1):GND   I122 @BASEBOARD_FAB2_LIB.BASEBOARD_FAB2(SCH_1):PAGE133
     2 PWRGD_SYS_PWROK @BASEBOARD_FAB2_LIB.BASEBOARD_FAB2(SCH_1):PWRGD_SYS_PWROK   I122 @BASEBOARD_FAB2_LIB.BASEBOARD_FAB2(SCH_1):PAGE133

R2N13 RES_0402-10.0K,1%,1/16W,CHIP,GA
     1 FM_BIOS_PREFRB2_GOOD @BASEBOARD_FAB2_LIB.BASEBOARD_FAB2(SCH_1):FM_BIOS_PREFRB2_GOOD    I75 @BASEBOARD_FAB2_LIB.BASEBOARD_FAB2(SCH_1):PAGE147
     2    GND @BASEBOARD_FAB2_LIB.BASEBOARD_FAB2(SCH_1):GND    I75 @BASEBOARD_FAB2_LIB.BASEBOARD_FAB2(SCH_1):PAGE147

R2N14 RES_0402-1.00K,1%,1/16W,EMPTY,A
     1 P3V3_STBY @BASEBOARD_FAB2_LIB.BASEBOARD_FAB2(SCH_1):P3V3_STBY    I83 @BASEBOARD_FAB2_LIB.BASEBOARD_FAB2(SCH_1):PAGE125
     2 FM_USB_P0_EN_BOOT_BIOS_STRAP_N @BASEBOARD_FAB2_LIB.BASEBOARD_FAB2(SCH_1):FM_USB_P0_EN_BOOT_BIOS_STRAP_N    I83 @BASEBOARD_FAB2_LIB.BASEBOARD_FAB2(SCH_1):PAGE125

R2N16 RES_0402-10.0K,1%,1/16W,CHIP,GA
     1 P3V3_STBY @BASEBOARD_FAB2_LIB.BASEBOARD_FAB2(SCH_1):P3V3_STBY   I247 @BASEBOARD_FAB2_LIB.BASEBOARD_FAB2(SCH_1):PAGE133
     2 PU_IRQ_VRALERT_N @BASEBOARD_FAB2_LIB.BASEBOARD_FAB2(SCH_1):PU_IRQ_VRALERT_N   I247 @BASEBOARD_FAB2_LIB.BASEBOARD_FAB2(SCH_1):PAGE133

R2N17 RES_0402-2.7K,1%,1/16W,EMPTY,GA
     1 P3V3_STBY @BASEBOARD_FAB2_LIB.BASEBOARD_FAB2(SCH_1):P3V3_STBY    I29 @BASEBOARD_FAB2_LIB.BASEBOARD_FAB2(SCH_1):PAGE164
     2 FM_BOARD_SKU_ID4 @BASEBOARD_FAB2_LIB.BASEBOARD_FAB2(SCH_1):FM_BOARD_SKU_ID4    I29 @BASEBOARD_FAB2_LIB.BASEBOARD_FAB2(SCH_1):PAGE164

R2N18 RES_0402-1.00K,1%,1/16W,CHIP,GA
     1 FM_BOARD_SKU_ID4 @BASEBOARD_FAB2_LIB.BASEBOARD_FAB2(SCH_1):FM_BOARD_SKU_ID4    I32 @BASEBOARD_FAB2_LIB.BASEBOARD_FAB2(SCH_1):PAGE164
     2    GND @BASEBOARD_FAB2_LIB.BASEBOARD_FAB2(SCH_1):GND    I32 @BASEBOARD_FAB2_LIB.BASEBOARD_FAB2(SCH_1):PAGE164

R2N19 RES_0402-49.9,1%,1/16W,CHIP,G2A
     1 SGPIO_PCH_SSATA_LOAD @BASEBOARD_FAB2_LIB.BASEBOARD_FAB2(SCH_1):SGPIO_PCH_SSATA_LOAD    I22 @BASEBOARD_FAB2_LIB.BASEBOARD_FAB2(SCH_1):PAGE178
     2 SGPIO_PCH_SSATA_LOAD_R @BASEBOARD_FAB2_LIB.BASEBOARD_FAB2(SCH_1):SGPIO_PCH_SSATA_LOAD_R    I22 @BASEBOARD_FAB2_LIB.BASEBOARD_FAB2(SCH_1):PAGE178

R2N20 RES_0402-0.0,5%,1/16W,CHIP,G21A
     1 SMB_LAN_STBY_LVC3_SDA_R2 @BASEBOARD_FAB2_LIB.BASEBOARD_FAB2(SCH_1):SMB_LAN_STBY_LVC3_SDA_R2   I171 @BASEBOARD_FAB2_LIB.BASEBOARD_FAB2(SCH_1):PAGE138
     2 SMB_LAN_STBY_LVC3_SDA @BASEBOARD_FAB2_LIB.BASEBOARD_FAB2(SCH_1):SMB_LAN_STBY_LVC3_SDA   I171 @BASEBOARD_FAB2_LIB.BASEBOARD_FAB2(SCH_1):PAGE138

R2N21 RES_0402-0.0,5%,1/16W,CHIP,G21A
     1 SMB_LAN_STBY_LVC3_SCL_R2 @BASEBOARD_FAB2_LIB.BASEBOARD_FAB2(SCH_1):SMB_LAN_STBY_LVC3_SCL_R2   I175 @BASEBOARD_FAB2_LIB.BASEBOARD_FAB2(SCH_1):PAGE138
     2 SMB_LAN_STBY_LVC3_SCL @BASEBOARD_FAB2_LIB.BASEBOARD_FAB2(SCH_1):SMB_LAN_STBY_LVC3_SCL   I175 @BASEBOARD_FAB2_LIB.BASEBOARD_FAB2(SCH_1):PAGE138

R2N22 RES_0402-49.9,1%,1/16W,CHIP,G2A
     1 SGPIO_PCH_SSATA_CLOCK @BASEBOARD_FAB2_LIB.BASEBOARD_FAB2(SCH_1):SGPIO_PCH_SSATA_CLOCK    I23 @BASEBOARD_FAB2_LIB.BASEBOARD_FAB2(SCH_1):PAGE178
     2 SGPIO_PCH_SSATA_CLOCK_R @BASEBOARD_FAB2_LIB.BASEBOARD_FAB2(SCH_1):SGPIO_PCH_SSATA_CLOCK_R    I23 @BASEBOARD_FAB2_LIB.BASEBOARD_FAB2(SCH_1):PAGE178

R2N23 RES_0402-10.0K,1%,1/16W,CHIP,GA
     1 P3V3_STBY @BASEBOARD_FAB2_LIB.BASEBOARD_FAB2(SCH_1):P3V3_STBY   I112 @BASEBOARD_FAB2_LIB.BASEBOARD_FAB2(SCH_1):PAGE135
     2 FM_QAT_EN_N @BASEBOARD_FAB2_LIB.BASEBOARD_FAB2(SCH_1):FM_QAT_EN_N   I112 @BASEBOARD_FAB2_LIB.BASEBOARD_FAB2(SCH_1):PAGE135

R2N24 RES_0402-1.00K,1%,1/16W,EMPTY,A
     1 FM_QAT_EN_N @BASEBOARD_FAB2_LIB.BASEBOARD_FAB2(SCH_1):FM_QAT_EN_N   I113 @BASEBOARD_FAB2_LIB.BASEBOARD_FAB2(SCH_1):PAGE135
     2    GND @BASEBOARD_FAB2_LIB.BASEBOARD_FAB2(SCH_1):GND   I113 @BASEBOARD_FAB2_LIB.BASEBOARD_FAB2(SCH_1):PAGE135

R2N25 RES_0402-51.1,1.0%,1/16W,CHIP,A
     1 FM_NMI_EVENT_N @BASEBOARD_FAB2_LIB.BASEBOARD_FAB2(SCH_1):FM_NMI_EVENT_N   I302 @BASEBOARD_FAB2_LIB.BASEBOARD_FAB2(SCH_1):PAGE157
     2 FM_BMC_NMI_N @BASEBOARD_FAB2_LIB.BASEBOARD_FAB2(SCH_1):FM_BMC_NMI_N   I302 @BASEBOARD_FAB2_LIB.BASEBOARD_FAB2(SCH_1):PAGE157

R2N26 RES_0402-33.2,1%,1/16W,CHIP,G2A
     1 FM_ADR_COMPLETE @BASEBOARD_FAB2_LIB.BASEBOARD_FAB2(SCH_1):FM_ADR_COMPLETE   I219 @BASEBOARD_FAB2_LIB.BASEBOARD_FAB2(SCH_1):PAGE120
     2 FM_ADR_COMPLETE_R1 @BASEBOARD_FAB2_LIB.BASEBOARD_FAB2(SCH_1):FM_ADR_COMPLETE_R1   I219 @BASEBOARD_FAB2_LIB.BASEBOARD_FAB2(SCH_1):PAGE120

R2N27 RES_0402-4.75K,1%,1/16W,CHIP,GA
     1   P3V3 @BASEBOARD_FAB2_LIB.BASEBOARD_FAB2(SCH_1):P3V3    I97 @BASEBOARD_FAB2_LIB.BASEBOARD_FAB2(SCH_1):PAGE157
     2 FM_BMC_NMI_N @BASEBOARD_FAB2_LIB.BASEBOARD_FAB2(SCH_1):FM_BMC_NMI_N    I97 @BASEBOARD_FAB2_LIB.BASEBOARD_FAB2(SCH_1):PAGE157

R2N28 RES_0402-10.0K,1%,1/16W,CHIP,GA
     1 P3V3_STBY @BASEBOARD_FAB2_LIB.BASEBOARD_FAB2(SCH_1):P3V3_STBY   I147 @BASEBOARD_FAB2_LIB.BASEBOARD_FAB2(SCH_1):PAGE136
     2 FM_PASSWORD_CLEAR_N @BASEBOARD_FAB2_LIB.BASEBOARD_FAB2(SCH_1):FM_PASSWORD_CLEAR_N   I147 @BASEBOARD_FAB2_LIB.BASEBOARD_FAB2(SCH_1):PAGE136

R2N29 RES_0402-1.5K,1%,1/16W,CHIP,G2A
     1 P3V3_STBY @BASEBOARD_FAB2_LIB.BASEBOARD_FAB2(SCH_1):P3V3_STBY   I352 @BASEBOARD_FAB2_LIB.BASEBOARD_FAB2(SCH_1):PAGE133
     2 FM_CPU1_RC_ERROR_N @BASEBOARD_FAB2_LIB.BASEBOARD_FAB2(SCH_1):FM_CPU1_RC_ERROR_N   I352 @BASEBOARD_FAB2_LIB.BASEBOARD_FAB2(SCH_1):PAGE133

R2N31 RES_0402-49.9,1%,1/16W,CHIP,G2A
     1 SGPIO_PCH_SATA_CLOCK @BASEBOARD_FAB2_LIB.BASEBOARD_FAB2(SCH_1):SGPIO_PCH_SATA_CLOCK    I11 @BASEBOARD_FAB2_LIB.BASEBOARD_FAB2(SCH_1):PAGE178
     2 SGPIO_PCH_SATA_CLOCK_R @BASEBOARD_FAB2_LIB.BASEBOARD_FAB2(SCH_1):SGPIO_PCH_SATA_CLOCK_R    I11 @BASEBOARD_FAB2_LIB.BASEBOARD_FAB2(SCH_1):PAGE178

R2N32 RES_0402-4.75K,1%,1/16W,CHIP,GA
     1 P3V3_STBY @BASEBOARD_FAB2_LIB.BASEBOARD_FAB2(SCH_1):P3V3_STBY   I341 @BASEBOARD_FAB2_LIB.BASEBOARD_FAB2(SCH_1):PAGE133
     2 FM_BIOS_SMI_ACTIVE_N @BASEBOARD_FAB2_LIB.BASEBOARD_FAB2(SCH_1):FM_BIOS_SMI_ACTIVE_N   I341 @BASEBOARD_FAB2_LIB.BASEBOARD_FAB2(SCH_1):PAGE133

R2P1 RES_0402-0.0,5%,1/16W,CHIP,G21A
     1 RMII_SPRNGVLLE_BMC_PCH_RXD1 @BASEBOARD_FAB2_LIB.BASEBOARD_FAB2(SCH_1):RMII_SPRNGVLLE_BMC_PCH_RXD1    I91 @BASEBOARD_FAB2_LIB.BASEBOARD_FAB2(SCH_1):PAGE121
     2 RMII_SPRNGVLLE_BMC_PCH_RXD1_R1 @BASEBOARD_FAB2_LIB.BASEBOARD_FAB2(SCH_1):RMII_SPRNGVLLE_BMC_PCH_RXD1_R1    I91 @BASEBOARD_FAB2_LIB.BASEBOARD_FAB2(SCH_1):PAGE121

R2P2 RES_0402-1.00K,1%,1/16W,CHIP,GA
     1 SPI_PCH_IO2 @BASEBOARD_FAB2_LIB.BASEBOARD_FAB2(SCH_1):SPI_PCH_IO2    I37 @BASEBOARD_FAB2_LIB.BASEBOARD_FAB2(SCH_1):PAGE111
     2 XDP_DEBUG_CONSENT_N @BASEBOARD_FAB2_LIB.BASEBOARD_FAB2(SCH_1):XDP_DEBUG_CONSENT_N    I37 @BASEBOARD_FAB2_LIB.BASEBOARD_FAB2(SCH_1):PAGE111

R2P3 RES_0402-4.75K,1%,1/16W,CHIP,GA
     1 P3V3_STBY @BASEBOARD_FAB2_LIB.BASEBOARD_FAB2(SCH_1):P3V3_STBY     I2 @BASEBOARD_FAB2_LIB.BASEBOARD_FAB2(SCH_1):PAGE170
     2 IRQ_FORCE_NM_THROTTLE_R_N @BASEBOARD_FAB2_LIB.BASEBOARD_FAB2(SCH_1):IRQ_FORCE_NM_THROTTLE_R_N     I2 @BASEBOARD_FAB2_LIB.BASEBOARD_FAB2(SCH_1):PAGE170

R2P4 RES_0402-33.2,1%,1/16W,CHIP,G2A
     1 IRQ_FORCE_NM_THROTTLE_R_N @BASEBOARD_FAB2_LIB.BASEBOARD_FAB2(SCH_1):IRQ_FORCE_NM_THROTTLE_R_N    I74 @BASEBOARD_FAB2_LIB.BASEBOARD_FAB2(SCH_1):PAGE170
     2 IRQ_FORCE_NM_THROTTLE_N @BASEBOARD_FAB2_LIB.BASEBOARD_FAB2(SCH_1):IRQ_FORCE_NM_THROTTLE_N    I74 @BASEBOARD_FAB2_LIB.BASEBOARD_FAB2(SCH_1):PAGE170

R2P5 RES_0402-4.75K,1%,1/16W,CHIP,GA
     1 P3V3_STBY @BASEBOARD_FAB2_LIB.BASEBOARD_FAB2(SCH_1):P3V3_STBY    I56 @BASEBOARD_FAB2_LIB.BASEBOARD_FAB2(SCH_1):PAGE170
     2 FM_PMBUS_ALERT_BUF_EN @BASEBOARD_FAB2_LIB.BASEBOARD_FAB2(SCH_1):FM_PMBUS_ALERT_BUF_EN    I56 @BASEBOARD_FAB2_LIB.BASEBOARD_FAB2(SCH_1):PAGE170

R2P8 RES_0402-560,5%,1/16W,CHIP,G21A
     1 P3V3_STBY @BASEBOARD_FAB2_LIB.BASEBOARD_FAB2(SCH_1):P3V3_STBY    I52 @BASEBOARD_FAB2_LIB.BASEBOARD_FAB2(SCH_1):PAGE170
     2 IRQ_SML1_PMBUS_ALERT_N @BASEBOARD_FAB2_LIB.BASEBOARD_FAB2(SCH_1):IRQ_SML1_PMBUS_ALERT_N    I52 @BASEBOARD_FAB2_LIB.BASEBOARD_FAB2(SCH_1):PAGE170

R2P11 RES_0402-1.00K,1%,1/16W,EMPTY,A
     1 FM_PMBUS_ALERT_BUF_EN_N @BASEBOARD_FAB2_LIB.BASEBOARD_FAB2(SCH_1):FM_PMBUS_ALERT_BUF_EN_N    I63 @BASEBOARD_FAB2_LIB.BASEBOARD_FAB2(SCH_1):PAGE170
     2    GND @BASEBOARD_FAB2_LIB.BASEBOARD_FAB2(SCH_1):GND    I63 @BASEBOARD_FAB2_LIB.BASEBOARD_FAB2(SCH_1):PAGE170

R2P12 RES_0402-0.0,5%,1/16W,EMPTY,G2A
     1 IRQ_DIMM_SAVE_LVT3_N @BASEBOARD_FAB2_LIB.BASEBOARD_FAB2(SCH_1):IRQ_DIMM_SAVE_LVT3_N    I23 @BASEBOARD_FAB2_LIB.BASEBOARD_FAB2(SCH_1):PAGE89
     2 FM_ADR_SMI_GPIO_N @BASEBOARD_FAB2_LIB.BASEBOARD_FAB2(SCH_1):FM_ADR_SMI_GPIO_N    I23 @BASEBOARD_FAB2_LIB.BASEBOARD_FAB2(SCH_1):PAGE89

R2P13 RES_0402-4.75K,1%,1/16W,CHIP,GA
     1 P3V3_STBY @BASEBOARD_FAB2_LIB.BASEBOARD_FAB2(SCH_1):P3V3_STBY    I61 @BASEBOARD_FAB2_LIB.BASEBOARD_FAB2(SCH_1):PAGE170
     2 FM_PMBUS_ALERT_BUF_EN_N @BASEBOARD_FAB2_LIB.BASEBOARD_FAB2(SCH_1):FM_PMBUS_ALERT_BUF_EN_N    I61 @BASEBOARD_FAB2_LIB.BASEBOARD_FAB2(SCH_1):PAGE170

R2P14 RES_0402-0.0,5%,1/16W,CHIP,G21A
     1 FM_M2_DET_LVC3 @BASEBOARD_FAB2_LIB.BASEBOARD_FAB2(SCH_1):FM_M2_DET_LVC3   I115 @BASEBOARD_FAB2_LIB.BASEBOARD_FAB2(SCH_1):PAGE185
     2 FM_SSATA_PCIE_M2_SEL @BASEBOARD_FAB2_LIB.BASEBOARD_FAB2(SCH_1):FM_SSATA_PCIE_M2_SEL   I115 @BASEBOARD_FAB2_LIB.BASEBOARD_FAB2(SCH_1):PAGE185

R2P15 RES_0402-10.0K,1%,1/16W,CHIP,GA
     1   P3V3 @BASEBOARD_FAB2_LIB.BASEBOARD_FAB2(SCH_1):P3V3   I111 @BASEBOARD_FAB2_LIB.BASEBOARD_FAB2(SCH_1):PAGE185
     2 FM_M2_SSD_PEDET @BASEBOARD_FAB2_LIB.BASEBOARD_FAB2(SCH_1):FM_M2_SSD_PEDET   I111 @BASEBOARD_FAB2_LIB.BASEBOARD_FAB2(SCH_1):PAGE185

R2P16 RES_0402-10.0K,1%,1/16W,CHIP,GA
     1 P3V3_STBY @BASEBOARD_FAB2_LIB.BASEBOARD_FAB2(SCH_1):P3V3_STBY   I113 @BASEBOARD_FAB2_LIB.BASEBOARD_FAB2(SCH_1):PAGE185
     2 FM_M2_DET_LVC3 @BASEBOARD_FAB2_LIB.BASEBOARD_FAB2(SCH_1):FM_M2_DET_LVC3   I113 @BASEBOARD_FAB2_LIB.BASEBOARD_FAB2(SCH_1):PAGE185

R2P17 RES_0402-4.75K,1%,1/16W,CHIP,GA
     1 P3V3_STBY @BASEBOARD_FAB2_LIB.BASEBOARD_FAB2(SCH_1):P3V3_STBY     I3 @BASEBOARD_FAB2_LIB.BASEBOARD_FAB2(SCH_1):PAGE134
     2 FM_PCH_BMC_THERMTRIP_N @BASEBOARD_FAB2_LIB.BASEBOARD_FAB2(SCH_1):FM_PCH_BMC_THERMTRIP_N     I3 @BASEBOARD_FAB2_LIB.BASEBOARD_FAB2(SCH_1):PAGE134

R2P18 RES_0402-10.0K,1%,1/16W,CHIP,GA
     1 P3V3_STBY @BASEBOARD_FAB2_LIB.BASEBOARD_FAB2(SCH_1):P3V3_STBY   I121 @BASEBOARD_FAB2_LIB.BASEBOARD_FAB2(SCH_1):PAGE196
     2 PWRGD_P5V_N @BASEBOARD_FAB2_LIB.BASEBOARD_FAB2(SCH_1):PWRGD_P5V_N   I121 @BASEBOARD_FAB2_LIB.BASEBOARD_FAB2(SCH_1):PAGE196

R2P19 RES_0402-10.0K,1%,1/16W,CHIP,GA
     1 P3V3_STBY @BASEBOARD_FAB2_LIB.BASEBOARD_FAB2(SCH_1):P3V3_STBY   I107 @BASEBOARD_FAB2_LIB.BASEBOARD_FAB2(SCH_1):PAGE135
     2 FM_DIS_ADR_DLY @BASEBOARD_FAB2_LIB.BASEBOARD_FAB2(SCH_1):FM_DIS_ADR_DLY   I107 @BASEBOARD_FAB2_LIB.BASEBOARD_FAB2(SCH_1):PAGE135

R2P20 RES_0402-100.0,1%,1/16W,CHIP,GA
     1 PWRGD_P5V_R @BASEBOARD_FAB2_LIB.BASEBOARD_FAB2(SCH_1):PWRGD_P5V_R    I65 @BASEBOARD_FAB2_LIB.BASEBOARD_FAB2(SCH_1):PAGE196
     2 PWRGD_P5V @BASEBOARD_FAB2_LIB.BASEBOARD_FAB2(SCH_1):PWRGD_P5V    I65 @BASEBOARD_FAB2_LIB.BASEBOARD_FAB2(SCH_1):PAGE196

R2P21 RES_0402-10.0K,1%,1/16W,CHIP,GA
     1 P3V3_STBY @BASEBOARD_FAB2_LIB.BASEBOARD_FAB2(SCH_1):P3V3_STBY   I122 @BASEBOARD_FAB2_LIB.BASEBOARD_FAB2(SCH_1):PAGE196
     2 PWRGD_P5V_R @BASEBOARD_FAB2_LIB.BASEBOARD_FAB2(SCH_1):PWRGD_P5V_R   I122 @BASEBOARD_FAB2_LIB.BASEBOARD_FAB2(SCH_1):PAGE196

R2P22 RES_0402-10.0K,1%,1/16W,CHIP,GA
     1 P3V3_STBY @BASEBOARD_FAB2_LIB.BASEBOARD_FAB2(SCH_1):P3V3_STBY   I360 @BASEBOARD_FAB2_LIB.BASEBOARD_FAB2(SCH_1):PAGE133
     2 FM_CPU1_RC_EN @BASEBOARD_FAB2_LIB.BASEBOARD_FAB2(SCH_1):FM_CPU1_RC_EN   I360 @BASEBOARD_FAB2_LIB.BASEBOARD_FAB2(SCH_1):PAGE133

R2R1 RES_0402-10.0K,1%,1/16W,CHIP,GA
     1 P3V3_STBY @BASEBOARD_FAB2_LIB.BASEBOARD_FAB2(SCH_1):P3V3_STBY    I34 @BASEBOARD_FAB2_LIB.BASEBOARD_FAB2(SCH_1):PAGE192
     2 PU_RST_PERST_BIT0 @BASEBOARD_FAB2_LIB.BASEBOARD_FAB2(SCH_1):PU_RST_PERST_BIT0    I34 @BASEBOARD_FAB2_LIB.BASEBOARD_FAB2(SCH_1):PAGE192

R2R2 RES_0402-33.2,1%,1/16W,CHIP,G2A
     1 RST_RSMRST_R_N @BASEBOARD_FAB2_LIB.BASEBOARD_FAB2(SCH_1):RST_RSMRST_R_N   I338 @BASEBOARD_FAB2_LIB.BASEBOARD_FAB2(SCH_1):PAGE190
     2 RST_RSMRST_N @BASEBOARD_FAB2_LIB.BASEBOARD_FAB2(SCH_1):RST_RSMRST_N   I338 @BASEBOARD_FAB2_LIB.BASEBOARD_FAB2(SCH_1):PAGE190

R2R3 RES_0402-10.0K,1%,1/16W,CHIP,GA
     1 P3V3_STBY @BASEBOARD_FAB2_LIB.BASEBOARD_FAB2(SCH_1):P3V3_STBY    I41 @BASEBOARD_FAB2_LIB.BASEBOARD_FAB2(SCH_1):PAGE192
     2 FM_PLD_DEBUG_MODE_N @BASEBOARD_FAB2_LIB.BASEBOARD_FAB2(SCH_1):FM_PLD_DEBUG_MODE_N    I41 @BASEBOARD_FAB2_LIB.BASEBOARD_FAB2(SCH_1):PAGE192

R2R4 RES_0402-0.0,5%,1/16W,CHIP,G21A
     1 FM_ADR_SMI_GPIO_R_N @BASEBOARD_FAB2_LIB.BASEBOARD_FAB2(SCH_1):FM_ADR_SMI_GPIO_R_N   I184 @BASEBOARD_FAB2_LIB.BASEBOARD_FAB2(SCH_1):PAGE191
     2 FM_ADR_SMI_GPIO_N @BASEBOARD_FAB2_LIB.BASEBOARD_FAB2(SCH_1):FM_ADR_SMI_GPIO_N   I184 @BASEBOARD_FAB2_LIB.BASEBOARD_FAB2(SCH_1):PAGE191

R2R5 RES_0402-1.00K,1%,1/16W,CHIP,GA
     1 P3V3_STBY @BASEBOARD_FAB2_LIB.BASEBOARD_FAB2(SCH_1):P3V3_STBY   I258 @BASEBOARD_FAB2_LIB.BASEBOARD_FAB2(SCH_1):PAGE133
     2 FM_PCH_PLD_DATA @BASEBOARD_FAB2_LIB.BASEBOARD_FAB2(SCH_1):FM_PCH_PLD_DATA   I258 @BASEBOARD_FAB2_LIB.BASEBOARD_FAB2(SCH_1):PAGE133

R2R6 RES_0402-51,5.0%,1/16W,CHIP,G2A
     1 SGPIO_BMC_DIN_R @BASEBOARD_FAB2_LIB.BASEBOARD_FAB2(SCH_1):SGPIO_BMC_DIN_R   I166 @BASEBOARD_FAB2_LIB.BASEBOARD_FAB2(SCH_1):PAGE191
     2 SGPIO_BMC_DIN @BASEBOARD_FAB2_LIB.BASEBOARD_FAB2(SCH_1):SGPIO_BMC_DIN   I166 @BASEBOARD_FAB2_LIB.BASEBOARD_FAB2(SCH_1):PAGE191

R2R7 RES_0402-4.75K,1%,1/16W,CHIP,GA
     1 P3V3_STBY @BASEBOARD_FAB2_LIB.BASEBOARD_FAB2(SCH_1):P3V3_STBY   I172 @BASEBOARD_FAB2_LIB.BASEBOARD_FAB2(SCH_1):PAGE191
     2 FM_FORCE_ADR_N @BASEBOARD_FAB2_LIB.BASEBOARD_FAB2(SCH_1):FM_FORCE_ADR_N   I172 @BASEBOARD_FAB2_LIB.BASEBOARD_FAB2(SCH_1):PAGE191

R2R8 RES_0402-100.0,1%,1/16W,CHIP,GA
     1 FM_MEZZ_PRSNTB1_N @BASEBOARD_FAB2_LIB.BASEBOARD_FAB2(SCH_1):FM_MEZZ_PRSNTB1_N    I18 @BASEBOARD_FAB2_LIB.BASEBOARD_FAB2(SCH_1):PAGE187
     2    GND @BASEBOARD_FAB2_LIB.BASEBOARD_FAB2(SCH_1):GND    I18 @BASEBOARD_FAB2_LIB.BASEBOARD_FAB2(SCH_1):PAGE187

R2R9 RES_0402-200.0,1%,1/16W,CHIP,GA
     1 FP_NMI_BTN_OUT_R_N @BASEBOARD_FAB2_LIB.BASEBOARD_FAB2(SCH_1):FP_NMI_BTN_OUT_R_N   I352 @BASEBOARD_FAB2_LIB.BASEBOARD_FAB2(SCH_1):PAGE157
     2 FP_NMI_BTN_OUT_N @BASEBOARD_FAB2_LIB.BASEBOARD_FAB2(SCH_1):FP_NMI_BTN_OUT_N   I352 @BASEBOARD_FAB2_LIB.BASEBOARD_FAB2(SCH_1):PAGE157

R2R10 RES_0402-33.2,1%,1/16W,CHIP,G2A
     1 FP_NMI_BTN_R_N @BASEBOARD_FAB2_LIB.BASEBOARD_FAB2(SCH_1):FP_NMI_BTN_R_N   I358 @BASEBOARD_FAB2_LIB.BASEBOARD_FAB2(SCH_1):PAGE157
     2 FP_NMI_BTN_N @BASEBOARD_FAB2_LIB.BASEBOARD_FAB2(SCH_1):FP_NMI_BTN_N   I358 @BASEBOARD_FAB2_LIB.BASEBOARD_FAB2(SCH_1):PAGE157

R2R11 RES_0402-1.00K,1%,1/16W,EMPTY,A
     1 SPI_PCH_IO2 @BASEBOARD_FAB2_LIB.BASEBOARD_FAB2(SCH_1):SPI_PCH_IO2    I11 @BASEBOARD_FAB2_LIB.BASEBOARD_FAB2(SCH_1):PAGE125
     2    GND @BASEBOARD_FAB2_LIB.BASEBOARD_FAB2(SCH_1):GND    I11 @BASEBOARD_FAB2_LIB.BASEBOARD_FAB2(SCH_1):PAGE125

R2R12 RES_0402-0.0,5%,1/16W,CHIP,G21A
     1 SPI_PCH_IO2 @BASEBOARD_FAB2_LIB.BASEBOARD_FAB2(SCH_1):SPI_PCH_IO2    I93 @BASEBOARD_FAB2_LIB.BASEBOARD_FAB2(SCH_1):PAGE154
     2 SPI_PCH_IO2_R1 @BASEBOARD_FAB2_LIB.BASEBOARD_FAB2(SCH_1):SPI_PCH_IO2_R1    I93 @BASEBOARD_FAB2_LIB.BASEBOARD_FAB2(SCH_1):PAGE154

R2T1 RES_0402-1.00K,1%,1/16W,CHIP,GA
     1 SPI_PCH_IO3 @BASEBOARD_FAB2_LIB.BASEBOARD_FAB2(SCH_1):SPI_PCH_IO3    I15 @BASEBOARD_FAB2_LIB.BASEBOARD_FAB2(SCH_1):PAGE125
     2    GND @BASEBOARD_FAB2_LIB.BASEBOARD_FAB2(SCH_1):GND    I15 @BASEBOARD_FAB2_LIB.BASEBOARD_FAB2(SCH_1):PAGE125

R2T2 RES_0402-0.0,5%,1/16W,CHIP,G21A
     1 SPI_PCH_IO3 @BASEBOARD_FAB2_LIB.BASEBOARD_FAB2(SCH_1):SPI_PCH_IO3    I92 @BASEBOARD_FAB2_LIB.BASEBOARD_FAB2(SCH_1):PAGE154
     2 SPI_PCH_IO3_R1 @BASEBOARD_FAB2_LIB.BASEBOARD_FAB2(SCH_1):SPI_PCH_IO3_R1    I92 @BASEBOARD_FAB2_LIB.BASEBOARD_FAB2(SCH_1):PAGE154

R2T3 RES_0402-4.75K,1%,1/16W,CHIP,GA
     1 P3V3_STBY @BASEBOARD_FAB2_LIB.BASEBOARD_FAB2(SCH_1):P3V3_STBY    I54 @BASEBOARD_FAB2_LIB.BASEBOARD_FAB2(SCH_1):PAGE170
     2 FM_FAST_PROCHOT_EN_N @BASEBOARD_FAB2_LIB.BASEBOARD_FAB2(SCH_1):FM_FAST_PROCHOT_EN_N    I54 @BASEBOARD_FAB2_LIB.BASEBOARD_FAB2(SCH_1):PAGE170

R2T4 RES_0402-1.0K,0.1%,1/16W,CHIP,A
     1 P3V3_STBY @BASEBOARD_FAB2_LIB.BASEBOARD_FAB2(SCH_1):P3V3_STBY   I152 @BASEBOARD_FAB2_LIB.BASEBOARD_FAB2(SCH_1):PAGE240
     2    GND @BASEBOARD_FAB2_LIB.BASEBOARD_FAB2(SCH_1):GND   I152 @BASEBOARD_FAB2_LIB.BASEBOARD_FAB2(SCH_1):PAGE240

R2T5 RES_0402-1.00K,1%,1/16W,CHIP,GA
     1 P3V3_STBY @BASEBOARD_FAB2_LIB.BASEBOARD_FAB2(SCH_1):P3V3_STBY   I326 @BASEBOARD_FAB2_LIB.BASEBOARD_FAB2(SCH_1):PAGE157
     2 H_CPU0_FAST_WAKE @BASEBOARD_FAB2_LIB.BASEBOARD_FAB2(SCH_1):H_CPU0_FAST_WAKE   I326 @BASEBOARD_FAB2_LIB.BASEBOARD_FAB2(SCH_1):PAGE157

R2T6 RES_0402-4.75K,1%,1/16W,CHIP,GA
     1 P3V3_STBY @BASEBOARD_FAB2_LIB.BASEBOARD_FAB2(SCH_1):P3V3_STBY   I127 @BASEBOARD_FAB2_LIB.BASEBOARD_FAB2(SCH_1):PAGE154
     2 FM_BACKUP_BIOS_SEL_N @BASEBOARD_FAB2_LIB.BASEBOARD_FAB2(SCH_1):FM_BACKUP_BIOS_SEL_N   I127 @BASEBOARD_FAB2_LIB.BASEBOARD_FAB2(SCH_1):PAGE154

R2T7 RES_0402-1.00K,1%,1/16W,CHIP,GA
     1 P3V3_STBY @BASEBOARD_FAB2_LIB.BASEBOARD_FAB2(SCH_1):P3V3_STBY   I327 @BASEBOARD_FAB2_LIB.BASEBOARD_FAB2(SCH_1):PAGE157
     2 H_CPU0_FAST_WAKE_LVT3_N @BASEBOARD_FAB2_LIB.BASEBOARD_FAB2(SCH_1):H_CPU0_FAST_WAKE_LVT3_N   I327 @BASEBOARD_FAB2_LIB.BASEBOARD_FAB2(SCH_1):PAGE157

R2T8 RES_0402-10.0K,1%,1/16W,CHIP,GA
     1 P3V3_STBY @BASEBOARD_FAB2_LIB.BASEBOARD_FAB2(SCH_1):P3V3_STBY   I106 @BASEBOARD_FAB2_LIB.BASEBOARD_FAB2(SCH_1):PAGE154
     2 SPI_SWITCH_CS0_N @BASEBOARD_FAB2_LIB.BASEBOARD_FAB2(SCH_1):SPI_SWITCH_CS0_N   I106 @BASEBOARD_FAB2_LIB.BASEBOARD_FAB2(SCH_1):PAGE154

R2T9 RES_0402-75,1.0%,1/16W,CHIP,G2A
     1 SPI_CS0_SECONDARY_N @BASEBOARD_FAB2_LIB.BASEBOARD_FAB2(SCH_1):SPI_CS0_SECONDARY_N    I62 @BASEBOARD_FAB2_LIB.BASEBOARD_FAB2(SCH_1):PAGE154
     2 SPI_CS0_SECONDARY_R_N @BASEBOARD_FAB2_LIB.BASEBOARD_FAB2(SCH_1):SPI_CS0_SECONDARY_R_N    I62 @BASEBOARD_FAB2_LIB.BASEBOARD_FAB2(SCH_1):PAGE154

R2T11 RES_0402-4.75K,1%,1/16W,CHIP,GA
     1 P3V3_STBY @BASEBOARD_FAB2_LIB.BASEBOARD_FAB2(SCH_1):P3V3_STBY   I105 @BASEBOARD_FAB2_LIB.BASEBOARD_FAB2(SCH_1):PAGE154
     2 FM_DUAL_BIOS_SEL_N @BASEBOARD_FAB2_LIB.BASEBOARD_FAB2(SCH_1):FM_DUAL_BIOS_SEL_N   I105 @BASEBOARD_FAB2_LIB.BASEBOARD_FAB2(SCH_1):PAGE154

R2T13 RES_0402-200.0,1%,1/16W,CHIP,GA
     1 SPI_CS0_PRIMARY_N @BASEBOARD_FAB2_LIB.BASEBOARD_FAB2(SCH_1):SPI_CS0_PRIMARY_N   I101 @BASEBOARD_FAB2_LIB.BASEBOARD_FAB2(SCH_1):PAGE154
     2 SPI_CS0_PRIMARY_R_N @BASEBOARD_FAB2_LIB.BASEBOARD_FAB2(SCH_1):SPI_CS0_PRIMARY_R_N   I101 @BASEBOARD_FAB2_LIB.BASEBOARD_FAB2(SCH_1):PAGE154

R2T16 RES_0402-75,1.0%,1/16W,CHIP,G2A
     1 H_CPU_ERR0_GTL_R_N @BASEBOARD_FAB2_LIB.BASEBOARD_FAB2(SCH_1):H_CPU_ERR0_GTL_R_N    I67 @BASEBOARD_FAB2_LIB.BASEBOARD_FAB2(SCH_1):PAGE93
     2 H_CPU_ERR0_GTL_N @BASEBOARD_FAB2_LIB.BASEBOARD_FAB2(SCH_1):H_CPU_ERR0_GTL_N    I67 @BASEBOARD_FAB2_LIB.BASEBOARD_FAB2(SCH_1):PAGE93

R2T17 RES_0402-0.0,5%,1/16W,CHIP,G21A
     1 H_CPU0_ERR0_G_N @BASEBOARD_FAB2_LIB.BASEBOARD_FAB2(SCH_1):H_CPU0_ERR0_G_N    I23 @BASEBOARD_FAB2_LIB.BASEBOARD_FAB2(SCH_1):PAGE93
     2 H_CPU_ERR0_GTL_R_N @BASEBOARD_FAB2_LIB.BASEBOARD_FAB2(SCH_1):H_CPU_ERR0_GTL_R_N    I23 @BASEBOARD_FAB2_LIB.BASEBOARD_FAB2(SCH_1):PAGE93

R2T18 RES_0402-49.9,1%,1/16W,CHIP,G2A
     1 RST_BMC_SYSRST_BTN_OUT_B_R_N @BASEBOARD_FAB2_LIB.BASEBOARD_FAB2(SCH_1):RST_BMC_SYSRST_BTN_OUT_B_R_N   I288 @BASEBOARD_FAB2_LIB.BASEBOARD_FAB2(SCH_1):PAGE156
     2 RST_BMC_SYSRST_BTN_OUT_B_N @BASEBOARD_FAB2_LIB.BASEBOARD_FAB2(SCH_1):RST_BMC_SYSRST_BTN_OUT_B_N   I288 @BASEBOARD_FAB2_LIB.BASEBOARD_FAB2(SCH_1):PAGE156

R2T19 RES_0402-200.0,1%,1/16W,CHIP,GA
     1 PVCCIO_CPU0 @BASEBOARD_FAB2_LIB.BASEBOARD_FAB2(SCH_1):PVCCIO_CPU0    I63 @BASEBOARD_FAB2_LIB.BASEBOARD_FAB2(SCH_1):PAGE93
     2 H_CPU_ERR0_GTL_R_N @BASEBOARD_FAB2_LIB.BASEBOARD_FAB2(SCH_1):H_CPU_ERR0_GTL_R_N    I63 @BASEBOARD_FAB2_LIB.BASEBOARD_FAB2(SCH_1):PAGE93

R2T20 RES_0402-0.0,5%,1/16W,CHIP,G21A
     1 H_CPU1_ERR0_G_N @BASEBOARD_FAB2_LIB.BASEBOARD_FAB2(SCH_1):H_CPU1_ERR0_G_N    I16 @BASEBOARD_FAB2_LIB.BASEBOARD_FAB2(SCH_1):PAGE93
     2 H_CPU_ERR0_GTL_R_N @BASEBOARD_FAB2_LIB.BASEBOARD_FAB2(SCH_1):H_CPU_ERR0_GTL_R_N    I16 @BASEBOARD_FAB2_LIB.BASEBOARD_FAB2(SCH_1):PAGE93

R2T21 RES_0603-2.2,1.0%,1/10W,CHIP,GA
     1 P3V3_STBY_MNG @BASEBOARD_FAB2_LIB.BASEBOARD_FAB2(SCH_1):P3V3_STBY_MNG   I105 @BASEBOARD_FAB2_LIB.BASEBOARD_FAB2(SCH_1):PAGE101
     2 P3V3_STBY_MNG_CPU @BASEBOARD_FAB2_LIB.BASEBOARD_FAB2(SCH_1):P3V3_STBY_MNG_CPU   I105 @BASEBOARD_FAB2_LIB.BASEBOARD_FAB2(SCH_1):PAGE101

R2T22 RES_0402-10.0K,1%,1/16W,CHIP,GA
     1 P3V3_STBY @BASEBOARD_FAB2_LIB.BASEBOARD_FAB2(SCH_1):P3V3_STBY   I210 @BASEBOARD_FAB2_LIB.BASEBOARD_FAB2(SCH_1):PAGE156
     2 RST_BMC_SYSRST_BTN_OUT_B_R_N @BASEBOARD_FAB2_LIB.BASEBOARD_FAB2(SCH_1):RST_BMC_SYSRST_BTN_OUT_B_R_N   I210 @BASEBOARD_FAB2_LIB.BASEBOARD_FAB2(SCH_1):PAGE156

R2T23 RES_0603-2.2,1.0%,1/10W,CHIP,GA
     1 P3V3_STBY_MNG @BASEBOARD_FAB2_LIB.BASEBOARD_FAB2(SCH_1):P3V3_STBY_MNG    I94 @BASEBOARD_FAB2_LIB.BASEBOARD_FAB2(SCH_1):PAGE101
     2 P3V3_STBY_MNG_RGMII @BASEBOARD_FAB2_LIB.BASEBOARD_FAB2(SCH_1):P3V3_STBY_MNG_RGMII    I94 @BASEBOARD_FAB2_LIB.BASEBOARD_FAB2(SCH_1):PAGE101

R2T25 RES_0402-1.00K,1%,1/16W,CHIP,GA
     1 PD_CKMNG_OE @BASEBOARD_FAB2_LIB.BASEBOARD_FAB2(SCH_1):PD_CKMNG_OE    I48 @BASEBOARD_FAB2_LIB.BASEBOARD_FAB2(SCH_1):PAGE101
     2    GND @BASEBOARD_FAB2_LIB.BASEBOARD_FAB2(SCH_1):GND    I48 @BASEBOARD_FAB2_LIB.BASEBOARD_FAB2(SCH_1):PAGE101

R2T26 RES_0402-200.0,1%,1/16W,CHIP,GA
     1 PVCCIO_CPU0 @BASEBOARD_FAB2_LIB.BASEBOARD_FAB2(SCH_1):PVCCIO_CPU0    I87 @BASEBOARD_FAB2_LIB.BASEBOARD_FAB2(SCH_1):PAGE93
     2 H_CPU_ERR1_GTL_R_N @BASEBOARD_FAB2_LIB.BASEBOARD_FAB2(SCH_1):H_CPU_ERR1_GTL_R_N    I87 @BASEBOARD_FAB2_LIB.BASEBOARD_FAB2(SCH_1):PAGE93

R2T27 RES_0402-0.0,5%,1/16W,CHIP,G21A
     1 H_CPU1_ERR1_G_N @BASEBOARD_FAB2_LIB.BASEBOARD_FAB2(SCH_1):H_CPU1_ERR1_G_N    I13 @BASEBOARD_FAB2_LIB.BASEBOARD_FAB2(SCH_1):PAGE93
     2 H_CPU_ERR1_GTL_R_N @BASEBOARD_FAB2_LIB.BASEBOARD_FAB2(SCH_1):H_CPU_ERR1_GTL_R_N    I13 @BASEBOARD_FAB2_LIB.BASEBOARD_FAB2(SCH_1):PAGE93

R2T28 RES_0402-33.2,1%,1/16W,CHIP,G2A
     1 FM_PCH_PWRBTN_R_N @BASEBOARD_FAB2_LIB.BASEBOARD_FAB2(SCH_1):FM_PCH_PWRBTN_R_N   I289 @BASEBOARD_FAB2_LIB.BASEBOARD_FAB2(SCH_1):PAGE156
     2 FM_PCH_PWRBTN_N @BASEBOARD_FAB2_LIB.BASEBOARD_FAB2(SCH_1):FM_PCH_PWRBTN_N   I289 @BASEBOARD_FAB2_LIB.BASEBOARD_FAB2(SCH_1):PAGE156

R2T29 RES_0402-2.21K,1%,1/16W,CHIP,GA
     1 P3V3_STBY @BASEBOARD_FAB2_LIB.BASEBOARD_FAB2(SCH_1):P3V3_STBY   I298 @BASEBOARD_FAB2_LIB.BASEBOARD_FAB2(SCH_1):PAGE157
     2 IRQ_OOB_MGMT_RISER_ALERT_N @BASEBOARD_FAB2_LIB.BASEBOARD_FAB2(SCH_1):IRQ_OOB_MGMT_RISER_ALERT_N   I298 @BASEBOARD_FAB2_LIB.BASEBOARD_FAB2(SCH_1):PAGE157

R2T30 RES_0402-33.2,1%,1/16W,CHIP,G2A
     1 FM_CPU_ERR0_LVT3_K_N @BASEBOARD_FAB2_LIB.BASEBOARD_FAB2(SCH_1):FM_CPU_ERR0_LVT3_K_N    I42 @BASEBOARD_FAB2_LIB.BASEBOARD_FAB2(SCH_1):PAGE93
     2 FM_CPU_ERR0_LVT3_N @BASEBOARD_FAB2_LIB.BASEBOARD_FAB2(SCH_1):FM_CPU_ERR0_LVT3_N    I42 @BASEBOARD_FAB2_LIB.BASEBOARD_FAB2(SCH_1):PAGE93

R2T31 RES_0402-75,1.0%,1/16W,CHIP,G2A
     1 H_CPU_ERR1_GTL_R_N @BASEBOARD_FAB2_LIB.BASEBOARD_FAB2(SCH_1):H_CPU_ERR1_GTL_R_N    I68 @BASEBOARD_FAB2_LIB.BASEBOARD_FAB2(SCH_1):PAGE93
     2 H_CPU_ERR1_GTL_N @BASEBOARD_FAB2_LIB.BASEBOARD_FAB2(SCH_1):H_CPU_ERR1_GTL_N    I68 @BASEBOARD_FAB2_LIB.BASEBOARD_FAB2(SCH_1):PAGE93

R2T32 RES_0402-0.0,5%,1/16W,CHIP,G21A
     1 H_CPU0_ERR1_G_N @BASEBOARD_FAB2_LIB.BASEBOARD_FAB2(SCH_1):H_CPU0_ERR1_G_N    I15 @BASEBOARD_FAB2_LIB.BASEBOARD_FAB2(SCH_1):PAGE93
     2 H_CPU_ERR1_GTL_R_N @BASEBOARD_FAB2_LIB.BASEBOARD_FAB2(SCH_1):H_CPU_ERR1_GTL_R_N    I15 @BASEBOARD_FAB2_LIB.BASEBOARD_FAB2(SCH_1):PAGE93

R2T33 RES_0402-33.2,1%,1/16W,CHIP,G2A
     1 FM_CPU_ERR1_LVT3_K_N @BASEBOARD_FAB2_LIB.BASEBOARD_FAB2(SCH_1):FM_CPU_ERR1_LVT3_K_N    I40 @BASEBOARD_FAB2_LIB.BASEBOARD_FAB2(SCH_1):PAGE93
     2 FM_CPU_ERR1_LVT3_N @BASEBOARD_FAB2_LIB.BASEBOARD_FAB2(SCH_1):FM_CPU_ERR1_LVT3_N    I40 @BASEBOARD_FAB2_LIB.BASEBOARD_FAB2(SCH_1):PAGE93

R2T34 RES_0402-4.75K,1%,1/16W,CHIP,GA
     1 P3V3_STBY @BASEBOARD_FAB2_LIB.BASEBOARD_FAB2(SCH_1):P3V3_STBY   I206 @BASEBOARD_FAB2_LIB.BASEBOARD_FAB2(SCH_1):PAGE156
     2 FM_BMC_PWRBTN_OUT_N @BASEBOARD_FAB2_LIB.BASEBOARD_FAB2(SCH_1):FM_BMC_PWRBTN_OUT_N   I206 @BASEBOARD_FAB2_LIB.BASEBOARD_FAB2(SCH_1):PAGE156

R2T35 RES_0402-4.75K,1%,1/16W,CHIP,GA
     1 P3V3_STBY @BASEBOARD_FAB2_LIB.BASEBOARD_FAB2(SCH_1):P3V3_STBY   I207 @BASEBOARD_FAB2_LIB.BASEBOARD_FAB2(SCH_1):PAGE156
     2 RST_BMC_SYSRST_BTN_OUT_N @BASEBOARD_FAB2_LIB.BASEBOARD_FAB2(SCH_1):RST_BMC_SYSRST_BTN_OUT_N   I207 @BASEBOARD_FAB2_LIB.BASEBOARD_FAB2(SCH_1):PAGE156

R2T36 RES_0402-49.9,1%,1/16W,CHIP,G2A
     1 PVCCIO_CPU0 @BASEBOARD_FAB2_LIB.BASEBOARD_FAB2(SCH_1):PVCCIO_CPU0    I97 @BASEBOARD_FAB2_LIB.BASEBOARD_FAB2(SCH_1):PAGE93
     2 P0V7_GTL2104_5_VREF @BASEBOARD_FAB2_LIB.BASEBOARD_FAB2(SCH_1):P0V7_GTL2104_5_VREF    I97 @BASEBOARD_FAB2_LIB.BASEBOARD_FAB2(SCH_1):PAGE93

R2T37 RES_0402-200.0,1%,1/16W,CHIP,GA
     1 PVCCIO_CPU0 @BASEBOARD_FAB2_LIB.BASEBOARD_FAB2(SCH_1):PVCCIO_CPU0    I94 @BASEBOARD_FAB2_LIB.BASEBOARD_FAB2(SCH_1):PAGE92
     2 H_CPU_ERR2_G_R_N @BASEBOARD_FAB2_LIB.BASEBOARD_FAB2(SCH_1):H_CPU_ERR2_G_R_N    I94 @BASEBOARD_FAB2_LIB.BASEBOARD_FAB2(SCH_1):PAGE92

R2T38 RES_0402-33.2,1%,1/16W,CHIP,G2A
     1 FM_CPU0_PROCHOT_LVT3_K_N @BASEBOARD_FAB2_LIB.BASEBOARD_FAB2(SCH_1):FM_CPU0_PROCHOT_LVT3_K_N    I39 @BASEBOARD_FAB2_LIB.BASEBOARD_FAB2(SCH_1):PAGE93
     2 FM_CPU0_PROCHOT_LVT3_N @BASEBOARD_FAB2_LIB.BASEBOARD_FAB2(SCH_1):FM_CPU0_PROCHOT_LVT3_N    I39 @BASEBOARD_FAB2_LIB.BASEBOARD_FAB2(SCH_1):PAGE93

R2T39 RES_0402-100.0,1%,1/16W,CHIP,GA
     1 P0V7_GTL2104_5_VREF @BASEBOARD_FAB2_LIB.BASEBOARD_FAB2(SCH_1):P0V7_GTL2104_5_VREF    I98 @BASEBOARD_FAB2_LIB.BASEBOARD_FAB2(SCH_1):PAGE93
     2    GND @BASEBOARD_FAB2_LIB.BASEBOARD_FAB2(SCH_1):GND    I98 @BASEBOARD_FAB2_LIB.BASEBOARD_FAB2(SCH_1):PAGE93

R2T40 RES_0402-0.0,5%,1/16W,CHIP,G21A
     1 H_CPU0_ERR2_G_N @BASEBOARD_FAB2_LIB.BASEBOARD_FAB2(SCH_1):H_CPU0_ERR2_G_N    I93 @BASEBOARD_FAB2_LIB.BASEBOARD_FAB2(SCH_1):PAGE92
     2 H_CPU_ERR2_G_R_N @BASEBOARD_FAB2_LIB.BASEBOARD_FAB2(SCH_1):H_CPU_ERR2_G_R_N    I93 @BASEBOARD_FAB2_LIB.BASEBOARD_FAB2(SCH_1):PAGE92

R2T41 RES_0402-22.1,1.0%,1/16W,CHIP,A
     1 IRQ_FORCE_NM_THROTTLE_N @BASEBOARD_FAB2_LIB.BASEBOARD_FAB2(SCH_1):IRQ_FORCE_NM_THROTTLE_N    I96 @BASEBOARD_FAB2_LIB.BASEBOARD_FAB2(SCH_1):PAGE146
     2 FM_BMC_SYS_THROTTLE_R_N @BASEBOARD_FAB2_LIB.BASEBOARD_FAB2(SCH_1):FM_BMC_SYS_THROTTLE_R_N    I96 @BASEBOARD_FAB2_LIB.BASEBOARD_FAB2(SCH_1):PAGE146

R2T42 RES_0402-22.1,1.0%,1/16W,CHIP,A
     1 CLK_50M_CKMNG_OCP_R @BASEBOARD_FAB2_LIB.BASEBOARD_FAB2(SCH_1):CLK_50M_CKMNG_OCP_R   I124 @BASEBOARD_FAB2_LIB.BASEBOARD_FAB2(SCH_1):PAGE101
     2 CLK_50M_CKMNG_OCP @BASEBOARD_FAB2_LIB.BASEBOARD_FAB2(SCH_1):CLK_50M_CKMNG_OCP   I124 @BASEBOARD_FAB2_LIB.BASEBOARD_FAB2(SCH_1):PAGE101

R2T43 RES_0402-75,1.0%,1/16W,CHIP,G2A
     1 H_CPU_ERR2_G_R_N @BASEBOARD_FAB2_LIB.BASEBOARD_FAB2(SCH_1):H_CPU_ERR2_G_R_N    I96 @BASEBOARD_FAB2_LIB.BASEBOARD_FAB2(SCH_1):PAGE92
     2 H_CPU_ERR2_GTL_N @BASEBOARD_FAB2_LIB.BASEBOARD_FAB2(SCH_1):H_CPU_ERR2_GTL_N    I96 @BASEBOARD_FAB2_LIB.BASEBOARD_FAB2(SCH_1):PAGE92

R2T44 RES_0402-0.0,5%,1/16W,CHIP,G21A
     1 H_CPU1_ERR2_G_N @BASEBOARD_FAB2_LIB.BASEBOARD_FAB2(SCH_1):H_CPU1_ERR2_G_N    I92 @BASEBOARD_FAB2_LIB.BASEBOARD_FAB2(SCH_1):PAGE92
     2 H_CPU_ERR2_G_R_N @BASEBOARD_FAB2_LIB.BASEBOARD_FAB2(SCH_1):H_CPU_ERR2_G_R_N    I92 @BASEBOARD_FAB2_LIB.BASEBOARD_FAB2(SCH_1):PAGE92

R2T46 RES_0402-22.1,1.0%,1/16W,CHIP,A
     1 CLK_50M_CKMNG_BMC_1_R @BASEBOARD_FAB2_LIB.BASEBOARD_FAB2(SCH_1):CLK_50M_CKMNG_BMC_1_R   I125 @BASEBOARD_FAB2_LIB.BASEBOARD_FAB2(SCH_1):PAGE101
     2 CLK_50M_CKMNG_BMC_1 @BASEBOARD_FAB2_LIB.BASEBOARD_FAB2(SCH_1):CLK_50M_CKMNG_BMC_1   I125 @BASEBOARD_FAB2_LIB.BASEBOARD_FAB2(SCH_1):PAGE101

R2T47 RES_0402-33.2,1%,1/16W,CHIP,G2A
     1 CLK_25M_CPLD_R @BASEBOARD_FAB2_LIB.BASEBOARD_FAB2(SCH_1):CLK_25M_CPLD_R   I130 @BASEBOARD_FAB2_LIB.BASEBOARD_FAB2(SCH_1):PAGE101
     2 CLK_25M_CPLD @BASEBOARD_FAB2_LIB.BASEBOARD_FAB2(SCH_1):CLK_25M_CPLD   I130 @BASEBOARD_FAB2_LIB.BASEBOARD_FAB2(SCH_1):PAGE101

R2T49 RES_0402-20.0,1%,1/16W,CHIP,G2A
     1 SMB_BMC_PMBUS_STBY_LVC3_SDA_R @BASEBOARD_FAB2_LIB.BASEBOARD_FAB2(SCH_1):SMB_BMC_PMBUS_STBY_LVC3_SDA_R   I219 @BASEBOARD_FAB2_LIB.BASEBOARD_FAB2(SCH_1):PAGE159
     2 SMB_BMC_PMBUS_STBY_LVC3_SDA @BASEBOARD_FAB2_LIB.BASEBOARD_FAB2(SCH_1):SMB_BMC_PMBUS_STBY_LVC3_SDA   I219 @BASEBOARD_FAB2_LIB.BASEBOARD_FAB2(SCH_1):PAGE159

R2T50 RES_0402-1.00K,1%,1/16W,CHIP,GA
     1 PD_GTL2104_4_DIR @BASEBOARD_FAB2_LIB.BASEBOARD_FAB2(SCH_1):PD_GTL2104_4_DIR   I127 @BASEBOARD_FAB2_LIB.BASEBOARD_FAB2(SCH_1):PAGE93
     2    GND @BASEBOARD_FAB2_LIB.BASEBOARD_FAB2(SCH_1):GND   I127 @BASEBOARD_FAB2_LIB.BASEBOARD_FAB2(SCH_1):PAGE93

R2T52 RES_0603-2.2,1.0%,1/10W,CHIP,GA
     1 P3V3_STBY_MNG @BASEBOARD_FAB2_LIB.BASEBOARD_FAB2(SCH_1):P3V3_STBY_MNG    I95 @BASEBOARD_FAB2_LIB.BASEBOARD_FAB2(SCH_1):PAGE101
     2 P3V3_STBY_MNG_RMII @BASEBOARD_FAB2_LIB.BASEBOARD_FAB2(SCH_1):P3V3_STBY_MNG_RMII    I95 @BASEBOARD_FAB2_LIB.BASEBOARD_FAB2(SCH_1):PAGE101

R2T53 RES_0402-665,1.0%,1/16W,CHIP,GA
     1 P3V3_STBY @BASEBOARD_FAB2_LIB.BASEBOARD_FAB2(SCH_1):P3V3_STBY    I83 @BASEBOARD_FAB2_LIB.BASEBOARD_FAB2(SCH_1):PAGE138
     2 SMB_BMC_PMBUS_STBY_LVC3_SDA @BASEBOARD_FAB2_LIB.BASEBOARD_FAB2(SCH_1):SMB_BMC_PMBUS_STBY_LVC3_SDA    I83 @BASEBOARD_FAB2_LIB.BASEBOARD_FAB2(SCH_1):PAGE138

R2T54 RES_0402-665,1.0%,1/16W,CHIP,GA
     1 P3V3_STBY @BASEBOARD_FAB2_LIB.BASEBOARD_FAB2(SCH_1):P3V3_STBY    I84 @BASEBOARD_FAB2_LIB.BASEBOARD_FAB2(SCH_1):PAGE138
     2 SMB_BMC_PMBUS_STBY_LVC3_SCL @BASEBOARD_FAB2_LIB.BASEBOARD_FAB2(SCH_1):SMB_BMC_PMBUS_STBY_LVC3_SCL    I84 @BASEBOARD_FAB2_LIB.BASEBOARD_FAB2(SCH_1):PAGE138

R2T55 RES_0402-20.0,1%,1/16W,CHIP,G2A
     1 SMB_PMBUS_BMC_STBY_LVC3_SDA_R1 @BASEBOARD_FAB2_LIB.BASEBOARD_FAB2(SCH_1):SMB_PMBUS_BMC_STBY_LVC3_SDA_R1   I116 @BASEBOARD_FAB2_LIB.BASEBOARD_FAB2(SCH_1):PAGE138
     2 SMB_BMC_PMBUS_STBY_LVC3_SDA @BASEBOARD_FAB2_LIB.BASEBOARD_FAB2(SCH_1):SMB_BMC_PMBUS_STBY_LVC3_SDA   I116 @BASEBOARD_FAB2_LIB.BASEBOARD_FAB2(SCH_1):PAGE138

R2T56 RES_0402-20.0,1%,1/16W,CHIP,G2A
     1 SMB_PMBUS_BMC_STBY_LVC3_SCL_R1 @BASEBOARD_FAB2_LIB.BASEBOARD_FAB2(SCH_1):SMB_PMBUS_BMC_STBY_LVC3_SCL_R1   I160 @BASEBOARD_FAB2_LIB.BASEBOARD_FAB2(SCH_1):PAGE138
     2 SMB_BMC_PMBUS_STBY_LVC3_SCL @BASEBOARD_FAB2_LIB.BASEBOARD_FAB2(SCH_1):SMB_BMC_PMBUS_STBY_LVC3_SCL   I160 @BASEBOARD_FAB2_LIB.BASEBOARD_FAB2(SCH_1):PAGE138

R2T57 RES_0402-0.0,5%,1/16W,EMPTY,G2A
     1 H_CPU_ERR0_PCH_N @BASEBOARD_FAB2_LIB.BASEBOARD_FAB2(SCH_1):H_CPU_ERR0_PCH_N    I88 @BASEBOARD_FAB2_LIB.BASEBOARD_FAB2(SCH_1):PAGE93
     2 H_CPU_ERR0_GTL_R_N @BASEBOARD_FAB2_LIB.BASEBOARD_FAB2(SCH_1):H_CPU_ERR0_GTL_R_N    I88 @BASEBOARD_FAB2_LIB.BASEBOARD_FAB2(SCH_1):PAGE93

R2T58 RES_0402-0.0,5%,1/16W,EMPTY,G2A
     1 H_CPU_ERR0_PCH_N @BASEBOARD_FAB2_LIB.BASEBOARD_FAB2(SCH_1):H_CPU_ERR0_PCH_N    I94 @BASEBOARD_FAB2_LIB.BASEBOARD_FAB2(SCH_1):PAGE93
     2 FM_CPU_ERR0_LVT3_K_N @BASEBOARD_FAB2_LIB.BASEBOARD_FAB2(SCH_1):FM_CPU_ERR0_LVT3_K_N    I94 @BASEBOARD_FAB2_LIB.BASEBOARD_FAB2(SCH_1):PAGE93

R2T59 RES_0402-0.0,5%,1/16W,EMPTY,G2A
     1 H_CPU0_PROCHOT_G_N @BASEBOARD_FAB2_LIB.BASEBOARD_FAB2(SCH_1):H_CPU0_PROCHOT_G_N   I107 @BASEBOARD_FAB2_LIB.BASEBOARD_FAB2(SCH_1):PAGE93
     2 H_CPU0_PROCHOT_G_PCH_N @BASEBOARD_FAB2_LIB.BASEBOARD_FAB2(SCH_1):H_CPU0_PROCHOT_G_PCH_N   I107 @BASEBOARD_FAB2_LIB.BASEBOARD_FAB2(SCH_1):PAGE93

R2T60 RES_0402-0.0,5%,1/16W,CHIP,G21A
     1 H_CPU0_PROCHOT_G_N @BASEBOARD_FAB2_LIB.BASEBOARD_FAB2(SCH_1):H_CPU0_PROCHOT_G_N   I103 @BASEBOARD_FAB2_LIB.BASEBOARD_FAB2(SCH_1):PAGE93
     2 H_CPU0_PROCHOT_G_R_N @BASEBOARD_FAB2_LIB.BASEBOARD_FAB2(SCH_1):H_CPU0_PROCHOT_G_R_N   I103 @BASEBOARD_FAB2_LIB.BASEBOARD_FAB2(SCH_1):PAGE93

R2T61 RES_0402-0.0,5%,1/16W,EMPTY,G2A
     1 H_CPU_ERR1_PCH_N @BASEBOARD_FAB2_LIB.BASEBOARD_FAB2(SCH_1):H_CPU_ERR1_PCH_N    I89 @BASEBOARD_FAB2_LIB.BASEBOARD_FAB2(SCH_1):PAGE93
     2 H_CPU_ERR1_GTL_R_N @BASEBOARD_FAB2_LIB.BASEBOARD_FAB2(SCH_1):H_CPU_ERR1_GTL_R_N    I89 @BASEBOARD_FAB2_LIB.BASEBOARD_FAB2(SCH_1):PAGE93

R2T62 RES_0402-0.0,5%,1/16W,EMPTY,G2A
     1 H_CPU_ERR1_PCH_N @BASEBOARD_FAB2_LIB.BASEBOARD_FAB2(SCH_1):H_CPU_ERR1_PCH_N    I93 @BASEBOARD_FAB2_LIB.BASEBOARD_FAB2(SCH_1):PAGE93
     2 FM_CPU_ERR1_LVT3_K_N @BASEBOARD_FAB2_LIB.BASEBOARD_FAB2(SCH_1):FM_CPU_ERR1_LVT3_K_N    I93 @BASEBOARD_FAB2_LIB.BASEBOARD_FAB2(SCH_1):PAGE93

R2T63 RES_0402-0.0,5%,1/16W,EMPTY,G2A
     1 FM_CPU_ERR1_LVT3_N @BASEBOARD_FAB2_LIB.BASEBOARD_FAB2(SCH_1):FM_CPU_ERR1_LVT3_N   I133 @BASEBOARD_FAB2_LIB.BASEBOARD_FAB2(SCH_1):PAGE93
     2 FM_CPU_ERR1_PCH_N @BASEBOARD_FAB2_LIB.BASEBOARD_FAB2(SCH_1):FM_CPU_ERR1_PCH_N   I133 @BASEBOARD_FAB2_LIB.BASEBOARD_FAB2(SCH_1):PAGE93

R2T64 RES_0402-0.0,5%,1/16W,CHIP,G21A
     1 FM_CPU_ERR1_LVT3_N @BASEBOARD_FAB2_LIB.BASEBOARD_FAB2(SCH_1):FM_CPU_ERR1_LVT3_N   I121 @BASEBOARD_FAB2_LIB.BASEBOARD_FAB2(SCH_1):PAGE93
     2 FM_CPU_ERR1_LVT3_BMC_N @BASEBOARD_FAB2_LIB.BASEBOARD_FAB2(SCH_1):FM_CPU_ERR1_LVT3_BMC_N   I121 @BASEBOARD_FAB2_LIB.BASEBOARD_FAB2(SCH_1):PAGE93

R2T65 RES_0402-0.0,5%,1/16W,CHIP,G21A
     1 FM_CPU_ERR0_LVT3_R_N @BASEBOARD_FAB2_LIB.BASEBOARD_FAB2(SCH_1):FM_CPU_ERR0_LVT3_R_N   I111 @BASEBOARD_FAB2_LIB.BASEBOARD_FAB2(SCH_1):PAGE93
     2 FM_CPU_ERR0_LVT3_K_N @BASEBOARD_FAB2_LIB.BASEBOARD_FAB2(SCH_1):FM_CPU_ERR0_LVT3_K_N   I111 @BASEBOARD_FAB2_LIB.BASEBOARD_FAB2(SCH_1):PAGE93

R2T66 RES_0402-0.0,5%,1/16W,CHIP,G21A
     1 FM_CPU_ERR1_LVT3_R_N @BASEBOARD_FAB2_LIB.BASEBOARD_FAB2(SCH_1):FM_CPU_ERR1_LVT3_R_N   I112 @BASEBOARD_FAB2_LIB.BASEBOARD_FAB2(SCH_1):PAGE93
     2 FM_CPU_ERR1_LVT3_K_N @BASEBOARD_FAB2_LIB.BASEBOARD_FAB2(SCH_1):FM_CPU_ERR1_LVT3_K_N   I112 @BASEBOARD_FAB2_LIB.BASEBOARD_FAB2(SCH_1):PAGE93

R2T67 RES_0402-0.0,5%,1/16W,CHIP,G21A
     1 FM_CPU0_PROCHOT_LVT3_R_N @BASEBOARD_FAB2_LIB.BASEBOARD_FAB2(SCH_1):FM_CPU0_PROCHOT_LVT3_R_N   I113 @BASEBOARD_FAB2_LIB.BASEBOARD_FAB2(SCH_1):PAGE93
     2 FM_CPU0_PROCHOT_LVT3_K_N @BASEBOARD_FAB2_LIB.BASEBOARD_FAB2(SCH_1):FM_CPU0_PROCHOT_LVT3_K_N   I113 @BASEBOARD_FAB2_LIB.BASEBOARD_FAB2(SCH_1):PAGE93

R2T68 RES_0402-0.0,5%,1/16W,CHIP,G21A
     1 H_CPU1_PROCHOT_G_N @BASEBOARD_FAB2_LIB.BASEBOARD_FAB2(SCH_1):H_CPU1_PROCHOT_G_N   I102 @BASEBOARD_FAB2_LIB.BASEBOARD_FAB2(SCH_1):PAGE93
     2 H_CPU1_PROCHOT_G_R_N @BASEBOARD_FAB2_LIB.BASEBOARD_FAB2(SCH_1):H_CPU1_PROCHOT_G_R_N   I102 @BASEBOARD_FAB2_LIB.BASEBOARD_FAB2(SCH_1):PAGE93

R2T69 RES_0402-0.0,5%,1/16W,EMPTY,G2A
     1 H_CPU1_PROCHOT_G_N @BASEBOARD_FAB2_LIB.BASEBOARD_FAB2(SCH_1):H_CPU1_PROCHOT_G_N   I108 @BASEBOARD_FAB2_LIB.BASEBOARD_FAB2(SCH_1):PAGE93
     2 H_CPU1_PROCHOT_G_PCH_N @BASEBOARD_FAB2_LIB.BASEBOARD_FAB2(SCH_1):H_CPU1_PROCHOT_G_PCH_N   I108 @BASEBOARD_FAB2_LIB.BASEBOARD_FAB2(SCH_1):PAGE93

R2T71 RES_0402-0.0,5%,1/16W,EMPTY,G2A
     1 FM_CPU0_PROCHOT_LVT3_K_N @BASEBOARD_FAB2_LIB.BASEBOARD_FAB2(SCH_1):FM_CPU0_PROCHOT_LVT3_K_N   I109 @BASEBOARD_FAB2_LIB.BASEBOARD_FAB2(SCH_1):PAGE93
     2 H_CPU0_PROCHOT_G_PCH_N @BASEBOARD_FAB2_LIB.BASEBOARD_FAB2(SCH_1):H_CPU0_PROCHOT_G_PCH_N   I109 @BASEBOARD_FAB2_LIB.BASEBOARD_FAB2(SCH_1):PAGE93

R2T72 RES_0402-150.0,1%,1/16W,CHIP,GA
     1 PVCCIO_CPU0 @BASEBOARD_FAB2_LIB.BASEBOARD_FAB2(SCH_1):PVCCIO_CPU0   I143 @BASEBOARD_FAB2_LIB.BASEBOARD_FAB2(SCH_1):PAGE93
     2 H_CPU0_PROCHOT_G_N @BASEBOARD_FAB2_LIB.BASEBOARD_FAB2(SCH_1):H_CPU0_PROCHOT_G_N   I143 @BASEBOARD_FAB2_LIB.BASEBOARD_FAB2(SCH_1):PAGE93

R2T73 RES_0402-150.0,1%,1/16W,CHIP,GA
     1 PVCCIO_CPU1 @BASEBOARD_FAB2_LIB.BASEBOARD_FAB2(SCH_1):PVCCIO_CPU1   I144 @BASEBOARD_FAB2_LIB.BASEBOARD_FAB2(SCH_1):PAGE93
     2 H_CPU1_PROCHOT_G_N @BASEBOARD_FAB2_LIB.BASEBOARD_FAB2(SCH_1):H_CPU1_PROCHOT_G_N   I144 @BASEBOARD_FAB2_LIB.BASEBOARD_FAB2(SCH_1):PAGE93

R2U1 RES_0402-20.0,1%,1/16W,CHIP,G2A
     1 SMB_BMC_PMBUS_STBY_LVC3_SCL_R @BASEBOARD_FAB2_LIB.BASEBOARD_FAB2(SCH_1):SMB_BMC_PMBUS_STBY_LVC3_SCL_R   I218 @BASEBOARD_FAB2_LIB.BASEBOARD_FAB2(SCH_1):PAGE159
     2 SMB_BMC_PMBUS_STBY_LVC3_SCL @BASEBOARD_FAB2_LIB.BASEBOARD_FAB2(SCH_1):SMB_BMC_PMBUS_STBY_LVC3_SCL   I218 @BASEBOARD_FAB2_LIB.BASEBOARD_FAB2(SCH_1):PAGE159

R2U2 RES_0402-4.75K,1%,1/16W,CHIP,GA
     1 P3V3_STBY @BASEBOARD_FAB2_LIB.BASEBOARD_FAB2(SCH_1):P3V3_STBY   I265 @BASEBOARD_FAB2_LIB.BASEBOARD_FAB2(SCH_1):PAGE156
     2 RST_PCH_SYSRST_BTN_OUT_N @BASEBOARD_FAB2_LIB.BASEBOARD_FAB2(SCH_1):RST_PCH_SYSRST_BTN_OUT_N   I265 @BASEBOARD_FAB2_LIB.BASEBOARD_FAB2(SCH_1):PAGE156

R2U3 RES_0402-665,1.0%,1/16W,CHIP,GA
     1 P3V3_STBY @BASEBOARD_FAB2_LIB.BASEBOARD_FAB2(SCH_1):P3V3_STBY    I98 @BASEBOARD_FAB2_LIB.BASEBOARD_FAB2(SCH_1):PAGE138
     2 SMB_LAN_STBY_LVC3_SCL @BASEBOARD_FAB2_LIB.BASEBOARD_FAB2(SCH_1):SMB_LAN_STBY_LVC3_SCL    I98 @BASEBOARD_FAB2_LIB.BASEBOARD_FAB2(SCH_1):PAGE138

R2U4 RES_0402-4.75K,1%,1/16W,CHIP,GA
     1 P3V3_STBY @BASEBOARD_FAB2_LIB.BASEBOARD_FAB2(SCH_1):P3V3_STBY   I367 @BASEBOARD_FAB2_LIB.BASEBOARD_FAB2(SCH_1):PAGE157
     2 FM_CPLD_BMC_PWRDN_N @BASEBOARD_FAB2_LIB.BASEBOARD_FAB2(SCH_1):FM_CPLD_BMC_PWRDN_N   I367 @BASEBOARD_FAB2_LIB.BASEBOARD_FAB2(SCH_1):PAGE157

R2U5 RES_0402-2.26K,1.0%,1/16W,CHIPA
     1 P3V3_STBY @BASEBOARD_FAB2_LIB.BASEBOARD_FAB2(SCH_1):P3V3_STBY   I214 @BASEBOARD_FAB2_LIB.BASEBOARD_FAB2(SCH_1):PAGE159
     2 SMB_OCP_FRU_STBY_LVC3_SCL_R @BASEBOARD_FAB2_LIB.BASEBOARD_FAB2(SCH_1):SMB_OCP_FRU_STBY_LVC3_SCL_R   I214 @BASEBOARD_FAB2_LIB.BASEBOARD_FAB2(SCH_1):PAGE159

R2U6 RES_0402-20.0,1%,1/16W,CHIP,G2A
     1 SMB_LAN_STBY_LVC3_SCL_R1 @BASEBOARD_FAB2_LIB.BASEBOARD_FAB2(SCH_1):SMB_LAN_STBY_LVC3_SCL_R1   I166 @BASEBOARD_FAB2_LIB.BASEBOARD_FAB2(SCH_1):PAGE138
     2 SMB_LAN_STBY_LVC3_SCL @BASEBOARD_FAB2_LIB.BASEBOARD_FAB2(SCH_1):SMB_LAN_STBY_LVC3_SCL   I166 @BASEBOARD_FAB2_LIB.BASEBOARD_FAB2(SCH_1):PAGE138

R2U7 RES_0402-20.0,1%,1/16W,CHIP,G2A
     1 SMB_OCP_FRU_STBY_LVC3_SCL_R @BASEBOARD_FAB2_LIB.BASEBOARD_FAB2(SCH_1):SMB_OCP_FRU_STBY_LVC3_SCL_R   I220 @BASEBOARD_FAB2_LIB.BASEBOARD_FAB2(SCH_1):PAGE159
     2 SMB_OCP_FRU_STBY_LVC3_SCL @BASEBOARD_FAB2_LIB.BASEBOARD_FAB2(SCH_1):SMB_OCP_FRU_STBY_LVC3_SCL   I220 @BASEBOARD_FAB2_LIB.BASEBOARD_FAB2(SCH_1):PAGE159

R2U8 RES_0402-20.0,1%,1/16W,EMPTY,GA
     1 SMB_LAN_STBY_LVC3_SCL @BASEBOARD_FAB2_LIB.BASEBOARD_FAB2(SCH_1):SMB_LAN_STBY_LVC3_SCL   I158 @BASEBOARD_FAB2_LIB.BASEBOARD_FAB2(SCH_1):PAGE138
     2 SMB_OCP_FRU_STBY_LVC3_SCL @BASEBOARD_FAB2_LIB.BASEBOARD_FAB2(SCH_1):SMB_OCP_FRU_STBY_LVC3_SCL   I158 @BASEBOARD_FAB2_LIB.BASEBOARD_FAB2(SCH_1):PAGE138

R2U9 RES_0402-20.0,1%,1/16W,CHIP,G2A
     1 SMB_LAN_STBY_LVC3_SDA_R1 @BASEBOARD_FAB2_LIB.BASEBOARD_FAB2(SCH_1):SMB_LAN_STBY_LVC3_SDA_R1   I165 @BASEBOARD_FAB2_LIB.BASEBOARD_FAB2(SCH_1):PAGE138
     2 SMB_LAN_STBY_LVC3_SDA @BASEBOARD_FAB2_LIB.BASEBOARD_FAB2(SCH_1):SMB_LAN_STBY_LVC3_SDA   I165 @BASEBOARD_FAB2_LIB.BASEBOARD_FAB2(SCH_1):PAGE138

R2U10 RES_0402-20.0,1%,1/16W,CHIP,G2A
     1 SMB_OCP_FRU_STBY_LVC3_SDA_R @BASEBOARD_FAB2_LIB.BASEBOARD_FAB2(SCH_1):SMB_OCP_FRU_STBY_LVC3_SDA_R   I221 @BASEBOARD_FAB2_LIB.BASEBOARD_FAB2(SCH_1):PAGE159
     2 SMB_OCP_FRU_STBY_LVC3_SDA @BASEBOARD_FAB2_LIB.BASEBOARD_FAB2(SCH_1):SMB_OCP_FRU_STBY_LVC3_SDA   I221 @BASEBOARD_FAB2_LIB.BASEBOARD_FAB2(SCH_1):PAGE159

R2U11 RES_0402-665,1.0%,1/16W,CHIP,GA
     1 P3V3_STBY @BASEBOARD_FAB2_LIB.BASEBOARD_FAB2(SCH_1):P3V3_STBY    I97 @BASEBOARD_FAB2_LIB.BASEBOARD_FAB2(SCH_1):PAGE138
     2 SMB_LAN_STBY_LVC3_SDA @BASEBOARD_FAB2_LIB.BASEBOARD_FAB2(SCH_1):SMB_LAN_STBY_LVC3_SDA    I97 @BASEBOARD_FAB2_LIB.BASEBOARD_FAB2(SCH_1):PAGE138

R2U12 RES_0402-20.0,1%,1/16W,EMPTY,GA
     1 SMB_LAN_STBY_LVC3_SDA @BASEBOARD_FAB2_LIB.BASEBOARD_FAB2(SCH_1):SMB_LAN_STBY_LVC3_SDA   I159 @BASEBOARD_FAB2_LIB.BASEBOARD_FAB2(SCH_1):PAGE138
     2 SMB_OCP_FRU_STBY_LVC3_SDA @BASEBOARD_FAB2_LIB.BASEBOARD_FAB2(SCH_1):SMB_OCP_FRU_STBY_LVC3_SDA   I159 @BASEBOARD_FAB2_LIB.BASEBOARD_FAB2(SCH_1):PAGE138

R2U13 RES_0402-2.26K,1.0%,1/16W,CHIPA
     1 P3V3_STBY @BASEBOARD_FAB2_LIB.BASEBOARD_FAB2(SCH_1):P3V3_STBY   I216 @BASEBOARD_FAB2_LIB.BASEBOARD_FAB2(SCH_1):PAGE159
     2 SMB_OCP_FRU_STBY_LVC3_SDA_R @BASEBOARD_FAB2_LIB.BASEBOARD_FAB2(SCH_1):SMB_OCP_FRU_STBY_LVC3_SDA_R   I216 @BASEBOARD_FAB2_LIB.BASEBOARD_FAB2(SCH_1):PAGE159

R2U14 RES_0402-0.0,5%,1/16W,EMPTY,G2A
     1 P3E_CPU0_PE1_SS_R_RXP<0> @BASEBOARD_FAB2_LIB.BASEBOARD_FAB2(SCH_1):P3E_CPU0_PE1_SS_R_RXP(0)   I466 @BASEBOARD_FAB2_LIB.BASEBOARD_FAB2(SCH_1):PAGE107
     2 P3E_CPU0_PE1_SS_RXP<0> @BASEBOARD_FAB2_LIB.BASEBOARD_FAB2(SCH_1):P3E_CPU0_PE1_SS_RXP(0)   I466 @BASEBOARD_FAB2_LIB.BASEBOARD_FAB2(SCH_1):PAGE107

R2U15 RES_0402-0.0,5%,1/16W,EMPTY,G2A
     1 P3E_CPU0_PE1_SS_R_RXN<0> @BASEBOARD_FAB2_LIB.BASEBOARD_FAB2(SCH_1):P3E_CPU0_PE1_SS_R_RXN(0)   I465 @BASEBOARD_FAB2_LIB.BASEBOARD_FAB2(SCH_1):PAGE107
     2 P3E_CPU0_PE1_SS_RXN<0> @BASEBOARD_FAB2_LIB.BASEBOARD_FAB2(SCH_1):P3E_CPU0_PE1_SS_RXN(0)   I465 @BASEBOARD_FAB2_LIB.BASEBOARD_FAB2(SCH_1):PAGE107

R2U16 RES_0402-0.0,5%,1/16W,EMPTY,G2A
     1 P3E_CPU0_PE1_SS_R_RXP<1> @BASEBOARD_FAB2_LIB.BASEBOARD_FAB2(SCH_1):P3E_CPU0_PE1_SS_R_RXP(1)   I467 @BASEBOARD_FAB2_LIB.BASEBOARD_FAB2(SCH_1):PAGE107
     2 P3E_CPU0_PE1_SS_RXP<1> @BASEBOARD_FAB2_LIB.BASEBOARD_FAB2(SCH_1):P3E_CPU0_PE1_SS_RXP(1)   I467 @BASEBOARD_FAB2_LIB.BASEBOARD_FAB2(SCH_1):PAGE107

R2U17 RES_0402-0.0,5%,1/16W,EMPTY,G2A
     1 P3E_CPU0_PE1_SS_R_RXN<1> @BASEBOARD_FAB2_LIB.BASEBOARD_FAB2(SCH_1):P3E_CPU0_PE1_SS_R_RXN(1)   I464 @BASEBOARD_FAB2_LIB.BASEBOARD_FAB2(SCH_1):PAGE107
     2 P3E_CPU0_PE1_SS_RXN<1> @BASEBOARD_FAB2_LIB.BASEBOARD_FAB2(SCH_1):P3E_CPU0_PE1_SS_RXN(1)   I464 @BASEBOARD_FAB2_LIB.BASEBOARD_FAB2(SCH_1):PAGE107

R2U18 RES_0402-0.0,5%,1/16W,EMPTY,G2A
     1 P3E_CPU0_PE1_SS_R_RXP<2> @BASEBOARD_FAB2_LIB.BASEBOARD_FAB2(SCH_1):P3E_CPU0_PE1_SS_R_RXP(2)   I468 @BASEBOARD_FAB2_LIB.BASEBOARD_FAB2(SCH_1):PAGE107
     2 P3E_CPU0_PE1_SS_RXP<2> @BASEBOARD_FAB2_LIB.BASEBOARD_FAB2(SCH_1):P3E_CPU0_PE1_SS_RXP(2)   I468 @BASEBOARD_FAB2_LIB.BASEBOARD_FAB2(SCH_1):PAGE107

R2U19 RES_0402-0.0,5%,1/16W,EMPTY,G2A
     1 P3E_CPU0_PE1_SS_R_RXN<2> @BASEBOARD_FAB2_LIB.BASEBOARD_FAB2(SCH_1):P3E_CPU0_PE1_SS_R_RXN(2)   I463 @BASEBOARD_FAB2_LIB.BASEBOARD_FAB2(SCH_1):PAGE107
     2 P3E_CPU0_PE1_SS_RXN<2> @BASEBOARD_FAB2_LIB.BASEBOARD_FAB2(SCH_1):P3E_CPU0_PE1_SS_RXN(2)   I463 @BASEBOARD_FAB2_LIB.BASEBOARD_FAB2(SCH_1):PAGE107

R2U20 RES_0402-0.0,5%,1/16W,EMPTY,G2A
     1 P3E_CPU0_PE1_SS_R_RXP<3> @BASEBOARD_FAB2_LIB.BASEBOARD_FAB2(SCH_1):P3E_CPU0_PE1_SS_R_RXP(3)   I469 @BASEBOARD_FAB2_LIB.BASEBOARD_FAB2(SCH_1):PAGE107
     2 P3E_CPU0_PE1_SS_RXP<3> @BASEBOARD_FAB2_LIB.BASEBOARD_FAB2(SCH_1):P3E_CPU0_PE1_SS_RXP(3)   I469 @BASEBOARD_FAB2_LIB.BASEBOARD_FAB2(SCH_1):PAGE107

R2U21 RES_0402-0.0,5%,1/16W,EMPTY,G2A
     1 P3E_CPU0_PE1_SS_R_RXN<3> @BASEBOARD_FAB2_LIB.BASEBOARD_FAB2(SCH_1):P3E_CPU0_PE1_SS_R_RXN(3)   I462 @BASEBOARD_FAB2_LIB.BASEBOARD_FAB2(SCH_1):PAGE107
     2 P3E_CPU0_PE1_SS_RXN<3> @BASEBOARD_FAB2_LIB.BASEBOARD_FAB2(SCH_1):P3E_CPU0_PE1_SS_RXN(3)   I462 @BASEBOARD_FAB2_LIB.BASEBOARD_FAB2(SCH_1):PAGE107

R2U22 RES_0402-0.0,5%,1/16W,EMPTY,G2A
     1 P3E_CPU0_PE1_SS_R_RXP<4> @BASEBOARD_FAB2_LIB.BASEBOARD_FAB2(SCH_1):P3E_CPU0_PE1_SS_R_RXP(4)   I470 @BASEBOARD_FAB2_LIB.BASEBOARD_FAB2(SCH_1):PAGE107
     2 P3E_CPU0_PE1_SS_RXP<4> @BASEBOARD_FAB2_LIB.BASEBOARD_FAB2(SCH_1):P3E_CPU0_PE1_SS_RXP(4)   I470 @BASEBOARD_FAB2_LIB.BASEBOARD_FAB2(SCH_1):PAGE107

R2U23 RES_0402-0.0,5%,1/16W,EMPTY,G2A
     1 P3E_CPU0_PE1_SS_R_RXN<4> @BASEBOARD_FAB2_LIB.BASEBOARD_FAB2(SCH_1):P3E_CPU0_PE1_SS_R_RXN(4)   I461 @BASEBOARD_FAB2_LIB.BASEBOARD_FAB2(SCH_1):PAGE107
     2 P3E_CPU0_PE1_SS_RXN<4> @BASEBOARD_FAB2_LIB.BASEBOARD_FAB2(SCH_1):P3E_CPU0_PE1_SS_RXN(4)   I461 @BASEBOARD_FAB2_LIB.BASEBOARD_FAB2(SCH_1):PAGE107

R2U24 RES_0402-0.0,5%,1/16W,EMPTY,G2A
     1 P3E_CPU0_PE1_SS_R_RXP<5> @BASEBOARD_FAB2_LIB.BASEBOARD_FAB2(SCH_1):P3E_CPU0_PE1_SS_R_RXP(5)   I471 @BASEBOARD_FAB2_LIB.BASEBOARD_FAB2(SCH_1):PAGE107
     2 P3E_CPU0_PE1_SS_RXP<5> @BASEBOARD_FAB2_LIB.BASEBOARD_FAB2(SCH_1):P3E_CPU0_PE1_SS_RXP(5)   I471 @BASEBOARD_FAB2_LIB.BASEBOARD_FAB2(SCH_1):PAGE107

R2U25 RES_0402-0.0,5%,1/16W,EMPTY,G2A
     1 P3E_CPU0_PE1_SS_R_RXN<5> @BASEBOARD_FAB2_LIB.BASEBOARD_FAB2(SCH_1):P3E_CPU0_PE1_SS_R_RXN(5)   I460 @BASEBOARD_FAB2_LIB.BASEBOARD_FAB2(SCH_1):PAGE107
     2 P3E_CPU0_PE1_SS_RXN<5> @BASEBOARD_FAB2_LIB.BASEBOARD_FAB2(SCH_1):P3E_CPU0_PE1_SS_RXN(5)   I460 @BASEBOARD_FAB2_LIB.BASEBOARD_FAB2(SCH_1):PAGE107

R2U26 RES_0402-0.0,5%,1/16W,EMPTY,G2A
     1 P3E_CPU0_PE1_SS_R_RXP<6> @BASEBOARD_FAB2_LIB.BASEBOARD_FAB2(SCH_1):P3E_CPU0_PE1_SS_R_RXP(6)   I472 @BASEBOARD_FAB2_LIB.BASEBOARD_FAB2(SCH_1):PAGE107
     2 P3E_CPU0_PE1_SS_RXP<6> @BASEBOARD_FAB2_LIB.BASEBOARD_FAB2(SCH_1):P3E_CPU0_PE1_SS_RXP(6)   I472 @BASEBOARD_FAB2_LIB.BASEBOARD_FAB2(SCH_1):PAGE107

R2U27 RES_0402-0.0,5%,1/16W,EMPTY,G2A
     1 P3E_CPU0_PE1_SS_R_RXN<6> @BASEBOARD_FAB2_LIB.BASEBOARD_FAB2(SCH_1):P3E_CPU0_PE1_SS_R_RXN(6)   I459 @BASEBOARD_FAB2_LIB.BASEBOARD_FAB2(SCH_1):PAGE107
     2 P3E_CPU0_PE1_SS_RXN<6> @BASEBOARD_FAB2_LIB.BASEBOARD_FAB2(SCH_1):P3E_CPU0_PE1_SS_RXN(6)   I459 @BASEBOARD_FAB2_LIB.BASEBOARD_FAB2(SCH_1):PAGE107

R2U28 RES_0402-0.0,5%,1/16W,EMPTY,G2A
     1 P3E_CPU0_PE1_SS_R_RXP<7> @BASEBOARD_FAB2_LIB.BASEBOARD_FAB2(SCH_1):P3E_CPU0_PE1_SS_R_RXP(7)   I473 @BASEBOARD_FAB2_LIB.BASEBOARD_FAB2(SCH_1):PAGE107
     2 P3E_CPU0_PE1_SS_RXP<7> @BASEBOARD_FAB2_LIB.BASEBOARD_FAB2(SCH_1):P3E_CPU0_PE1_SS_RXP(7)   I473 @BASEBOARD_FAB2_LIB.BASEBOARD_FAB2(SCH_1):PAGE107

R2U29 RES_0402-0.0,5%,1/16W,EMPTY,G2A
     1 P3E_CPU0_PE1_SS_R_RXN<7> @BASEBOARD_FAB2_LIB.BASEBOARD_FAB2(SCH_1):P3E_CPU0_PE1_SS_R_RXN(7)   I458 @BASEBOARD_FAB2_LIB.BASEBOARD_FAB2(SCH_1):PAGE107
     2 P3E_CPU0_PE1_SS_RXN<7> @BASEBOARD_FAB2_LIB.BASEBOARD_FAB2(SCH_1):P3E_CPU0_PE1_SS_RXN(7)   I458 @BASEBOARD_FAB2_LIB.BASEBOARD_FAB2(SCH_1):PAGE107

R2U30 RES_0402-4.75K,1%,1/16W,CHIP,GA
     1 P3V3_STBY @BASEBOARD_FAB2_LIB.BASEBOARD_FAB2(SCH_1):P3V3_STBY    I76 @BASEBOARD_FAB2_LIB.BASEBOARD_FAB2(SCH_1):PAGE125
     2 FM_UV_ADR_TRIGGER_EN @BASEBOARD_FAB2_LIB.BASEBOARD_FAB2(SCH_1):FM_UV_ADR_TRIGGER_EN    I76 @BASEBOARD_FAB2_LIB.BASEBOARD_FAB2(SCH_1):PAGE125

R2U31 RES_0402-20.0,1%,1/16W,CHIP,G2A
     1 SMB_SLOTX24_BMC_STBY_LVC3_SDA @BASEBOARD_FAB2_LIB.BASEBOARD_FAB2(SCH_1):SMB_SLOTX24_BMC_STBY_LVC3_SDA   I330 @BASEBOARD_FAB2_LIB.BASEBOARD_FAB2(SCH_1):PAGE108
     2 SMB_SLOTX24_STBY_LVC3_SDA_R2 @BASEBOARD_FAB2_LIB.BASEBOARD_FAB2(SCH_1):SMB_SLOTX24_STBY_LVC3_SDA_R2   I330 @BASEBOARD_FAB2_LIB.BASEBOARD_FAB2(SCH_1):PAGE108

R2U32 RES_0402-20.0,1%,1/16W,CHIP,G2A
     1 SMB_SLOTX24_BMC_STBY_LVC3_SCL @BASEBOARD_FAB2_LIB.BASEBOARD_FAB2(SCH_1):SMB_SLOTX24_BMC_STBY_LVC3_SCL   I339 @BASEBOARD_FAB2_LIB.BASEBOARD_FAB2(SCH_1):PAGE108
     2 SMB_SLOTX24_STBY_LVC3_SCL_R2 @BASEBOARD_FAB2_LIB.BASEBOARD_FAB2(SCH_1):SMB_SLOTX24_STBY_LVC3_SCL_R2   I339 @BASEBOARD_FAB2_LIB.BASEBOARD_FAB2(SCH_1):PAGE108

R2U33 RES_0402-20.0,1%,1/16W,CHIP,G2A
     1 SMB_HOST_STBY_LVC3_SDA_R @BASEBOARD_FAB2_LIB.BASEBOARD_FAB2(SCH_1):SMB_HOST_STBY_LVC3_SDA_R   I231 @BASEBOARD_FAB2_LIB.BASEBOARD_FAB2(SCH_1):PAGE159
     2 SMB_HOST_STBY_LVC3_SDA @BASEBOARD_FAB2_LIB.BASEBOARD_FAB2(SCH_1):SMB_HOST_STBY_LVC3_SDA   I231 @BASEBOARD_FAB2_LIB.BASEBOARD_FAB2(SCH_1):PAGE159

R2U34 RES_0402-20.0,1%,1/16W,CHIP,G2A
     1 SMB_HOST_STBY_LVC3_SCL_R @BASEBOARD_FAB2_LIB.BASEBOARD_FAB2(SCH_1):SMB_HOST_STBY_LVC3_SCL_R   I230 @BASEBOARD_FAB2_LIB.BASEBOARD_FAB2(SCH_1):PAGE159
     2 SMB_HOST_STBY_LVC3_SCL @BASEBOARD_FAB2_LIB.BASEBOARD_FAB2(SCH_1):SMB_HOST_STBY_LVC3_SCL   I230 @BASEBOARD_FAB2_LIB.BASEBOARD_FAB2(SCH_1):PAGE159

R2U35 RES_0402-20.0,1%,1/16W,EMPTY,GA
     1 SMB_SLOTX24_PCH_STBY_LVC3_SDA @BASEBOARD_FAB2_LIB.BASEBOARD_FAB2(SCH_1):SMB_SLOTX24_PCH_STBY_LVC3_SDA   I320 @BASEBOARD_FAB2_LIB.BASEBOARD_FAB2(SCH_1):PAGE108
     2 SMB_SLOTX24_STBY_LVC3_SDA_R2 @BASEBOARD_FAB2_LIB.BASEBOARD_FAB2(SCH_1):SMB_SLOTX24_STBY_LVC3_SDA_R2   I320 @BASEBOARD_FAB2_LIB.BASEBOARD_FAB2(SCH_1):PAGE108

R2U36 RES_0402-20.0,1%,1/16W,EMPTY,GA
     1 SMB_SLOTX24_PCH_STBY_LVC3_SCL @BASEBOARD_FAB2_LIB.BASEBOARD_FAB2(SCH_1):SMB_SLOTX24_PCH_STBY_LVC3_SCL   I340 @BASEBOARD_FAB2_LIB.BASEBOARD_FAB2(SCH_1):PAGE108
     2 SMB_SLOTX24_STBY_LVC3_SCL_R2 @BASEBOARD_FAB2_LIB.BASEBOARD_FAB2(SCH_1):SMB_SLOTX24_STBY_LVC3_SCL_R2   I340 @BASEBOARD_FAB2_LIB.BASEBOARD_FAB2(SCH_1):PAGE108

R2U37 RES_0402-0.0,5%,1/16W,CHIP,G21A
     1 RST_PCIE_RISER1_PERST_N @BASEBOARD_FAB2_LIB.BASEBOARD_FAB2(SCH_1):RST_PCIE_RISER1_PERST_N   I173 @BASEBOARD_FAB2_LIB.BASEBOARD_FAB2(SCH_1):PAGE108
     2 RST_PCIE_RISER1_PERST_R_N @BASEBOARD_FAB2_LIB.BASEBOARD_FAB2(SCH_1):RST_PCIE_RISER1_PERST_R_N   I173 @BASEBOARD_FAB2_LIB.BASEBOARD_FAB2(SCH_1):PAGE108

R2U38 RES_0402-665,1.0%,1/16W,CHIP,GA
     1 P3V3_STBY @BASEBOARD_FAB2_LIB.BASEBOARD_FAB2(SCH_1):P3V3_STBY    I80 @BASEBOARD_FAB2_LIB.BASEBOARD_FAB2(SCH_1):PAGE167
     2 SMB_SENSOR_STBY_LVC3_SCL @BASEBOARD_FAB2_LIB.BASEBOARD_FAB2(SCH_1):SMB_SENSOR_STBY_LVC3_SCL    I80 @BASEBOARD_FAB2_LIB.BASEBOARD_FAB2(SCH_1):PAGE167

R2U39 RES_0402-665,1.0%,1/16W,CHIP,GA
     1 P3V3_STBY @BASEBOARD_FAB2_LIB.BASEBOARD_FAB2(SCH_1):P3V3_STBY    I83 @BASEBOARD_FAB2_LIB.BASEBOARD_FAB2(SCH_1):PAGE167
     2 SMB_SENSOR_STBY_LVC3_SDA @BASEBOARD_FAB2_LIB.BASEBOARD_FAB2(SCH_1):SMB_SENSOR_STBY_LVC3_SDA    I83 @BASEBOARD_FAB2_LIB.BASEBOARD_FAB2(SCH_1):PAGE167

R2U40 RES_0402-150.0,1%,1/16W,CHIP,GA
     1 PVCCIO_CPU0 @BASEBOARD_FAB2_LIB.BASEBOARD_FAB2(SCH_1):PVCCIO_CPU0    I53 @BASEBOARD_FAB2_LIB.BASEBOARD_FAB2(SCH_1):PAGE152
     2 H_CPU0_MEMABC_MEMHOT_G_N @BASEBOARD_FAB2_LIB.BASEBOARD_FAB2(SCH_1):H_CPU0_MEMABC_MEMHOT_G_N    I53 @BASEBOARD_FAB2_LIB.BASEBOARD_FAB2(SCH_1):PAGE152

R2U41 RES_0402-150.0,1%,1/16W,CHIP,GA
     1 PVCCIO_CPU0 @BASEBOARD_FAB2_LIB.BASEBOARD_FAB2(SCH_1):PVCCIO_CPU0    I54 @BASEBOARD_FAB2_LIB.BASEBOARD_FAB2(SCH_1):PAGE152
     2 H_CPU0_MEMDEF_MEMHOT_G_N @BASEBOARD_FAB2_LIB.BASEBOARD_FAB2(SCH_1):H_CPU0_MEMDEF_MEMHOT_G_N    I54 @BASEBOARD_FAB2_LIB.BASEBOARD_FAB2(SCH_1):PAGE152

R2U42 RES_0402-221,1.0%,1/16W,CHIP,GA
     1 FAN_PWM_OUT_SYS0_BUF @BASEBOARD_FAB2_LIB.BASEBOARD_FAB2(SCH_1):FAN_PWM_OUT_SYS0_BUF    I99 @BASEBOARD_FAB2_LIB.BASEBOARD_FAB2(SCH_1):PAGE161
     2 FAN_PWM_OUT_SYS0_R @BASEBOARD_FAB2_LIB.BASEBOARD_FAB2(SCH_1):FAN_PWM_OUT_SYS0_R    I99 @BASEBOARD_FAB2_LIB.BASEBOARD_FAB2(SCH_1):PAGE161

R2U43 RES_0402-1.00K,1%,1/16W,CHIP,GA
     1 P3V_BAT_SOURCE @BASEBOARD_FAB2_LIB.BASEBOARD_FAB2(SCH_1):P3V_BAT_SOURCE    I46 @BASEBOARD_FAB2_LIB.BASEBOARD_FAB2(SCH_1):PAGE196
     2 A_P3V_BAT_R @BASEBOARD_FAB2_LIB.BASEBOARD_FAB2(SCH_1):A_P3V_BAT_R    I46 @BASEBOARD_FAB2_LIB.BASEBOARD_FAB2(SCH_1):PAGE196

R2U44 RES_0402-221,1.0%,1/16W,CHIP,GA
     1 FAN_PWM_OUT_SYS1_BUF @BASEBOARD_FAB2_LIB.BASEBOARD_FAB2(SCH_1):FAN_PWM_OUT_SYS1_BUF   I102 @BASEBOARD_FAB2_LIB.BASEBOARD_FAB2(SCH_1):PAGE161
     2 FAN_PWM_OUT_SYS1_R @BASEBOARD_FAB2_LIB.BASEBOARD_FAB2(SCH_1):FAN_PWM_OUT_SYS1_R   I102 @BASEBOARD_FAB2_LIB.BASEBOARD_FAB2(SCH_1):PAGE161

R2U45 RES_0402-0.0,5%,1/16W,EMPTY,G2A
     1 H_CPU1_MEMKLM_MEMHOT_LVT3_N @BASEBOARD_FAB2_LIB.BASEBOARD_FAB2(SCH_1):H_CPU1_MEMKLM_MEMHOT_LVT3_N   I102 @BASEBOARD_FAB2_LIB.BASEBOARD_FAB2(SCH_1):PAGE152
     2 H_CPU1_MEMKLM_MEMHOT_PCH_N @BASEBOARD_FAB2_LIB.BASEBOARD_FAB2(SCH_1):H_CPU1_MEMKLM_MEMHOT_PCH_N   I102 @BASEBOARD_FAB2_LIB.BASEBOARD_FAB2(SCH_1):PAGE152

R2U46 RES_0402-0.0,5%,1/16W,CHIP,G21A
     1 H_CPU1_MEMKLM_MEMHOT_LVT3_N @BASEBOARD_FAB2_LIB.BASEBOARD_FAB2(SCH_1):H_CPU1_MEMKLM_MEMHOT_LVT3_N    I94 @BASEBOARD_FAB2_LIB.BASEBOARD_FAB2(SCH_1):PAGE152
     2 H_CPU1_MEMKLM_MEMHOT_LVT3_BMC_N @BASEBOARD_FAB2_LIB.BASEBOARD_FAB2(SCH_1):H_CPU1_MEMKLM_MEMHOT_LVT3_BMC_N    I94 @BASEBOARD_FAB2_LIB.BASEBOARD_FAB2(SCH_1):PAGE152

R2U47 RES_0402-0.0,5%,1/16W,CHIP,G21A
     1 H_CPU0_MEMABC_MEMHOT_LVT3_N @BASEBOARD_FAB2_LIB.BASEBOARD_FAB2(SCH_1):H_CPU0_MEMABC_MEMHOT_LVT3_N    I79 @BASEBOARD_FAB2_LIB.BASEBOARD_FAB2(SCH_1):PAGE152
     2 H_CPU0_MEMABC_MEMHOT_LVT3_BMC_N @BASEBOARD_FAB2_LIB.BASEBOARD_FAB2(SCH_1):H_CPU0_MEMABC_MEMHOT_LVT3_BMC_N    I79 @BASEBOARD_FAB2_LIB.BASEBOARD_FAB2(SCH_1):PAGE152

R2U48 RES_0402-4.75K,1%,1/16W,CHIP,GA
     1 P3V3_STBY @BASEBOARD_FAB2_LIB.BASEBOARD_FAB2(SCH_1):P3V3_STBY   I213 @BASEBOARD_FAB2_LIB.BASEBOARD_FAB2(SCH_1):PAGE119
     2 FM_SLT_CFG2_R @BASEBOARD_FAB2_LIB.BASEBOARD_FAB2(SCH_1):FM_SLT_CFG2_R   I213 @BASEBOARD_FAB2_LIB.BASEBOARD_FAB2(SCH_1):PAGE119

R2U49 RES_0402-0.0,5%,1/16W,EMPTY,G2A
     1 H_CPU0_MEMABC_MEMHOT_G_PCH_N @BASEBOARD_FAB2_LIB.BASEBOARD_FAB2(SCH_1):H_CPU0_MEMABC_MEMHOT_G_PCH_N    I66 @BASEBOARD_FAB2_LIB.BASEBOARD_FAB2(SCH_1):PAGE152
     2 H_CPU0_MEMABC_MEMHOT_LVT3_K_N @BASEBOARD_FAB2_LIB.BASEBOARD_FAB2(SCH_1):H_CPU0_MEMABC_MEMHOT_LVT3_K_N    I66 @BASEBOARD_FAB2_LIB.BASEBOARD_FAB2(SCH_1):PAGE152

R2U50 RES_0402-0.0,5%,1/16W,EMPTY,G2A
     1 FM_SLT_CFG2_R @BASEBOARD_FAB2_LIB.BASEBOARD_FAB2(SCH_1):FM_SLT_CFG2_R   I215 @BASEBOARD_FAB2_LIB.BASEBOARD_FAB2(SCH_1):PAGE119
     2 FM_PWRBRK_SLOT_N @BASEBOARD_FAB2_LIB.BASEBOARD_FAB2(SCH_1):FM_PWRBRK_SLOT_N   I215 @BASEBOARD_FAB2_LIB.BASEBOARD_FAB2(SCH_1):PAGE119

R2U51 RES_0402-0.0,5%,1/16W,EMPTY,G2A
     1 H_CPU0_MEMABC_MEMHOT_G_PCH_N @BASEBOARD_FAB2_LIB.BASEBOARD_FAB2(SCH_1):H_CPU0_MEMABC_MEMHOT_G_PCH_N    I51 @BASEBOARD_FAB2_LIB.BASEBOARD_FAB2(SCH_1):PAGE152
     2 H_CPU0_MEMABC_MEMHOT_G_N @BASEBOARD_FAB2_LIB.BASEBOARD_FAB2(SCH_1):H_CPU0_MEMABC_MEMHOT_G_N    I51 @BASEBOARD_FAB2_LIB.BASEBOARD_FAB2(SCH_1):PAGE152

R3B1 RES_0402-221,1.0%,1/16W,CHIP,GA
     1 SVID_ALERT0_CPU1_N @BASEBOARD_FAB2_LIB.BASEBOARD_FAB2(SCH_1):SVID_ALERT0_CPU1_N    I27 @BASEBOARD_FAB2_LIB.BASEBOARD_FAB2(SCH_1):PAGE55
     2 SVID_ALERT0_CPU1_R_N @BASEBOARD_FAB2_LIB.BASEBOARD_FAB2(SCH_1):SVID_ALERT0_CPU1_R_N    I27 @BASEBOARD_FAB2_LIB.BASEBOARD_FAB2(SCH_1):PAGE55

R3B2 RES_0402-49.9,1%,1/16W,CHIP,G2A
     1 SVID_ALERT0_CPU1_R_N @BASEBOARD_FAB2_LIB.BASEBOARD_FAB2(SCH_1):SVID_ALERT0_CPU1_R_N    I19 @BASEBOARD_FAB2_LIB.BASEBOARD_FAB2(SCH_1):PAGE55
     2 PVCCIO_CPU1 @BASEBOARD_FAB2_LIB.BASEBOARD_FAB2(SCH_1):PVCCIO_CPU1    I19 @BASEBOARD_FAB2_LIB.BASEBOARD_FAB2(SCH_1):PAGE55

R3B3 RES_0402-0.0,5%,1/16W,CHIP,G21A
     1 SVID_DIO0_CPU1 @BASEBOARD_FAB2_LIB.BASEBOARD_FAB2(SCH_1):SVID_DIO0_CPU1    I29 @BASEBOARD_FAB2_LIB.BASEBOARD_FAB2(SCH_1):PAGE55
     2 SVID_DIO0_CPU1_R @BASEBOARD_FAB2_LIB.BASEBOARD_FAB2(SCH_1):SVID_DIO0_CPU1_R    I29 @BASEBOARD_FAB2_LIB.BASEBOARD_FAB2(SCH_1):PAGE55

R3B4 RES_0402-100.0,1%,1/16W,CHIP,GA
     1 SVID_DIO0_CPU1_R @BASEBOARD_FAB2_LIB.BASEBOARD_FAB2(SCH_1):SVID_DIO0_CPU1_R    I21 @BASEBOARD_FAB2_LIB.BASEBOARD_FAB2(SCH_1):PAGE55
     2 PVCCIO_CPU1 @BASEBOARD_FAB2_LIB.BASEBOARD_FAB2(SCH_1):PVCCIO_CPU1    I21 @BASEBOARD_FAB2_LIB.BASEBOARD_FAB2(SCH_1):PAGE55

R3B5 RES_0402-0.0,5%,1/16W,CHIP,G21A
     1 SVID_CLK0_CPU1 @BASEBOARD_FAB2_LIB.BASEBOARD_FAB2(SCH_1):SVID_CLK0_CPU1    I28 @BASEBOARD_FAB2_LIB.BASEBOARD_FAB2(SCH_1):PAGE55
     2 SVID_CLK0_CPU1_R @BASEBOARD_FAB2_LIB.BASEBOARD_FAB2(SCH_1):SVID_CLK0_CPU1_R    I28 @BASEBOARD_FAB2_LIB.BASEBOARD_FAB2(SCH_1):PAGE55

R3D1 RES_0402-90.9,1%,1/16W,CHIP,G2A
     1 A_CPU1_KLM_RCOMP0 @BASEBOARD_FAB2_LIB.BASEBOARD_FAB2(SCH_1):A_CPU1_KLM_RCOMP0   I116 @BASEBOARD_FAB2_LIB.BASEBOARD_FAB2(SCH_1):PAGE55
     2    GND @BASEBOARD_FAB2_LIB.BASEBOARD_FAB2(SCH_1):GND   I116 @BASEBOARD_FAB2_LIB.BASEBOARD_FAB2(SCH_1):PAGE55

R3D2 RES_0402-90.9,1%,1/16W,CHIP,G2A
     1 A_CPU1_KLM_RCOMP1 @BASEBOARD_FAB2_LIB.BASEBOARD_FAB2(SCH_1):A_CPU1_KLM_RCOMP1   I117 @BASEBOARD_FAB2_LIB.BASEBOARD_FAB2(SCH_1):PAGE55
     2    GND @BASEBOARD_FAB2_LIB.BASEBOARD_FAB2(SCH_1):GND   I117 @BASEBOARD_FAB2_LIB.BASEBOARD_FAB2(SCH_1):PAGE55

R3D3 RES_0402-100.0,1%,1/16W,CHIP,GA
     1 A_CPU1_KLM_RCOMP2 @BASEBOARD_FAB2_LIB.BASEBOARD_FAB2(SCH_1):A_CPU1_KLM_RCOMP2   I118 @BASEBOARD_FAB2_LIB.BASEBOARD_FAB2(SCH_1):PAGE55
     2    GND @BASEBOARD_FAB2_LIB.BASEBOARD_FAB2(SCH_1):GND   I118 @BASEBOARD_FAB2_LIB.BASEBOARD_FAB2(SCH_1):PAGE55

R3D4 RES_0402-49.9,1%,1/16W,CHIP,G2A
     1 A_CPU1_MCP01_RBIAS @BASEBOARD_FAB2_LIB.BASEBOARD_FAB2(SCH_1):A_CPU1_MCP01_RBIAS   I155 @BASEBOARD_FAB2_LIB.BASEBOARD_FAB2(SCH_1):PAGE55
     2    GND @BASEBOARD_FAB2_LIB.BASEBOARD_FAB2(SCH_1):GND   I155 @BASEBOARD_FAB2_LIB.BASEBOARD_FAB2(SCH_1):PAGE55

R3D9 RES_0402-49.9,1%,1/16W,CHIP,G2A
     1 PD_CPU1_TEST12 @BASEBOARD_FAB2_LIB.BASEBOARD_FAB2(SCH_1):PD_CPU1_TEST12    I88 @BASEBOARD_FAB2_LIB.BASEBOARD_FAB2(SCH_1):PAGE90
     2    GND @BASEBOARD_FAB2_LIB.BASEBOARD_FAB2(SCH_1):GND    I88 @BASEBOARD_FAB2_LIB.BASEBOARD_FAB2(SCH_1):PAGE90

R3D12 RES_0402-240,1.0%,1/16W,CHIP,GA
     1    GND @BASEBOARD_FAB2_LIB.BASEBOARD_FAB2(SCH_1):GND    I11 @BASEBOARD_FAB2_LIB.BASEBOARD_FAB2(SCH_1):PAGE90
     2 PD_CPU1_TXT_PLTEN @BASEBOARD_FAB2_LIB.BASEBOARD_FAB2(SCH_1):PD_CPU1_TXT_PLTEN    I11 @BASEBOARD_FAB2_LIB.BASEBOARD_FAB2(SCH_1):PAGE90

R3D13 RES_0402-240,1.0%,1/16W,EMPTY,A
     1    GND @BASEBOARD_FAB2_LIB.BASEBOARD_FAB2(SCH_1):GND    I12 @BASEBOARD_FAB2_LIB.BASEBOARD_FAB2(SCH_1):PAGE90
     2 PD_CPU1_BIST_ENABLE @BASEBOARD_FAB2_LIB.BASEBOARD_FAB2(SCH_1):PD_CPU1_BIST_ENABLE    I12 @BASEBOARD_FAB2_LIB.BASEBOARD_FAB2(SCH_1):PAGE90

R3D14 RES_0603-2.2,1.0%,1/10W,CHIP,GA
     1 P3V3_DB1200 @BASEBOARD_FAB2_LIB.BASEBOARD_FAB2(SCH_1):P3V3_DB1200    I21 @BASEBOARD_FAB2_LIB.BASEBOARD_FAB2(SCH_1):PAGE102
     2 P3V3_DB1200_A @BASEBOARD_FAB2_LIB.BASEBOARD_FAB2(SCH_1):P3V3_DB1200_A    I21 @BASEBOARD_FAB2_LIB.BASEBOARD_FAB2(SCH_1):PAGE102

R3D15 RES_0402-49.9,1%,1/16W,CHIP,G2A
     1 PVCCIO_CPU1 @BASEBOARD_FAB2_LIB.BASEBOARD_FAB2(SCH_1):PVCCIO_CPU1    I26 @BASEBOARD_FAB2_LIB.BASEBOARD_FAB2(SCH_1):PAGE96
     2 PWRGD_CPU1_G @BASEBOARD_FAB2_LIB.BASEBOARD_FAB2(SCH_1):PWRGD_CPU1_G    I26 @BASEBOARD_FAB2_LIB.BASEBOARD_FAB2(SCH_1):PAGE96

R3D16 RES_0402-240,1.0%,1/16W,EMPTY,A
     1 PVCCIO_CPU1 @BASEBOARD_FAB2_LIB.BASEBOARD_FAB2(SCH_1):PVCCIO_CPU1    I24 @BASEBOARD_FAB2_LIB.BASEBOARD_FAB2(SCH_1):PAGE90
     2 H_CPU1_BMCINIT @BASEBOARD_FAB2_LIB.BASEBOARD_FAB2(SCH_1):H_CPU1_BMCINIT    I24 @BASEBOARD_FAB2_LIB.BASEBOARD_FAB2(SCH_1):PAGE90

R3D17 RES_0402-240,1.0%,1/16W,EMPTY,A
     1 PVCCIO_CPU1 @BASEBOARD_FAB2_LIB.BASEBOARD_FAB2(SCH_1):PVCCIO_CPU1    I60 @BASEBOARD_FAB2_LIB.BASEBOARD_FAB2(SCH_1):PAGE90
     2 PU_CPU1_SOCKET_ID_1 @BASEBOARD_FAB2_LIB.BASEBOARD_FAB2(SCH_1):PU_CPU1_SOCKET_ID_1    I60 @BASEBOARD_FAB2_LIB.BASEBOARD_FAB2(SCH_1):PAGE90

R3D18 RES_0402-0.0,5%,1/16W,CHIP,G21A
     1 H_CPU0_FAST_WAKE_N @BASEBOARD_FAB2_LIB.BASEBOARD_FAB2(SCH_1):H_CPU0_FAST_WAKE_N    I33 @BASEBOARD_FAB2_LIB.BASEBOARD_FAB2(SCH_1):PAGE97
     2 H_CPU1_FAST_WAKE_N @BASEBOARD_FAB2_LIB.BASEBOARD_FAB2(SCH_1):H_CPU1_FAST_WAKE_N    I33 @BASEBOARD_FAB2_LIB.BASEBOARD_FAB2(SCH_1):PAGE97

R3D19 RES_0402-49.9,1%,1/16W,CHIP,G2A
     1 A_CPU1_UPI01_RBIAS @BASEBOARD_FAB2_LIB.BASEBOARD_FAB2(SCH_1):A_CPU1_UPI01_RBIAS   I125 @BASEBOARD_FAB2_LIB.BASEBOARD_FAB2(SCH_1):PAGE55
     2    GND @BASEBOARD_FAB2_LIB.BASEBOARD_FAB2(SCH_1):GND   I125 @BASEBOARD_FAB2_LIB.BASEBOARD_FAB2(SCH_1):PAGE55

R3D20 RES_0402-49.9,1%,1/16W,CHIP,G2A
     1 PVCCIO_CPU1 @BASEBOARD_FAB2_LIB.BASEBOARD_FAB2(SCH_1):PVCCIO_CPU1    I25 @BASEBOARD_FAB2_LIB.BASEBOARD_FAB2(SCH_1):PAGE96
     2 RST_CPU1_G_N @BASEBOARD_FAB2_LIB.BASEBOARD_FAB2(SCH_1):RST_CPU1_G_N    I25 @BASEBOARD_FAB2_LIB.BASEBOARD_FAB2(SCH_1):PAGE96

R3D21 RES_0402-64.9,1.0%,1/16W,CHIP,A
     1 PVDDQ_GHJ @BASEBOARD_FAB2_LIB.BASEBOARD_FAB2(SCH_1):PVDDQ_GHJ    I30 @BASEBOARD_FAB2_LIB.BASEBOARD_FAB2(SCH_1):PAGE96
     2 PWRGD_CPU1_DRAMPWROK_GHJ_G @BASEBOARD_FAB2_LIB.BASEBOARD_FAB2(SCH_1):PWRGD_CPU1_DRAMPWROK_GHJ_G    I30 @BASEBOARD_FAB2_LIB.BASEBOARD_FAB2(SCH_1):PAGE96

R3D22 RES_0402-240,1.0%,1/16W,EMPTY,A
     1 PVCCIO_CPU1 @BASEBOARD_FAB2_LIB.BASEBOARD_FAB2(SCH_1):PVCCIO_CPU1    I17 @BASEBOARD_FAB2_LIB.BASEBOARD_FAB2(SCH_1):PAGE90
     2 PU_CPU1_FRMAGENT @BASEBOARD_FAB2_LIB.BASEBOARD_FAB2(SCH_1):PU_CPU1_FRMAGENT    I17 @BASEBOARD_FAB2_LIB.BASEBOARD_FAB2(SCH_1):PAGE90

R3D23 RES_0402-240,1.0%,1/16W,EMPTY,A
     1 PVCCIO_CPU1 @BASEBOARD_FAB2_LIB.BASEBOARD_FAB2(SCH_1):PVCCIO_CPU1    I25 @BASEBOARD_FAB2_LIB.BASEBOARD_FAB2(SCH_1):PAGE90
     2 PU_CPU1_TXT_AGENT @BASEBOARD_FAB2_LIB.BASEBOARD_FAB2(SCH_1):PU_CPU1_TXT_AGENT    I25 @BASEBOARD_FAB2_LIB.BASEBOARD_FAB2(SCH_1):PAGE90

R3D24 RES_0402-240,1.0%,1/16W,CHIP,GA
     1 PVCCIO_CPU1 @BASEBOARD_FAB2_LIB.BASEBOARD_FAB2(SCH_1):PVCCIO_CPU1    I59 @BASEBOARD_FAB2_LIB.BASEBOARD_FAB2(SCH_1):PAGE90
     2 PU_CPU1_SOCKET_ID_0 @BASEBOARD_FAB2_LIB.BASEBOARD_FAB2(SCH_1):PU_CPU1_SOCKET_ID_0    I59 @BASEBOARD_FAB2_LIB.BASEBOARD_FAB2(SCH_1):PAGE90

R3D25 RES_0402-240,1.0%,1/16W,EMPTY,A
     1 PVCCIO_CPU1 @BASEBOARD_FAB2_LIB.BASEBOARD_FAB2(SCH_1):PVCCIO_CPU1    I66 @BASEBOARD_FAB2_LIB.BASEBOARD_FAB2(SCH_1):PAGE90
     2 PU_CPU1_EAR_N @BASEBOARD_FAB2_LIB.BASEBOARD_FAB2(SCH_1):PU_CPU1_EAR_N    I66 @BASEBOARD_FAB2_LIB.BASEBOARD_FAB2(SCH_1):PAGE90

R3D26 RES_0402-240,1.0%,1/16W,EMPTY,A
     1 PVCCIO_CPU1 @BASEBOARD_FAB2_LIB.BASEBOARD_FAB2(SCH_1):PVCCIO_CPU1    I28 @BASEBOARD_FAB2_LIB.BASEBOARD_FAB2(SCH_1):PAGE90
     2 PU_CPU1_SAFE_MODE_BOOT @BASEBOARD_FAB2_LIB.BASEBOARD_FAB2(SCH_1):PU_CPU1_SAFE_MODE_BOOT    I28 @BASEBOARD_FAB2_LIB.BASEBOARD_FAB2(SCH_1):PAGE90

R3D27 RES_0402-249,0.1%,1/16W,CHIP,GA
     1 VSENSE_PMAX_CPU1 @BASEBOARD_FAB2_LIB.BASEBOARD_FAB2(SCH_1):VSENSE_PMAX_CPU1    I43 @BASEBOARD_FAB2_LIB.BASEBOARD_FAB2(SCH_1):PAGE71
     2    GND @BASEBOARD_FAB2_LIB.BASEBOARD_FAB2(SCH_1):GND    I43 @BASEBOARD_FAB2_LIB.BASEBOARD_FAB2(SCH_1):PAGE71

R3D28 RES_0402-100.0,1%,1/16W,CHIP,GA
     1 VSENSE_PVCCIO_CPU1_AVSN @BASEBOARD_FAB2_LIB.BASEBOARD_FAB2(SCH_1):VSENSE_PVCCIO_CPU1_AVSN   I101 @BASEBOARD_FAB2_LIB.BASEBOARD_FAB2(SCH_1):PAGE214
     2    GND @BASEBOARD_FAB2_LIB.BASEBOARD_FAB2(SCH_1):GND   I101 @BASEBOARD_FAB2_LIB.BASEBOARD_FAB2(SCH_1):PAGE214

R3D31 RES_0402-0.0,5%,1/16W,EMPTY,G2A
     1 FM_CPU_BMC_INIT @BASEBOARD_FAB2_LIB.BASEBOARD_FAB2(SCH_1):FM_CPU_BMC_INIT   I300 @BASEBOARD_FAB2_LIB.BASEBOARD_FAB2(SCH_1):PAGE156
     2 H_CPU1_BMCINIT @BASEBOARD_FAB2_LIB.BASEBOARD_FAB2(SCH_1):H_CPU1_BMCINIT   I300 @BASEBOARD_FAB2_LIB.BASEBOARD_FAB2(SCH_1):PAGE156

R3D32 RES_0402-10.0,1%,1/16W,EMPTY,GA
     1 PVCCIO_CPU1 @BASEBOARD_FAB2_LIB.BASEBOARD_FAB2(SCH_1):PVCCIO_CPU1    I53 @BASEBOARD_FAB2_LIB.BASEBOARD_FAB2(SCH_1):PAGE71
     2 VSENSE_PMAX_CPU1 @BASEBOARD_FAB2_LIB.BASEBOARD_FAB2(SCH_1):VSENSE_PMAX_CPU1    I53 @BASEBOARD_FAB2_LIB.BASEBOARD_FAB2(SCH_1):PAGE71

R3E1 RES_0402-100.0,1%,1/16W,CHIP,GA
     1 VSENSE_PVCCIO_CPU1_AVSP @BASEBOARD_FAB2_LIB.BASEBOARD_FAB2(SCH_1):VSENSE_PVCCIO_CPU1_AVSP   I105 @BASEBOARD_FAB2_LIB.BASEBOARD_FAB2(SCH_1):PAGE214
     2 PVCCIO_CPU1 @BASEBOARD_FAB2_LIB.BASEBOARD_FAB2(SCH_1):PVCCIO_CPU1   I105 @BASEBOARD_FAB2_LIB.BASEBOARD_FAB2(SCH_1):PAGE214

R3F1 RES_0402-0.0,5%,1/16W,EMPTY,G2A
     1 CLK_322M_156M_CPU1_OSC_VRM_DN @BASEBOARD_FAB2_LIB.BASEBOARD_FAB2(SCH_1):CLK_322M_156M_CPU1_OSC_VRM_DN    I51 @BASEBOARD_FAB2_LIB.BASEBOARD_FAB2(SCH_1):PAGE104
     2 CLK_156M_OSC_CPU1_HFI_DN @BASEBOARD_FAB2_LIB.BASEBOARD_FAB2(SCH_1):CLK_156M_OSC_CPU1_HFI_DN    I51 @BASEBOARD_FAB2_LIB.BASEBOARD_FAB2(SCH_1):PAGE104

R3F2 RES_0402-0.0,5%,1/16W,CHIP,G21A
     1 CLK_156M_OSC_BRD_CPU1_DN @BASEBOARD_FAB2_LIB.BASEBOARD_FAB2(SCH_1):CLK_156M_OSC_BRD_CPU1_DN    I69 @BASEBOARD_FAB2_LIB.BASEBOARD_FAB2(SCH_1):PAGE104
     2 CLK_156M_OSC_CPU1_HFI_DN @BASEBOARD_FAB2_LIB.BASEBOARD_FAB2(SCH_1):CLK_156M_OSC_CPU1_HFI_DN    I69 @BASEBOARD_FAB2_LIB.BASEBOARD_FAB2(SCH_1):PAGE104

R3F3 RES_0402-0.0,5%,1/16W,EMPTY,G2A
     1 CLK_322M_156M_CPU1_OSC_VRM_DP @BASEBOARD_FAB2_LIB.BASEBOARD_FAB2(SCH_1):CLK_322M_156M_CPU1_OSC_VRM_DP    I53 @BASEBOARD_FAB2_LIB.BASEBOARD_FAB2(SCH_1):PAGE104
     2 CLK_156M_OSC_CPU1_HFI_DP @BASEBOARD_FAB2_LIB.BASEBOARD_FAB2(SCH_1):CLK_156M_OSC_CPU1_HFI_DP    I53 @BASEBOARD_FAB2_LIB.BASEBOARD_FAB2(SCH_1):PAGE104

R3F4 RES_0402-0.0,5%,1/16W,CHIP,G21A
     1 CLK_156M_OSC_BRD_CPU1_DP @BASEBOARD_FAB2_LIB.BASEBOARD_FAB2(SCH_1):CLK_156M_OSC_BRD_CPU1_DP    I70 @BASEBOARD_FAB2_LIB.BASEBOARD_FAB2(SCH_1):PAGE104
     2 CLK_156M_OSC_CPU1_HFI_DP @BASEBOARD_FAB2_LIB.BASEBOARD_FAB2(SCH_1):CLK_156M_OSC_CPU1_HFI_DP    I70 @BASEBOARD_FAB2_LIB.BASEBOARD_FAB2(SCH_1):PAGE104

R3F5 RES_0402-0.0,5%,1/16W,EMPTY,G2A
     1 CLK_322M_156M_CPU1_OSC_VRM_DN @BASEBOARD_FAB2_LIB.BASEBOARD_FAB2(SCH_1):CLK_322M_156M_CPU1_OSC_VRM_DN    I84 @BASEBOARD_FAB2_LIB.BASEBOARD_FAB2(SCH_1):PAGE104
     2 CLK_322M_OSC_CPU1_RC_DN @BASEBOARD_FAB2_LIB.BASEBOARD_FAB2(SCH_1):CLK_322M_OSC_CPU1_RC_DN    I84 @BASEBOARD_FAB2_LIB.BASEBOARD_FAB2(SCH_1):PAGE104

R3F6 RES_0402-0.0,5%,1/16W,EMPTY,G2A
     1 CLK_322M_156M_CPU1_OSC_VRM_DP @BASEBOARD_FAB2_LIB.BASEBOARD_FAB2(SCH_1):CLK_322M_156M_CPU1_OSC_VRM_DP    I88 @BASEBOARD_FAB2_LIB.BASEBOARD_FAB2(SCH_1):PAGE104
     2 CLK_322M_OSC_CPU1_RC_DP @BASEBOARD_FAB2_LIB.BASEBOARD_FAB2(SCH_1):CLK_322M_OSC_CPU1_RC_DP    I88 @BASEBOARD_FAB2_LIB.BASEBOARD_FAB2(SCH_1):PAGE104

R3L1 RES_0402-1.0,1%,1/16W,CHIP,G21A
     1 VR_PVNN_PCH_PH1_VCIN @BASEBOARD_FAB2_LIB.BASEBOARD_FAB2(SCH_1):VR_PVNN_PCH_PH1_VCIN    I14 @BASEBOARD_FAB2_LIB.BASEBOARD_FAB2(SCH_1):PAGE236
     2 P5V_STBY @BASEBOARD_FAB2_LIB.BASEBOARD_FAB2(SCH_1):P5V_STBY    I14 @BASEBOARD_FAB2_LIB.BASEBOARD_FAB2(SCH_1):PAGE236

R3L4 RES_0402-1.0,1%,1/16W,CHIP,G21A
     1 VR_P1V05_PCH_STBY_PH1_VCIN @BASEBOARD_FAB2_LIB.BASEBOARD_FAB2(SCH_1):VR_P1V05_PCH_STBY_PH1_VCIN    I41 @BASEBOARD_FAB2_LIB.BASEBOARD_FAB2(SCH_1):PAGE236
     2 P5V_STBY @BASEBOARD_FAB2_LIB.BASEBOARD_FAB2(SCH_1):P5V_STBY    I41 @BASEBOARD_FAB2_LIB.BASEBOARD_FAB2(SCH_1):PAGE236

R3L6 RES_0402-1.0,1%,1/16W,CHIP,G21A
     1 VR_PVDDQ_DEF_PH1_VCIN @BASEBOARD_FAB2_LIB.BASEBOARD_FAB2(SCH_1):VR_PVDDQ_DEF_PH1_VCIN    I52 @BASEBOARD_FAB2_LIB.BASEBOARD_FAB2(SCH_1):PAGE219
     2 P5V_STBY @BASEBOARD_FAB2_LIB.BASEBOARD_FAB2(SCH_1):P5V_STBY    I52 @BASEBOARD_FAB2_LIB.BASEBOARD_FAB2(SCH_1):PAGE219

R3L8 RES_0402-1.0,1%,1/16W,CHIP,G21A
     1 VR_PVDDQ_DEF_PH2_VCIN @BASEBOARD_FAB2_LIB.BASEBOARD_FAB2(SCH_1):VR_PVDDQ_DEF_PH2_VCIN    I76 @BASEBOARD_FAB2_LIB.BASEBOARD_FAB2(SCH_1):PAGE219
     2 P5V_STBY @BASEBOARD_FAB2_LIB.BASEBOARD_FAB2(SCH_1):P5V_STBY    I76 @BASEBOARD_FAB2_LIB.BASEBOARD_FAB2(SCH_1):PAGE219

R3L9 RES_0402-0.0,5%,1/16W,CHIP,G21A
     1 VR_PVDDQ_DEF_VD12 @BASEBOARD_FAB2_LIB.BASEBOARD_FAB2(SCH_1):VR_PVDDQ_DEF_VD12    I57 @BASEBOARD_FAB2_LIB.BASEBOARD_FAB2(SCH_1):PAGE218
     2 VR_PVDDQ_DEF_AIREF1 @BASEBOARD_FAB2_LIB.BASEBOARD_FAB2(SCH_1):VR_PVDDQ_DEF_AIREF1    I57 @BASEBOARD_FAB2_LIB.BASEBOARD_FAB2(SCH_1):PAGE218

R3L10 RES_0402-0.0,5%,1/16W,CHIP,G21A
     1 VR_PVDDQ_DEF_VD12 @BASEBOARD_FAB2_LIB.BASEBOARD_FAB2(SCH_1):VR_PVDDQ_DEF_VD12    I50 @BASEBOARD_FAB2_LIB.BASEBOARD_FAB2(SCH_1):PAGE218
     2 VR_PVDDQ_DEF_AIREF2 @BASEBOARD_FAB2_LIB.BASEBOARD_FAB2(SCH_1):VR_PVDDQ_DEF_AIREF2    I50 @BASEBOARD_FAB2_LIB.BASEBOARD_FAB2(SCH_1):PAGE218

R3L11 RES_0402-100.0,1%,1/16W,EMPTY,A
     1 PVCCIO_CPU0 @BASEBOARD_FAB2_LIB.BASEBOARD_FAB2(SCH_1):PVCCIO_CPU0     I7 @BASEBOARD_FAB2_LIB.BASEBOARD_FAB2(SCH_1):PAGE218
     2 SVID_DIO1_CPU0_R @BASEBOARD_FAB2_LIB.BASEBOARD_FAB2(SCH_1):SVID_DIO1_CPU0_R     I7 @BASEBOARD_FAB2_LIB.BASEBOARD_FAB2(SCH_1):PAGE218

R3L12 RES_0402-100.0K,1%,1/16W,CHIP,B
     1 VR_FET_SW_P12V_STBY_PVDDQ_DEF @BASEBOARD_FAB2_LIB.BASEBOARD_FAB2(SCH_1):VR_FET_SW_P12V_STBY_PVDDQ_DEF    I53 @BASEBOARD_FAB2_LIB.BASEBOARD_FAB2(SCH_1):PAGE218
     2 VR_PVDDQ_DEF_VINSEN @BASEBOARD_FAB2_LIB.BASEBOARD_FAB2(SCH_1):VR_PVDDQ_DEF_VINSEN    I53 @BASEBOARD_FAB2_LIB.BASEBOARD_FAB2(SCH_1):PAGE218

R3L13 RES_0402-49.9,1%,1/16W,CHIP,G2A
     1 PVCCIO_CPU0 @BASEBOARD_FAB2_LIB.BASEBOARD_FAB2(SCH_1):PVCCIO_CPU0    I47 @BASEBOARD_FAB2_LIB.BASEBOARD_FAB2(SCH_1):PAGE218
     2 SVID_CLK1_CPU0_R @BASEBOARD_FAB2_LIB.BASEBOARD_FAB2(SCH_1):SVID_CLK1_CPU0_R    I47 @BASEBOARD_FAB2_LIB.BASEBOARD_FAB2(SCH_1):PAGE218

R3L14 RES_0402-68.1K,1%,1/16W,EMPTY,A
     1 VR_P1V05_PCH_STBY_OCSET @BASEBOARD_FAB2_LIB.BASEBOARD_FAB2(SCH_1):VR_P1V05_PCH_STBY_OCSET   I120 @BASEBOARD_FAB2_LIB.BASEBOARD_FAB2(SCH_1):PAGE236
     2    GND @BASEBOARD_FAB2_LIB.BASEBOARD_FAB2(SCH_1):GND   I120 @BASEBOARD_FAB2_LIB.BASEBOARD_FAB2(SCH_1):PAGE236

R3L15 RES_0402-68.1K,1%,1/16W,EMPTY,A
     1 VR_PVNN_PCH_STBY_OCSET @BASEBOARD_FAB2_LIB.BASEBOARD_FAB2(SCH_1):VR_PVNN_PCH_STBY_OCSET   I118 @BASEBOARD_FAB2_LIB.BASEBOARD_FAB2(SCH_1):PAGE236
     2    GND @BASEBOARD_FAB2_LIB.BASEBOARD_FAB2(SCH_1):GND   I118 @BASEBOARD_FAB2_LIB.BASEBOARD_FAB2(SCH_1):PAGE236

R3M1 RES_0402-0.0,5%,1/16W,CHIP,G21A
     1 P3V3_STBY @BASEBOARD_FAB2_LIB.BASEBOARD_FAB2(SCH_1):P3V3_STBY    I34 @BASEBOARD_FAB2_LIB.BASEBOARD_FAB2(SCH_1):PAGE218
     2 VR_PVDDQ_DEF_VDD @BASEBOARD_FAB2_LIB.BASEBOARD_FAB2(SCH_1):VR_PVDDQ_DEF_VDD    I34 @BASEBOARD_FAB2_LIB.BASEBOARD_FAB2(SCH_1):PAGE218

R3M3 RES_0402-22.1,1.0%,1/16W,CHIP,A
     1 PWRGD_PVDDQ_DEF_R @BASEBOARD_FAB2_LIB.BASEBOARD_FAB2(SCH_1):PWRGD_PVDDQ_DEF_R    I11 @BASEBOARD_FAB2_LIB.BASEBOARD_FAB2(SCH_1):PAGE218
     2 PWRGD_PVDDQ_DEF @BASEBOARD_FAB2_LIB.BASEBOARD_FAB2(SCH_1):PWRGD_PVDDQ_DEF    I11 @BASEBOARD_FAB2_LIB.BASEBOARD_FAB2(SCH_1):PAGE218

R3M5 RES_0402-100.0K,1%,1/16W,EMPTYA
     1 P3V3_STBY @BASEBOARD_FAB2_LIB.BASEBOARD_FAB2(SCH_1):P3V3_STBY    I35 @BASEBOARD_FAB2_LIB.BASEBOARD_FAB2(SCH_1):PAGE218
     2 VR_PVDDQ_DEF_VREN @BASEBOARD_FAB2_LIB.BASEBOARD_FAB2(SCH_1):VR_PVDDQ_DEF_VREN    I35 @BASEBOARD_FAB2_LIB.BASEBOARD_FAB2(SCH_1):PAGE218

R3M6 RES_0402-0.0,5%,1/16W,CHIP,G21A
     1 FM_PVDDQ_DEF_EN @BASEBOARD_FAB2_LIB.BASEBOARD_FAB2(SCH_1):FM_PVDDQ_DEF_EN    I59 @BASEBOARD_FAB2_LIB.BASEBOARD_FAB2(SCH_1):PAGE218
     2 VR_PVDDQ_DEF_VREN @BASEBOARD_FAB2_LIB.BASEBOARD_FAB2(SCH_1):VR_PVDDQ_DEF_VREN    I59 @BASEBOARD_FAB2_LIB.BASEBOARD_FAB2(SCH_1):PAGE218

R3M8 RES_0402-100.0K,1%,1/16W,CHIP,A
     1 P2E_SSB_BMC_RX_C_DP @BASEBOARD_FAB2_LIB.BASEBOARD_FAB2(SCH_1):P2E_SSB_BMC_RX_C_DP   I235 @BASEBOARD_FAB2_LIB.BASEBOARD_FAB2(SCH_1):PAGE116
     2    GND @BASEBOARD_FAB2_LIB.BASEBOARD_FAB2(SCH_1):GND   I235 @BASEBOARD_FAB2_LIB.BASEBOARD_FAB2(SCH_1):PAGE116

R3M9 RES_0402-100.0K,1%,1/16W,CHIP,A
     1 P2E_SSB_BMC_RX_C_DN @BASEBOARD_FAB2_LIB.BASEBOARD_FAB2(SCH_1):P2E_SSB_BMC_RX_C_DN   I234 @BASEBOARD_FAB2_LIB.BASEBOARD_FAB2(SCH_1):PAGE116
     2    GND @BASEBOARD_FAB2_LIB.BASEBOARD_FAB2(SCH_1):GND   I234 @BASEBOARD_FAB2_LIB.BASEBOARD_FAB2(SCH_1):PAGE116

R3M10 RES_0402-1.00K,1%,1/16W,CHIP,GA
     1 XDP_PCH_CPU_TCK0 @BASEBOARD_FAB2_LIB.BASEBOARD_FAB2(SCH_1):XDP_PCH_CPU_TCK0    I85 @BASEBOARD_FAB2_LIB.BASEBOARD_FAB2(SCH_1):PAGE112
     2    GND @BASEBOARD_FAB2_LIB.BASEBOARD_FAB2(SCH_1):GND    I85 @BASEBOARD_FAB2_LIB.BASEBOARD_FAB2(SCH_1):PAGE112

R3M11 RES_0402-100.0,1%,1/16W,CHIP,GA
     1 A_PCIE_RCOMP_P @BASEBOARD_FAB2_LIB.BASEBOARD_FAB2(SCH_1):A_PCIE_RCOMP_P   I108 @BASEBOARD_FAB2_LIB.BASEBOARD_FAB2(SCH_1):PAGE116
     2 A_PCIE_RCOMP_N @BASEBOARD_FAB2_LIB.BASEBOARD_FAB2(SCH_1):A_PCIE_RCOMP_N   I108 @BASEBOARD_FAB2_LIB.BASEBOARD_FAB2(SCH_1):PAGE116

R3M12 RES_0402-100.0,1%,1/16W,CHIP,GA
     1 A_PCIEUP_RCOMP_P @BASEBOARD_FAB2_LIB.BASEBOARD_FAB2(SCH_1):A_PCIEUP_RCOMP_P   I181 @BASEBOARD_FAB2_LIB.BASEBOARD_FAB2(SCH_1):PAGE116
     2 A_PCIEUP_RCOMP_N @BASEBOARD_FAB2_LIB.BASEBOARD_FAB2(SCH_1):A_PCIEUP_RCOMP_N   I181 @BASEBOARD_FAB2_LIB.BASEBOARD_FAB2(SCH_1):PAGE116

R3N1 RES_0402-169,1.0%,1/16W,CHIP,GA
     1 A_PCH_XCLK_BIASREF @BASEBOARD_FAB2_LIB.BASEBOARD_FAB2(SCH_1):A_PCH_XCLK_BIASREF   I149 @BASEBOARD_FAB2_LIB.BASEBOARD_FAB2(SCH_1):PAGE114
     2    GND @BASEBOARD_FAB2_LIB.BASEBOARD_FAB2(SCH_1):GND   I149 @BASEBOARD_FAB2_LIB.BASEBOARD_FAB2(SCH_1):PAGE114

R3N2 RES_0402-4.75K,1%,1/16W,EMPTY,A
     1 P3V3_STBY @BASEBOARD_FAB2_LIB.BASEBOARD_FAB2(SCH_1):P3V3_STBY    I72 @BASEBOARD_FAB2_LIB.BASEBOARD_FAB2(SCH_1):PAGE125
     2 FM_FLASH_DESC_OVERRIDE @BASEBOARD_FAB2_LIB.BASEBOARD_FAB2(SCH_1):FM_FLASH_DESC_OVERRIDE    I72 @BASEBOARD_FAB2_LIB.BASEBOARD_FAB2(SCH_1):PAGE125

R3N3 RES_0402-2.0K,1%,1/16W,CHIP,G2A
     1    GND @BASEBOARD_FAB2_LIB.BASEBOARD_FAB2(SCH_1):GND   I120 @BASEBOARD_FAB2_LIB.BASEBOARD_FAB2(SCH_1):PAGE133
     2 PWRGD_PCH_PWROK @BASEBOARD_FAB2_LIB.BASEBOARD_FAB2(SCH_1):PWRGD_PCH_PWROK   I120 @BASEBOARD_FAB2_LIB.BASEBOARD_FAB2(SCH_1):PAGE133

R3N4 RES_0402-20.0K,1%,1/16W,CHIP,GA
     1 P3V3_RTC_STBY @BASEBOARD_FAB2_LIB.BASEBOARD_FAB2(SCH_1):P3V3_RTC_STBY    I19 @BASEBOARD_FAB2_LIB.BASEBOARD_FAB2(SCH_1):PAGE137
     2 RST_SRTCRST_N @BASEBOARD_FAB2_LIB.BASEBOARD_FAB2(SCH_1):RST_SRTCRST_N    I19 @BASEBOARD_FAB2_LIB.BASEBOARD_FAB2(SCH_1):PAGE137

R3N7 RES_0402-1.0,1%,1/16W,CHIP,G21A
     1 VR_PVCCIO_CPU0_PH1_VCIN @BASEBOARD_FAB2_LIB.BASEBOARD_FAB2(SCH_1):VR_PVCCIO_CPU0_PH1_VCIN    I32 @BASEBOARD_FAB2_LIB.BASEBOARD_FAB2(SCH_1):PAGE212
     2 P5V_STBY @BASEBOARD_FAB2_LIB.BASEBOARD_FAB2(SCH_1):P5V_STBY    I32 @BASEBOARD_FAB2_LIB.BASEBOARD_FAB2(SCH_1):PAGE212

R3N9 RES_0402-10.0,1%,1/16W,CHIP,G2A
     1 H_PM_SYNC1_GTL_R @BASEBOARD_FAB2_LIB.BASEBOARD_FAB2(SCH_1):H_PM_SYNC1_GTL_R    I66 @BASEBOARD_FAB2_LIB.BASEBOARD_FAB2(SCH_1):PAGE118
     2 H_PM_SYNC_GTL @BASEBOARD_FAB2_LIB.BASEBOARD_FAB2(SCH_1):H_PM_SYNC_GTL    I66 @BASEBOARD_FAB2_LIB.BASEBOARD_FAB2(SCH_1):PAGE118

R3N10 RES_0402-10.0K,1%,1/16W,CHIP,GA
     1 P3V3_STBY @BASEBOARD_FAB2_LIB.BASEBOARD_FAB2(SCH_1):P3V3_STBY    I37 @BASEBOARD_FAB2_LIB.BASEBOARD_FAB2(SCH_1):PAGE121
     2 FM_INTRUDER_HDR_PCH_N @BASEBOARD_FAB2_LIB.BASEBOARD_FAB2(SCH_1):FM_INTRUDER_HDR_PCH_N    I37 @BASEBOARD_FAB2_LIB.BASEBOARD_FAB2(SCH_1):PAGE121

R3N11 RES_0402-4.75K,1%,1/16W,CHIP,GA
     1 P3V3_STBY @BASEBOARD_FAB2_LIB.BASEBOARD_FAB2(SCH_1):P3V3_STBY   I344 @BASEBOARD_FAB2_LIB.BASEBOARD_FAB2(SCH_1):PAGE157
     2 FM_MP_PS_REDUNDANT_LOST_N @BASEBOARD_FAB2_LIB.BASEBOARD_FAB2(SCH_1):FM_MP_PS_REDUNDANT_LOST_N   I344 @BASEBOARD_FAB2_LIB.BASEBOARD_FAB2(SCH_1):PAGE157

R3N12 RES_0402-4.75K,1%,1/16W,CHIP,GA
     1 P3V3_STBY @BASEBOARD_FAB2_LIB.BASEBOARD_FAB2(SCH_1):P3V3_STBY   I342 @BASEBOARD_FAB2_LIB.BASEBOARD_FAB2(SCH_1):PAGE157
     2 FM_MP_PS_FAIL_N @BASEBOARD_FAB2_LIB.BASEBOARD_FAB2(SCH_1):FM_MP_PS_FAIL_N   I342 @BASEBOARD_FAB2_LIB.BASEBOARD_FAB2(SCH_1):PAGE157

R3N13 RES_0402-4.75K,1%,1/16W,CHIP,GA
     1 P3V3_STBY @BASEBOARD_FAB2_LIB.BASEBOARD_FAB2(SCH_1):P3V3_STBY    I71 @BASEBOARD_FAB2_LIB.BASEBOARD_FAB2(SCH_1):PAGE118
     2 IRQ_LVC3_WAKE_N @BASEBOARD_FAB2_LIB.BASEBOARD_FAB2(SCH_1):IRQ_LVC3_WAKE_N    I71 @BASEBOARD_FAB2_LIB.BASEBOARD_FAB2(SCH_1):PAGE118

R3N14 RES_0402-49.9,1%,1/16W,EMPTY,GA
     1 H_PM_SYNC_GTL @BASEBOARD_FAB2_LIB.BASEBOARD_FAB2(SCH_1):H_PM_SYNC_GTL    I67 @BASEBOARD_FAB2_LIB.BASEBOARD_FAB2(SCH_1):PAGE118
     2    GND @BASEBOARD_FAB2_LIB.BASEBOARD_FAB2(SCH_1):GND    I67 @BASEBOARD_FAB2_LIB.BASEBOARD_FAB2(SCH_1):PAGE118

R3N15 RES_0402-1.00K,1%,1/16W,CHIP,GA
     1 P1V05_PCH_STBY @BASEBOARD_FAB2_LIB.BASEBOARD_FAB2(SCH_1):P1V05_PCH_STBY   I318 @BASEBOARD_FAB2_LIB.BASEBOARD_FAB2(SCH_1):PAGE133
     2 FM_PRSNT_2_4_N @BASEBOARD_FAB2_LIB.BASEBOARD_FAB2(SCH_1):FM_PRSNT_2_4_N   I318 @BASEBOARD_FAB2_LIB.BASEBOARD_FAB2(SCH_1):PAGE133

R3N16 RES_0402-1.00K,1%,1/16W,CHIP,GA
     1 P1V05_PCH_STBY @BASEBOARD_FAB2_LIB.BASEBOARD_FAB2(SCH_1):P1V05_PCH_STBY   I321 @BASEBOARD_FAB2_LIB.BASEBOARD_FAB2(SCH_1):PAGE133
     2 FM_PRSNT_2_5_N @BASEBOARD_FAB2_LIB.BASEBOARD_FAB2(SCH_1):FM_PRSNT_2_5_N   I321 @BASEBOARD_FAB2_LIB.BASEBOARD_FAB2(SCH_1):PAGE133

R3N17 RES_0402-1.00K,1%,1/16W,EMPTY,A
     1 P3V3_STBY @BASEBOARD_FAB2_LIB.BASEBOARD_FAB2(SCH_1):P3V3_STBY    I78 @BASEBOARD_FAB2_LIB.BASEBOARD_FAB2(SCH_1):PAGE125
     2 SPI_PCH_IO3 @BASEBOARD_FAB2_LIB.BASEBOARD_FAB2(SCH_1):SPI_PCH_IO3    I78 @BASEBOARD_FAB2_LIB.BASEBOARD_FAB2(SCH_1):PAGE125

R3N19 RES_0402-10.0,1%,1/16W,CHIP,G2A
     1 VSENSE_PVCCIO_CPU0_AVSP @BASEBOARD_FAB2_LIB.BASEBOARD_FAB2(SCH_1):VSENSE_PVCCIO_CPU0_AVSP    I81 @BASEBOARD_FAB2_LIB.BASEBOARD_FAB2(SCH_1):PAGE211
     2 VR_PVCCIO_CPU0_AVSP @BASEBOARD_FAB2_LIB.BASEBOARD_FAB2(SCH_1):VR_PVCCIO_CPU0_AVSP    I81 @BASEBOARD_FAB2_LIB.BASEBOARD_FAB2(SCH_1):PAGE211

R3N20 RES_0402-100.0,1%,1/16W,CHIP,GA
     1 VSENSE_PVCCIO_CPU0_AVSN @BASEBOARD_FAB2_LIB.BASEBOARD_FAB2(SCH_1):VSENSE_PVCCIO_CPU0_AVSN    I68 @BASEBOARD_FAB2_LIB.BASEBOARD_FAB2(SCH_1):PAGE212
     2    GND @BASEBOARD_FAB2_LIB.BASEBOARD_FAB2(SCH_1):GND    I68 @BASEBOARD_FAB2_LIB.BASEBOARD_FAB2(SCH_1):PAGE212

R3N21 RES_0402-100.0,1%,1/16W,CHIP,GA
     1 VSENSE_PVCCIO_CPU0_AVSP @BASEBOARD_FAB2_LIB.BASEBOARD_FAB2(SCH_1):VSENSE_PVCCIO_CPU0_AVSP    I74 @BASEBOARD_FAB2_LIB.BASEBOARD_FAB2(SCH_1):PAGE212
     2 PVCCIO_CPU0 @BASEBOARD_FAB2_LIB.BASEBOARD_FAB2(SCH_1):PVCCIO_CPU0    I74 @BASEBOARD_FAB2_LIB.BASEBOARD_FAB2(SCH_1):PAGE212

R3N22 RES_0402-4.02K,1%,1/16W,CHIP,GA
     1 VR_PVCCIO_CPU0_XADDR2 @BASEBOARD_FAB2_LIB.BASEBOARD_FAB2(SCH_1):VR_PVCCIO_CPU0_XADDR2    I65 @BASEBOARD_FAB2_LIB.BASEBOARD_FAB2(SCH_1):PAGE211
     2    GND @BASEBOARD_FAB2_LIB.BASEBOARD_FAB2(SCH_1):GND    I65 @BASEBOARD_FAB2_LIB.BASEBOARD_FAB2(SCH_1):PAGE211

R3N23 RES_0402-2.26K,1.0%,1/16W,EMPTA
     1 P3V3_STBY @BASEBOARD_FAB2_LIB.BASEBOARD_FAB2(SCH_1):P3V3_STBY    I60 @BASEBOARD_FAB2_LIB.BASEBOARD_FAB2(SCH_1):PAGE211
     2 PU_VR_PVCCIO_CPU0_FAULT1 @BASEBOARD_FAB2_LIB.BASEBOARD_FAB2(SCH_1):PU_VR_PVCCIO_CPU0_FAULT1    I60 @BASEBOARD_FAB2_LIB.BASEBOARD_FAB2(SCH_1):PAGE211

R3N24 RES_0402-33.2,1%,1/16W,CHIP,G2A
     1 LPC_LAD2_IO2 @BASEBOARD_FAB2_LIB.BASEBOARD_FAB2(SCH_1):LPC_LAD2_IO2    I74 @BASEBOARD_FAB2_LIB.BASEBOARD_FAB2(SCH_1):PAGE146
     2 LPC_LAD2_IO2_R @BASEBOARD_FAB2_LIB.BASEBOARD_FAB2(SCH_1):LPC_LAD2_IO2_R    I74 @BASEBOARD_FAB2_LIB.BASEBOARD_FAB2(SCH_1):PAGE146

R3N26 RES_0402-33.2,1%,1/16W,CHIP,G2A
     1 LPC_LAD0_IO0 @BASEBOARD_FAB2_LIB.BASEBOARD_FAB2(SCH_1):LPC_LAD0_IO0    I75 @BASEBOARD_FAB2_LIB.BASEBOARD_FAB2(SCH_1):PAGE146
     2 LPC_LAD0_IO0_R @BASEBOARD_FAB2_LIB.BASEBOARD_FAB2(SCH_1):LPC_LAD0_IO0_R    I75 @BASEBOARD_FAB2_LIB.BASEBOARD_FAB2(SCH_1):PAGE146

R3N29 RES_0402-16K,1.0%,1/16W,CHIP,GA
     1 VR_PVCCIOMCP_CPU0_XADDR1 @BASEBOARD_FAB2_LIB.BASEBOARD_FAB2(SCH_1):VR_PVCCIOMCP_CPU0_XADDR1   I156 @BASEBOARD_FAB2_LIB.BASEBOARD_FAB2(SCH_1):PAGE194
     2    GND @BASEBOARD_FAB2_LIB.BASEBOARD_FAB2(SCH_1):GND   I156 @BASEBOARD_FAB2_LIB.BASEBOARD_FAB2(SCH_1):PAGE194

R3N30 RES_0402-0.0,5%,1/16W,EMPTY,G2A
     1 H_CPU0_MEMABC_MEMHOT_LVT3_N @BASEBOARD_FAB2_LIB.BASEBOARD_FAB2(SCH_1):H_CPU0_MEMABC_MEMHOT_LVT3_N    I95 @BASEBOARD_FAB2_LIB.BASEBOARD_FAB2(SCH_1):PAGE152
     2 H_CPU0_MEMABC_MEMHOT_PCH_N @BASEBOARD_FAB2_LIB.BASEBOARD_FAB2(SCH_1):H_CPU0_MEMABC_MEMHOT_PCH_N    I95 @BASEBOARD_FAB2_LIB.BASEBOARD_FAB2(SCH_1):PAGE152

R3N31 RES_0402-3.16K,1%,1/16W,CHIP,GA
     1 VR_PVCCIO_CPU0_XADDR1 @BASEBOARD_FAB2_LIB.BASEBOARD_FAB2(SCH_1):VR_PVCCIO_CPU0_XADDR1    I52 @BASEBOARD_FAB2_LIB.BASEBOARD_FAB2(SCH_1):PAGE211
     2    GND @BASEBOARD_FAB2_LIB.BASEBOARD_FAB2(SCH_1):GND    I52 @BASEBOARD_FAB2_LIB.BASEBOARD_FAB2(SCH_1):PAGE211

R3P1 RES_0402-0.0,5%,1/16W,CHIP,G21A
     1 SVID_ALERT_PVCCIO_CPU0 @BASEBOARD_FAB2_LIB.BASEBOARD_FAB2(SCH_1):SVID_ALERT_PVCCIO_CPU0    I61 @BASEBOARD_FAB2_LIB.BASEBOARD_FAB2(SCH_1):PAGE211
     2 SVID_ALERT0_CPU0_R_N @BASEBOARD_FAB2_LIB.BASEBOARD_FAB2(SCH_1):SVID_ALERT0_CPU0_R_N    I61 @BASEBOARD_FAB2_LIB.BASEBOARD_FAB2(SCH_1):PAGE211

R3P2 RES_0402-0.0,5%,1/16W,CHIP,G21A
     1 RMII_BMC_PCH_SPRNGVLLE_CRSDV @BASEBOARD_FAB2_LIB.BASEBOARD_FAB2(SCH_1):RMII_BMC_PCH_SPRNGVLLE_CRSDV    I90 @BASEBOARD_FAB2_LIB.BASEBOARD_FAB2(SCH_1):PAGE121
     2 RMII_BMC_PCH_SPRNGVLLE_CRSDV_R1 @BASEBOARD_FAB2_LIB.BASEBOARD_FAB2(SCH_1):RMII_BMC_PCH_SPRNGVLLE_CRSDV_R1    I90 @BASEBOARD_FAB2_LIB.BASEBOARD_FAB2(SCH_1):PAGE121

R3P3 RES_0402-0.0,5%,1/16W,CHIP,G21A
     1 RMII_SPRNGVLLE_BMC_PCH_RXD0 @BASEBOARD_FAB2_LIB.BASEBOARD_FAB2(SCH_1):RMII_SPRNGVLLE_BMC_PCH_RXD0    I89 @BASEBOARD_FAB2_LIB.BASEBOARD_FAB2(SCH_1):PAGE121
     2 RMII_SPRNGVLLE_BMC_PCH_RXD0_R1 @BASEBOARD_FAB2_LIB.BASEBOARD_FAB2(SCH_1):RMII_SPRNGVLLE_BMC_PCH_RXD0_R1    I89 @BASEBOARD_FAB2_LIB.BASEBOARD_FAB2(SCH_1):PAGE121

R3P5 RES_0402-1.00K,1%,1/16W,CHIP,GA
     1 P1V05_PCH_STBY @BASEBOARD_FAB2_LIB.BASEBOARD_FAB2(SCH_1):P1V05_PCH_STBY   I316 @BASEBOARD_FAB2_LIB.BASEBOARD_FAB2(SCH_1):PAGE133
     2 FM_PRSNT_2_2_N @BASEBOARD_FAB2_LIB.BASEBOARD_FAB2(SCH_1):FM_PRSNT_2_2_N   I316 @BASEBOARD_FAB2_LIB.BASEBOARD_FAB2(SCH_1):PAGE133

R3P6 RES_0402-1.00K,1%,1/16W,CHIP,GA
     1 P1V05_PCH_STBY @BASEBOARD_FAB2_LIB.BASEBOARD_FAB2(SCH_1):P1V05_PCH_STBY   I317 @BASEBOARD_FAB2_LIB.BASEBOARD_FAB2(SCH_1):PAGE133
     2 FM_PRSNT_2_3_N @BASEBOARD_FAB2_LIB.BASEBOARD_FAB2(SCH_1):FM_PRSNT_2_3_N   I317 @BASEBOARD_FAB2_LIB.BASEBOARD_FAB2(SCH_1):PAGE133

R3P7 RES_0402-1.00K,1%,1/16W,CHIP,GA
     1 P1V05_PCH_STBY @BASEBOARD_FAB2_LIB.BASEBOARD_FAB2(SCH_1):P1V05_PCH_STBY   I315 @BASEBOARD_FAB2_LIB.BASEBOARD_FAB2(SCH_1):PAGE133
     2 FM_PRSNT_2_1_N @BASEBOARD_FAB2_LIB.BASEBOARD_FAB2(SCH_1):FM_PRSNT_2_1_N   I315 @BASEBOARD_FAB2_LIB.BASEBOARD_FAB2(SCH_1):PAGE133

R3P8 RES_0402-1.00K,1%,1/16W,CHIP,GA
     1 P1V05_PCH_STBY @BASEBOARD_FAB2_LIB.BASEBOARD_FAB2(SCH_1):P1V05_PCH_STBY   I322 @BASEBOARD_FAB2_LIB.BASEBOARD_FAB2(SCH_1):PAGE133
     2 FM_PRSNT_2_6_N @BASEBOARD_FAB2_LIB.BASEBOARD_FAB2(SCH_1):FM_PRSNT_2_6_N   I322 @BASEBOARD_FAB2_LIB.BASEBOARD_FAB2(SCH_1):PAGE133

R3P11 RES_0402-0.0,5%,1/16W,CHIP,G21A
     1 SVID_DIO0_CPU0_R @BASEBOARD_FAB2_LIB.BASEBOARD_FAB2(SCH_1):SVID_DIO0_CPU0_R    I16 @BASEBOARD_FAB2_LIB.BASEBOARD_FAB2(SCH_1):PAGE211
     2 SVID_VDIO_PVCCIO_CPU0 @BASEBOARD_FAB2_LIB.BASEBOARD_FAB2(SCH_1):SVID_VDIO_PVCCIO_CPU0    I16 @BASEBOARD_FAB2_LIB.BASEBOARD_FAB2(SCH_1):PAGE211

R3P12 RES_0402-100.0K,1%,1/16W,CHIP,B
     1 VR_FET_SW_P12V_STBY_PVCCIO_CPU0 @BASEBOARD_FAB2_LIB.BASEBOARD_FAB2(SCH_1):VR_FET_SW_P12V_STBY_PVCCIO_CPU0    I31 @BASEBOARD_FAB2_LIB.BASEBOARD_FAB2(SCH_1):PAGE211
     2 VR_PVCCIO_CPU0_VINSEN @BASEBOARD_FAB2_LIB.BASEBOARD_FAB2(SCH_1):VR_PVCCIO_CPU0_VINSEN    I31 @BASEBOARD_FAB2_LIB.BASEBOARD_FAB2(SCH_1):PAGE211

R3P13 RES_0402-100.0,1%,1/16W,EMPTY,A
     1 PVCCIO_CPU0 @BASEBOARD_FAB2_LIB.BASEBOARD_FAB2(SCH_1):PVCCIO_CPU0    I17 @BASEBOARD_FAB2_LIB.BASEBOARD_FAB2(SCH_1):PAGE211
     2 SVID_DIO0_CPU0_R @BASEBOARD_FAB2_LIB.BASEBOARD_FAB2(SCH_1):SVID_DIO0_CPU0_R    I17 @BASEBOARD_FAB2_LIB.BASEBOARD_FAB2(SCH_1):PAGE211

R3P15 RES_0402-150.0,1%,1/16W,CHIP,GA
     1 SVID_CLK0_CPU0_R @BASEBOARD_FAB2_LIB.BASEBOARD_FAB2(SCH_1):SVID_CLK0_CPU0_R    I29 @BASEBOARD_FAB2_LIB.BASEBOARD_FAB2(SCH_1):PAGE211
     2 SVID_CLK_PVCCIO_CPU0 @BASEBOARD_FAB2_LIB.BASEBOARD_FAB2(SCH_1):SVID_CLK_PVCCIO_CPU0    I29 @BASEBOARD_FAB2_LIB.BASEBOARD_FAB2(SCH_1):PAGE211

R3P16 RES_0402-1.5K,1%,1/16W,CHIP,G2A
     1 VR_PVCCIO_CPU0_VINSEN @BASEBOARD_FAB2_LIB.BASEBOARD_FAB2(SCH_1):VR_PVCCIO_CPU0_VINSEN    I32 @BASEBOARD_FAB2_LIB.BASEBOARD_FAB2(SCH_1):PAGE211
     2    GND @BASEBOARD_FAB2_LIB.BASEBOARD_FAB2(SCH_1):GND    I32 @BASEBOARD_FAB2_LIB.BASEBOARD_FAB2(SCH_1):PAGE211

R3P17 RES_0402-49.9,1%,1/16W,EMPTY,GA
     1 PVCCIO_CPU0 @BASEBOARD_FAB2_LIB.BASEBOARD_FAB2(SCH_1):PVCCIO_CPU0    I28 @BASEBOARD_FAB2_LIB.BASEBOARD_FAB2(SCH_1):PAGE211
     2 SVID_CLK0_CPU0_R @BASEBOARD_FAB2_LIB.BASEBOARD_FAB2(SCH_1):SVID_CLK0_CPU0_R    I28 @BASEBOARD_FAB2_LIB.BASEBOARD_FAB2(SCH_1):PAGE211

R3P18 RES_0402-1.00K,1%,1/16W,CHIP,GA
     1 P3V3_STBY @BASEBOARD_FAB2_LIB.BASEBOARD_FAB2(SCH_1):P3V3_STBY    I64 @BASEBOARD_FAB2_LIB.BASEBOARD_FAB2(SCH_1):PAGE211
     2 IRQ_PVCCIO_CPU0_VRHOT_N @BASEBOARD_FAB2_LIB.BASEBOARD_FAB2(SCH_1):IRQ_PVCCIO_CPU0_VRHOT_N    I64 @BASEBOARD_FAB2_LIB.BASEBOARD_FAB2(SCH_1):PAGE211

R3P20 RES_0402-22.1,1.0%,1/16W,CHIP,A
     1 PWRGD_PVCCIO_CPU0_R @BASEBOARD_FAB2_LIB.BASEBOARD_FAB2(SCH_1):PWRGD_PVCCIO_CPU0_R    I58 @BASEBOARD_FAB2_LIB.BASEBOARD_FAB2(SCH_1):PAGE211
     2 PWRGD_PVCCIO_CPU0 @BASEBOARD_FAB2_LIB.BASEBOARD_FAB2(SCH_1):PWRGD_PVCCIO_CPU0    I58 @BASEBOARD_FAB2_LIB.BASEBOARD_FAB2(SCH_1):PAGE211

R3P21 RES_0402-100.0K,1%,1/16W,EMPTYA
     1 P3V3_STBY @BASEBOARD_FAB2_LIB.BASEBOARD_FAB2(SCH_1):P3V3_STBY    I88 @BASEBOARD_FAB2_LIB.BASEBOARD_FAB2(SCH_1):PAGE211
     2 VR_PVCCIO_CPU0_EN @BASEBOARD_FAB2_LIB.BASEBOARD_FAB2(SCH_1):VR_PVCCIO_CPU0_EN    I88 @BASEBOARD_FAB2_LIB.BASEBOARD_FAB2(SCH_1):PAGE211

R3P22 RES_0402-0.0,5%,1/16W,CHIP,G21A
     1 P3V3_STBY @BASEBOARD_FAB2_LIB.BASEBOARD_FAB2(SCH_1):P3V3_STBY    I24 @BASEBOARD_FAB2_LIB.BASEBOARD_FAB2(SCH_1):PAGE211
     2 VR_PVCCIO_CPU0_VDD @BASEBOARD_FAB2_LIB.BASEBOARD_FAB2(SCH_1):VR_PVCCIO_CPU0_VDD    I24 @BASEBOARD_FAB2_LIB.BASEBOARD_FAB2(SCH_1):PAGE211

R3P23 RES_0402-20.0,1%,1/16W,CHIP,G2A
     1 SMB_VR_STBY_LVC3_SDA @BASEBOARD_FAB2_LIB.BASEBOARD_FAB2(SCH_1):SMB_VR_STBY_LVC3_SDA    I47 @BASEBOARD_FAB2_LIB.BASEBOARD_FAB2(SCH_1):PAGE211
     2 SMB_VR_SDA_PVCCIO_CPU0 @BASEBOARD_FAB2_LIB.BASEBOARD_FAB2(SCH_1):SMB_VR_SDA_PVCCIO_CPU0    I47 @BASEBOARD_FAB2_LIB.BASEBOARD_FAB2(SCH_1):PAGE211

R3P24 RES_0402-20.0,1%,1/16W,CHIP,G2A
     1 SMB_VR_STBY_LVC3_SCL @BASEBOARD_FAB2_LIB.BASEBOARD_FAB2(SCH_1):SMB_VR_STBY_LVC3_SCL    I46 @BASEBOARD_FAB2_LIB.BASEBOARD_FAB2(SCH_1):PAGE211
     2 SMB_VR_SCL_PVCCIO_CPU0 @BASEBOARD_FAB2_LIB.BASEBOARD_FAB2(SCH_1):SMB_VR_SCL_PVCCIO_CPU0    I46 @BASEBOARD_FAB2_LIB.BASEBOARD_FAB2(SCH_1):PAGE211

R3P25 RES_0402-1.00K,1%,1/16W,CHIP,GA
     1 P3V3_STBY @BASEBOARD_FAB2_LIB.BASEBOARD_FAB2(SCH_1):P3V3_STBY    I56 @BASEBOARD_FAB2_LIB.BASEBOARD_FAB2(SCH_1):PAGE211
     2 PWRGD_PVCCIO_CPU0_R @BASEBOARD_FAB2_LIB.BASEBOARD_FAB2(SCH_1):PWRGD_PVCCIO_CPU0_R    I56 @BASEBOARD_FAB2_LIB.BASEBOARD_FAB2(SCH_1):PAGE211

R3P26 RES_0402-0.0,5%,1/16W,CHIP,G21A
     1 FM_PVCCIO_CPU0_EN @BASEBOARD_FAB2_LIB.BASEBOARD_FAB2(SCH_1):FM_PVCCIO_CPU0_EN    I87 @BASEBOARD_FAB2_LIB.BASEBOARD_FAB2(SCH_1):PAGE211
     2 VR_PVCCIO_CPU0_EN @BASEBOARD_FAB2_LIB.BASEBOARD_FAB2(SCH_1):VR_PVCCIO_CPU0_EN    I87 @BASEBOARD_FAB2_LIB.BASEBOARD_FAB2(SCH_1):PAGE211

R3P29 RES_0402-64.9,1.0%,1/16W,CHIP,A
     1 PVDDQ_DEF @BASEBOARD_FAB2_LIB.BASEBOARD_FAB2(SCH_1):PVDDQ_DEF     I5 @BASEBOARD_FAB2_LIB.BASEBOARD_FAB2(SCH_1):PAGE96
     2 PWRGD_CPU0_DRAMPWROK_DEF_G @BASEBOARD_FAB2_LIB.BASEBOARD_FAB2(SCH_1):PWRGD_CPU0_DRAMPWROK_DEF_G     I5 @BASEBOARD_FAB2_LIB.BASEBOARD_FAB2(SCH_1):PAGE96

R3P32 RES_0402-1.00K,1%,1/16W,CHIP,GA
     1    GND @BASEBOARD_FAB2_LIB.BASEBOARD_FAB2(SCH_1):GND    I71 @BASEBOARD_FAB2_LIB.BASEBOARD_FAB2(SCH_1):PAGE96
     2 PD_GTL2014_1_VREF @BASEBOARD_FAB2_LIB.BASEBOARD_FAB2(SCH_1):PD_GTL2014_1_VREF    I71 @BASEBOARD_FAB2_LIB.BASEBOARD_FAB2(SCH_1):PAGE96

R3P34 RES_0402-0.0,5%,1/16W,CHIP,G21A
     1 RST_CPU0_LVC3_R1_N @BASEBOARD_FAB2_LIB.BASEBOARD_FAB2(SCH_1):RST_CPU0_LVC3_R1_N   I116 @BASEBOARD_FAB2_LIB.BASEBOARD_FAB2(SCH_1):PAGE190
     2 RST_CPU0_LVC3_N @BASEBOARD_FAB2_LIB.BASEBOARD_FAB2(SCH_1):RST_CPU0_LVC3_N   I116 @BASEBOARD_FAB2_LIB.BASEBOARD_FAB2(SCH_1):PAGE190

R3P35 RES_0402-0.0,5%,1/16W,CHIP,G21A
     1 RST_CPU1_LVC3_R1_N @BASEBOARD_FAB2_LIB.BASEBOARD_FAB2(SCH_1):RST_CPU1_LVC3_R1_N   I117 @BASEBOARD_FAB2_LIB.BASEBOARD_FAB2(SCH_1):PAGE190
     2 RST_CPU1_LVC3_N @BASEBOARD_FAB2_LIB.BASEBOARD_FAB2(SCH_1):RST_CPU1_LVC3_N   I117 @BASEBOARD_FAB2_LIB.BASEBOARD_FAB2(SCH_1):PAGE190

R3P36 RES_0402-1.00K,1%,1/16W,CHIP,GA
     1 P3V3_STBY @BASEBOARD_FAB2_LIB.BASEBOARD_FAB2(SCH_1):P3V3_STBY    I36 @BASEBOARD_FAB2_LIB.BASEBOARD_FAB2(SCH_1):PAGE96
     2 PU_GTL2014_1_DIR @BASEBOARD_FAB2_LIB.BASEBOARD_FAB2(SCH_1):PU_GTL2014_1_DIR    I36 @BASEBOARD_FAB2_LIB.BASEBOARD_FAB2(SCH_1):PAGE96

R3P38 RES_0402-64.9,1.0%,1/16W,CHIP,A
     1 PVDDQ_ABC @BASEBOARD_FAB2_LIB.BASEBOARD_FAB2(SCH_1):PVDDQ_ABC     I7 @BASEBOARD_FAB2_LIB.BASEBOARD_FAB2(SCH_1):PAGE96
     2 PWRGD_CPU0_DRAMPWROK_ABC_G @BASEBOARD_FAB2_LIB.BASEBOARD_FAB2(SCH_1):PWRGD_CPU0_DRAMPWROK_ABC_G     I7 @BASEBOARD_FAB2_LIB.BASEBOARD_FAB2(SCH_1):PAGE96

R3P41 RES_0402-75,1.0%,1/16W,CHIP,G2A
     1 PVCCIO_CPU1 @BASEBOARD_FAB2_LIB.BASEBOARD_FAB2(SCH_1):PVCCIO_CPU1     I9 @BASEBOARD_FAB2_LIB.BASEBOARD_FAB2(SCH_1):PAGE92
     2 H_CPU1_THERMTRIP_G_N @BASEBOARD_FAB2_LIB.BASEBOARD_FAB2(SCH_1):H_CPU1_THERMTRIP_G_N     I9 @BASEBOARD_FAB2_LIB.BASEBOARD_FAB2(SCH_1):PAGE92

R3P42 RES_0402-33.2,1%,1/16W,CHIP,G2A
     1 FM_CPU1_THERMTRIP_LVT3_R_N @BASEBOARD_FAB2_LIB.BASEBOARD_FAB2(SCH_1):FM_CPU1_THERMTRIP_LVT3_R_N    I14 @BASEBOARD_FAB2_LIB.BASEBOARD_FAB2(SCH_1):PAGE92
     2 FM_CPU1_THERMTRIP_LVT3_N @BASEBOARD_FAB2_LIB.BASEBOARD_FAB2(SCH_1):FM_CPU1_THERMTRIP_LVT3_N    I14 @BASEBOARD_FAB2_LIB.BASEBOARD_FAB2(SCH_1):PAGE92

R3P43 RES_0402-33.2,1%,1/16W,CHIP,G2A
     1 FM_CPU_CATERR_LVT3_R2_N @BASEBOARD_FAB2_LIB.BASEBOARD_FAB2(SCH_1):FM_CPU_CATERR_LVT3_R2_N    I13 @BASEBOARD_FAB2_LIB.BASEBOARD_FAB2(SCH_1):PAGE92
     2 FM_CPU_CATERR_LVT3_N @BASEBOARD_FAB2_LIB.BASEBOARD_FAB2(SCH_1):FM_CPU_CATERR_LVT3_N    I13 @BASEBOARD_FAB2_LIB.BASEBOARD_FAB2(SCH_1):PAGE92

R3P44 RES_0402-4.75K,1%,1/16W,CHIP,GA
     1 P3V3_STBY @BASEBOARD_FAB2_LIB.BASEBOARD_FAB2(SCH_1):P3V3_STBY    I59 @BASEBOARD_FAB2_LIB.BASEBOARD_FAB2(SCH_1):PAGE196
     2 PWRGD_DSW_PWROK @BASEBOARD_FAB2_LIB.BASEBOARD_FAB2(SCH_1):PWRGD_DSW_PWROK    I59 @BASEBOARD_FAB2_LIB.BASEBOARD_FAB2(SCH_1):PAGE196

R3P45 RES_0402-49.9,1%,1/16W,CHIP,G2A
     1 PVCCIO_CPU0 @BASEBOARD_FAB2_LIB.BASEBOARD_FAB2(SCH_1):PVCCIO_CPU0    I39 @BASEBOARD_FAB2_LIB.BASEBOARD_FAB2(SCH_1):PAGE92
     2 P0V7_GTL2104_VREF_1 @BASEBOARD_FAB2_LIB.BASEBOARD_FAB2(SCH_1):P0V7_GTL2104_VREF_1    I39 @BASEBOARD_FAB2_LIB.BASEBOARD_FAB2(SCH_1):PAGE92

R3P46 RES_0402-33.2,1%,1/16W,CHIP,G2A
     1 FM_CPU1_FIVR_FAULT_R_LVT3 @BASEBOARD_FAB2_LIB.BASEBOARD_FAB2(SCH_1):FM_CPU1_FIVR_FAULT_R_LVT3    I12 @BASEBOARD_FAB2_LIB.BASEBOARD_FAB2(SCH_1):PAGE92
     2 FM_CPU1_FIVR_FAULT_LVT3 @BASEBOARD_FAB2_LIB.BASEBOARD_FAB2(SCH_1):FM_CPU1_FIVR_FAULT_LVT3    I12 @BASEBOARD_FAB2_LIB.BASEBOARD_FAB2(SCH_1):PAGE92

R3P48 RES_0402-90.9K,1%,1/16W,CHIP,GA
     1 P12V_STBY @BASEBOARD_FAB2_LIB.BASEBOARD_FAB2(SCH_1):P12V_STBY    I74 @BASEBOARD_FAB2_LIB.BASEBOARD_FAB2(SCH_1):PAGE196
     2 VSENSE_P12V_ADM1085 @BASEBOARD_FAB2_LIB.BASEBOARD_FAB2(SCH_1):VSENSE_P12V_ADM1085    I74 @BASEBOARD_FAB2_LIB.BASEBOARD_FAB2(SCH_1):PAGE196

R3P49 RES_0402-100.0,1%,1/16W,CHIP,GA
     1 P0V7_GTL2104_VREF_1 @BASEBOARD_FAB2_LIB.BASEBOARD_FAB2(SCH_1):P0V7_GTL2104_VREF_1    I38 @BASEBOARD_FAB2_LIB.BASEBOARD_FAB2(SCH_1):PAGE92
     2    GND @BASEBOARD_FAB2_LIB.BASEBOARD_FAB2(SCH_1):GND    I38 @BASEBOARD_FAB2_LIB.BASEBOARD_FAB2(SCH_1):PAGE92

R3P50 RES_0402-10.0K,1%,1/16W,EMPTY,A
     1 P3V3_STBY @BASEBOARD_FAB2_LIB.BASEBOARD_FAB2(SCH_1):P3V3_STBY    I71 @BASEBOARD_FAB2_LIB.BASEBOARD_FAB2(SCH_1):PAGE196
     2 PWRGD_P3V3_STBY @BASEBOARD_FAB2_LIB.BASEBOARD_FAB2(SCH_1):PWRGD_P3V3_STBY    I71 @BASEBOARD_FAB2_LIB.BASEBOARD_FAB2(SCH_1):PAGE196

R3P51 RES_0402-6.34K,1%,1/16W,CHIP,GA
     1 VSENSE_P12V_ADM1085 @BASEBOARD_FAB2_LIB.BASEBOARD_FAB2(SCH_1):VSENSE_P12V_ADM1085    I75 @BASEBOARD_FAB2_LIB.BASEBOARD_FAB2(SCH_1):PAGE196
     2    GND @BASEBOARD_FAB2_LIB.BASEBOARD_FAB2(SCH_1):GND    I75 @BASEBOARD_FAB2_LIB.BASEBOARD_FAB2(SCH_1):PAGE196

R3P53 RES_0402-4.75K,1%,1/16W,CHIP,GA
     1 P1V05_PCH_STBY @BASEBOARD_FAB2_LIB.BASEBOARD_FAB2(SCH_1):P1V05_PCH_STBY   I357 @BASEBOARD_FAB2_LIB.BASEBOARD_FAB2(SCH_1):PAGE133
     2 FM_OCP_MEZZC_PRES_N @BASEBOARD_FAB2_LIB.BASEBOARD_FAB2(SCH_1):FM_OCP_MEZZC_PRES_N   I357 @BASEBOARD_FAB2_LIB.BASEBOARD_FAB2(SCH_1):PAGE133

R3P54 RES_0402-3.32K,1%,1/16W,EMPTY,A
     1 P3V3_STBY @BASEBOARD_FAB2_LIB.BASEBOARD_FAB2(SCH_1):P3V3_STBY   I331 @BASEBOARD_FAB2_LIB.BASEBOARD_FAB2(SCH_1):PAGE156
     2 FM_CPU0_SM_WP @BASEBOARD_FAB2_LIB.BASEBOARD_FAB2(SCH_1):FM_CPU0_SM_WP   I331 @BASEBOARD_FAB2_LIB.BASEBOARD_FAB2(SCH_1):PAGE156

R3P56 RES_0402-1.00K,1%,1/16W,CHIP,GA
     1 FM_CPU0_SM_WP @BASEBOARD_FAB2_LIB.BASEBOARD_FAB2(SCH_1):FM_CPU0_SM_WP   I333 @BASEBOARD_FAB2_LIB.BASEBOARD_FAB2(SCH_1):PAGE156
     2    GND @BASEBOARD_FAB2_LIB.BASEBOARD_FAB2(SCH_1):GND   I333 @BASEBOARD_FAB2_LIB.BASEBOARD_FAB2(SCH_1):PAGE156

R3P57 RES_0402-0.0,5%,1/16W,CHIP,G21A
     1 VR_PVCCIO_CPU0_VD12 @BASEBOARD_FAB2_LIB.BASEBOARD_FAB2(SCH_1):VR_PVCCIO_CPU0_VD12    I91 @BASEBOARD_FAB2_LIB.BASEBOARD_FAB2(SCH_1):PAGE211
     2 VR_PVCCIO_CPU0_AIREF1 @BASEBOARD_FAB2_LIB.BASEBOARD_FAB2(SCH_1):VR_PVCCIO_CPU0_AIREF1    I91 @BASEBOARD_FAB2_LIB.BASEBOARD_FAB2(SCH_1):PAGE211

R3P58 RES_0402-0.0,5%,1/16W,CHIP,G21A
     1 H_CPU1_CATERR_G_N @BASEBOARD_FAB2_LIB.BASEBOARD_FAB2(SCH_1):H_CPU1_CATERR_G_N    I98 @BASEBOARD_FAB2_LIB.BASEBOARD_FAB2(SCH_1):PAGE92
     2 H_CPU_CATERR_G_N @BASEBOARD_FAB2_LIB.BASEBOARD_FAB2(SCH_1):H_CPU_CATERR_G_N    I98 @BASEBOARD_FAB2_LIB.BASEBOARD_FAB2(SCH_1):PAGE92

R3P59 RES_0402-0.0,5%,1/16W,CHIP,G21A
     1 H_CPU0_CATERR_G_N @BASEBOARD_FAB2_LIB.BASEBOARD_FAB2(SCH_1):H_CPU0_CATERR_G_N    I97 @BASEBOARD_FAB2_LIB.BASEBOARD_FAB2(SCH_1):PAGE92
     2 H_CPU_CATERR_G_N @BASEBOARD_FAB2_LIB.BASEBOARD_FAB2(SCH_1):H_CPU_CATERR_G_N    I97 @BASEBOARD_FAB2_LIB.BASEBOARD_FAB2(SCH_1):PAGE92

R3P60 RES_0402-240,1.0%,1/16W,CHIP,GA
     1 PVCCIO_CPU0 @BASEBOARD_FAB2_LIB.BASEBOARD_FAB2(SCH_1):PVCCIO_CPU0    I67 @BASEBOARD_FAB2_LIB.BASEBOARD_FAB2(SCH_1):PAGE99
     2 SMB_DDR_DEF_SCL_G @BASEBOARD_FAB2_LIB.BASEBOARD_FAB2(SCH_1):SMB_DDR_DEF_SCL_G    I67 @BASEBOARD_FAB2_LIB.BASEBOARD_FAB2(SCH_1):PAGE99

R3P61 RES_0402-2.26K,1.0%,1/16W,CHIPA
     1 P3V3_STBY @BASEBOARD_FAB2_LIB.BASEBOARD_FAB2(SCH_1):P3V3_STBY   I201 @BASEBOARD_FAB2_LIB.BASEBOARD_FAB2(SCH_1):PAGE181
     2 FM_MB_SLOT_ID2 @BASEBOARD_FAB2_LIB.BASEBOARD_FAB2(SCH_1):FM_MB_SLOT_ID2   I201 @BASEBOARD_FAB2_LIB.BASEBOARD_FAB2(SCH_1):PAGE181

R3P62 RES_0402-4.75K,1%,1/16W,EMPTY,A
     1 P3V3_STBY @BASEBOARD_FAB2_LIB.BASEBOARD_FAB2(SCH_1):P3V3_STBY    I22 @BASEBOARD_FAB2_LIB.BASEBOARD_FAB2(SCH_1):PAGE126
     2 FM_FLASH_ATTACH_CFG_STRAP @BASEBOARD_FAB2_LIB.BASEBOARD_FAB2(SCH_1):FM_FLASH_ATTACH_CFG_STRAP    I22 @BASEBOARD_FAB2_LIB.BASEBOARD_FAB2(SCH_1):PAGE126

R3P63 RES_0402-0.0,5%,1/16W,EMPTY,G2A
     1 H_CPU1_MEMGHJ_MEMHOT_LVT3_N @BASEBOARD_FAB2_LIB.BASEBOARD_FAB2(SCH_1):H_CPU1_MEMGHJ_MEMHOT_LVT3_N   I100 @BASEBOARD_FAB2_LIB.BASEBOARD_FAB2(SCH_1):PAGE152
     2 H_CPU1_MEMGHJ_MEMHOT_PCH_N @BASEBOARD_FAB2_LIB.BASEBOARD_FAB2(SCH_1):H_CPU1_MEMGHJ_MEMHOT_PCH_N   I100 @BASEBOARD_FAB2_LIB.BASEBOARD_FAB2(SCH_1):PAGE152

R3P64 RES_0402-1.00K,1%,1/16W,EMPTY,A
     1 FM_FLASH_ATTACH_CFG_STRAP @BASEBOARD_FAB2_LIB.BASEBOARD_FAB2(SCH_1):FM_FLASH_ATTACH_CFG_STRAP    I23 @BASEBOARD_FAB2_LIB.BASEBOARD_FAB2(SCH_1):PAGE126
     2    GND @BASEBOARD_FAB2_LIB.BASEBOARD_FAB2(SCH_1):GND    I23 @BASEBOARD_FAB2_LIB.BASEBOARD_FAB2(SCH_1):PAGE126

R3R1 RES_0402-1.00K,1%,1/16W,CHIP,GA
     1 PD_GTL2104_DIR_1 @BASEBOARD_FAB2_LIB.BASEBOARD_FAB2(SCH_1):PD_GTL2104_DIR_1    I46 @BASEBOARD_FAB2_LIB.BASEBOARD_FAB2(SCH_1):PAGE92
     2    GND @BASEBOARD_FAB2_LIB.BASEBOARD_FAB2(SCH_1):GND    I46 @BASEBOARD_FAB2_LIB.BASEBOARD_FAB2(SCH_1):PAGE92

R3R2 RES_0402-1.00K,1%,1/16W,CHIP,GA
     1 H_CPU1_FIVR_FAULT_G @BASEBOARD_FAB2_LIB.BASEBOARD_FAB2(SCH_1):H_CPU1_FIVR_FAULT_G    I75 @BASEBOARD_FAB2_LIB.BASEBOARD_FAB2(SCH_1):PAGE92
     2    GND @BASEBOARD_FAB2_LIB.BASEBOARD_FAB2(SCH_1):GND    I75 @BASEBOARD_FAB2_LIB.BASEBOARD_FAB2(SCH_1):PAGE92

R3R3 RES_0402-33.2,1%,1/16W,CHIP,G2A
     1 PWRGD_CPUPWRGD_R1 @BASEBOARD_FAB2_LIB.BASEBOARD_FAB2(SCH_1):PWRGD_CPUPWRGD_R1    I61 @BASEBOARD_FAB2_LIB.BASEBOARD_FAB2(SCH_1):PAGE92
     2 PWRGD_CPUPWRGD @BASEBOARD_FAB2_LIB.BASEBOARD_FAB2(SCH_1):PWRGD_CPUPWRGD    I61 @BASEBOARD_FAB2_LIB.BASEBOARD_FAB2(SCH_1):PAGE92

R3R4 RES_0402-4.75K,1%,1/16W,CHIP,GA
     1   P3V3 @BASEBOARD_FAB2_LIB.BASEBOARD_FAB2(SCH_1):P3V3    I66 @BASEBOARD_FAB2_LIB.BASEBOARD_FAB2(SCH_1):PAGE94
     2 H_CPU0_MEMDEF_MEMHOT @BASEBOARD_FAB2_LIB.BASEBOARD_FAB2(SCH_1):H_CPU0_MEMDEF_MEMHOT    I66 @BASEBOARD_FAB2_LIB.BASEBOARD_FAB2(SCH_1):PAGE94

R3R5 RES_0402-665,1.0%,1/16W,CHIP,GA
     1 PVPP_DEF @BASEBOARD_FAB2_LIB.BASEBOARD_FAB2(SCH_1):PVPP_DEF   I103 @BASEBOARD_FAB2_LIB.BASEBOARD_FAB2(SCH_1):PAGE99
     2 SMB_DDR_DEF_VPP_SCL_R @BASEBOARD_FAB2_LIB.BASEBOARD_FAB2(SCH_1):SMB_DDR_DEF_VPP_SCL_R   I103 @BASEBOARD_FAB2_LIB.BASEBOARD_FAB2(SCH_1):PAGE99

R3R7 RES_0402-10.0,1%,1/16W,CHIP,G2A
     1 SMB_DDR_DEF_SCL_G_R @BASEBOARD_FAB2_LIB.BASEBOARD_FAB2(SCH_1):SMB_DDR_DEF_SCL_G_R    I88 @BASEBOARD_FAB2_LIB.BASEBOARD_FAB2(SCH_1):PAGE99
     2 SMB_DDR_DEF_SCL_G @BASEBOARD_FAB2_LIB.BASEBOARD_FAB2(SCH_1):SMB_DDR_DEF_SCL_G    I88 @BASEBOARD_FAB2_LIB.BASEBOARD_FAB2(SCH_1):PAGE99

R3R8 RES_0402-20.0,1%,1/16W,CHIP,G2A
     1 SMB_DDR_DEF_VPP_SCL_R @BASEBOARD_FAB2_LIB.BASEBOARD_FAB2(SCH_1):SMB_DDR_DEF_VPP_SCL_R    I35 @BASEBOARD_FAB2_LIB.BASEBOARD_FAB2(SCH_1):PAGE99
     2 SMB_DDR_DEF_VPP_SCL @BASEBOARD_FAB2_LIB.BASEBOARD_FAB2(SCH_1):SMB_DDR_DEF_VPP_SCL    I35 @BASEBOARD_FAB2_LIB.BASEBOARD_FAB2(SCH_1):PAGE99

R3R9 RES_0402-20.0,1%,1/16W,CHIP,G2A
     1 SMB_DDR_DEF_VPP_SDA_R @BASEBOARD_FAB2_LIB.BASEBOARD_FAB2(SCH_1):SMB_DDR_DEF_VPP_SDA_R    I34 @BASEBOARD_FAB2_LIB.BASEBOARD_FAB2(SCH_1):PAGE99
     2 SMB_DDR_DEF_VPP_SDA @BASEBOARD_FAB2_LIB.BASEBOARD_FAB2(SCH_1):SMB_DDR_DEF_VPP_SDA    I34 @BASEBOARD_FAB2_LIB.BASEBOARD_FAB2(SCH_1):PAGE99

R3R10 RES_0402-4.75K,1%,1/16W,CHIP,GA
     1   P3V3 @BASEBOARD_FAB2_LIB.BASEBOARD_FAB2(SCH_1):P3V3    I79 @BASEBOARD_FAB2_LIB.BASEBOARD_FAB2(SCH_1):PAGE94
     2 H_CPU1_MEMGHJ_MEMHOT @BASEBOARD_FAB2_LIB.BASEBOARD_FAB2(SCH_1):H_CPU1_MEMGHJ_MEMHOT    I79 @BASEBOARD_FAB2_LIB.BASEBOARD_FAB2(SCH_1):PAGE94

R3R11 RES_0402-10.0K,1%,1/16W,EMPTY,A
     1 FM_JTAG_PLD_EN_DEBUG @BASEBOARD_FAB2_LIB.BASEBOARD_FAB2(SCH_1):FM_JTAG_PLD_EN_DEBUG    I45 @BASEBOARD_FAB2_LIB.BASEBOARD_FAB2(SCH_1):PAGE189
     2    GND @BASEBOARD_FAB2_LIB.BASEBOARD_FAB2(SCH_1):GND    I45 @BASEBOARD_FAB2_LIB.BASEBOARD_FAB2(SCH_1):PAGE189

R3R12 RES_0402-665,1.0%,1/16W,CHIP,GA
     1 PVPP_DEF @BASEBOARD_FAB2_LIB.BASEBOARD_FAB2(SCH_1):PVPP_DEF   I101 @BASEBOARD_FAB2_LIB.BASEBOARD_FAB2(SCH_1):PAGE99
     2 SMB_DDR_DEF_VPP_SDA_R @BASEBOARD_FAB2_LIB.BASEBOARD_FAB2(SCH_1):SMB_DDR_DEF_VPP_SDA_R   I101 @BASEBOARD_FAB2_LIB.BASEBOARD_FAB2(SCH_1):PAGE99

R3R13 RES_0402-240,1.0%,1/16W,CHIP,GA
     1 PVCCIO_CPU0 @BASEBOARD_FAB2_LIB.BASEBOARD_FAB2(SCH_1):PVCCIO_CPU0    I65 @BASEBOARD_FAB2_LIB.BASEBOARD_FAB2(SCH_1):PAGE99
     2 SMB_DDR_DEF_SDA_G @BASEBOARD_FAB2_LIB.BASEBOARD_FAB2(SCH_1):SMB_DDR_DEF_SDA_G    I65 @BASEBOARD_FAB2_LIB.BASEBOARD_FAB2(SCH_1):PAGE99

R3R14 RES_0402-10.0,1%,1/16W,CHIP,G2A
     1 SMB_DDR_DEF_SDA_G_R @BASEBOARD_FAB2_LIB.BASEBOARD_FAB2(SCH_1):SMB_DDR_DEF_SDA_G_R   I110 @BASEBOARD_FAB2_LIB.BASEBOARD_FAB2(SCH_1):PAGE99
     2 SMB_DDR_DEF_SDA_G @BASEBOARD_FAB2_LIB.BASEBOARD_FAB2(SCH_1):SMB_DDR_DEF_SDA_G   I110 @BASEBOARD_FAB2_LIB.BASEBOARD_FAB2(SCH_1):PAGE99

R3R15 RES_0402-1.00K,1%,1/16W,CHIP,GA
     1 P3V3_STBY @BASEBOARD_FAB2_LIB.BASEBOARD_FAB2(SCH_1):P3V3_STBY    I44 @BASEBOARD_FAB2_LIB.BASEBOARD_FAB2(SCH_1):PAGE189
     2 FM_JTAG_PLD_EN_DEBUG @BASEBOARD_FAB2_LIB.BASEBOARD_FAB2(SCH_1):FM_JTAG_PLD_EN_DEBUG    I44 @BASEBOARD_FAB2_LIB.BASEBOARD_FAB2(SCH_1):PAGE189

R3R16 RES_0402-4.75K,1%,1/16W,CHIP,GA
     1 PVPP_ABC @BASEBOARD_FAB2_LIB.BASEBOARD_FAB2(SCH_1):PVPP_ABC    I48 @BASEBOARD_FAB2_LIB.BASEBOARD_FAB2(SCH_1):PAGE192
     2 RST_CD_CPU0_POR_N @BASEBOARD_FAB2_LIB.BASEBOARD_FAB2(SCH_1):RST_CD_CPU0_POR_N    I48 @BASEBOARD_FAB2_LIB.BASEBOARD_FAB2(SCH_1):PAGE192

R3T1 RES_0402-33.2,1%,1/16W,CHIP,G2A
     1 SPI_BIOS_SOCKET_IO3 @BASEBOARD_FAB2_LIB.BASEBOARD_FAB2(SCH_1):SPI_BIOS_SOCKET_IO3   I157 @BASEBOARD_FAB2_LIB.BASEBOARD_FAB2(SCH_1):PAGE153
     2 PU_BIOS_SPI_HOLD1_N @BASEBOARD_FAB2_LIB.BASEBOARD_FAB2(SCH_1):PU_BIOS_SPI_HOLD1_N   I157 @BASEBOARD_FAB2_LIB.BASEBOARD_FAB2(SCH_1):PAGE153

R3T2 RES_0402-33.2,1%,1/16W,CHIP,G2A
     1 SPI_SWITCH_MISO @BASEBOARD_FAB2_LIB.BASEBOARD_FAB2(SCH_1):SPI_SWITCH_MISO   I155 @BASEBOARD_FAB2_LIB.BASEBOARD_FAB2(SCH_1):PAGE153
     2 SPI_MISO_R1 @BASEBOARD_FAB2_LIB.BASEBOARD_FAB2(SCH_1):SPI_MISO_R1   I155 @BASEBOARD_FAB2_LIB.BASEBOARD_FAB2(SCH_1):PAGE153

R3T3 RES_0402-4.75K,1%,1/16W,EMPTY,A
     1 P3V3_STBY @BASEBOARD_FAB2_LIB.BASEBOARD_FAB2(SCH_1):P3V3_STBY   I150 @BASEBOARD_FAB2_LIB.BASEBOARD_FAB2(SCH_1):PAGE153
     2 PU_SPI1_RST @BASEBOARD_FAB2_LIB.BASEBOARD_FAB2(SCH_1):PU_SPI1_RST   I150 @BASEBOARD_FAB2_LIB.BASEBOARD_FAB2(SCH_1):PAGE153

R3T4 RES_0402-10.0K,1%,1/16W,CHIP,GA
     1 P3V3_STBY @BASEBOARD_FAB2_LIB.BASEBOARD_FAB2(SCH_1):P3V3_STBY   I174 @BASEBOARD_FAB2_LIB.BASEBOARD_FAB2(SCH_1):PAGE153
     2 PU_BIOS_SPI_HOLD1_N @BASEBOARD_FAB2_LIB.BASEBOARD_FAB2(SCH_1):PU_BIOS_SPI_HOLD1_N   I174 @BASEBOARD_FAB2_LIB.BASEBOARD_FAB2(SCH_1):PAGE153

R3T5 RES_0402-4.75K,1%,1/16W,CHIP,GA
     1 P3V3_STBY @BASEBOARD_FAB2_LIB.BASEBOARD_FAB2(SCH_1):P3V3_STBY   I152 @BASEBOARD_FAB2_LIB.BASEBOARD_FAB2(SCH_1):PAGE153
     2 SPI_CS0_SECONDARY_R_N @BASEBOARD_FAB2_LIB.BASEBOARD_FAB2(SCH_1):SPI_CS0_SECONDARY_R_N   I152 @BASEBOARD_FAB2_LIB.BASEBOARD_FAB2(SCH_1):PAGE153

R3T9 RES_0402-10.0K,1%,1/16W,EMPTY,A
     1 PU_BIOS_SPI_WP1_N @BASEBOARD_FAB2_LIB.BASEBOARD_FAB2(SCH_1):PU_BIOS_SPI_WP1_N   I179 @BASEBOARD_FAB2_LIB.BASEBOARD_FAB2(SCH_1):PAGE153
     2    GND @BASEBOARD_FAB2_LIB.BASEBOARD_FAB2(SCH_1):GND   I179 @BASEBOARD_FAB2_LIB.BASEBOARD_FAB2(SCH_1):PAGE153

R3T10 RES_0402-33.2,1%,1/16W,CHIP,G2A
     1 SPI_SWITCH_MOSI @BASEBOARD_FAB2_LIB.BASEBOARD_FAB2(SCH_1):SPI_SWITCH_MOSI   I184 @BASEBOARD_FAB2_LIB.BASEBOARD_FAB2(SCH_1):PAGE153
     2 SPI_SWITCH_MOSI_R1 @BASEBOARD_FAB2_LIB.BASEBOARD_FAB2(SCH_1):SPI_SWITCH_MOSI_R1   I184 @BASEBOARD_FAB2_LIB.BASEBOARD_FAB2(SCH_1):PAGE153

R3T11 RES_0402-49.9,1%,1/16W,EMPTY,GA
     1 PVCCIO_CPU0 @BASEBOARD_FAB2_LIB.BASEBOARD_FAB2(SCH_1):PVCCIO_CPU0   I330 @BASEBOARD_FAB2_LIB.BASEBOARD_FAB2(SCH_1):PAGE215
     2 SVID_CLK1_CPU0_R @BASEBOARD_FAB2_LIB.BASEBOARD_FAB2(SCH_1):SVID_CLK1_CPU0_R   I330 @BASEBOARD_FAB2_LIB.BASEBOARD_FAB2(SCH_1):PAGE215

R3T12 RES_0402-10.0K,1%,1/16W,CHIP,GA
     1 P3V3_STBY @BASEBOARD_FAB2_LIB.BASEBOARD_FAB2(SCH_1):P3V3_STBY   I178 @BASEBOARD_FAB2_LIB.BASEBOARD_FAB2(SCH_1):PAGE153
     2 PU_BIOS_SPI_WP1_N @BASEBOARD_FAB2_LIB.BASEBOARD_FAB2(SCH_1):PU_BIOS_SPI_WP1_N   I178 @BASEBOARD_FAB2_LIB.BASEBOARD_FAB2(SCH_1):PAGE153

R3T13 RES_0402-0.0,5%,1/16W,CHIP,G21A
     1 P3V3_STBY @BASEBOARD_FAB2_LIB.BASEBOARD_FAB2(SCH_1):P3V3_STBY   I313 @BASEBOARD_FAB2_LIB.BASEBOARD_FAB2(SCH_1):PAGE215
     2 VR_PVDDQ_ABC_VDD @BASEBOARD_FAB2_LIB.BASEBOARD_FAB2(SCH_1):VR_PVDDQ_ABC_VDD   I313 @BASEBOARD_FAB2_LIB.BASEBOARD_FAB2(SCH_1):PAGE215

R3T14 RES_0402-10.0K,1%,1/16W,CHIP,GA
     1 FM_BIOS_USB_RECOVERY @BASEBOARD_FAB2_LIB.BASEBOARD_FAB2(SCH_1):FM_BIOS_USB_RECOVERY   I156 @BASEBOARD_FAB2_LIB.BASEBOARD_FAB2(SCH_1):PAGE136
     2    GND @BASEBOARD_FAB2_LIB.BASEBOARD_FAB2(SCH_1):GND   I156 @BASEBOARD_FAB2_LIB.BASEBOARD_FAB2(SCH_1):PAGE136

R3U1 RES_0402-33.2,1%,1/16W,CHIP,G2A
     1 SPI_BIOS_SOCKET_IO2 @BASEBOARD_FAB2_LIB.BASEBOARD_FAB2(SCH_1):SPI_BIOS_SOCKET_IO2   I156 @BASEBOARD_FAB2_LIB.BASEBOARD_FAB2(SCH_1):PAGE153
     2 PU_BIOS_SPI_WP1_N @BASEBOARD_FAB2_LIB.BASEBOARD_FAB2(SCH_1):PU_BIOS_SPI_WP1_N   I156 @BASEBOARD_FAB2_LIB.BASEBOARD_FAB2(SCH_1):PAGE153

R3U2 RES_0402-100.0,1%,1/16W,CHIP,GA
     1 PVCCIO_CPU0 @BASEBOARD_FAB2_LIB.BASEBOARD_FAB2(SCH_1):PVCCIO_CPU0   I295 @BASEBOARD_FAB2_LIB.BASEBOARD_FAB2(SCH_1):PAGE215
     2 SVID_DIO1_CPU0_R @BASEBOARD_FAB2_LIB.BASEBOARD_FAB2(SCH_1):SVID_DIO1_CPU0_R   I295 @BASEBOARD_FAB2_LIB.BASEBOARD_FAB2(SCH_1):PAGE215

R3U3 RES_0402-0.0,5%,1/16W,CHIP,G21A
     1 VR_PVDDQ_ABC_VD12 @BASEBOARD_FAB2_LIB.BASEBOARD_FAB2(SCH_1):VR_PVDDQ_ABC_VD12   I332 @BASEBOARD_FAB2_LIB.BASEBOARD_FAB2(SCH_1):PAGE215
     2 VR_PVDDQ_ABC_AIREF2 @BASEBOARD_FAB2_LIB.BASEBOARD_FAB2(SCH_1):VR_PVDDQ_ABC_AIREF2   I332 @BASEBOARD_FAB2_LIB.BASEBOARD_FAB2(SCH_1):PAGE215

R3U4 RES_0603-120.0,1%,1/10W,CHIP,GA
     1 PVDDQ_ABC @BASEBOARD_FAB2_LIB.BASEBOARD_FAB2(SCH_1):PVDDQ_ABC    I58 @BASEBOARD_FAB2_LIB.BASEBOARD_FAB2(SCH_1):PAGE217
     2    GND @BASEBOARD_FAB2_LIB.BASEBOARD_FAB2(SCH_1):GND    I58 @BASEBOARD_FAB2_LIB.BASEBOARD_FAB2(SCH_1):PAGE217

R3U6 RES_0402-1.0,1%,1/16W,CHIP,G21A
     1 VR_PVDDQ_ABC_PH1_VCIN @BASEBOARD_FAB2_LIB.BASEBOARD_FAB2(SCH_1):VR_PVDDQ_ABC_PH1_VCIN    I52 @BASEBOARD_FAB2_LIB.BASEBOARD_FAB2(SCH_1):PAGE216
     2 P5V_STBY @BASEBOARD_FAB2_LIB.BASEBOARD_FAB2(SCH_1):P5V_STBY    I52 @BASEBOARD_FAB2_LIB.BASEBOARD_FAB2(SCH_1):PAGE216

R3U9 RES_0402-1.0,1%,1/16W,CHIP,G21A
     1 VR_PVDDQ_ABC_PH2_VCIN @BASEBOARD_FAB2_LIB.BASEBOARD_FAB2(SCH_1):VR_PVDDQ_ABC_PH2_VCIN    I76 @BASEBOARD_FAB2_LIB.BASEBOARD_FAB2(SCH_1):PAGE216
     2 P5V_STBY @BASEBOARD_FAB2_LIB.BASEBOARD_FAB2(SCH_1):P5V_STBY    I76 @BASEBOARD_FAB2_LIB.BASEBOARD_FAB2(SCH_1):PAGE216

R3U10 RES_0402-0.0,5%,1/16W,CHIP,G21A
     1 VR_PVDDQ_ABC_VD12 @BASEBOARD_FAB2_LIB.BASEBOARD_FAB2(SCH_1):VR_PVDDQ_ABC_VD12   I341 @BASEBOARD_FAB2_LIB.BASEBOARD_FAB2(SCH_1):PAGE215
     2 VR_PVDDQ_ABC_AIREF1 @BASEBOARD_FAB2_LIB.BASEBOARD_FAB2(SCH_1):VR_PVDDQ_ABC_AIREF1   I341 @BASEBOARD_FAB2_LIB.BASEBOARD_FAB2(SCH_1):PAGE215

R3W1 RES_0402-1.00K,1%,1/16W,CHIP,GA
     1 BMC_TPM_HW_RST @BASEBOARD_FAB2_LIB.BASEBOARD_FAB2(SCH_1):BMC_TPM_HW_RST     I2 @BASEBOARD_FAB2_LIB.BASEBOARD_FAB2(SCH_1):PAGE249
     2    GND @BASEBOARD_FAB2_LIB.BASEBOARD_FAB2(SCH_1):GND     I2 @BASEBOARD_FAB2_LIB.BASEBOARD_FAB2(SCH_1):PAGE249

R3W2 RES_0402-1.00K,1%,1/16W,CHIP,GA
     1 BMC_TPM_HW_C_RST @BASEBOARD_FAB2_LIB.BASEBOARD_FAB2(SCH_1):BMC_TPM_HW_C_RST    I12 @BASEBOARD_FAB2_LIB.BASEBOARD_FAB2(SCH_1):PAGE249
     2    GND @BASEBOARD_FAB2_LIB.BASEBOARD_FAB2(SCH_1):GND    I12 @BASEBOARD_FAB2_LIB.BASEBOARD_FAB2(SCH_1):PAGE249

R3W3 RES_0402-10.0K,1%,1/16W,CHIP,GA
     1 P3V3_STBY @BASEBOARD_FAB2_LIB.BASEBOARD_FAB2(SCH_1):P3V3_STBY    I17 @BASEBOARD_FAB2_LIB.BASEBOARD_FAB2(SCH_1):PAGE249
     2 FM_TPM_PRES_RST_N @BASEBOARD_FAB2_LIB.BASEBOARD_FAB2(SCH_1):FM_TPM_PRES_RST_N    I17 @BASEBOARD_FAB2_LIB.BASEBOARD_FAB2(SCH_1):PAGE249

R3W4 47KR2F-GP_RCL_GP-47KR2F-GP,64.A
     1 FM_TPM_PRES_RST_N @BASEBOARD_FAB2_LIB.BASEBOARD_FAB2(SCH_1):FM_TPM_PRES_RST_N    I31 @BASEBOARD_FAB2_LIB.BASEBOARD_FAB2(SCH_1):PAGE249
     2 FM_TPM_PRES_RST_N_R @BASEBOARD_FAB2_LIB.BASEBOARD_FAB2(SCH_1):FM_TPM_PRES_RST_N_R    I31 @BASEBOARD_FAB2_LIB.BASEBOARD_FAB2(SCH_1):PAGE249

R3W5 82K5R2F-GP_SMD-RG-82K5R2F-GP,6A
     1 P3V3_STBY @BASEBOARD_FAB2_LIB.BASEBOARD_FAB2(SCH_1):P3V3_STBY    I33 @BASEBOARD_FAB2_LIB.BASEBOARD_FAB2(SCH_1):PAGE249
     2 FM_TPM_PRES_RST @BASEBOARD_FAB2_LIB.BASEBOARD_FAB2(SCH_1):FM_TPM_PRES_RST    I33 @BASEBOARD_FAB2_LIB.BASEBOARD_FAB2(SCH_1):PAGE249

R3W6 RES_0402-4.75K,1%,1/16W,CHIP,GA
     1 P3V3_STBY @BASEBOARD_FAB2_LIB.BASEBOARD_FAB2(SCH_1):P3V3_STBY    I27 @BASEBOARD_FAB2_LIB.BASEBOARD_FAB2(SCH_1):PAGE249
     2 RST_BMC_SRST_N @BASEBOARD_FAB2_LIB.BASEBOARD_FAB2(SCH_1):RST_BMC_SRST_N    I27 @BASEBOARD_FAB2_LIB.BASEBOARD_FAB2(SCH_1):PAGE249

R3W7 RES_0402-4.75K,1%,1/16W,CHIP,GA
     1 P3V3_STBY @BASEBOARD_FAB2_LIB.BASEBOARD_FAB2(SCH_1):P3V3_STBY     I8 @BASEBOARD_FAB2_LIB.BASEBOARD_FAB2(SCH_1):PAGE249
     2 VREF_2V2 @BASEBOARD_FAB2_LIB.BASEBOARD_FAB2(SCH_1):VREF_2V2     I8 @BASEBOARD_FAB2_LIB.BASEBOARD_FAB2(SCH_1):PAGE249

R3W9 RES_0402-10.0K,1%,1/16W,CHIP,GA
     1 VREF_2V2 @BASEBOARD_FAB2_LIB.BASEBOARD_FAB2(SCH_1):VREF_2V2     I7 @BASEBOARD_FAB2_LIB.BASEBOARD_FAB2(SCH_1):PAGE249
     2    GND @BASEBOARD_FAB2_LIB.BASEBOARD_FAB2(SCH_1):GND     I7 @BASEBOARD_FAB2_LIB.BASEBOARD_FAB2(SCH_1):PAGE249

R4A1 RES_0402-51.1,1.0%,1/16W,CHIP,A
     1    GND @BASEBOARD_FAB2_LIB.BASEBOARD_FAB2(SCH_1):GND    I52 @BASEBOARD_FAB2_LIB.BASEBOARD_FAB2(SCH_1):PAGE222
     2 PVTT_DEF @BASEBOARD_FAB2_LIB.BASEBOARD_FAB2(SCH_1):PVTT_DEF    I52 @BASEBOARD_FAB2_LIB.BASEBOARD_FAB2(SCH_1):PAGE222

R4A2 RES_0402-0.0,5%,1/16W,CHIP,G21A
     1 PWRGD_PVDDQ_DEF @BASEBOARD_FAB2_LIB.BASEBOARD_FAB2(SCH_1):PWRGD_PVDDQ_DEF    I38 @BASEBOARD_FAB2_LIB.BASEBOARD_FAB2(SCH_1):PAGE222
     2 FM_PVTT_DEF_EN_R @BASEBOARD_FAB2_LIB.BASEBOARD_FAB2(SCH_1):FM_PVTT_DEF_EN_R    I38 @BASEBOARD_FAB2_LIB.BASEBOARD_FAB2(SCH_1):PAGE222

R4A3 RES_0402-0.0,5%,1/16W,CHIP,G21A
     1 PWRGD_PVDDQ_KLM @BASEBOARD_FAB2_LIB.BASEBOARD_FAB2(SCH_1):PWRGD_PVDDQ_KLM    I38 @BASEBOARD_FAB2_LIB.BASEBOARD_FAB2(SCH_1):PAGE230
     2 FM_PVTT_KLM_EN_R @BASEBOARD_FAB2_LIB.BASEBOARD_FAB2(SCH_1):FM_PVTT_KLM_EN_R    I38 @BASEBOARD_FAB2_LIB.BASEBOARD_FAB2(SCH_1):PAGE230

R4A4 RES_0402-33.2,1%,1/16W,CHIP,G2A
     1 PWRGD_PVTT_KLM_CPU1_R @BASEBOARD_FAB2_LIB.BASEBOARD_FAB2(SCH_1):PWRGD_PVTT_KLM_CPU1_R    I51 @BASEBOARD_FAB2_LIB.BASEBOARD_FAB2(SCH_1):PAGE230
     2 PWRGD_PVTT_CPU1 @BASEBOARD_FAB2_LIB.BASEBOARD_FAB2(SCH_1):PWRGD_PVTT_CPU1    I51 @BASEBOARD_FAB2_LIB.BASEBOARD_FAB2(SCH_1):PAGE230

R4A5 RES_0402-10.0K,1%,1/16W,CHIP,GA
     1   P3V3 @BASEBOARD_FAB2_LIB.BASEBOARD_FAB2(SCH_1):P3V3    I17 @BASEBOARD_FAB2_LIB.BASEBOARD_FAB2(SCH_1):PAGE230
     2 PWRGD_PVTT_KLM_CPU1_R @BASEBOARD_FAB2_LIB.BASEBOARD_FAB2(SCH_1):PWRGD_PVTT_KLM_CPU1_R    I17 @BASEBOARD_FAB2_LIB.BASEBOARD_FAB2(SCH_1):PAGE230

R4A6 RES_0402-33.2,1%,1/16W,CHIP,G2A
     1 PWRGD_PVTT_DEF_CPU0_R @BASEBOARD_FAB2_LIB.BASEBOARD_FAB2(SCH_1):PWRGD_PVTT_DEF_CPU0_R    I51 @BASEBOARD_FAB2_LIB.BASEBOARD_FAB2(SCH_1):PAGE222
     2 PWRGD_PVTT_CPU0 @BASEBOARD_FAB2_LIB.BASEBOARD_FAB2(SCH_1):PWRGD_PVTT_CPU0    I51 @BASEBOARD_FAB2_LIB.BASEBOARD_FAB2(SCH_1):PAGE222

R4A7 RES_0402-2.2,5%,1/16W,EMPTY,G2A
     1 VR_PVPP_KLM_SNUB @BASEBOARD_FAB2_LIB.BASEBOARD_FAB2(SCH_1):VR_PVPP_KLM_SNUB   I162 @BASEBOARD_FAB2_LIB.BASEBOARD_FAB2(SCH_1):PAGE234
     2    GND @BASEBOARD_FAB2_LIB.BASEBOARD_FAB2(SCH_1):GND   I162 @BASEBOARD_FAB2_LIB.BASEBOARD_FAB2(SCH_1):PAGE234

R4A8 RES_0402-0.0,5%,1/16W,CHIP,G21A
     1 SMB_LAN_STBY_LVC3_SDA @BASEBOARD_FAB2_LIB.BASEBOARD_FAB2(SCH_1):SMB_LAN_STBY_LVC3_SDA   I322 @BASEBOARD_FAB2_LIB.BASEBOARD_FAB2(SCH_1):PAGE156
     2 SMB_PIROM_CPU0_SDA @BASEBOARD_FAB2_LIB.BASEBOARD_FAB2(SCH_1):SMB_PIROM_CPU0_SDA   I322 @BASEBOARD_FAB2_LIB.BASEBOARD_FAB2(SCH_1):PAGE156

R4A9 RES_0402-0.0,5%,1/16W,CHIP,G21A
     1 SMB_LAN_STBY_LVC3_SCL @BASEBOARD_FAB2_LIB.BASEBOARD_FAB2(SCH_1):SMB_LAN_STBY_LVC3_SCL   I324 @BASEBOARD_FAB2_LIB.BASEBOARD_FAB2(SCH_1):PAGE156
     2 SMB_PIROM_CPU0_SCL @BASEBOARD_FAB2_LIB.BASEBOARD_FAB2(SCH_1):SMB_PIROM_CPU0_SCL   I324 @BASEBOARD_FAB2_LIB.BASEBOARD_FAB2(SCH_1):PAGE156

R4B1 RES_0402-0.0,5%,1/16W,CHIP,G21A
     1 FM_PVPP_CPU1_EN @BASEBOARD_FAB2_LIB.BASEBOARD_FAB2(SCH_1):FM_PVPP_CPU1_EN   I220 @BASEBOARD_FAB2_LIB.BASEBOARD_FAB2(SCH_1):PAGE234
     2 FM_PVPP_PVDDQ_CPU1_EN_KLM @BASEBOARD_FAB2_LIB.BASEBOARD_FAB2(SCH_1):FM_PVPP_PVDDQ_CPU1_EN_KLM   I220 @BASEBOARD_FAB2_LIB.BASEBOARD_FAB2(SCH_1):PAGE234

R4B2 RES_0603-120.0,1%,1/10W,CHIP,GA
     1 PVPP_KLM @BASEBOARD_FAB2_LIB.BASEBOARD_FAB2(SCH_1):PVPP_KLM   I183 @BASEBOARD_FAB2_LIB.BASEBOARD_FAB2(SCH_1):PAGE234
     2    GND @BASEBOARD_FAB2_LIB.BASEBOARD_FAB2(SCH_1):GND   I183 @BASEBOARD_FAB2_LIB.BASEBOARD_FAB2(SCH_1):PAGE234

R4B3 RES_0402-0.0,5%,1/16W,CHIP,G21A
     1 PVPP_KLM @BASEBOARD_FAB2_LIB.BASEBOARD_FAB2(SCH_1):PVPP_KLM   I214 @BASEBOARD_FAB2_LIB.BASEBOARD_FAB2(SCH_1):PAGE234
     2 VSENSE_PVPP_KLM @BASEBOARD_FAB2_LIB.BASEBOARD_FAB2(SCH_1):VSENSE_PVPP_KLM   I214 @BASEBOARD_FAB2_LIB.BASEBOARD_FAB2(SCH_1):PAGE234

R4B4 RES_0402-6.34K,1%,1/16W,CHIP,GA
     1 VR_FB_PVPP_KLM @BASEBOARD_FAB2_LIB.BASEBOARD_FAB2(SCH_1):VR_FB_PVPP_KLM   I216 @BASEBOARD_FAB2_LIB.BASEBOARD_FAB2(SCH_1):PAGE234
     2 AGND_PVPP_KLM @BASEBOARD_FAB2_LIB.BASEBOARD_FAB2(SCH_1):AGND_PVPP_KLM   I216 @BASEBOARD_FAB2_LIB.BASEBOARD_FAB2(SCH_1):PAGE234

R4B5 RES_0402-20.0K,1%,1/16W,CHIP,GA
     1 VSENSE_PVPP_KLM @BASEBOARD_FAB2_LIB.BASEBOARD_FAB2(SCH_1):VSENSE_PVPP_KLM   I215 @BASEBOARD_FAB2_LIB.BASEBOARD_FAB2(SCH_1):PAGE234
     2 VR_FB_PVPP_KLM @BASEBOARD_FAB2_LIB.BASEBOARD_FAB2(SCH_1):VR_FB_PVPP_KLM   I215 @BASEBOARD_FAB2_LIB.BASEBOARD_FAB2(SCH_1):PAGE234

R4B6 RES_0402-7.87K,1.0%,1/16W,CHIPA
     1 VR_PVPP_KLM_ISET @BASEBOARD_FAB2_LIB.BASEBOARD_FAB2(SCH_1):VR_PVPP_KLM_ISET   I140 @BASEBOARD_FAB2_LIB.BASEBOARD_FAB2(SCH_1):PAGE234
     2 AGND_PVPP_KLM @BASEBOARD_FAB2_LIB.BASEBOARD_FAB2(SCH_1):AGND_PVPP_KLM   I140 @BASEBOARD_FAB2_LIB.BASEBOARD_FAB2(SCH_1):PAGE234

R4B7 RES_0402-22.1,1.0%,1/16W,CHIP,A
     1 PWRGD_PVPP_KLM_R @BASEBOARD_FAB2_LIB.BASEBOARD_FAB2(SCH_1):PWRGD_PVPP_KLM_R   I201 @BASEBOARD_FAB2_LIB.BASEBOARD_FAB2(SCH_1):PAGE234
     2 PWRGD_PVPP_KLM @BASEBOARD_FAB2_LIB.BASEBOARD_FAB2(SCH_1):PWRGD_PVPP_KLM   I201 @BASEBOARD_FAB2_LIB.BASEBOARD_FAB2(SCH_1):PAGE234

R4B8 RES_0402-7.87K,1.0%,1/16W,CHIPA
     1 VR_COMP_RC_PVPP_KLM @BASEBOARD_FAB2_LIB.BASEBOARD_FAB2(SCH_1):VR_COMP_RC_PVPP_KLM   I213 @BASEBOARD_FAB2_LIB.BASEBOARD_FAB2(SCH_1):PAGE234
     2 VR_FB_PVPP_KLM @BASEBOARD_FAB2_LIB.BASEBOARD_FAB2(SCH_1):VR_FB_PVPP_KLM   I213 @BASEBOARD_FAB2_LIB.BASEBOARD_FAB2(SCH_1):PAGE234

R4B9 RES_0402-1.0K,0.1%,1/16W,CHIP,A
     1 VSENSE_PVPP_KLM @BASEBOARD_FAB2_LIB.BASEBOARD_FAB2(SCH_1):VSENSE_PVPP_KLM   I219 @BASEBOARD_FAB2_LIB.BASEBOARD_FAB2(SCH_1):PAGE234
     2 VR_COMP_PVPP_KLM @BASEBOARD_FAB2_LIB.BASEBOARD_FAB2(SCH_1):VR_COMP_PVPP_KLM   I219 @BASEBOARD_FAB2_LIB.BASEBOARD_FAB2(SCH_1):PAGE234

R4B10 RES_0402-1.00K,1%,1/16W,CHIP,GA
     1 P3V3_STBY @BASEBOARD_FAB2_LIB.BASEBOARD_FAB2(SCH_1):P3V3_STBY   I143 @BASEBOARD_FAB2_LIB.BASEBOARD_FAB2(SCH_1):PAGE234
     2 PWRGD_PVPP_KLM_R @BASEBOARD_FAB2_LIB.BASEBOARD_FAB2(SCH_1):PWRGD_PVPP_KLM_R   I143 @BASEBOARD_FAB2_LIB.BASEBOARD_FAB2(SCH_1):PAGE234

R4B11 RES_0402-0.0,5%,1/16W,CHIP,G21A
     1 VR_PVDDQ_DEF_AIINSEN_R @BASEBOARD_FAB2_LIB.BASEBOARD_FAB2(SCH_1):VR_PVDDQ_DEF_AIINSEN_R   I113 @BASEBOARD_FAB2_LIB.BASEBOARD_FAB2(SCH_1):PAGE197
     2 VR_PVDDQ_DEF_AIINSEN @BASEBOARD_FAB2_LIB.BASEBOARD_FAB2(SCH_1):VR_PVDDQ_DEF_AIINSEN   I113 @BASEBOARD_FAB2_LIB.BASEBOARD_FAB2(SCH_1):PAGE197

R4B12 RES_1206-0.002,1%,1W,CHIP,G521A
     1 P12V_NVDIMM_DEF @BASEBOARD_FAB2_LIB.BASEBOARD_FAB2(SCH_1):P12V_NVDIMM_DEF   I121 @BASEBOARD_FAB2_LIB.BASEBOARD_FAB2(SCH_1):PAGE197
     2 P12V_STBY @BASEBOARD_FAB2_LIB.BASEBOARD_FAB2(SCH_1):P12V_STBY   I121 @BASEBOARD_FAB2_LIB.BASEBOARD_FAB2(SCH_1):PAGE197

R4B13 RES_0402-0.0,5%,1/16W,CHIP,G21A
     1 VR_PVPP_KLM_BOOT @BASEBOARD_FAB2_LIB.BASEBOARD_FAB2(SCH_1):VR_PVPP_KLM_BOOT   I155 @BASEBOARD_FAB2_LIB.BASEBOARD_FAB2(SCH_1):PAGE234
     2 VR_PVPP_KLM_BOOT_R @BASEBOARD_FAB2_LIB.BASEBOARD_FAB2(SCH_1):VR_PVPP_KLM_BOOT_R   I155 @BASEBOARD_FAB2_LIB.BASEBOARD_FAB2(SCH_1):PAGE234

R4B14 RES_0402-0.0,5%,1/16W,CHIP,G21A
     1    GND @BASEBOARD_FAB2_LIB.BASEBOARD_FAB2(SCH_1):GND    I29 @BASEBOARD_FAB2_LIB.BASEBOARD_FAB2(SCH_1):PAGE234
     2 AGND_PVPP_KLM @BASEBOARD_FAB2_LIB.BASEBOARD_FAB2(SCH_1):AGND_PVPP_KLM    I29 @BASEBOARD_FAB2_LIB.BASEBOARD_FAB2(SCH_1):PAGE234

R4C1 RES_0402-100.0,1%,1/16W,CHIP,GA
     1 VSENSE_PVSA_CPU0_N @BASEBOARD_FAB2_LIB.BASEBOARD_FAB2(SCH_1):VSENSE_PVSA_CPU0_N    I29 @BASEBOARD_FAB2_LIB.BASEBOARD_FAB2(SCH_1):PAGE205
     2    GND @BASEBOARD_FAB2_LIB.BASEBOARD_FAB2(SCH_1):GND    I29 @BASEBOARD_FAB2_LIB.BASEBOARD_FAB2(SCH_1):PAGE205

R4C2 RES_0402-0.0,5%,1/16W,CHIP,G21A
     1 VSENSE_PVSA_CPU0_N @BASEBOARD_FAB2_LIB.BASEBOARD_FAB2(SCH_1):VSENSE_PVSA_CPU0_N    I30 @BASEBOARD_FAB2_LIB.BASEBOARD_FAB2(SCH_1):PAGE205
     2 VSENSE_PVSA_CPU0_SKT_VRTN @BASEBOARD_FAB2_LIB.BASEBOARD_FAB2(SCH_1):VSENSE_PVSA_CPU0_SKT_VRTN    I30 @BASEBOARD_FAB2_LIB.BASEBOARD_FAB2(SCH_1):PAGE205

R4C3 RES_0402-1.00K,1%,1/16W,EMPTY,A
     1 VSENSE_PVSA_CPU0_P @BASEBOARD_FAB2_LIB.BASEBOARD_FAB2(SCH_1):VSENSE_PVSA_CPU0_P    I37 @BASEBOARD_FAB2_LIB.BASEBOARD_FAB2(SCH_1):PAGE205
     2 VSENSE_PVSA_CPU0_N @BASEBOARD_FAB2_LIB.BASEBOARD_FAB2(SCH_1):VSENSE_PVSA_CPU0_N    I37 @BASEBOARD_FAB2_LIB.BASEBOARD_FAB2(SCH_1):PAGE205

R4C4 RES_0402-0.0,5%,1/16W,CHIP,G21A
     1 VSENSE_PVSA_CPU0_P @BASEBOARD_FAB2_LIB.BASEBOARD_FAB2(SCH_1):VSENSE_PVSA_CPU0_P    I26 @BASEBOARD_FAB2_LIB.BASEBOARD_FAB2(SCH_1):PAGE205
     2 VSENSE_PVSA_CPU0_SKT_VSEN @BASEBOARD_FAB2_LIB.BASEBOARD_FAB2(SCH_1):VSENSE_PVSA_CPU0_SKT_VSEN    I26 @BASEBOARD_FAB2_LIB.BASEBOARD_FAB2(SCH_1):PAGE205

R4C5 RES_0402-100.0,1%,1/16W,CHIP,GA
     1 VSENSE_PVSA_CPU0_P @BASEBOARD_FAB2_LIB.BASEBOARD_FAB2(SCH_1):VSENSE_PVSA_CPU0_P    I24 @BASEBOARD_FAB2_LIB.BASEBOARD_FAB2(SCH_1):PAGE205
     2 PVSA_CPU0 @BASEBOARD_FAB2_LIB.BASEBOARD_FAB2(SCH_1):PVSA_CPU0    I24 @BASEBOARD_FAB2_LIB.BASEBOARD_FAB2(SCH_1):PAGE205

R4C6 RES_2010-0.001,1%,1W,CHIP,E309A
     1 VR_FET_SW_P12V_PVCCIN_CPU0_R @BASEBOARD_FAB2_LIB.BASEBOARD_FAB2(SCH_1):VR_FET_SW_P12V_PVCCIN_CPU0_R    I45 @BASEBOARD_FAB2_LIB.BASEBOARD_FAB2(SCH_1):PAGE204
     2 VR_FET_SW_P12V_STBY_PVCCIN_CPU0 @BASEBOARD_FAB2_LIB.BASEBOARD_FAB2(SCH_1):VR_FET_SW_P12V_STBY_PVCCIN_CPU0    I45 @BASEBOARD_FAB2_LIB.BASEBOARD_FAB2(SCH_1):PAGE204

R4C8 RES_0402-1.00K,1%,1/16W,CHIP,GA
     1 P3V3_STBY @BASEBOARD_FAB2_LIB.BASEBOARD_FAB2(SCH_1):P3V3_STBY    I55 @BASEBOARD_FAB2_LIB.BASEBOARD_FAB2(SCH_1):PAGE96
     2 PU_GTL2014_2_DIR @BASEBOARD_FAB2_LIB.BASEBOARD_FAB2(SCH_1):PU_GTL2014_2_DIR    I55 @BASEBOARD_FAB2_LIB.BASEBOARD_FAB2(SCH_1):PAGE96

R4C9 RES_0402-1.00K,1%,1/16W,CHIP,GA
     1    GND @BASEBOARD_FAB2_LIB.BASEBOARD_FAB2(SCH_1):GND    I69 @BASEBOARD_FAB2_LIB.BASEBOARD_FAB2(SCH_1):PAGE96
     2 PD_GTL2014_2_VREF @BASEBOARD_FAB2_LIB.BASEBOARD_FAB2(SCH_1):PD_GTL2014_2_VREF    I69 @BASEBOARD_FAB2_LIB.BASEBOARD_FAB2(SCH_1):PAGE96

R4C10 RES_0402-240,1.0%,1/16W,CHIP,GA
     1 PVCCIO_CPU1 @BASEBOARD_FAB2_LIB.BASEBOARD_FAB2(SCH_1):PVCCIO_CPU1    I76 @BASEBOARD_FAB2_LIB.BASEBOARD_FAB2(SCH_1):PAGE97
     2 PU_CPU1_TSC_SYNC @BASEBOARD_FAB2_LIB.BASEBOARD_FAB2(SCH_1):PU_CPU1_TSC_SYNC    I76 @BASEBOARD_FAB2_LIB.BASEBOARD_FAB2(SCH_1):PAGE97

R4C11 RES_0402-3.16K,1%,1/16W,CHIP,GA
     1 VR_PVCCMCP_CPU1_XADDR2 @BASEBOARD_FAB2_LIB.BASEBOARD_FAB2(SCH_1):VR_PVCCMCP_CPU1_XADDR2   I170 @BASEBOARD_FAB2_LIB.BASEBOARD_FAB2(SCH_1):PAGE193
     2    GND @BASEBOARD_FAB2_LIB.BASEBOARD_FAB2(SCH_1):GND   I170 @BASEBOARD_FAB2_LIB.BASEBOARD_FAB2(SCH_1):PAGE193

R4C12 RES_0402-8.06K,1%,1/16W,CHIP,GA
     1 VR_PVCCIOMCP_CPU1_XADDR1 @BASEBOARD_FAB2_LIB.BASEBOARD_FAB2(SCH_1):VR_PVCCIOMCP_CPU1_XADDR1   I169 @BASEBOARD_FAB2_LIB.BASEBOARD_FAB2(SCH_1):PAGE193
     2    GND @BASEBOARD_FAB2_LIB.BASEBOARD_FAB2(SCH_1):GND   I169 @BASEBOARD_FAB2_LIB.BASEBOARD_FAB2(SCH_1):PAGE193

R4C13 RES_0402-68.1K,1%,1/16W,EMPTY,A
     1 VR_PVSA_CPU0_OCSET @BASEBOARD_FAB2_LIB.BASEBOARD_FAB2(SCH_1):VR_PVSA_CPU0_OCSET    I62 @BASEBOARD_FAB2_LIB.BASEBOARD_FAB2(SCH_1):PAGE205
     2    GND @BASEBOARD_FAB2_LIB.BASEBOARD_FAB2(SCH_1):GND    I62 @BASEBOARD_FAB2_LIB.BASEBOARD_FAB2(SCH_1):PAGE205

R4D1 RES_0402-27.4,1%,1/16W,CHIP,G2A
     1 CLK_100M_CPU1_BCLK1_R_DN @BASEBOARD_FAB2_LIB.BASEBOARD_FAB2(SCH_1):CLK_100M_CPU1_BCLK1_R_DN    I54 @BASEBOARD_FAB2_LIB.BASEBOARD_FAB2(SCH_1):PAGE103
     2 CLK_100M_CPU1_BCLK1_DN @BASEBOARD_FAB2_LIB.BASEBOARD_FAB2(SCH_1):CLK_100M_CPU1_BCLK1_DN    I54 @BASEBOARD_FAB2_LIB.BASEBOARD_FAB2(SCH_1):PAGE103

R4D2 RES_0402-27.4,1%,1/16W,CHIP,G2A
     1 CLK_100M_CPU1_BCLK1_R_DP @BASEBOARD_FAB2_LIB.BASEBOARD_FAB2(SCH_1):CLK_100M_CPU1_BCLK1_R_DP    I49 @BASEBOARD_FAB2_LIB.BASEBOARD_FAB2(SCH_1):PAGE103
     2 CLK_100M_CPU1_BCLK1_DP @BASEBOARD_FAB2_LIB.BASEBOARD_FAB2(SCH_1):CLK_100M_CPU1_BCLK1_DP    I49 @BASEBOARD_FAB2_LIB.BASEBOARD_FAB2(SCH_1):PAGE103

R4D3 RES_0402-27.4,1%,1/16W,CHIP,G2A
     1 CLK_100M_CPU1_BCLK0_R_DN @BASEBOARD_FAB2_LIB.BASEBOARD_FAB2(SCH_1):CLK_100M_CPU1_BCLK0_R_DN    I64 @BASEBOARD_FAB2_LIB.BASEBOARD_FAB2(SCH_1):PAGE103
     2 CLK_100M_CPU1_BCLK0_DN @BASEBOARD_FAB2_LIB.BASEBOARD_FAB2(SCH_1):CLK_100M_CPU1_BCLK0_DN    I64 @BASEBOARD_FAB2_LIB.BASEBOARD_FAB2(SCH_1):PAGE103

R4D4 RES_0402-27.4,1%,1/16W,CHIP,G2A
     1 CLK_100M_CPU1_BCLK0_R_DP @BASEBOARD_FAB2_LIB.BASEBOARD_FAB2(SCH_1):CLK_100M_CPU1_BCLK0_R_DP    I59 @BASEBOARD_FAB2_LIB.BASEBOARD_FAB2(SCH_1):PAGE103
     2 CLK_100M_CPU1_BCLK0_DP @BASEBOARD_FAB2_LIB.BASEBOARD_FAB2(SCH_1):CLK_100M_CPU1_BCLK0_DP    I59 @BASEBOARD_FAB2_LIB.BASEBOARD_FAB2(SCH_1):PAGE103

R4D5 RES_0402-27.4,1%,1/16W,CHIP,G2A
     1 CLK_100M_CPU0_RC_REFCLK1_R_DN @BASEBOARD_FAB2_LIB.BASEBOARD_FAB2(SCH_1):CLK_100M_CPU0_RC_REFCLK1_R_DN    I79 @BASEBOARD_FAB2_LIB.BASEBOARD_FAB2(SCH_1):PAGE103
     2 CLK_100M_CPU0_RC_REFCLK1_DN @BASEBOARD_FAB2_LIB.BASEBOARD_FAB2(SCH_1):CLK_100M_CPU0_RC_REFCLK1_DN    I79 @BASEBOARD_FAB2_LIB.BASEBOARD_FAB2(SCH_1):PAGE103

R4D6 RES_0402-27.4,1%,1/16W,CHIP,G2A
     1 CLK_100M_CPU0_RC_REFCLK1_R_DP @BASEBOARD_FAB2_LIB.BASEBOARD_FAB2(SCH_1):CLK_100M_CPU0_RC_REFCLK1_R_DP    I74 @BASEBOARD_FAB2_LIB.BASEBOARD_FAB2(SCH_1):PAGE103
     2 CLK_100M_CPU0_RC_REFCLK1_DP @BASEBOARD_FAB2_LIB.BASEBOARD_FAB2(SCH_1):CLK_100M_CPU0_RC_REFCLK1_DP    I74 @BASEBOARD_FAB2_LIB.BASEBOARD_FAB2(SCH_1):PAGE103

R4D7 RES_0402-27.4,1%,1/16W,CHIP,G2A
     1 CLK_100M_CPU0_RC_REFCLK0_R_DN @BASEBOARD_FAB2_LIB.BASEBOARD_FAB2(SCH_1):CLK_100M_CPU0_RC_REFCLK0_R_DN    I89 @BASEBOARD_FAB2_LIB.BASEBOARD_FAB2(SCH_1):PAGE103
     2 CLK_100M_CPU0_RC_REFCLK0_DN @BASEBOARD_FAB2_LIB.BASEBOARD_FAB2(SCH_1):CLK_100M_CPU0_RC_REFCLK0_DN    I89 @BASEBOARD_FAB2_LIB.BASEBOARD_FAB2(SCH_1):PAGE103

R4D8 RES_0402-27.4,1%,1/16W,CHIP,G2A
     1 CLK_100M_CPU0_RC_REFCLK0_R_DP @BASEBOARD_FAB2_LIB.BASEBOARD_FAB2(SCH_1):CLK_100M_CPU0_RC_REFCLK0_R_DP    I84 @BASEBOARD_FAB2_LIB.BASEBOARD_FAB2(SCH_1):PAGE103
     2 CLK_100M_CPU0_RC_REFCLK0_DP @BASEBOARD_FAB2_LIB.BASEBOARD_FAB2(SCH_1):CLK_100M_CPU0_RC_REFCLK0_DP    I84 @BASEBOARD_FAB2_LIB.BASEBOARD_FAB2(SCH_1):PAGE103

R4D9 RES_0402-27.4,1%,1/16W,CHIP,G2A
     1 CLK_100M_CPU1_BCLK2_R_DP @BASEBOARD_FAB2_LIB.BASEBOARD_FAB2(SCH_1):CLK_100M_CPU1_BCLK2_R_DP    I39 @BASEBOARD_FAB2_LIB.BASEBOARD_FAB2(SCH_1):PAGE103
     2 CLK_100M_CPU1_BCLK2_DP @BASEBOARD_FAB2_LIB.BASEBOARD_FAB2(SCH_1):CLK_100M_CPU1_BCLK2_DP    I39 @BASEBOARD_FAB2_LIB.BASEBOARD_FAB2(SCH_1):PAGE103

R4D10 RES_0402-27.4,1%,1/16W,CHIP,G2A
     1 CLK_100M_CPU0_PE_REFCLK_R_DN @BASEBOARD_FAB2_LIB.BASEBOARD_FAB2(SCH_1):CLK_100M_CPU0_PE_REFCLK_R_DN    I99 @BASEBOARD_FAB2_LIB.BASEBOARD_FAB2(SCH_1):PAGE103
     2 CLK_100M_CPU0_PE_REFCLK_DN @BASEBOARD_FAB2_LIB.BASEBOARD_FAB2(SCH_1):CLK_100M_CPU0_PE_REFCLK_DN    I99 @BASEBOARD_FAB2_LIB.BASEBOARD_FAB2(SCH_1):PAGE103

R4D11 RES_0402-27.4,1%,1/16W,CHIP,G2A
     1 CLK_100M_CPU1_BCLK2_R_DN @BASEBOARD_FAB2_LIB.BASEBOARD_FAB2(SCH_1):CLK_100M_CPU1_BCLK2_R_DN    I44 @BASEBOARD_FAB2_LIB.BASEBOARD_FAB2(SCH_1):PAGE103
     2 CLK_100M_CPU1_BCLK2_DN @BASEBOARD_FAB2_LIB.BASEBOARD_FAB2(SCH_1):CLK_100M_CPU1_BCLK2_DN    I44 @BASEBOARD_FAB2_LIB.BASEBOARD_FAB2(SCH_1):PAGE103

R4D12 RES_0402-27.4,1%,1/16W,CHIP,G2A
     1 CLK_100M_CPU0_PE_REFCLK_R_DP @BASEBOARD_FAB2_LIB.BASEBOARD_FAB2(SCH_1):CLK_100M_CPU0_PE_REFCLK_R_DP    I94 @BASEBOARD_FAB2_LIB.BASEBOARD_FAB2(SCH_1):PAGE103
     2 CLK_100M_CPU0_PE_REFCLK_DP @BASEBOARD_FAB2_LIB.BASEBOARD_FAB2(SCH_1):CLK_100M_CPU0_PE_REFCLK_DP    I94 @BASEBOARD_FAB2_LIB.BASEBOARD_FAB2(SCH_1):PAGE103

R4D13 RES_0402-27.4,1%,1/16W,CHIP,G2A
     1 CLK_100M_CPU1_PE_REFCLK_R_DP @BASEBOARD_FAB2_LIB.BASEBOARD_FAB2(SCH_1):CLK_100M_CPU1_PE_REFCLK_R_DP    I29 @BASEBOARD_FAB2_LIB.BASEBOARD_FAB2(SCH_1):PAGE103
     2 CLK_100M_CPU1_PE_REFCLK_DP @BASEBOARD_FAB2_LIB.BASEBOARD_FAB2(SCH_1):CLK_100M_CPU1_PE_REFCLK_DP    I29 @BASEBOARD_FAB2_LIB.BASEBOARD_FAB2(SCH_1):PAGE103

R4D14 RES_0402-27.4,1%,1/16W,CHIP,G2A
     1 CLK_100M_CPU0_BCLK2_R_DN @BASEBOARD_FAB2_LIB.BASEBOARD_FAB2(SCH_1):CLK_100M_CPU0_BCLK2_R_DN   I109 @BASEBOARD_FAB2_LIB.BASEBOARD_FAB2(SCH_1):PAGE103
     2 CLK_100M_CPU0_BCLK2_DN @BASEBOARD_FAB2_LIB.BASEBOARD_FAB2(SCH_1):CLK_100M_CPU0_BCLK2_DN   I109 @BASEBOARD_FAB2_LIB.BASEBOARD_FAB2(SCH_1):PAGE103

R4D16 RES_0402-27.4,1%,1/16W,CHIP,G2A
     1 CLK_100M_CPU1_PE_REFCLK_R_DN @BASEBOARD_FAB2_LIB.BASEBOARD_FAB2(SCH_1):CLK_100M_CPU1_PE_REFCLK_R_DN    I34 @BASEBOARD_FAB2_LIB.BASEBOARD_FAB2(SCH_1):PAGE103
     2 CLK_100M_CPU1_PE_REFCLK_DN @BASEBOARD_FAB2_LIB.BASEBOARD_FAB2(SCH_1):CLK_100M_CPU1_PE_REFCLK_DN    I34 @BASEBOARD_FAB2_LIB.BASEBOARD_FAB2(SCH_1):PAGE103

R4D17 RES_0402-27.4,1%,1/16W,CHIP,G2A
     1 CLK_100M_CPU0_BCLK2_R_DP @BASEBOARD_FAB2_LIB.BASEBOARD_FAB2(SCH_1):CLK_100M_CPU0_BCLK2_R_DP   I104 @BASEBOARD_FAB2_LIB.BASEBOARD_FAB2(SCH_1):PAGE103
     2 CLK_100M_CPU0_BCLK2_DP @BASEBOARD_FAB2_LIB.BASEBOARD_FAB2(SCH_1):CLK_100M_CPU0_BCLK2_DP   I104 @BASEBOARD_FAB2_LIB.BASEBOARD_FAB2(SCH_1):PAGE103

R4D18 RES_0402-42.2,1.0%,1/16W,EMPTYA
     1 CLK_100M_CPU0_BCLK1_DN @BASEBOARD_FAB2_LIB.BASEBOARD_FAB2(SCH_1):CLK_100M_CPU0_BCLK1_DN   I163 @BASEBOARD_FAB2_LIB.BASEBOARD_FAB2(SCH_1):PAGE103
     2    GND @BASEBOARD_FAB2_LIB.BASEBOARD_FAB2(SCH_1):GND   I163 @BASEBOARD_FAB2_LIB.BASEBOARD_FAB2(SCH_1):PAGE103

R4D19 RES_0402-27.4,1%,1/16W,CHIP,G2A
     1 CLK_100M_CPU1_RC_REFCLK0_R_DP @BASEBOARD_FAB2_LIB.BASEBOARD_FAB2(SCH_1):CLK_100M_CPU1_RC_REFCLK0_R_DP    I19 @BASEBOARD_FAB2_LIB.BASEBOARD_FAB2(SCH_1):PAGE103
     2 CLK_100M_CPU1_RC_REFCLK0_DP @BASEBOARD_FAB2_LIB.BASEBOARD_FAB2(SCH_1):CLK_100M_CPU1_RC_REFCLK0_DP    I19 @BASEBOARD_FAB2_LIB.BASEBOARD_FAB2(SCH_1):PAGE103

R4D20 RES_0402-27.4,1%,1/16W,CHIP,G2A
     1 CLK_100M_CPU0_BCLK1_R_DN @BASEBOARD_FAB2_LIB.BASEBOARD_FAB2(SCH_1):CLK_100M_CPU0_BCLK1_R_DN   I119 @BASEBOARD_FAB2_LIB.BASEBOARD_FAB2(SCH_1):PAGE103
     2 CLK_100M_CPU0_BCLK1_DN @BASEBOARD_FAB2_LIB.BASEBOARD_FAB2(SCH_1):CLK_100M_CPU0_BCLK1_DN   I119 @BASEBOARD_FAB2_LIB.BASEBOARD_FAB2(SCH_1):PAGE103

R4D21 RES_0402-27.4,1%,1/16W,CHIP,G2A
     1 CLK_100M_CPU1_RC_REFCLK0_R_DN @BASEBOARD_FAB2_LIB.BASEBOARD_FAB2(SCH_1):CLK_100M_CPU1_RC_REFCLK0_R_DN    I24 @BASEBOARD_FAB2_LIB.BASEBOARD_FAB2(SCH_1):PAGE103
     2 CLK_100M_CPU1_RC_REFCLK0_DN @BASEBOARD_FAB2_LIB.BASEBOARD_FAB2(SCH_1):CLK_100M_CPU1_RC_REFCLK0_DN    I24 @BASEBOARD_FAB2_LIB.BASEBOARD_FAB2(SCH_1):PAGE103

R4D22 RES_0402-27.4,1%,1/16W,CHIP,G2A
     1 CLK_100M_CPU0_BCLK1_R_DP @BASEBOARD_FAB2_LIB.BASEBOARD_FAB2(SCH_1):CLK_100M_CPU0_BCLK1_R_DP   I114 @BASEBOARD_FAB2_LIB.BASEBOARD_FAB2(SCH_1):PAGE103
     2 CLK_100M_CPU0_BCLK1_DP @BASEBOARD_FAB2_LIB.BASEBOARD_FAB2(SCH_1):CLK_100M_CPU0_BCLK1_DP   I114 @BASEBOARD_FAB2_LIB.BASEBOARD_FAB2(SCH_1):PAGE103

R4D23 RES_0402-27.4,1%,1/16W,CHIP,G2A
     1 CLK_100M_CPU1_RC_REFCLK1_R_DP @BASEBOARD_FAB2_LIB.BASEBOARD_FAB2(SCH_1):CLK_100M_CPU1_RC_REFCLK1_R_DP     I9 @BASEBOARD_FAB2_LIB.BASEBOARD_FAB2(SCH_1):PAGE103
     2 CLK_100M_CPU1_RC_REFCLK1_DP @BASEBOARD_FAB2_LIB.BASEBOARD_FAB2(SCH_1):CLK_100M_CPU1_RC_REFCLK1_DP     I9 @BASEBOARD_FAB2_LIB.BASEBOARD_FAB2(SCH_1):PAGE103

R4D24 RES_0402-42.2,1.0%,1/16W,EMPTYA
     1 CLK_100M_CPU0_BCLK1_DP @BASEBOARD_FAB2_LIB.BASEBOARD_FAB2(SCH_1):CLK_100M_CPU0_BCLK1_DP   I161 @BASEBOARD_FAB2_LIB.BASEBOARD_FAB2(SCH_1):PAGE103
     2    GND @BASEBOARD_FAB2_LIB.BASEBOARD_FAB2(SCH_1):GND   I161 @BASEBOARD_FAB2_LIB.BASEBOARD_FAB2(SCH_1):PAGE103

R4D25 RES_0402-27.4,1%,1/16W,CHIP,G2A
     1 CLK_100M_CPU0_BCLK0_R_DN @BASEBOARD_FAB2_LIB.BASEBOARD_FAB2(SCH_1):CLK_100M_CPU0_BCLK0_R_DN     I1 @BASEBOARD_FAB2_LIB.BASEBOARD_FAB2(SCH_1):PAGE103
     2 CLK_100M_CPU0_BCLK0_DN @BASEBOARD_FAB2_LIB.BASEBOARD_FAB2(SCH_1):CLK_100M_CPU0_BCLK0_DN     I1 @BASEBOARD_FAB2_LIB.BASEBOARD_FAB2(SCH_1):PAGE103

R4D26 RES_0402-0.0,5%,1/16W,CHIP,G21A
     1 P3V3_STBY @BASEBOARD_FAB2_LIB.BASEBOARD_FAB2(SCH_1):P3V3_STBY    I40 @BASEBOARD_FAB2_LIB.BASEBOARD_FAB2(SCH_1):PAGE201
     2 VR_PVCCIN_CPU0_VDD @BASEBOARD_FAB2_LIB.BASEBOARD_FAB2(SCH_1):VR_PVCCIN_CPU0_VDD    I40 @BASEBOARD_FAB2_LIB.BASEBOARD_FAB2(SCH_1):PAGE201

R4D27 RES_0402-100.0K,1%,1/16W,CHIP,B
     1 VR_FET_SW_P12V_STBY_PVCCIN_CPU0 @BASEBOARD_FAB2_LIB.BASEBOARD_FAB2(SCH_1):VR_FET_SW_P12V_STBY_PVCCIN_CPU0    I54 @BASEBOARD_FAB2_LIB.BASEBOARD_FAB2(SCH_1):PAGE201
     2 VR_PVCCIN_CPU0_AVINSEN @BASEBOARD_FAB2_LIB.BASEBOARD_FAB2(SCH_1):VR_PVCCIN_CPU0_AVINSEN    I54 @BASEBOARD_FAB2_LIB.BASEBOARD_FAB2(SCH_1):PAGE201

R4D28 RES_0402-27.4,1%,1/16W,CHIP,G2A
     1 CLK_100M_CPU1_RC_REFCLK1_R_DN @BASEBOARD_FAB2_LIB.BASEBOARD_FAB2(SCH_1):CLK_100M_CPU1_RC_REFCLK1_R_DN    I14 @BASEBOARD_FAB2_LIB.BASEBOARD_FAB2(SCH_1):PAGE103
     2 CLK_100M_CPU1_RC_REFCLK1_DN @BASEBOARD_FAB2_LIB.BASEBOARD_FAB2(SCH_1):CLK_100M_CPU1_RC_REFCLK1_DN    I14 @BASEBOARD_FAB2_LIB.BASEBOARD_FAB2(SCH_1):PAGE103

R4D29 RES_0402-27.4,1%,1/16W,CHIP,G2A
     1 CLK_100M_CPU0_BCLK0_R_DP @BASEBOARD_FAB2_LIB.BASEBOARD_FAB2(SCH_1):CLK_100M_CPU0_BCLK0_R_DP    I69 @BASEBOARD_FAB2_LIB.BASEBOARD_FAB2(SCH_1):PAGE103
     2 CLK_100M_CPU0_BCLK0_DP @BASEBOARD_FAB2_LIB.BASEBOARD_FAB2(SCH_1):CLK_100M_CPU0_BCLK0_DP    I69 @BASEBOARD_FAB2_LIB.BASEBOARD_FAB2(SCH_1):PAGE103

R4D31 RES_0402-2.26K,1.0%,1/16W,EMPTA
     1 P3V3_STBY @BASEBOARD_FAB2_LIB.BASEBOARD_FAB2(SCH_1):P3V3_STBY    I22 @BASEBOARD_FAB2_LIB.BASEBOARD_FAB2(SCH_1):PAGE201
     2 PU_VR_PVCCIN_CPU0_IMON @BASEBOARD_FAB2_LIB.BASEBOARD_FAB2(SCH_1):PU_VR_PVCCIN_CPU0_IMON    I22 @BASEBOARD_FAB2_LIB.BASEBOARD_FAB2(SCH_1):PAGE201

R4D32 RES_0402-1.5K,1%,1/16W,CHIP,G2A
     1 VR_PVCCIN_CPU0_AVINSEN @BASEBOARD_FAB2_LIB.BASEBOARD_FAB2(SCH_1):VR_PVCCIN_CPU0_AVINSEN    I55 @BASEBOARD_FAB2_LIB.BASEBOARD_FAB2(SCH_1):PAGE201
     2    GND @BASEBOARD_FAB2_LIB.BASEBOARD_FAB2(SCH_1):GND    I55 @BASEBOARD_FAB2_LIB.BASEBOARD_FAB2(SCH_1):PAGE201

R4D35 RES_0402-10.0K,1%,1/16W,EMPTY,A
     1 P3V3_DB1200 @BASEBOARD_FAB2_LIB.BASEBOARD_FAB2(SCH_1):P3V3_DB1200    I38 @BASEBOARD_FAB2_LIB.BASEBOARD_FAB2(SCH_1):PAGE102
     2 FM_DB1200_SMB_SA0 @BASEBOARD_FAB2_LIB.BASEBOARD_FAB2(SCH_1):FM_DB1200_SMB_SA0    I38 @BASEBOARD_FAB2_LIB.BASEBOARD_FAB2(SCH_1):PAGE102

R4D36 RES_0402-33.2,1%,1/16W,CHIP,G2A
     1 SMB_HOST_STBY_LVC3_SDA @BASEBOARD_FAB2_LIB.BASEBOARD_FAB2(SCH_1):SMB_HOST_STBY_LVC3_SDA    I82 @BASEBOARD_FAB2_LIB.BASEBOARD_FAB2(SCH_1):PAGE102
     2 SMB_HOST_STBY_LVC3_SDA_R2 @BASEBOARD_FAB2_LIB.BASEBOARD_FAB2(SCH_1):SMB_HOST_STBY_LVC3_SDA_R2    I82 @BASEBOARD_FAB2_LIB.BASEBOARD_FAB2(SCH_1):PAGE102

R4D37 RES_0402-33.2,1%,1/16W,CHIP,G2A
     1 SMB_HOST_STBY_LVC3_SCL @BASEBOARD_FAB2_LIB.BASEBOARD_FAB2(SCH_1):SMB_HOST_STBY_LVC3_SCL    I87 @BASEBOARD_FAB2_LIB.BASEBOARD_FAB2(SCH_1):PAGE102
     2 SMB_HOST_STBY_LVC3_SCL_R2 @BASEBOARD_FAB2_LIB.BASEBOARD_FAB2(SCH_1):SMB_HOST_STBY_LVC3_SCL_R2    I87 @BASEBOARD_FAB2_LIB.BASEBOARD_FAB2(SCH_1):PAGE102

R4D38 RES_0402-10.0K,1%,1/16W,EMPTY,A
     1 P3V3_DB1200 @BASEBOARD_FAB2_LIB.BASEBOARD_FAB2(SCH_1):P3V3_DB1200    I37 @BASEBOARD_FAB2_LIB.BASEBOARD_FAB2(SCH_1):PAGE102
     2 FM_DB1200_SMB_SA1 @BASEBOARD_FAB2_LIB.BASEBOARD_FAB2(SCH_1):FM_DB1200_SMB_SA1    I37 @BASEBOARD_FAB2_LIB.BASEBOARD_FAB2(SCH_1):PAGE102

R4D39 RES_0402-10.0,1%,1/16W,CHIP,G2A
     1 VSENSE_PVSA_CPU0_P @BASEBOARD_FAB2_LIB.BASEBOARD_FAB2(SCH_1):VSENSE_PVSA_CPU0_P   I110 @BASEBOARD_FAB2_LIB.BASEBOARD_FAB2(SCH_1):PAGE201
     2 VSENSE_PVSA_CPU0_BVSP @BASEBOARD_FAB2_LIB.BASEBOARD_FAB2(SCH_1):VSENSE_PVSA_CPU0_BVSP   I110 @BASEBOARD_FAB2_LIB.BASEBOARD_FAB2(SCH_1):PAGE201

R4D40 RES_0402-4.75K,1%,1/16W,CHIP,GA
     1 P3V3_DB1200 @BASEBOARD_FAB2_LIB.BASEBOARD_FAB2(SCH_1):P3V3_DB1200    I45 @BASEBOARD_FAB2_LIB.BASEBOARD_FAB2(SCH_1):PAGE102
     2 FM_100M_N @BASEBOARD_FAB2_LIB.BASEBOARD_FAB2(SCH_1):FM_100M_N    I45 @BASEBOARD_FAB2_LIB.BASEBOARD_FAB2(SCH_1):PAGE102

R4D41 RES_0402-4.75K,1%,1/16W,CHIP,GA
     1 P3V3_DB1200 @BASEBOARD_FAB2_LIB.BASEBOARD_FAB2(SCH_1):P3V3_DB1200    I53 @BASEBOARD_FAB2_LIB.BASEBOARD_FAB2(SCH_1):PAGE102
     2 FM_HBW_BYPASS_LOWBW_N @BASEBOARD_FAB2_LIB.BASEBOARD_FAB2(SCH_1):FM_HBW_BYPASS_LOWBW_N    I53 @BASEBOARD_FAB2_LIB.BASEBOARD_FAB2(SCH_1):PAGE102

R4D42 RES_0402-1.00K,1%,1/16W,CHIP,GA
     1 P3V3_STBY @BASEBOARD_FAB2_LIB.BASEBOARD_FAB2(SCH_1):P3V3_STBY    I15 @BASEBOARD_FAB2_LIB.BASEBOARD_FAB2(SCH_1):PAGE213
     2 PWRGD_PVCCIO_CPU1_R @BASEBOARD_FAB2_LIB.BASEBOARD_FAB2(SCH_1):PWRGD_PVCCIO_CPU1_R    I15 @BASEBOARD_FAB2_LIB.BASEBOARD_FAB2(SCH_1):PAGE213

R4D43 RES_0402-20.0,1%,1/16W,CHIP,G2A
     1 SMB_VR_STBY_LVC3_SCL @BASEBOARD_FAB2_LIB.BASEBOARD_FAB2(SCH_1):SMB_VR_STBY_LVC3_SCL    I39 @BASEBOARD_FAB2_LIB.BASEBOARD_FAB2(SCH_1):PAGE213
     2 SMB_VR_SCL_PVCCIO_CPU1 @BASEBOARD_FAB2_LIB.BASEBOARD_FAB2(SCH_1):SMB_VR_SCL_PVCCIO_CPU1    I39 @BASEBOARD_FAB2_LIB.BASEBOARD_FAB2(SCH_1):PAGE213

R4D44 RES_0402-20.0,1%,1/16W,CHIP,G2A
     1 SMB_VR_STBY_LVC3_SDA @BASEBOARD_FAB2_LIB.BASEBOARD_FAB2(SCH_1):SMB_VR_STBY_LVC3_SDA    I38 @BASEBOARD_FAB2_LIB.BASEBOARD_FAB2(SCH_1):PAGE213
     2 SMB_VR_SDA_PVCCIO_CPU1 @BASEBOARD_FAB2_LIB.BASEBOARD_FAB2(SCH_1):SMB_VR_SDA_PVCCIO_CPU1    I38 @BASEBOARD_FAB2_LIB.BASEBOARD_FAB2(SCH_1):PAGE213

R4D45 RES_0402-0.0,5%,1/16W,CHIP,G21A
     1 VR_PVCCIO_CPU1_VD12 @BASEBOARD_FAB2_LIB.BASEBOARD_FAB2(SCH_1):VR_PVCCIO_CPU1_VD12    I94 @BASEBOARD_FAB2_LIB.BASEBOARD_FAB2(SCH_1):PAGE213
     2 VR_PVCCIO_CPU1_AIREF1 @BASEBOARD_FAB2_LIB.BASEBOARD_FAB2(SCH_1):VR_PVCCIO_CPU1_AIREF1    I94 @BASEBOARD_FAB2_LIB.BASEBOARD_FAB2(SCH_1):PAGE213

R4D46 RES_0402-22.1,1.0%,1/16W,CHIP,A
     1 PWRGD_PVCCIO_CPU1_R @BASEBOARD_FAB2_LIB.BASEBOARD_FAB2(SCH_1):PWRGD_PVCCIO_CPU1_R    I13 @BASEBOARD_FAB2_LIB.BASEBOARD_FAB2(SCH_1):PAGE213
     2 PWRGD_PVCCIO_CPU1 @BASEBOARD_FAB2_LIB.BASEBOARD_FAB2(SCH_1):PWRGD_PVCCIO_CPU1    I13 @BASEBOARD_FAB2_LIB.BASEBOARD_FAB2(SCH_1):PAGE213

R4D47 RES_0402-0.0,5%,1/16W,CHIP,G21A
     1 P3V3_STBY @BASEBOARD_FAB2_LIB.BASEBOARD_FAB2(SCH_1):P3V3_STBY    I25 @BASEBOARD_FAB2_LIB.BASEBOARD_FAB2(SCH_1):PAGE213
     2 VR_PVCCIO_CPU1_VDD @BASEBOARD_FAB2_LIB.BASEBOARD_FAB2(SCH_1):VR_PVCCIO_CPU1_VDD    I25 @BASEBOARD_FAB2_LIB.BASEBOARD_FAB2(SCH_1):PAGE213

R4D49 RES_0402-1.00K,1%,1/16W,CHIP,GA
     1 P3V3_STBY @BASEBOARD_FAB2_LIB.BASEBOARD_FAB2(SCH_1):P3V3_STBY    I63 @BASEBOARD_FAB2_LIB.BASEBOARD_FAB2(SCH_1):PAGE213
     2 IRQ_PVCCIO_CPU1_VRHOT_N @BASEBOARD_FAB2_LIB.BASEBOARD_FAB2(SCH_1):IRQ_PVCCIO_CPU1_VRHOT_N    I63 @BASEBOARD_FAB2_LIB.BASEBOARD_FAB2(SCH_1):PAGE213

R4D50 RES_0402-0.0,5%,1/16W,CHIP,G21A
     1 SMB_VR_SDA_R @BASEBOARD_FAB2_LIB.BASEBOARD_FAB2(SCH_1):SMB_VR_SDA_R    I28 @BASEBOARD_FAB2_LIB.BASEBOARD_FAB2(SCH_1):PAGE201
     2 SMB_VR_STBY_LVC3_SDA @BASEBOARD_FAB2_LIB.BASEBOARD_FAB2(SCH_1):SMB_VR_STBY_LVC3_SDA    I28 @BASEBOARD_FAB2_LIB.BASEBOARD_FAB2(SCH_1):PAGE201

R4D51 RES_0402-150.0,1%,1/16W,CHIP,GA
     1 SVID_CLK0_CPU1_R @BASEBOARD_FAB2_LIB.BASEBOARD_FAB2(SCH_1):SVID_CLK0_CPU1_R    I46 @BASEBOARD_FAB2_LIB.BASEBOARD_FAB2(SCH_1):PAGE213
     2 SVID_CLK_PVCCIO_CPU1 @BASEBOARD_FAB2_LIB.BASEBOARD_FAB2(SCH_1):SVID_CLK_PVCCIO_CPU1    I46 @BASEBOARD_FAB2_LIB.BASEBOARD_FAB2(SCH_1):PAGE213

R4D53 RES_0402-0.0,5%,1/16W,CHIP,G21A
     1 SMB_VR_SCL_R @BASEBOARD_FAB2_LIB.BASEBOARD_FAB2(SCH_1):SMB_VR_SCL_R    I31 @BASEBOARD_FAB2_LIB.BASEBOARD_FAB2(SCH_1):PAGE201
     2 SMB_VR_STBY_LVC3_SCL @BASEBOARD_FAB2_LIB.BASEBOARD_FAB2(SCH_1):SMB_VR_STBY_LVC3_SCL    I31 @BASEBOARD_FAB2_LIB.BASEBOARD_FAB2(SCH_1):PAGE201

R4D54 RES_0402-0.0,5%,1/16W,CHIP,G21A
     1 SVID_DIO0_CPU1_R @BASEBOARD_FAB2_LIB.BASEBOARD_FAB2(SCH_1):SVID_DIO0_CPU1_R    I37 @BASEBOARD_FAB2_LIB.BASEBOARD_FAB2(SCH_1):PAGE213
     2 SVID_VDIO_PVCCIO_CPU1 @BASEBOARD_FAB2_LIB.BASEBOARD_FAB2(SCH_1):SVID_VDIO_PVCCIO_CPU1    I37 @BASEBOARD_FAB2_LIB.BASEBOARD_FAB2(SCH_1):PAGE213

R4D56 RES_0402-0.0,5%,1/16W,CHIP,G21A
     1 SVID_ALERT_PVCCIO_CPU1 @BASEBOARD_FAB2_LIB.BASEBOARD_FAB2(SCH_1):SVID_ALERT_PVCCIO_CPU1    I16 @BASEBOARD_FAB2_LIB.BASEBOARD_FAB2(SCH_1):PAGE213
     2 SVID_ALERT0_CPU1_R_N @BASEBOARD_FAB2_LIB.BASEBOARD_FAB2(SCH_1):SVID_ALERT0_CPU1_R_N    I16 @BASEBOARD_FAB2_LIB.BASEBOARD_FAB2(SCH_1):PAGE213

R4D57 RES_0402-1.5K,1%,1/16W,CHIP,G2A
     1 VR_PVCCIO_CPU1_VINSEN @BASEBOARD_FAB2_LIB.BASEBOARD_FAB2(SCH_1):VR_PVCCIO_CPU1_VINSEN    I32 @BASEBOARD_FAB2_LIB.BASEBOARD_FAB2(SCH_1):PAGE213
     2    GND @BASEBOARD_FAB2_LIB.BASEBOARD_FAB2(SCH_1):GND    I32 @BASEBOARD_FAB2_LIB.BASEBOARD_FAB2(SCH_1):PAGE213

R4D58 RES_0402-1.00K,1%,1/16W,CHIP,GA
     1 P3V3_STBY @BASEBOARD_FAB2_LIB.BASEBOARD_FAB2(SCH_1):P3V3_STBY    I25 @BASEBOARD_FAB2_LIB.BASEBOARD_FAB2(SCH_1):PAGE201
     2 VR_VRRDY_PVCCIN_CPU0 @BASEBOARD_FAB2_LIB.BASEBOARD_FAB2(SCH_1):VR_VRRDY_PVCCIN_CPU0    I25 @BASEBOARD_FAB2_LIB.BASEBOARD_FAB2(SCH_1):PAGE201

R4D60 RES_0402-100.0K,1%,1/16W,CHIP,B
     1 VR_FET_SW_P12V_STBY_PVCCIN_CPU0 @BASEBOARD_FAB2_LIB.BASEBOARD_FAB2(SCH_1):VR_FET_SW_P12V_STBY_PVCCIN_CPU0    I31 @BASEBOARD_FAB2_LIB.BASEBOARD_FAB2(SCH_1):PAGE213
     2 VR_PVCCIO_CPU1_VINSEN @BASEBOARD_FAB2_LIB.BASEBOARD_FAB2(SCH_1):VR_PVCCIO_CPU1_VINSEN    I31 @BASEBOARD_FAB2_LIB.BASEBOARD_FAB2(SCH_1):PAGE213

R4D63 RES_0402-22.1,1.0%,1/16W,CHIP,A
     1 VR_VRRDY_PVCCIN_CPU0 @BASEBOARD_FAB2_LIB.BASEBOARD_FAB2(SCH_1):VR_VRRDY_PVCCIN_CPU0   I124 @BASEBOARD_FAB2_LIB.BASEBOARD_FAB2(SCH_1):PAGE201
     2 PWRGD_PVCCIN_CPU0 @BASEBOARD_FAB2_LIB.BASEBOARD_FAB2(SCH_1):PWRGD_PVCCIN_CPU0   I124 @BASEBOARD_FAB2_LIB.BASEBOARD_FAB2(SCH_1):PAGE201

R4D64 RES_0402-3.16K,1%,1/16W,CHIP,GA
     1 VR_PVCCIO_CPU1_XADDR1 @BASEBOARD_FAB2_LIB.BASEBOARD_FAB2(SCH_1):VR_PVCCIO_CPU1_XADDR1    I42 @BASEBOARD_FAB2_LIB.BASEBOARD_FAB2(SCH_1):PAGE213
     2    GND @BASEBOARD_FAB2_LIB.BASEBOARD_FAB2(SCH_1):GND    I42 @BASEBOARD_FAB2_LIB.BASEBOARD_FAB2(SCH_1):PAGE213

R4D65 RES_0402-33.2,1%,1/16W,CHIP,G2A
     1 PWRGD_PVSA_CPU0_R @BASEBOARD_FAB2_LIB.BASEBOARD_FAB2(SCH_1):PWRGD_PVSA_CPU0_R   I127 @BASEBOARD_FAB2_LIB.BASEBOARD_FAB2(SCH_1):PAGE201
     2 PWRGD_PVSA_CPU0 @BASEBOARD_FAB2_LIB.BASEBOARD_FAB2(SCH_1):PWRGD_PVSA_CPU0   I127 @BASEBOARD_FAB2_LIB.BASEBOARD_FAB2(SCH_1):PAGE201

R4D66 RES_0402-0.0,5%,1/16W,CHIP,G21A
     1 SVID_VDIO_PVCCIN_CPU0 @BASEBOARD_FAB2_LIB.BASEBOARD_FAB2(SCH_1):SVID_VDIO_PVCCIN_CPU0    I98 @BASEBOARD_FAB2_LIB.BASEBOARD_FAB2(SCH_1):PAGE201
     2 SVID_DIO0_CPU0_R @BASEBOARD_FAB2_LIB.BASEBOARD_FAB2(SCH_1):SVID_DIO0_CPU0_R    I98 @BASEBOARD_FAB2_LIB.BASEBOARD_FAB2(SCH_1):PAGE201

R4D67 RES_0402-0.0,5%,1/16W,CHIP,G21A
     1 SVID_VALERT_VCCIN_CPU0 @BASEBOARD_FAB2_LIB.BASEBOARD_FAB2(SCH_1):SVID_VALERT_VCCIN_CPU0    I26 @BASEBOARD_FAB2_LIB.BASEBOARD_FAB2(SCH_1):PAGE201
     2 SVID_ALERT0_CPU0_R_N @BASEBOARD_FAB2_LIB.BASEBOARD_FAB2(SCH_1):SVID_ALERT0_CPU0_R_N    I26 @BASEBOARD_FAB2_LIB.BASEBOARD_FAB2(SCH_1):PAGE201

R4D68 RES_0402-68.1K,1%,1/16W,EMPTY,A
     1 VR_PVCCIN_CPU0_PH5_OCSET @BASEBOARD_FAB2_LIB.BASEBOARD_FAB2(SCH_1):VR_PVCCIN_CPU0_PH5_OCSET    I83 @BASEBOARD_FAB2_LIB.BASEBOARD_FAB2(SCH_1):PAGE204
     2    GND @BASEBOARD_FAB2_LIB.BASEBOARD_FAB2(SCH_1):GND    I83 @BASEBOARD_FAB2_LIB.BASEBOARD_FAB2(SCH_1):PAGE204

R4D69 RES_0402-4.75K,1%,1/16W,CHIP,GA
     1   P3V3 @BASEBOARD_FAB2_LIB.BASEBOARD_FAB2(SCH_1):P3V3    I93 @BASEBOARD_FAB2_LIB.BASEBOARD_FAB2(SCH_1):PAGE102
     2 FM_CPU1_MCP_CLK_EN_N @BASEBOARD_FAB2_LIB.BASEBOARD_FAB2(SCH_1):FM_CPU1_MCP_CLK_EN_N    I93 @BASEBOARD_FAB2_LIB.BASEBOARD_FAB2(SCH_1):PAGE102

R4D70 RES_0402-4.75K,1%,1/16W,CHIP,GA
     1   P3V3 @BASEBOARD_FAB2_LIB.BASEBOARD_FAB2(SCH_1):P3V3    I94 @BASEBOARD_FAB2_LIB.BASEBOARD_FAB2(SCH_1):PAGE102
     2 FM_CPU0_MCP_CLK_EN_N @BASEBOARD_FAB2_LIB.BASEBOARD_FAB2(SCH_1):FM_CPU0_MCP_CLK_EN_N    I94 @BASEBOARD_FAB2_LIB.BASEBOARD_FAB2(SCH_1):PAGE102

R4D71 RES_0402-68.1K,1%,1/16W,EMPTY,A
     1 VR_PVCCIN_CPU0_PH4_OCSET @BASEBOARD_FAB2_LIB.BASEBOARD_FAB2(SCH_1):VR_PVCCIN_CPU0_PH4_OCSET    I91 @BASEBOARD_FAB2_LIB.BASEBOARD_FAB2(SCH_1):PAGE203
     2    GND @BASEBOARD_FAB2_LIB.BASEBOARD_FAB2(SCH_1):GND    I91 @BASEBOARD_FAB2_LIB.BASEBOARD_FAB2(SCH_1):PAGE203

R4D72 RES_0402-68.1K,1%,1/16W,EMPTY,A
     1 VR_PVCCIN_CPU0_PH3_OCSET @BASEBOARD_FAB2_LIB.BASEBOARD_FAB2(SCH_1):VR_PVCCIN_CPU0_PH3_OCSET    I89 @BASEBOARD_FAB2_LIB.BASEBOARD_FAB2(SCH_1):PAGE203
     2    GND @BASEBOARD_FAB2_LIB.BASEBOARD_FAB2(SCH_1):GND    I89 @BASEBOARD_FAB2_LIB.BASEBOARD_FAB2(SCH_1):PAGE203

R4E2 RES_0402-3.16K,1%,1/16W,CHIP,GA
     1 VR_PVCCIO_CPU1_XADDR2 @BASEBOARD_FAB2_LIB.BASEBOARD_FAB2(SCH_1):VR_PVCCIO_CPU1_XADDR2    I65 @BASEBOARD_FAB2_LIB.BASEBOARD_FAB2(SCH_1):PAGE213
     2    GND @BASEBOARD_FAB2_LIB.BASEBOARD_FAB2(SCH_1):GND    I65 @BASEBOARD_FAB2_LIB.BASEBOARD_FAB2(SCH_1):PAGE213

R4E3 RES_0402-1.00K,1%,1/16W,CHIP,GA
     1 P3V3_STBY @BASEBOARD_FAB2_LIB.BASEBOARD_FAB2(SCH_1):P3V3_STBY   I111 @BASEBOARD_FAB2_LIB.BASEBOARD_FAB2(SCH_1):PAGE201
     2 IRQ_PVCCIN_CPU0_VRHOT_LVC3_R_N @BASEBOARD_FAB2_LIB.BASEBOARD_FAB2(SCH_1):IRQ_PVCCIN_CPU0_VRHOT_LVC3_R_N   I111 @BASEBOARD_FAB2_LIB.BASEBOARD_FAB2(SCH_1):PAGE201

R4E4 RES_0402-2.26K,1.0%,1/16W,CHIPA
     1 P3V3_STBY @BASEBOARD_FAB2_LIB.BASEBOARD_FAB2(SCH_1):P3V3_STBY    I19 @BASEBOARD_FAB2_LIB.BASEBOARD_FAB2(SCH_1):PAGE201
     2 FM_PVCCIN_CPU0_PWR_IN_ALERT_N @BASEBOARD_FAB2_LIB.BASEBOARD_FAB2(SCH_1):FM_PVCCIN_CPU0_PWR_IN_ALERT_N    I19 @BASEBOARD_FAB2_LIB.BASEBOARD_FAB2(SCH_1):PAGE201

R4E5 RES_0402-1.00K,1%,1/16W,CHIP,GA
     1 P3V3_STBY @BASEBOARD_FAB2_LIB.BASEBOARD_FAB2(SCH_1):P3V3_STBY    I27 @BASEBOARD_FAB2_LIB.BASEBOARD_FAB2(SCH_1):PAGE201
     2 PWRGD_PVSA_CPU0_R @BASEBOARD_FAB2_LIB.BASEBOARD_FAB2(SCH_1):PWRGD_PVSA_CPU0_R    I27 @BASEBOARD_FAB2_LIB.BASEBOARD_FAB2(SCH_1):PAGE201

R4E6 RES_0402-150.0,1%,1/16W,CHIP,GA
     1 SVID_CLK0_CPU0_R @BASEBOARD_FAB2_LIB.BASEBOARD_FAB2(SCH_1):SVID_CLK0_CPU0_R    I56 @BASEBOARD_FAB2_LIB.BASEBOARD_FAB2(SCH_1):PAGE201
     2 SVID_VCLK_PVCCIN_CPU0 @BASEBOARD_FAB2_LIB.BASEBOARD_FAB2(SCH_1):SVID_VCLK_PVCCIN_CPU0    I56 @BASEBOARD_FAB2_LIB.BASEBOARD_FAB2(SCH_1):PAGE201

R4E7 RES_0402-10.0,1%,1/16W,CHIP,G2A
     1 VSENSE_PVCCIO_CPU1_AVSP @BASEBOARD_FAB2_LIB.BASEBOARD_FAB2(SCH_1):VSENSE_PVCCIO_CPU1_AVSP    I84 @BASEBOARD_FAB2_LIB.BASEBOARD_FAB2(SCH_1):PAGE213
     2 VR_PVCCIO_CPU1_AVSP @BASEBOARD_FAB2_LIB.BASEBOARD_FAB2(SCH_1):VR_PVCCIO_CPU1_AVSP    I84 @BASEBOARD_FAB2_LIB.BASEBOARD_FAB2(SCH_1):PAGE213

R4E8 RES_0402-10.0,1%,1/16W,CHIP,G2A
     1 VSENSE_PVCCIN_CPU0_P @BASEBOARD_FAB2_LIB.BASEBOARD_FAB2(SCH_1):VSENSE_PVCCIN_CPU0_P   I109 @BASEBOARD_FAB2_LIB.BASEBOARD_FAB2(SCH_1):PAGE201
     2 VSENSE_PVCCIN_CPU0_AVSP @BASEBOARD_FAB2_LIB.BASEBOARD_FAB2(SCH_1):VSENSE_PVCCIN_CPU0_AVSP   I109 @BASEBOARD_FAB2_LIB.BASEBOARD_FAB2(SCH_1):PAGE201

R4E9 RES_0402-49.9,1%,1/16W,CHIP,G2A
     1 PVCCIO_CPU0 @BASEBOARD_FAB2_LIB.BASEBOARD_FAB2(SCH_1):PVCCIO_CPU0    I52 @BASEBOARD_FAB2_LIB.BASEBOARD_FAB2(SCH_1):PAGE201
     2 SVID_CLK0_CPU0_R @BASEBOARD_FAB2_LIB.BASEBOARD_FAB2(SCH_1):SVID_CLK0_CPU0_R    I52 @BASEBOARD_FAB2_LIB.BASEBOARD_FAB2(SCH_1):PAGE201

R4E10 RES_0402-100.0,1%,1/16W,CHIP,GA
     1 PVCCIO_CPU0 @BASEBOARD_FAB2_LIB.BASEBOARD_FAB2(SCH_1):PVCCIO_CPU0    I20 @BASEBOARD_FAB2_LIB.BASEBOARD_FAB2(SCH_1):PAGE201
     2 SVID_DIO0_CPU0_R @BASEBOARD_FAB2_LIB.BASEBOARD_FAB2(SCH_1):SVID_DIO0_CPU0_R    I20 @BASEBOARD_FAB2_LIB.BASEBOARD_FAB2(SCH_1):PAGE201

R4E13 RES_0603-100.0,1%,1/10W,CHIP,GA
     1 PVCCIN_CPU0 @BASEBOARD_FAB2_LIB.BASEBOARD_FAB2(SCH_1):PVCCIN_CPU0    I67 @BASEBOARD_FAB2_LIB.BASEBOARD_FAB2(SCH_1):PAGE203
     2    GND @BASEBOARD_FAB2_LIB.BASEBOARD_FAB2(SCH_1):GND    I67 @BASEBOARD_FAB2_LIB.BASEBOARD_FAB2(SCH_1):PAGE203

R4E14 RES_0402-100.0,1%,1/16W,CHIP,GA
     1 VSENSE_PVCCIN_CPU0_P @BASEBOARD_FAB2_LIB.BASEBOARD_FAB2(SCH_1):VSENSE_PVCCIN_CPU0_P    I60 @BASEBOARD_FAB2_LIB.BASEBOARD_FAB2(SCH_1):PAGE204
     2 PVCCIN_CPU0 @BASEBOARD_FAB2_LIB.BASEBOARD_FAB2(SCH_1):PVCCIN_CPU0    I60 @BASEBOARD_FAB2_LIB.BASEBOARD_FAB2(SCH_1):PAGE204

R4E15 RES_0402-1.00K,1%,1/16W,EMPTY,A
     1 VSENSE_PVCCIN_CPU0_P @BASEBOARD_FAB2_LIB.BASEBOARD_FAB2(SCH_1):VSENSE_PVCCIN_CPU0_P    I63 @BASEBOARD_FAB2_LIB.BASEBOARD_FAB2(SCH_1):PAGE204
     2 VSENSE_PVCCIN_CPU0_N @BASEBOARD_FAB2_LIB.BASEBOARD_FAB2(SCH_1):VSENSE_PVCCIN_CPU0_N    I63 @BASEBOARD_FAB2_LIB.BASEBOARD_FAB2(SCH_1):PAGE204

R4E16 RES_0402-0.0,5%,1/16W,CHIP,G21A
     1 VSENSE_PVCCIN_CPU0_P @BASEBOARD_FAB2_LIB.BASEBOARD_FAB2(SCH_1):VSENSE_PVCCIN_CPU0_P    I61 @BASEBOARD_FAB2_LIB.BASEBOARD_FAB2(SCH_1):PAGE204
     2 VSENSE_PVCCIN_CPU0_SKT_VSEN @BASEBOARD_FAB2_LIB.BASEBOARD_FAB2(SCH_1):VSENSE_PVCCIN_CPU0_SKT_VSEN    I61 @BASEBOARD_FAB2_LIB.BASEBOARD_FAB2(SCH_1):PAGE204

R4E17 RES_0402-0.0,5%,1/16W,CHIP,G21A
     1 VSENSE_PVCCIN_CPU0_N @BASEBOARD_FAB2_LIB.BASEBOARD_FAB2(SCH_1):VSENSE_PVCCIN_CPU0_N    I62 @BASEBOARD_FAB2_LIB.BASEBOARD_FAB2(SCH_1):PAGE204
     2 VSENSE_PVCCIN_CPU0_SKT_VRTN @BASEBOARD_FAB2_LIB.BASEBOARD_FAB2(SCH_1):VSENSE_PVCCIN_CPU0_SKT_VRTN    I62 @BASEBOARD_FAB2_LIB.BASEBOARD_FAB2(SCH_1):PAGE204

R4E18 RES_0402-100.0,1%,1/16W,CHIP,GA
     1 VSENSE_PVCCIN_CPU0_N @BASEBOARD_FAB2_LIB.BASEBOARD_FAB2(SCH_1):VSENSE_PVCCIN_CPU0_N    I64 @BASEBOARD_FAB2_LIB.BASEBOARD_FAB2(SCH_1):PAGE204
     2    GND @BASEBOARD_FAB2_LIB.BASEBOARD_FAB2(SCH_1):GND    I64 @BASEBOARD_FAB2_LIB.BASEBOARD_FAB2(SCH_1):PAGE204

R4E19 RES_0402-68.1K,1%,1/16W,EMPTY,A
     1 VR_PVCCIN_CPU0_PH2_OCSET @BASEBOARD_FAB2_LIB.BASEBOARD_FAB2(SCH_1):VR_PVCCIN_CPU0_PH2_OCSET    I67 @BASEBOARD_FAB2_LIB.BASEBOARD_FAB2(SCH_1):PAGE202
     2    GND @BASEBOARD_FAB2_LIB.BASEBOARD_FAB2(SCH_1):GND    I67 @BASEBOARD_FAB2_LIB.BASEBOARD_FAB2(SCH_1):PAGE202

R4E20 RES_0402-2.26K,1.0%,1/16W,EMPTA
     1 P3V3_STBY @BASEBOARD_FAB2_LIB.BASEBOARD_FAB2(SCH_1):P3V3_STBY   I116 @BASEBOARD_FAB2_LIB.BASEBOARD_FAB2(SCH_1):PAGE201
     2 PU_VR_PVCCIN_CPU0_FLT1_SMBALT_N @BASEBOARD_FAB2_LIB.BASEBOARD_FAB2(SCH_1):PU_VR_PVCCIN_CPU0_FLT1_SMBALT_N_IMON   I116 @BASEBOARD_FAB2_LIB.BASEBOARD_FAB2(SCH_1):PAGE201

R4E21 RES_0402-68.1K,1%,1/16W,EMPTY,A
     1 VR_PVCCIO_CPU1_OCSET @BASEBOARD_FAB2_LIB.BASEBOARD_FAB2(SCH_1):VR_PVCCIO_CPU1_OCSET   I127 @BASEBOARD_FAB2_LIB.BASEBOARD_FAB2(SCH_1):PAGE214
     2    GND @BASEBOARD_FAB2_LIB.BASEBOARD_FAB2(SCH_1):GND   I127 @BASEBOARD_FAB2_LIB.BASEBOARD_FAB2(SCH_1):PAGE214

R4E22 RES_0402-68.1K,1%,1/16W,EMPTY,A
     1 VR_PVCCIN_CPU0_PH1_OCSET @BASEBOARD_FAB2_LIB.BASEBOARD_FAB2(SCH_1):VR_PVCCIN_CPU0_PH1_OCSET    I65 @BASEBOARD_FAB2_LIB.BASEBOARD_FAB2(SCH_1):PAGE202
     2    GND @BASEBOARD_FAB2_LIB.BASEBOARD_FAB2(SCH_1):GND    I65 @BASEBOARD_FAB2_LIB.BASEBOARD_FAB2(SCH_1):PAGE202

R4F1 RES_0402-0.0,5%,1/16W,CHIP,G21A
     1 VR_PVDDQ_ABC_AIINSEN_R @BASEBOARD_FAB2_LIB.BASEBOARD_FAB2(SCH_1):VR_PVDDQ_ABC_AIINSEN_R   I110 @BASEBOARD_FAB2_LIB.BASEBOARD_FAB2(SCH_1):PAGE197
     2 VR_PVDDQ_ABC_AIINSEN @BASEBOARD_FAB2_LIB.BASEBOARD_FAB2(SCH_1):VR_PVDDQ_ABC_AIINSEN   I110 @BASEBOARD_FAB2_LIB.BASEBOARD_FAB2(SCH_1):PAGE197

R4F2 RES_1206-0.002,1%,1W,CHIP,G521A
     1 P12V_NVDIMM_ABC @BASEBOARD_FAB2_LIB.BASEBOARD_FAB2(SCH_1):P12V_NVDIMM_ABC    I99 @BASEBOARD_FAB2_LIB.BASEBOARD_FAB2(SCH_1):PAGE197
     2 P12V_STBY @BASEBOARD_FAB2_LIB.BASEBOARD_FAB2(SCH_1):P12V_STBY    I99 @BASEBOARD_FAB2_LIB.BASEBOARD_FAB2(SCH_1):PAGE197

R4F3 RES_0402-2,1.0%,1/16W,CHIP,G21A
     1 M_A_CPU_VREF @BASEBOARD_FAB2_LIB.BASEBOARD_FAB2(SCH_1):M_A_CPU_VREF     I5 @BASEBOARD_FAB2_LIB.BASEBOARD_FAB2(SCH_1):PAGE98
     2 M_A_VREF @BASEBOARD_FAB2_LIB.BASEBOARD_FAB2(SCH_1):M_A_VREF     I5 @BASEBOARD_FAB2_LIB.BASEBOARD_FAB2(SCH_1):PAGE98

R4F4 RES_0402-1.00K,1%,1/16W,CHIP,GA
     1 PVDDQ_ABC @BASEBOARD_FAB2_LIB.BASEBOARD_FAB2(SCH_1):PVDDQ_ABC    I36 @BASEBOARD_FAB2_LIB.BASEBOARD_FAB2(SCH_1):PAGE98
     2 M_A_VREF @BASEBOARD_FAB2_LIB.BASEBOARD_FAB2(SCH_1):M_A_VREF    I36 @BASEBOARD_FAB2_LIB.BASEBOARD_FAB2(SCH_1):PAGE98

R4F5 RES_0402-1.00K,1%,1/16W,CHIP,GA
     1 M_A_VREF @BASEBOARD_FAB2_LIB.BASEBOARD_FAB2(SCH_1):M_A_VREF     I4 @BASEBOARD_FAB2_LIB.BASEBOARD_FAB2(SCH_1):PAGE98
     2    GND @BASEBOARD_FAB2_LIB.BASEBOARD_FAB2(SCH_1):GND     I4 @BASEBOARD_FAB2_LIB.BASEBOARD_FAB2(SCH_1):PAGE98

R4F6 RES_0402-2.2,5%,1/16W,EMPTY,G2A
     1 VR_PVPP_GHJ_SNUB @BASEBOARD_FAB2_LIB.BASEBOARD_FAB2(SCH_1):VR_PVPP_GHJ_SNUB   I208 @BASEBOARD_FAB2_LIB.BASEBOARD_FAB2(SCH_1):PAGE233
     2    GND @BASEBOARD_FAB2_LIB.BASEBOARD_FAB2(SCH_1):GND   I208 @BASEBOARD_FAB2_LIB.BASEBOARD_FAB2(SCH_1):PAGE233

R4G1 RES_0402-2,1.0%,1/16W,CHIP,G21A
     1 M_B_CPU_VREF @BASEBOARD_FAB2_LIB.BASEBOARD_FAB2(SCH_1):M_B_CPU_VREF    I42 @BASEBOARD_FAB2_LIB.BASEBOARD_FAB2(SCH_1):PAGE98
     2 M_B_VREF @BASEBOARD_FAB2_LIB.BASEBOARD_FAB2(SCH_1):M_B_VREF    I42 @BASEBOARD_FAB2_LIB.BASEBOARD_FAB2(SCH_1):PAGE98

R4G2 RES_0402-1.00K,1%,1/16W,CHIP,GA
     1 PVDDQ_ABC @BASEBOARD_FAB2_LIB.BASEBOARD_FAB2(SCH_1):PVDDQ_ABC    I38 @BASEBOARD_FAB2_LIB.BASEBOARD_FAB2(SCH_1):PAGE98
     2 M_B_VREF @BASEBOARD_FAB2_LIB.BASEBOARD_FAB2(SCH_1):M_B_VREF    I38 @BASEBOARD_FAB2_LIB.BASEBOARD_FAB2(SCH_1):PAGE98

R4G3 RES_0402-1.00K,1%,1/16W,CHIP,GA
     1 M_B_VREF @BASEBOARD_FAB2_LIB.BASEBOARD_FAB2(SCH_1):M_B_VREF    I40 @BASEBOARD_FAB2_LIB.BASEBOARD_FAB2(SCH_1):PAGE98
     2    GND @BASEBOARD_FAB2_LIB.BASEBOARD_FAB2(SCH_1):GND    I40 @BASEBOARD_FAB2_LIB.BASEBOARD_FAB2(SCH_1):PAGE98

R4G4 RES_0402-0.0,5%,1/16W,CHIP,G21A
     1 FM_PVPP_CPU1_EN @BASEBOARD_FAB2_LIB.BASEBOARD_FAB2(SCH_1):FM_PVPP_CPU1_EN   I275 @BASEBOARD_FAB2_LIB.BASEBOARD_FAB2(SCH_1):PAGE233
     2 FM_PVPP_PVDDQ_CPU1_EN_GHJ @BASEBOARD_FAB2_LIB.BASEBOARD_FAB2(SCH_1):FM_PVPP_PVDDQ_CPU1_EN_GHJ   I275 @BASEBOARD_FAB2_LIB.BASEBOARD_FAB2(SCH_1):PAGE233

R4G5 RES_0402-10.0K,1%,1/16W,CHIP,GA
     1 FM_PVPP_CPU1_EN @BASEBOARD_FAB2_LIB.BASEBOARD_FAB2(SCH_1):FM_PVPP_CPU1_EN   I182 @BASEBOARD_FAB2_LIB.BASEBOARD_FAB2(SCH_1):PAGE233
     2    GND @BASEBOARD_FAB2_LIB.BASEBOARD_FAB2(SCH_1):GND   I182 @BASEBOARD_FAB2_LIB.BASEBOARD_FAB2(SCH_1):PAGE233

R4G6 RES_0603-120.0,1%,1/10W,CHIP,GA
     1 PVPP_GHJ @BASEBOARD_FAB2_LIB.BASEBOARD_FAB2(SCH_1):PVPP_GHJ   I211 @BASEBOARD_FAB2_LIB.BASEBOARD_FAB2(SCH_1):PAGE233
     2    GND @BASEBOARD_FAB2_LIB.BASEBOARD_FAB2(SCH_1):GND   I211 @BASEBOARD_FAB2_LIB.BASEBOARD_FAB2(SCH_1):PAGE233

R4G7 RES_0402-20.0K,1%,1/16W,CHIP,GA
     1 VSENSE_PVPP_GHJ @BASEBOARD_FAB2_LIB.BASEBOARD_FAB2(SCH_1):VSENSE_PVPP_GHJ   I270 @BASEBOARD_FAB2_LIB.BASEBOARD_FAB2(SCH_1):PAGE233
     2 VR_FB_PVPP_GHJ @BASEBOARD_FAB2_LIB.BASEBOARD_FAB2(SCH_1):VR_FB_PVPP_GHJ   I270 @BASEBOARD_FAB2_LIB.BASEBOARD_FAB2(SCH_1):PAGE233

R4G8 RES_0402-0.0,5%,1/16W,CHIP,G21A
     1 PVPP_GHJ @BASEBOARD_FAB2_LIB.BASEBOARD_FAB2(SCH_1):PVPP_GHJ   I271 @BASEBOARD_FAB2_LIB.BASEBOARD_FAB2(SCH_1):PAGE233
     2 VSENSE_PVPP_GHJ @BASEBOARD_FAB2_LIB.BASEBOARD_FAB2(SCH_1):VSENSE_PVPP_GHJ   I271 @BASEBOARD_FAB2_LIB.BASEBOARD_FAB2(SCH_1):PAGE233

R4G9 RES_0402-6.34K,1%,1/16W,CHIP,GA
     1 VR_FB_PVPP_GHJ @BASEBOARD_FAB2_LIB.BASEBOARD_FAB2(SCH_1):VR_FB_PVPP_GHJ   I269 @BASEBOARD_FAB2_LIB.BASEBOARD_FAB2(SCH_1):PAGE233
     2 AGND_PVPP_GHJ @BASEBOARD_FAB2_LIB.BASEBOARD_FAB2(SCH_1):AGND_PVPP_GHJ   I269 @BASEBOARD_FAB2_LIB.BASEBOARD_FAB2(SCH_1):PAGE233

R4G10 RES_0402-1.0K,0.1%,1/16W,CHIP,A
     1 VSENSE_PVPP_GHJ @BASEBOARD_FAB2_LIB.BASEBOARD_FAB2(SCH_1):VSENSE_PVPP_GHJ   I266 @BASEBOARD_FAB2_LIB.BASEBOARD_FAB2(SCH_1):PAGE233
     2 VR_COMP_PVPP_GHJ @BASEBOARD_FAB2_LIB.BASEBOARD_FAB2(SCH_1):VR_COMP_PVPP_GHJ   I266 @BASEBOARD_FAB2_LIB.BASEBOARD_FAB2(SCH_1):PAGE233

R4G11 RES_0402-7.87K,1.0%,1/16W,CHIPA
     1 VR_PVPP_GHJ_ISET @BASEBOARD_FAB2_LIB.BASEBOARD_FAB2(SCH_1):VR_PVPP_GHJ_ISET   I184 @BASEBOARD_FAB2_LIB.BASEBOARD_FAB2(SCH_1):PAGE233
     2 AGND_PVPP_GHJ @BASEBOARD_FAB2_LIB.BASEBOARD_FAB2(SCH_1):AGND_PVPP_GHJ   I184 @BASEBOARD_FAB2_LIB.BASEBOARD_FAB2(SCH_1):PAGE233

R4G12 RES_0402-22.1,1.0%,1/16W,CHIP,A
     1 PWRGD_PVPP_GHJ_R @BASEBOARD_FAB2_LIB.BASEBOARD_FAB2(SCH_1):PWRGD_PVPP_GHJ_R   I247 @BASEBOARD_FAB2_LIB.BASEBOARD_FAB2(SCH_1):PAGE233
     2 PWRGD_PVPP_GHJ @BASEBOARD_FAB2_LIB.BASEBOARD_FAB2(SCH_1):PWRGD_PVPP_GHJ   I247 @BASEBOARD_FAB2_LIB.BASEBOARD_FAB2(SCH_1):PAGE233

R4G13 RES_0402-7.87K,1.0%,1/16W,CHIPA
     1 VR_COMP_RC_PVPP_GHJ @BASEBOARD_FAB2_LIB.BASEBOARD_FAB2(SCH_1):VR_COMP_RC_PVPP_GHJ   I272 @BASEBOARD_FAB2_LIB.BASEBOARD_FAB2(SCH_1):PAGE233
     2 VR_FB_PVPP_GHJ @BASEBOARD_FAB2_LIB.BASEBOARD_FAB2(SCH_1):VR_FB_PVPP_GHJ   I272 @BASEBOARD_FAB2_LIB.BASEBOARD_FAB2(SCH_1):PAGE233

R4G14 RES_0402-1.00K,1%,1/16W,CHIP,GA
     1 P3V3_STBY @BASEBOARD_FAB2_LIB.BASEBOARD_FAB2(SCH_1):P3V3_STBY   I185 @BASEBOARD_FAB2_LIB.BASEBOARD_FAB2(SCH_1):PAGE233
     2 PWRGD_PVPP_GHJ_R @BASEBOARD_FAB2_LIB.BASEBOARD_FAB2(SCH_1):PWRGD_PVPP_GHJ_R   I185 @BASEBOARD_FAB2_LIB.BASEBOARD_FAB2(SCH_1):PAGE233

R4G15 RES_0402-33.2,1%,1/16W,CHIP,G2A
     1 PWRGD_PVTT_GHJ_CPU1_R @BASEBOARD_FAB2_LIB.BASEBOARD_FAB2(SCH_1):PWRGD_PVTT_GHJ_CPU1_R    I51 @BASEBOARD_FAB2_LIB.BASEBOARD_FAB2(SCH_1):PAGE229
     2 PWRGD_PVTT_CPU1 @BASEBOARD_FAB2_LIB.BASEBOARD_FAB2(SCH_1):PWRGD_PVTT_CPU1    I51 @BASEBOARD_FAB2_LIB.BASEBOARD_FAB2(SCH_1):PAGE229

R4G16 RES_0402-0.0,5%,1/16W,CHIP,G21A
     1 PWRGD_PVDDQ_GHJ @BASEBOARD_FAB2_LIB.BASEBOARD_FAB2(SCH_1):PWRGD_PVDDQ_GHJ    I35 @BASEBOARD_FAB2_LIB.BASEBOARD_FAB2(SCH_1):PAGE229
     2 FM_PVTT_GHJ_EN_R @BASEBOARD_FAB2_LIB.BASEBOARD_FAB2(SCH_1):FM_PVTT_GHJ_EN_R    I35 @BASEBOARD_FAB2_LIB.BASEBOARD_FAB2(SCH_1):PAGE229

R4G17 RES_0402-10.0K,1%,1/16W,CHIP,GA
     1   P3V3 @BASEBOARD_FAB2_LIB.BASEBOARD_FAB2(SCH_1):P3V3    I14 @BASEBOARD_FAB2_LIB.BASEBOARD_FAB2(SCH_1):PAGE229
     2 PWRGD_PVTT_GHJ_CPU1_R @BASEBOARD_FAB2_LIB.BASEBOARD_FAB2(SCH_1):PWRGD_PVTT_GHJ_CPU1_R    I14 @BASEBOARD_FAB2_LIB.BASEBOARD_FAB2(SCH_1):PAGE229

R4G18 RES_0402-10.0K,1%,1/16W,CHIP,GA
     1   P3V3 @BASEBOARD_FAB2_LIB.BASEBOARD_FAB2(SCH_1):P3V3    I45 @BASEBOARD_FAB2_LIB.BASEBOARD_FAB2(SCH_1):PAGE221
     2 PWRGD_PVTT_ABC_CPU0_R @BASEBOARD_FAB2_LIB.BASEBOARD_FAB2(SCH_1):PWRGD_PVTT_ABC_CPU0_R    I45 @BASEBOARD_FAB2_LIB.BASEBOARD_FAB2(SCH_1):PAGE221

R4G19 RES_0402-33.2,1%,1/16W,CHIP,G2A
     1 PWRGD_PVTT_ABC_CPU0_R @BASEBOARD_FAB2_LIB.BASEBOARD_FAB2(SCH_1):PWRGD_PVTT_ABC_CPU0_R    I54 @BASEBOARD_FAB2_LIB.BASEBOARD_FAB2(SCH_1):PAGE221
     2 PWRGD_PVTT_CPU0 @BASEBOARD_FAB2_LIB.BASEBOARD_FAB2(SCH_1):PWRGD_PVTT_CPU0    I54 @BASEBOARD_FAB2_LIB.BASEBOARD_FAB2(SCH_1):PAGE221

R4G20 RES_0402-2,1.0%,1/16W,CHIP,G21A
     1 M_C_CPU_VREF @BASEBOARD_FAB2_LIB.BASEBOARD_FAB2(SCH_1):M_C_CPU_VREF    I50 @BASEBOARD_FAB2_LIB.BASEBOARD_FAB2(SCH_1):PAGE98
     2 M_C_VREF @BASEBOARD_FAB2_LIB.BASEBOARD_FAB2(SCH_1):M_C_VREF    I50 @BASEBOARD_FAB2_LIB.BASEBOARD_FAB2(SCH_1):PAGE98

R4G21 RES_0402-1.00K,1%,1/16W,CHIP,GA
     1 PVDDQ_ABC @BASEBOARD_FAB2_LIB.BASEBOARD_FAB2(SCH_1):PVDDQ_ABC    I46 @BASEBOARD_FAB2_LIB.BASEBOARD_FAB2(SCH_1):PAGE98
     2 M_C_VREF @BASEBOARD_FAB2_LIB.BASEBOARD_FAB2(SCH_1):M_C_VREF    I46 @BASEBOARD_FAB2_LIB.BASEBOARD_FAB2(SCH_1):PAGE98

R4G22 RES_0402-1.00K,1%,1/16W,CHIP,GA
     1 M_C_VREF @BASEBOARD_FAB2_LIB.BASEBOARD_FAB2(SCH_1):M_C_VREF    I48 @BASEBOARD_FAB2_LIB.BASEBOARD_FAB2(SCH_1):PAGE98
     2    GND @BASEBOARD_FAB2_LIB.BASEBOARD_FAB2(SCH_1):GND    I48 @BASEBOARD_FAB2_LIB.BASEBOARD_FAB2(SCH_1):PAGE98

R4G23 RES_0402-0.0,5%,1/16W,CHIP,G21A
     1 PWRGD_PVDDQ_ABC @BASEBOARD_FAB2_LIB.BASEBOARD_FAB2(SCH_1):PWRGD_PVDDQ_ABC    I38 @BASEBOARD_FAB2_LIB.BASEBOARD_FAB2(SCH_1):PAGE221
     2 FM_PVTT_ABC_EN_R @BASEBOARD_FAB2_LIB.BASEBOARD_FAB2(SCH_1):FM_PVTT_ABC_EN_R    I38 @BASEBOARD_FAB2_LIB.BASEBOARD_FAB2(SCH_1):PAGE221

R4G24 RES_0402-0.0,5%,1/16W,CHIP,G21A
     1 VR_PVPP_GHJ_BOOT @BASEBOARD_FAB2_LIB.BASEBOARD_FAB2(SCH_1):VR_PVPP_GHJ_BOOT   I199 @BASEBOARD_FAB2_LIB.BASEBOARD_FAB2(SCH_1):PAGE233
     2 VR_PVPP_GHJ_BOOT_R @BASEBOARD_FAB2_LIB.BASEBOARD_FAB2(SCH_1):VR_PVPP_GHJ_BOOT_R   I199 @BASEBOARD_FAB2_LIB.BASEBOARD_FAB2(SCH_1):PAGE233

R4G25 RES_0402-0.0,5%,1/16W,CHIP,G21A
     1    GND @BASEBOARD_FAB2_LIB.BASEBOARD_FAB2(SCH_1):GND   I157 @BASEBOARD_FAB2_LIB.BASEBOARD_FAB2(SCH_1):PAGE233
     2 AGND_PVPP_GHJ @BASEBOARD_FAB2_LIB.BASEBOARD_FAB2(SCH_1):AGND_PVPP_GHJ   I157 @BASEBOARD_FAB2_LIB.BASEBOARD_FAB2(SCH_1):PAGE233

R4L2 RES_0402-100.0,1%,1/16W,EMPTY,A
     1 VSENSE_PVDDQ_DEF_P @BASEBOARD_FAB2_LIB.BASEBOARD_FAB2(SCH_1):VSENSE_PVDDQ_DEF_P    I74 @BASEBOARD_FAB2_LIB.BASEBOARD_FAB2(SCH_1):PAGE220
     2 VSENSE_PVDDQ_DEF_N @BASEBOARD_FAB2_LIB.BASEBOARD_FAB2(SCH_1):VSENSE_PVDDQ_DEF_N    I74 @BASEBOARD_FAB2_LIB.BASEBOARD_FAB2(SCH_1):PAGE220

R4L4 RES_0603-120.0,1%,1/10W,CHIP,GA
     1 PVDDQ_DEF @BASEBOARD_FAB2_LIB.BASEBOARD_FAB2(SCH_1):PVDDQ_DEF    I58 @BASEBOARD_FAB2_LIB.BASEBOARD_FAB2(SCH_1):PAGE220
     2    GND @BASEBOARD_FAB2_LIB.BASEBOARD_FAB2(SCH_1):GND    I58 @BASEBOARD_FAB2_LIB.BASEBOARD_FAB2(SCH_1):PAGE220

R4P1 RES_0402-240,1.0%,1/16W,EMPTY,A
     1    GND @BASEBOARD_FAB2_LIB.BASEBOARD_FAB2(SCH_1):GND     I4 @BASEBOARD_FAB2_LIB.BASEBOARD_FAB2(SCH_1):PAGE90
     2 PD_CPU0_BIST_ENABLE @BASEBOARD_FAB2_LIB.BASEBOARD_FAB2(SCH_1):PD_CPU0_BIST_ENABLE     I4 @BASEBOARD_FAB2_LIB.BASEBOARD_FAB2(SCH_1):PAGE90

R4P2 RES_0402-49.9,1%,1/16W,CHIP,G2A
     1 A_CPU0_PE3_RBIAS @BASEBOARD_FAB2_LIB.BASEBOARD_FAB2(SCH_1):A_CPU0_PE3_RBIAS   I188 @BASEBOARD_FAB2_LIB.BASEBOARD_FAB2(SCH_1):PAGE21
     2    GND @BASEBOARD_FAB2_LIB.BASEBOARD_FAB2(SCH_1):GND   I188 @BASEBOARD_FAB2_LIB.BASEBOARD_FAB2(SCH_1):PAGE21

R4P3 RES_0402-49.9,1%,1/16W,CHIP,G2A
     1 A_CPU0_PE012_RBIAS @BASEBOARD_FAB2_LIB.BASEBOARD_FAB2(SCH_1):A_CPU0_PE012_RBIAS   I186 @BASEBOARD_FAB2_LIB.BASEBOARD_FAB2(SCH_1):PAGE21
     2    GND @BASEBOARD_FAB2_LIB.BASEBOARD_FAB2(SCH_1):GND   I186 @BASEBOARD_FAB2_LIB.BASEBOARD_FAB2(SCH_1):PAGE21

R4P4 RES_0402-49.9,1%,1/16W,CHIP,G2A
     1 A_CPU0_UPI2_RBIAS @BASEBOARD_FAB2_LIB.BASEBOARD_FAB2(SCH_1):A_CPU0_UPI2_RBIAS   I189 @BASEBOARD_FAB2_LIB.BASEBOARD_FAB2(SCH_1):PAGE21
     2    GND @BASEBOARD_FAB2_LIB.BASEBOARD_FAB2(SCH_1):GND   I189 @BASEBOARD_FAB2_LIB.BASEBOARD_FAB2(SCH_1):PAGE21

R4P5 RES_0402-10.0K,1%,1/16W,CHIP,GA
     1    GND @BASEBOARD_FAB2_LIB.BASEBOARD_FAB2(SCH_1):GND    I80 @BASEBOARD_FAB2_LIB.BASEBOARD_FAB2(SCH_1):PAGE97
     2 PD_CPU0_MCP01_DMON @BASEBOARD_FAB2_LIB.BASEBOARD_FAB2(SCH_1):PD_CPU0_MCP01_DMON    I80 @BASEBOARD_FAB2_LIB.BASEBOARD_FAB2(SCH_1):PAGE97

R4P6 RES_0402-240,1.0%,1/16W,EMPTY,A
     1    GND @BASEBOARD_FAB2_LIB.BASEBOARD_FAB2(SCH_1):GND    I68 @BASEBOARD_FAB2_LIB.BASEBOARD_FAB2(SCH_1):PAGE90
     2 PD_CPU0_DMIMODE_OVERRIDE @BASEBOARD_FAB2_LIB.BASEBOARD_FAB2(SCH_1):PD_CPU0_DMIMODE_OVERRIDE    I68 @BASEBOARD_FAB2_LIB.BASEBOARD_FAB2(SCH_1):PAGE90

R4P7 RES_0402-240,1.0%,1/16W,EMPTY,A
     1    GND @BASEBOARD_FAB2_LIB.BASEBOARD_FAB2(SCH_1):GND    I72 @BASEBOARD_FAB2_LIB.BASEBOARD_FAB2(SCH_1):PAGE90
     2 PD_CPU0_KSFC_DIS @BASEBOARD_FAB2_LIB.BASEBOARD_FAB2(SCH_1):PD_CPU0_KSFC_DIS    I72 @BASEBOARD_FAB2_LIB.BASEBOARD_FAB2(SCH_1):PAGE90

R4P8 RES_0402-90.9,1%,1/16W,CHIP,G2A
     1 A_CPU0_ABC_RCOMP0 @BASEBOARD_FAB2_LIB.BASEBOARD_FAB2(SCH_1):A_CPU0_ABC_RCOMP0   I180 @BASEBOARD_FAB2_LIB.BASEBOARD_FAB2(SCH_1):PAGE21
     2    GND @BASEBOARD_FAB2_LIB.BASEBOARD_FAB2(SCH_1):GND   I180 @BASEBOARD_FAB2_LIB.BASEBOARD_FAB2(SCH_1):PAGE21

R4P10 RES_0402-90.9,1%,1/16W,CHIP,G2A
     1 A_CPU0_ABC_RCOMP1 @BASEBOARD_FAB2_LIB.BASEBOARD_FAB2(SCH_1):A_CPU0_ABC_RCOMP1   I181 @BASEBOARD_FAB2_LIB.BASEBOARD_FAB2(SCH_1):PAGE21
     2    GND @BASEBOARD_FAB2_LIB.BASEBOARD_FAB2(SCH_1):GND   I181 @BASEBOARD_FAB2_LIB.BASEBOARD_FAB2(SCH_1):PAGE21

R4P11 RES_0402-100.0,1%,1/16W,CHIP,GA
     1 A_CPU0_ABC_RCOMP2 @BASEBOARD_FAB2_LIB.BASEBOARD_FAB2(SCH_1):A_CPU0_ABC_RCOMP2   I182 @BASEBOARD_FAB2_LIB.BASEBOARD_FAB2(SCH_1):PAGE21
     2    GND @BASEBOARD_FAB2_LIB.BASEBOARD_FAB2(SCH_1):GND   I182 @BASEBOARD_FAB2_LIB.BASEBOARD_FAB2(SCH_1):PAGE21

R4P12 RES_0402-100.0,1%,1/16W,CHIP,GA
     1 PVCCIO_CPU0 @BASEBOARD_FAB2_LIB.BASEBOARD_FAB2(SCH_1):PVCCIO_CPU0    I57 @BASEBOARD_FAB2_LIB.BASEBOARD_FAB2(SCH_1):PAGE112
     2 XDP_CPU_MBP0_N @BASEBOARD_FAB2_LIB.BASEBOARD_FAB2(SCH_1):XDP_CPU_MBP0_N    I57 @BASEBOARD_FAB2_LIB.BASEBOARD_FAB2(SCH_1):PAGE112

R4P14 RES_0402-240,1.0%,1/16W,CHIP,GA
     1 PVCCIO_CPU0 @BASEBOARD_FAB2_LIB.BASEBOARD_FAB2(SCH_1):PVCCIO_CPU0    I53 @BASEBOARD_FAB2_LIB.BASEBOARD_FAB2(SCH_1):PAGE90
     2 PU_CPU0_LEGACY_SKT @BASEBOARD_FAB2_LIB.BASEBOARD_FAB2(SCH_1):PU_CPU0_LEGACY_SKT    I53 @BASEBOARD_FAB2_LIB.BASEBOARD_FAB2(SCH_1):PAGE90

R4P15 RES_0402-100.0,1%,1/16W,CHIP,GA
     1 PVCCIO_CPU0 @BASEBOARD_FAB2_LIB.BASEBOARD_FAB2(SCH_1):PVCCIO_CPU0    I53 @BASEBOARD_FAB2_LIB.BASEBOARD_FAB2(SCH_1):PAGE112
     2 XDP_CPU_MBP1_N @BASEBOARD_FAB2_LIB.BASEBOARD_FAB2(SCH_1):XDP_CPU_MBP1_N    I53 @BASEBOARD_FAB2_LIB.BASEBOARD_FAB2(SCH_1):PAGE112

R4P17 RES_0402-150.0,1%,1/16W,CHIP,GA
     1 H_CPU0_MEMABC_MEMHOT_G_N @BASEBOARD_FAB2_LIB.BASEBOARD_FAB2(SCH_1):H_CPU0_MEMABC_MEMHOT_G_N    I58 @BASEBOARD_FAB2_LIB.BASEBOARD_FAB2(SCH_1):PAGE152
     2 PVCCIO_CPU0 @BASEBOARD_FAB2_LIB.BASEBOARD_FAB2(SCH_1):PVCCIO_CPU0    I58 @BASEBOARD_FAB2_LIB.BASEBOARD_FAB2(SCH_1):PAGE152

R4P18 RES_0402-49.9,1%,1/16W,CHIP,G2A
     1 H_PM_SYNC_GTL_R1 @BASEBOARD_FAB2_LIB.BASEBOARD_FAB2(SCH_1):H_PM_SYNC_GTL_R1   I244 @BASEBOARD_FAB2_LIB.BASEBOARD_FAB2(SCH_1):PAGE21
     2 H_PM_SYNC_GTL @BASEBOARD_FAB2_LIB.BASEBOARD_FAB2(SCH_1):H_PM_SYNC_GTL   I244 @BASEBOARD_FAB2_LIB.BASEBOARD_FAB2(SCH_1):PAGE21

R4P19 RES_0402-49.9,1%,1/16W,CHIP,G2A
     1 H_PMSYNC_CLK_24M_CPU0 @BASEBOARD_FAB2_LIB.BASEBOARD_FAB2(SCH_1):H_PMSYNC_CLK_24M_CPU0   I219 @BASEBOARD_FAB2_LIB.BASEBOARD_FAB2(SCH_1):PAGE21
     2 H_PMSYNC_CLK_24M @BASEBOARD_FAB2_LIB.BASEBOARD_FAB2(SCH_1):H_PMSYNC_CLK_24M   I219 @BASEBOARD_FAB2_LIB.BASEBOARD_FAB2(SCH_1):PAGE21

R4P20 RES_0402-150.0,1%,1/16W,CHIP,GA
     1 H_CPU0_MEMDEF_MEMHOT_G_N @BASEBOARD_FAB2_LIB.BASEBOARD_FAB2(SCH_1):H_CPU0_MEMDEF_MEMHOT_G_N    I59 @BASEBOARD_FAB2_LIB.BASEBOARD_FAB2(SCH_1):PAGE152
     2 PVCCIO_CPU0 @BASEBOARD_FAB2_LIB.BASEBOARD_FAB2(SCH_1):PVCCIO_CPU0    I59 @BASEBOARD_FAB2_LIB.BASEBOARD_FAB2(SCH_1):PAGE152

R4P21 RES_0402-240,1.0%,1/16W,CHIP,GA
     1 PVCCIO_CPU0 @BASEBOARD_FAB2_LIB.BASEBOARD_FAB2(SCH_1):PVCCIO_CPU0    I72 @BASEBOARD_FAB2_LIB.BASEBOARD_FAB2(SCH_1):PAGE97
     2 PU_CPU0_TSC_SYNC @BASEBOARD_FAB2_LIB.BASEBOARD_FAB2(SCH_1):PU_CPU0_TSC_SYNC    I72 @BASEBOARD_FAB2_LIB.BASEBOARD_FAB2(SCH_1):PAGE97

R4P23 RES_0402-150.0,1%,1/16W,CHIP,GA
     1 PVCCIO_CPU0 @BASEBOARD_FAB2_LIB.BASEBOARD_FAB2(SCH_1):PVCCIO_CPU0    I58 @BASEBOARD_FAB2_LIB.BASEBOARD_FAB2(SCH_1):PAGE112
     2 XDP_CPU0_TDO @BASEBOARD_FAB2_LIB.BASEBOARD_FAB2(SCH_1):XDP_CPU0_TDO    I58 @BASEBOARD_FAB2_LIB.BASEBOARD_FAB2(SCH_1):PAGE112

R4P24 RES_0402-150.0,1%,1/16W,CHIP,GA
     1 PVCCIO_CPU0 @BASEBOARD_FAB2_LIB.BASEBOARD_FAB2(SCH_1):PVCCIO_CPU0    I59 @BASEBOARD_FAB2_LIB.BASEBOARD_FAB2(SCH_1):PAGE112
     2 XDP_CPU_TDI @BASEBOARD_FAB2_LIB.BASEBOARD_FAB2(SCH_1):XDP_CPU_TDI    I59 @BASEBOARD_FAB2_LIB.BASEBOARD_FAB2(SCH_1):PAGE112

R4R1 RES_0402-1.00K,1%,1/16W,CHIP,GA
     1 H_CPU0_FAST_WAKE_N @BASEBOARD_FAB2_LIB.BASEBOARD_FAB2(SCH_1):H_CPU0_FAST_WAKE_N   I368 @BASEBOARD_FAB2_LIB.BASEBOARD_FAB2(SCH_1):PAGE157
     2 H_CPU0_FAST_WAKE_B_N @BASEBOARD_FAB2_LIB.BASEBOARD_FAB2(SCH_1):H_CPU0_FAST_WAKE_B_N   I368 @BASEBOARD_FAB2_LIB.BASEBOARD_FAB2(SCH_1):PAGE157

R4R2 RES_0402-150.0,1%,1/16W,CHIP,GA
     1 PVCCIO_CPU0 @BASEBOARD_FAB2_LIB.BASEBOARD_FAB2(SCH_1):PVCCIO_CPU0   I101 @BASEBOARD_FAB2_LIB.BASEBOARD_FAB2(SCH_1):PAGE92
     2 H_CPU0_CATERR_G_N @BASEBOARD_FAB2_LIB.BASEBOARD_FAB2(SCH_1):H_CPU0_CATERR_G_N   I101 @BASEBOARD_FAB2_LIB.BASEBOARD_FAB2(SCH_1):PAGE92

R4R3 RES_0402-150.0,1%,1/16W,CHIP,GA
     1 PVCCIO_CPU0 @BASEBOARD_FAB2_LIB.BASEBOARD_FAB2(SCH_1):PVCCIO_CPU0    I79 @BASEBOARD_FAB2_LIB.BASEBOARD_FAB2(SCH_1):PAGE93
     2 H_CPU0_PROCHOT_G_N @BASEBOARD_FAB2_LIB.BASEBOARD_FAB2(SCH_1):H_CPU0_PROCHOT_G_N    I79 @BASEBOARD_FAB2_LIB.BASEBOARD_FAB2(SCH_1):PAGE93

R4R4 RES_0402-150.0,1%,1/16W,CHIP,GA
     1 PVCCIO_CPU0 @BASEBOARD_FAB2_LIB.BASEBOARD_FAB2(SCH_1):PVCCIO_CPU0    I42 @BASEBOARD_FAB2_LIB.BASEBOARD_FAB2(SCH_1):PAGE97
     2 H_CPU0_FAST_WAKE_N @BASEBOARD_FAB2_LIB.BASEBOARD_FAB2(SCH_1):H_CPU0_FAST_WAKE_N    I42 @BASEBOARD_FAB2_LIB.BASEBOARD_FAB2(SCH_1):PAGE97

R4R5 RES_0402-4.75K,1%,1/16W,CHIP,GA
     1 P3V3_STBY @BASEBOARD_FAB2_LIB.BASEBOARD_FAB2(SCH_1):P3V3_STBY   I258 @BASEBOARD_FAB2_LIB.BASEBOARD_FAB2(SCH_1):PAGE21
     2 FM_CPU0_SKTOCC_LVT3_N @BASEBOARD_FAB2_LIB.BASEBOARD_FAB2(SCH_1):FM_CPU0_SKTOCC_LVT3_N   I258 @BASEBOARD_FAB2_LIB.BASEBOARD_FAB2(SCH_1):PAGE21

R4R6 RES_0402-49.9,1%,1/16W,CHIP,G2A
     1 JTAG_MCP_CPU0_TDI_R @BASEBOARD_FAB2_LIB.BASEBOARD_FAB2(SCH_1):JTAG_MCP_CPU0_TDI_R   I134 @BASEBOARD_FAB2_LIB.BASEBOARD_FAB2(SCH_1):PAGE113
     2 JTAG_MCP_CPU0_TDI @BASEBOARD_FAB2_LIB.BASEBOARD_FAB2(SCH_1):JTAG_MCP_CPU0_TDI   I134 @BASEBOARD_FAB2_LIB.BASEBOARD_FAB2(SCH_1):PAGE113

R4T1 RES_0402-0.0,5%,1/16W,CHIP,G21A
     1 FM_ADR_COMPLETE_DLY @BASEBOARD_FAB2_LIB.BASEBOARD_FAB2(SCH_1):FM_ADR_COMPLETE_DLY     I2 @BASEBOARD_FAB2_LIB.BASEBOARD_FAB2(SCH_1):PAGE89
     2 FM_ADR_COMPLETE_R @BASEBOARD_FAB2_LIB.BASEBOARD_FAB2(SCH_1):FM_ADR_COMPLETE_R     I2 @BASEBOARD_FAB2_LIB.BASEBOARD_FAB2(SCH_1):PAGE89

R4T2 RES_0402-0.0,5%,1/16W,EMPTY,G2A
     1 FM_ADR_COMPLETE @BASEBOARD_FAB2_LIB.BASEBOARD_FAB2(SCH_1):FM_ADR_COMPLETE     I1 @BASEBOARD_FAB2_LIB.BASEBOARD_FAB2(SCH_1):PAGE89
     2 FM_ADR_COMPLETE_R @BASEBOARD_FAB2_LIB.BASEBOARD_FAB2(SCH_1):FM_ADR_COMPLETE_R     I1 @BASEBOARD_FAB2_LIB.BASEBOARD_FAB2(SCH_1):PAGE89

R4T3 RES_0402-10.0,1%,1/16W,CHIP,G2A
     1 SMB_DDR_ABC_SCL_G_R @BASEBOARD_FAB2_LIB.BASEBOARD_FAB2(SCH_1):SMB_DDR_ABC_SCL_G_R    I83 @BASEBOARD_FAB2_LIB.BASEBOARD_FAB2(SCH_1):PAGE99
     2 SMB_DDR_ABC_SCL_G @BASEBOARD_FAB2_LIB.BASEBOARD_FAB2(SCH_1):SMB_DDR_ABC_SCL_G    I83 @BASEBOARD_FAB2_LIB.BASEBOARD_FAB2(SCH_1):PAGE99

R4T4 RES_0402-10.0,1%,1/16W,CHIP,G2A
     1 SMB_DDR_ABC_SDA_G_R @BASEBOARD_FAB2_LIB.BASEBOARD_FAB2(SCH_1):SMB_DDR_ABC_SDA_G_R    I20 @BASEBOARD_FAB2_LIB.BASEBOARD_FAB2(SCH_1):PAGE99
     2 SMB_DDR_ABC_SDA_G @BASEBOARD_FAB2_LIB.BASEBOARD_FAB2(SCH_1):SMB_DDR_ABC_SDA_G    I20 @BASEBOARD_FAB2_LIB.BASEBOARD_FAB2(SCH_1):PAGE99

R4T5 RES_0402-240,1.0%,1/16W,CHIP,GA
     1 PVCCIO_CPU0 @BASEBOARD_FAB2_LIB.BASEBOARD_FAB2(SCH_1):PVCCIO_CPU0    I19 @BASEBOARD_FAB2_LIB.BASEBOARD_FAB2(SCH_1):PAGE99
     2 SMB_DDR_ABC_SCL_G @BASEBOARD_FAB2_LIB.BASEBOARD_FAB2(SCH_1):SMB_DDR_ABC_SCL_G    I19 @BASEBOARD_FAB2_LIB.BASEBOARD_FAB2(SCH_1):PAGE99

R4T6 RES_0402-240,1.0%,1/16W,CHIP,GA
     1 PVCCIO_CPU0 @BASEBOARD_FAB2_LIB.BASEBOARD_FAB2(SCH_1):PVCCIO_CPU0    I17 @BASEBOARD_FAB2_LIB.BASEBOARD_FAB2(SCH_1):PAGE99
     2 SMB_DDR_ABC_SDA_G @BASEBOARD_FAB2_LIB.BASEBOARD_FAB2(SCH_1):SMB_DDR_ABC_SDA_G    I17 @BASEBOARD_FAB2_LIB.BASEBOARD_FAB2(SCH_1):PAGE99

R4T7 RES_0402-665,1.0%,1/16W,CHIP,GA
     1 PVPP_ABC @BASEBOARD_FAB2_LIB.BASEBOARD_FAB2(SCH_1):PVPP_ABC    I13 @BASEBOARD_FAB2_LIB.BASEBOARD_FAB2(SCH_1):PAGE99
     2 SMB_DDR_ABC_VPP_SCL_R @BASEBOARD_FAB2_LIB.BASEBOARD_FAB2(SCH_1):SMB_DDR_ABC_VPP_SCL_R    I13 @BASEBOARD_FAB2_LIB.BASEBOARD_FAB2(SCH_1):PAGE99

R4T8 RES_0402-665,1.0%,1/16W,CHIP,GA
     1 PVPP_ABC @BASEBOARD_FAB2_LIB.BASEBOARD_FAB2(SCH_1):PVPP_ABC    I11 @BASEBOARD_FAB2_LIB.BASEBOARD_FAB2(SCH_1):PAGE99
     2 SMB_DDR_ABC_VPP_SDA_R @BASEBOARD_FAB2_LIB.BASEBOARD_FAB2(SCH_1):SMB_DDR_ABC_VPP_SDA_R    I11 @BASEBOARD_FAB2_LIB.BASEBOARD_FAB2(SCH_1):PAGE99

R4T9 RES_0402-20.0,1%,1/16W,CHIP,G2A
     1 SMB_DDR_ABC_VPP_SCL_R @BASEBOARD_FAB2_LIB.BASEBOARD_FAB2(SCH_1):SMB_DDR_ABC_VPP_SCL_R     I9 @BASEBOARD_FAB2_LIB.BASEBOARD_FAB2(SCH_1):PAGE99
     2 SMB_DDR_ABC_VPP_SCL @BASEBOARD_FAB2_LIB.BASEBOARD_FAB2(SCH_1):SMB_DDR_ABC_VPP_SCL     I9 @BASEBOARD_FAB2_LIB.BASEBOARD_FAB2(SCH_1):PAGE99

R4T10 RES_0402-20.0,1%,1/16W,CHIP,G2A
     1 SMB_DDR_ABC_VPP_SDA_R @BASEBOARD_FAB2_LIB.BASEBOARD_FAB2(SCH_1):SMB_DDR_ABC_VPP_SDA_R    I10 @BASEBOARD_FAB2_LIB.BASEBOARD_FAB2(SCH_1):PAGE99
     2 SMB_DDR_ABC_VPP_SDA @BASEBOARD_FAB2_LIB.BASEBOARD_FAB2(SCH_1):SMB_DDR_ABC_VPP_SDA    I10 @BASEBOARD_FAB2_LIB.BASEBOARD_FAB2(SCH_1):PAGE99

R4U1 RES_0402-4.75K,1%,1/16W,CHIP,GA
     1 P3V3_STBY @BASEBOARD_FAB2_LIB.BASEBOARD_FAB2(SCH_1):P3V3_STBY    I91 @BASEBOARD_FAB2_LIB.BASEBOARD_FAB2(SCH_1):PAGE94
     2 FM_MEM_THERM_EVENT_LVT3_N @BASEBOARD_FAB2_LIB.BASEBOARD_FAB2(SCH_1):FM_MEM_THERM_EVENT_LVT3_N    I91 @BASEBOARD_FAB2_LIB.BASEBOARD_FAB2(SCH_1):PAGE94

R4U2 RES_0402-2.21K,1%,1/16W,CHIP,GA
     1 PVPP_ABC @BASEBOARD_FAB2_LIB.BASEBOARD_FAB2(SCH_1):PVPP_ABC   I100 @BASEBOARD_FAB2_LIB.BASEBOARD_FAB2(SCH_1):PAGE94
     2 FM_DIMM_EVENT_COD_N @BASEBOARD_FAB2_LIB.BASEBOARD_FAB2(SCH_1):FM_DIMM_EVENT_COD_N   I100 @BASEBOARD_FAB2_LIB.BASEBOARD_FAB2(SCH_1):PAGE94

R4U3 RES_0402-4.75K,1%,1/16W,CHIP,GA
     1 PVPP_ABC @BASEBOARD_FAB2_LIB.BASEBOARD_FAB2(SCH_1):PVPP_ABC    I94 @BASEBOARD_FAB2_LIB.BASEBOARD_FAB2(SCH_1):PAGE94
     2 FM_DIMM_EVENT_FET @BASEBOARD_FAB2_LIB.BASEBOARD_FAB2(SCH_1):FM_DIMM_EVENT_FET    I94 @BASEBOARD_FAB2_LIB.BASEBOARD_FAB2(SCH_1):PAGE94

R4U4 RES_0402-33.0K,5%,1/16W,CHIP,GA
     1 FM_DIMM_EVENT_FET @BASEBOARD_FAB2_LIB.BASEBOARD_FAB2(SCH_1):FM_DIMM_EVENT_FET   I104 @BASEBOARD_FAB2_LIB.BASEBOARD_FAB2(SCH_1):PAGE94
     2    GND @BASEBOARD_FAB2_LIB.BASEBOARD_FAB2(SCH_1):GND   I104 @BASEBOARD_FAB2_LIB.BASEBOARD_FAB2(SCH_1):PAGE94

R4U6 RES_0402-100.0,1%,1/16W,EMPTY,A
     1 VSENSE_PVDDQ_ABC_P @BASEBOARD_FAB2_LIB.BASEBOARD_FAB2(SCH_1):VSENSE_PVDDQ_ABC_P    I74 @BASEBOARD_FAB2_LIB.BASEBOARD_FAB2(SCH_1):PAGE217
     2 VSENSE_PVDDQ_ABC_N @BASEBOARD_FAB2_LIB.BASEBOARD_FAB2(SCH_1):VSENSE_PVDDQ_ABC_N    I74 @BASEBOARD_FAB2_LIB.BASEBOARD_FAB2(SCH_1):PAGE217

R5D1 RES_0402-90.9,1%,1/16W,CHIP,G2A
     1 A_CPU0_DEF_RCOMP0 @BASEBOARD_FAB2_LIB.BASEBOARD_FAB2(SCH_1):A_CPU0_DEF_RCOMP0   I177 @BASEBOARD_FAB2_LIB.BASEBOARD_FAB2(SCH_1):PAGE21
     2    GND @BASEBOARD_FAB2_LIB.BASEBOARD_FAB2(SCH_1):GND   I177 @BASEBOARD_FAB2_LIB.BASEBOARD_FAB2(SCH_1):PAGE21

R5D2 RES_0402-90.9,1%,1/16W,CHIP,G2A
     1 A_CPU0_DEF_RCOMP1 @BASEBOARD_FAB2_LIB.BASEBOARD_FAB2(SCH_1):A_CPU0_DEF_RCOMP1   I178 @BASEBOARD_FAB2_LIB.BASEBOARD_FAB2(SCH_1):PAGE21
     2    GND @BASEBOARD_FAB2_LIB.BASEBOARD_FAB2(SCH_1):GND   I178 @BASEBOARD_FAB2_LIB.BASEBOARD_FAB2(SCH_1):PAGE21

R5D3 RES_0402-240,1.0%,1/16W,CHIP,GA
     1 PVCCIO_CPU0 @BASEBOARD_FAB2_LIB.BASEBOARD_FAB2(SCH_1):PVCCIO_CPU0    I29 @BASEBOARD_FAB2_LIB.BASEBOARD_FAB2(SCH_1):PAGE90
     2 PU_CPU0_FRMAGENT @BASEBOARD_FAB2_LIB.BASEBOARD_FAB2(SCH_1):PU_CPU0_FRMAGENT    I29 @BASEBOARD_FAB2_LIB.BASEBOARD_FAB2(SCH_1):PAGE90

R5D4 RES_0402-240,1.0%,1/16W,EMPTY,A
     1 PVCCIO_CPU0 @BASEBOARD_FAB2_LIB.BASEBOARD_FAB2(SCH_1):PVCCIO_CPU0    I32 @BASEBOARD_FAB2_LIB.BASEBOARD_FAB2(SCH_1):PAGE90
     2 PU_CPU0_TXT_AGENT @BASEBOARD_FAB2_LIB.BASEBOARD_FAB2(SCH_1):PU_CPU0_TXT_AGENT    I32 @BASEBOARD_FAB2_LIB.BASEBOARD_FAB2(SCH_1):PAGE90

R5D5 RES_0402-249,0.1%,1/16W,CHIP,GA
     1 VSENSE_PMAX_CPU0 @BASEBOARD_FAB2_LIB.BASEBOARD_FAB2(SCH_1):VSENSE_PMAX_CPU0   I303 @BASEBOARD_FAB2_LIB.BASEBOARD_FAB2(SCH_1):PAGE37
     2    GND @BASEBOARD_FAB2_LIB.BASEBOARD_FAB2(SCH_1):GND   I303 @BASEBOARD_FAB2_LIB.BASEBOARD_FAB2(SCH_1):PAGE37

R5D6 RES_0402-10.0,1%,1/16W,EMPTY,GA
     1 PVCCIO_CPU0 @BASEBOARD_FAB2_LIB.BASEBOARD_FAB2(SCH_1):PVCCIO_CPU0   I312 @BASEBOARD_FAB2_LIB.BASEBOARD_FAB2(SCH_1):PAGE37
     2 VSENSE_PMAX_CPU0 @BASEBOARD_FAB2_LIB.BASEBOARD_FAB2(SCH_1):VSENSE_PMAX_CPU0   I312 @BASEBOARD_FAB2_LIB.BASEBOARD_FAB2(SCH_1):PAGE37

R5N1 RES_0402-10.0K,1%,1/16W,CHIP,GA
     1 P3V3_STBY @BASEBOARD_FAB2_LIB.BASEBOARD_FAB2(SCH_1):P3V3_STBY   I238 @BASEBOARD_FAB2_LIB.BASEBOARD_FAB2(SCH_1):PAGE21
     2 FM_CPU0_PKGID0 @BASEBOARD_FAB2_LIB.BASEBOARD_FAB2(SCH_1):FM_CPU0_PKGID0   I238 @BASEBOARD_FAB2_LIB.BASEBOARD_FAB2(SCH_1):PAGE21

R5N2 RES_0402-1.8K,1%,1/16W,CHIP,G2A
     1 P3V3_STBY @BASEBOARD_FAB2_LIB.BASEBOARD_FAB2(SCH_1):P3V3_STBY   I227 @BASEBOARD_FAB2_LIB.BASEBOARD_FAB2(SCH_1):PAGE21
     2 FM_CPU0_PROC_ID1 @BASEBOARD_FAB2_LIB.BASEBOARD_FAB2(SCH_1):FM_CPU0_PROC_ID1   I227 @BASEBOARD_FAB2_LIB.BASEBOARD_FAB2(SCH_1):PAGE21

R5N3 RES_0402-10.0K,1%,1/16W,CHIP,GA
     1 P3V3_STBY @BASEBOARD_FAB2_LIB.BASEBOARD_FAB2(SCH_1):P3V3_STBY   I240 @BASEBOARD_FAB2_LIB.BASEBOARD_FAB2(SCH_1):PAGE21
     2 FM_CPU0_PKGID2 @BASEBOARD_FAB2_LIB.BASEBOARD_FAB2(SCH_1):FM_CPU0_PKGID2   I240 @BASEBOARD_FAB2_LIB.BASEBOARD_FAB2(SCH_1):PAGE21

R5N4 RES_0402-1.8K,1%,1/16W,CHIP,G2A
     1 P3V3_STBY @BASEBOARD_FAB2_LIB.BASEBOARD_FAB2(SCH_1):P3V3_STBY   I241 @BASEBOARD_FAB2_LIB.BASEBOARD_FAB2(SCH_1):PAGE21
     2 FM_CPU0_PROC_ID0 @BASEBOARD_FAB2_LIB.BASEBOARD_FAB2(SCH_1):FM_CPU0_PROC_ID0   I241 @BASEBOARD_FAB2_LIB.BASEBOARD_FAB2(SCH_1):PAGE21

R5N5 RES_0402-10.0K,1%,1/16W,CHIP,GA
     1 P3V3_STBY @BASEBOARD_FAB2_LIB.BASEBOARD_FAB2(SCH_1):P3V3_STBY   I239 @BASEBOARD_FAB2_LIB.BASEBOARD_FAB2(SCH_1):PAGE21
     2 FM_CPU0_PKGID1 @BASEBOARD_FAB2_LIB.BASEBOARD_FAB2(SCH_1):FM_CPU0_PKGID1   I239 @BASEBOARD_FAB2_LIB.BASEBOARD_FAB2(SCH_1):PAGE21

R5P1 RES_0603-100.0K,1%,1/10W,CHIP,A
     1 PVCCIN_CPU0 @BASEBOARD_FAB2_LIB.BASEBOARD_FAB2(SCH_1):PVCCIN_CPU0   I309 @BASEBOARD_FAB2_LIB.BASEBOARD_FAB2(SCH_1):PAGE37
     2 VSENSE_VCCINR2PMAX_CPU0 @BASEBOARD_FAB2_LIB.BASEBOARD_FAB2(SCH_1):VSENSE_VCCINR2PMAX_CPU0   I309 @BASEBOARD_FAB2_LIB.BASEBOARD_FAB2(SCH_1):PAGE37

R5P2 RES_0402-49.9,1%,1/16W,CHIP,G2A
     1 PD_CPU0_TEST14 @BASEBOARD_FAB2_LIB.BASEBOARD_FAB2(SCH_1):PD_CPU0_TEST14    I79 @BASEBOARD_FAB2_LIB.BASEBOARD_FAB2(SCH_1):PAGE90
     2    GND @BASEBOARD_FAB2_LIB.BASEBOARD_FAB2(SCH_1):GND    I79 @BASEBOARD_FAB2_LIB.BASEBOARD_FAB2(SCH_1):PAGE90

R5P3 RES_0402-49.9,1%,1/16W,CHIP,G2A
     1 PD_CPU0_TEST13 @BASEBOARD_FAB2_LIB.BASEBOARD_FAB2(SCH_1):PD_CPU0_TEST13    I80 @BASEBOARD_FAB2_LIB.BASEBOARD_FAB2(SCH_1):PAGE90
     2    GND @BASEBOARD_FAB2_LIB.BASEBOARD_FAB2(SCH_1):GND    I80 @BASEBOARD_FAB2_LIB.BASEBOARD_FAB2(SCH_1):PAGE90

R5P4 RES_0402-49.9,1%,1/16W,CHIP,G2A
     1 PD_CPU0_RSVD_TEST_2 @BASEBOARD_FAB2_LIB.BASEBOARD_FAB2(SCH_1):PD_CPU0_RSVD_TEST_2   I190 @BASEBOARD_FAB2_LIB.BASEBOARD_FAB2(SCH_1):PAGE22
     2    GND @BASEBOARD_FAB2_LIB.BASEBOARD_FAB2(SCH_1):GND   I190 @BASEBOARD_FAB2_LIB.BASEBOARD_FAB2(SCH_1):PAGE22

R5R1 RES_0402-49.9,1%,1/16W,CHIP,G2A
     1 PD_CPU0_RSVD_TEST_1 @BASEBOARD_FAB2_LIB.BASEBOARD_FAB2(SCH_1):PD_CPU0_RSVD_TEST_1   I188 @BASEBOARD_FAB2_LIB.BASEBOARD_FAB2(SCH_1):PAGE22
     2    GND @BASEBOARD_FAB2_LIB.BASEBOARD_FAB2(SCH_1):GND   I188 @BASEBOARD_FAB2_LIB.BASEBOARD_FAB2(SCH_1):PAGE22

R6B1 RES_0402-49.9,1%,1/16W,CHIP,G2A
     1 PVCCIO_CPU0 @BASEBOARD_FAB2_LIB.BASEBOARD_FAB2(SCH_1):PVCCIO_CPU0   I161 @BASEBOARD_FAB2_LIB.BASEBOARD_FAB2(SCH_1):PAGE21
     2 SVID_ALERT1_CPU0_R_N @BASEBOARD_FAB2_LIB.BASEBOARD_FAB2(SCH_1):SVID_ALERT1_CPU0_R_N   I161 @BASEBOARD_FAB2_LIB.BASEBOARD_FAB2(SCH_1):PAGE21

R6B2 RES_0402-100.0,1%,1/16W,CHIP,GA
     1 PVCCIO_CPU0 @BASEBOARD_FAB2_LIB.BASEBOARD_FAB2(SCH_1):PVCCIO_CPU0   I159 @BASEBOARD_FAB2_LIB.BASEBOARD_FAB2(SCH_1):PAGE21
     2 SVID_DIO1_CPU0_R @BASEBOARD_FAB2_LIB.BASEBOARD_FAB2(SCH_1):SVID_DIO1_CPU0_R   I159 @BASEBOARD_FAB2_LIB.BASEBOARD_FAB2(SCH_1):PAGE21

R6B3 RES_0402-221,1.0%,1/16W,CHIP,GA
     1 SVID_ALERT1_CPU0_N @BASEBOARD_FAB2_LIB.BASEBOARD_FAB2(SCH_1):SVID_ALERT1_CPU0_N   I152 @BASEBOARD_FAB2_LIB.BASEBOARD_FAB2(SCH_1):PAGE21
     2 SVID_ALERT1_CPU0_R_N @BASEBOARD_FAB2_LIB.BASEBOARD_FAB2(SCH_1):SVID_ALERT1_CPU0_R_N   I152 @BASEBOARD_FAB2_LIB.BASEBOARD_FAB2(SCH_1):PAGE21

R6B4 RES_0402-0.0,5%,1/16W,CHIP,G21A
     1 SVID_DIO1_CPU0 @BASEBOARD_FAB2_LIB.BASEBOARD_FAB2(SCH_1):SVID_DIO1_CPU0   I154 @BASEBOARD_FAB2_LIB.BASEBOARD_FAB2(SCH_1):PAGE21
     2 SVID_DIO1_CPU0_R @BASEBOARD_FAB2_LIB.BASEBOARD_FAB2(SCH_1):SVID_DIO1_CPU0_R   I154 @BASEBOARD_FAB2_LIB.BASEBOARD_FAB2(SCH_1):PAGE21

R6B5 RES_0402-0.0,5%,1/16W,CHIP,G21A
     1 SVID_CLK1_CPU0 @BASEBOARD_FAB2_LIB.BASEBOARD_FAB2(SCH_1):SVID_CLK1_CPU0   I153 @BASEBOARD_FAB2_LIB.BASEBOARD_FAB2(SCH_1):PAGE21
     2 SVID_CLK1_CPU0_R @BASEBOARD_FAB2_LIB.BASEBOARD_FAB2(SCH_1):SVID_CLK1_CPU0_R   I153 @BASEBOARD_FAB2_LIB.BASEBOARD_FAB2(SCH_1):PAGE21

R6D1 RES_0402-100.0,1%,1/16W,CHIP,GA
     1 A_CPU0_DEF_RCOMP2 @BASEBOARD_FAB2_LIB.BASEBOARD_FAB2(SCH_1):A_CPU0_DEF_RCOMP2   I179 @BASEBOARD_FAB2_LIB.BASEBOARD_FAB2(SCH_1):PAGE21
     2    GND @BASEBOARD_FAB2_LIB.BASEBOARD_FAB2(SCH_1):GND   I179 @BASEBOARD_FAB2_LIB.BASEBOARD_FAB2(SCH_1):PAGE21

R6D2 RES_0402-49.9,1%,1/16W,CHIP,G2A
     1 A_CPU0_MCP01_RBIAS @BASEBOARD_FAB2_LIB.BASEBOARD_FAB2(SCH_1):A_CPU0_MCP01_RBIAS   I204 @BASEBOARD_FAB2_LIB.BASEBOARD_FAB2(SCH_1):PAGE21
     2    GND @BASEBOARD_FAB2_LIB.BASEBOARD_FAB2(SCH_1):GND   I204 @BASEBOARD_FAB2_LIB.BASEBOARD_FAB2(SCH_1):PAGE21

R6D5 RES_0402-49.9,1%,1/16W,CHIP,G2A
     1 PD_CPU0_TEST12 @BASEBOARD_FAB2_LIB.BASEBOARD_FAB2(SCH_1):PD_CPU0_TEST12    I81 @BASEBOARD_FAB2_LIB.BASEBOARD_FAB2(SCH_1):PAGE90
     2    GND @BASEBOARD_FAB2_LIB.BASEBOARD_FAB2(SCH_1):GND    I81 @BASEBOARD_FAB2_LIB.BASEBOARD_FAB2(SCH_1):PAGE90

R6D6 RES_0402-240,1.0%,1/16W,CHIP,GA
     1    GND @BASEBOARD_FAB2_LIB.BASEBOARD_FAB2(SCH_1):GND     I3 @BASEBOARD_FAB2_LIB.BASEBOARD_FAB2(SCH_1):PAGE90
     2 PD_CPU0_TXT_PLTEN @BASEBOARD_FAB2_LIB.BASEBOARD_FAB2(SCH_1):PD_CPU0_TXT_PLTEN     I3 @BASEBOARD_FAB2_LIB.BASEBOARD_FAB2(SCH_1):PAGE90

R6D7 RES_0402-240,1.0%,1/16W,EMPTY,A
     1 PVCCIO_CPU0 @BASEBOARD_FAB2_LIB.BASEBOARD_FAB2(SCH_1):PVCCIO_CPU0    I31 @BASEBOARD_FAB2_LIB.BASEBOARD_FAB2(SCH_1):PAGE90
     2 H_CPU0_BMCINIT @BASEBOARD_FAB2_LIB.BASEBOARD_FAB2(SCH_1):H_CPU0_BMCINIT    I31 @BASEBOARD_FAB2_LIB.BASEBOARD_FAB2(SCH_1):PAGE90

R6D8 RES_0402-49.9,1%,1/16W,CHIP,G2A
     1 PVCCIO_CPU0 @BASEBOARD_FAB2_LIB.BASEBOARD_FAB2(SCH_1):PVCCIO_CPU0     I3 @BASEBOARD_FAB2_LIB.BASEBOARD_FAB2(SCH_1):PAGE96
     2 PWRGD_CPU0_G @BASEBOARD_FAB2_LIB.BASEBOARD_FAB2(SCH_1):PWRGD_CPU0_G     I3 @BASEBOARD_FAB2_LIB.BASEBOARD_FAB2(SCH_1):PAGE96

R6D9 RES_0402-150.0,1%,1/16W,CHIP,GA
     1 PVCCIO_CPU0 @BASEBOARD_FAB2_LIB.BASEBOARD_FAB2(SCH_1):PVCCIO_CPU0    I64 @BASEBOARD_FAB2_LIB.BASEBOARD_FAB2(SCH_1):PAGE92
     2 H_CPU0_MSMI_G_N @BASEBOARD_FAB2_LIB.BASEBOARD_FAB2(SCH_1):H_CPU0_MSMI_G_N    I64 @BASEBOARD_FAB2_LIB.BASEBOARD_FAB2(SCH_1):PAGE92

R6D10 RES_0402-240,1.0%,1/16W,EMPTY,A
     1 PVCCIO_CPU0 @BASEBOARD_FAB2_LIB.BASEBOARD_FAB2(SCH_1):PVCCIO_CPU0    I49 @BASEBOARD_FAB2_LIB.BASEBOARD_FAB2(SCH_1):PAGE90
     2 PU_CPU0_SOCKET_ID_1 @BASEBOARD_FAB2_LIB.BASEBOARD_FAB2(SCH_1):PU_CPU0_SOCKET_ID_1    I49 @BASEBOARD_FAB2_LIB.BASEBOARD_FAB2(SCH_1):PAGE90

R6D11 RES_0402-49.9,1%,1/16W,CHIP,G2A
     1 A_CPU0_UPI01_RBIAS @BASEBOARD_FAB2_LIB.BASEBOARD_FAB2(SCH_1):A_CPU0_UPI01_RBIAS   I184 @BASEBOARD_FAB2_LIB.BASEBOARD_FAB2(SCH_1):PAGE21
     2    GND @BASEBOARD_FAB2_LIB.BASEBOARD_FAB2(SCH_1):GND   I184 @BASEBOARD_FAB2_LIB.BASEBOARD_FAB2(SCH_1):PAGE21

R6D12 RES_0402-49.9,1%,1/16W,CHIP,G2A
     1 PVCCIO_CPU0 @BASEBOARD_FAB2_LIB.BASEBOARD_FAB2(SCH_1):PVCCIO_CPU0     I2 @BASEBOARD_FAB2_LIB.BASEBOARD_FAB2(SCH_1):PAGE96
     2 RST_CPU0_G_N @BASEBOARD_FAB2_LIB.BASEBOARD_FAB2(SCH_1):RST_CPU0_G_N     I2 @BASEBOARD_FAB2_LIB.BASEBOARD_FAB2(SCH_1):PAGE96

R6D13 RES_0402-240,1.0%,1/16W,EMPTY,A
     1 PVCCIO_CPU0 @BASEBOARD_FAB2_LIB.BASEBOARD_FAB2(SCH_1):PVCCIO_CPU0    I33 @BASEBOARD_FAB2_LIB.BASEBOARD_FAB2(SCH_1):PAGE90
     2 PU_CPU0_SAFE_MODE_BOOT @BASEBOARD_FAB2_LIB.BASEBOARD_FAB2(SCH_1):PU_CPU0_SAFE_MODE_BOOT    I33 @BASEBOARD_FAB2_LIB.BASEBOARD_FAB2(SCH_1):PAGE90

R6D14 RES_0402-240,1.0%,1/16W,EMPTY,A
     1 PVCCIO_CPU0 @BASEBOARD_FAB2_LIB.BASEBOARD_FAB2(SCH_1):PVCCIO_CPU0    I52 @BASEBOARD_FAB2_LIB.BASEBOARD_FAB2(SCH_1):PAGE90
     2 PU_CPU0_EAR_N @BASEBOARD_FAB2_LIB.BASEBOARD_FAB2(SCH_1):PU_CPU0_EAR_N    I52 @BASEBOARD_FAB2_LIB.BASEBOARD_FAB2(SCH_1):PAGE90

R6D15 RES_0402-240,1.0%,1/16W,EMPTY,A
     1 PVCCIO_CPU0 @BASEBOARD_FAB2_LIB.BASEBOARD_FAB2(SCH_1):PVCCIO_CPU0    I48 @BASEBOARD_FAB2_LIB.BASEBOARD_FAB2(SCH_1):PAGE90
     2 PU_CPU0_SOCKET_ID_0 @BASEBOARD_FAB2_LIB.BASEBOARD_FAB2(SCH_1):PU_CPU0_SOCKET_ID_0    I48 @BASEBOARD_FAB2_LIB.BASEBOARD_FAB2(SCH_1):PAGE90

R6D16 RES_0402-0.0,5%,1/16W,EMPTY,G2A
     1 FM_CPU_BMC_INIT @BASEBOARD_FAB2_LIB.BASEBOARD_FAB2(SCH_1):FM_CPU_BMC_INIT   I299 @BASEBOARD_FAB2_LIB.BASEBOARD_FAB2(SCH_1):PAGE156
     2 H_CPU0_BMCINIT @BASEBOARD_FAB2_LIB.BASEBOARD_FAB2(SCH_1):H_CPU0_BMCINIT   I299 @BASEBOARD_FAB2_LIB.BASEBOARD_FAB2(SCH_1):PAGE156

R6F1 RES_0402-49.9,1%,1/16W,CHIP,G2A
     1 IRQ_DIMM_SAVE_N @BASEBOARD_FAB2_LIB.BASEBOARD_FAB2(SCH_1):IRQ_DIMM_SAVE_N     I4 @BASEBOARD_FAB2_LIB.BASEBOARD_FAB2(SCH_1):PAGE89
     2 FM_ADR_COMPLETE_DEF_N @BASEBOARD_FAB2_LIB.BASEBOARD_FAB2(SCH_1):FM_ADR_COMPLETE_DEF_N     I4 @BASEBOARD_FAB2_LIB.BASEBOARD_FAB2(SCH_1):PAGE89

R6F2 RES_0402-49.9,1%,1/16W,CHIP,G2A
     1 IRQ_DIMM_SAVE_N @BASEBOARD_FAB2_LIB.BASEBOARD_FAB2(SCH_1):IRQ_DIMM_SAVE_N     I6 @BASEBOARD_FAB2_LIB.BASEBOARD_FAB2(SCH_1):PAGE89
     2 FM_ADR_COMPLETE_KLM_N @BASEBOARD_FAB2_LIB.BASEBOARD_FAB2(SCH_1):FM_ADR_COMPLETE_KLM_N     I6 @BASEBOARD_FAB2_LIB.BASEBOARD_FAB2(SCH_1):PAGE89

R6F3 RES_0402-10.0K,1%,1/16W,CHIP,GA
     1 PVPP_ABC @BASEBOARD_FAB2_LIB.BASEBOARD_FAB2(SCH_1):PVPP_ABC     I7 @BASEBOARD_FAB2_LIB.BASEBOARD_FAB2(SCH_1):PAGE89
     2 IRQ_DIMM_SAVE_N @BASEBOARD_FAB2_LIB.BASEBOARD_FAB2(SCH_1):IRQ_DIMM_SAVE_N     I7 @BASEBOARD_FAB2_LIB.BASEBOARD_FAB2(SCH_1):PAGE89

R6F4 RES_0402-49.9,1%,1/16W,CHIP,G2A
     1 IRQ_DIMM_SAVE_N @BASEBOARD_FAB2_LIB.BASEBOARD_FAB2(SCH_1):IRQ_DIMM_SAVE_N     I3 @BASEBOARD_FAB2_LIB.BASEBOARD_FAB2(SCH_1):PAGE89
     2 FM_ADR_COMPLETE_ABC_N @BASEBOARD_FAB2_LIB.BASEBOARD_FAB2(SCH_1):FM_ADR_COMPLETE_ABC_N     I3 @BASEBOARD_FAB2_LIB.BASEBOARD_FAB2(SCH_1):PAGE89

R6F5 RES_0402-49.9,1%,1/16W,CHIP,G2A
     1 IRQ_DIMM_SAVE_N @BASEBOARD_FAB2_LIB.BASEBOARD_FAB2(SCH_1):IRQ_DIMM_SAVE_N     I5 @BASEBOARD_FAB2_LIB.BASEBOARD_FAB2(SCH_1):PAGE89
     2 FM_ADR_COMPLETE_GHJ_N @BASEBOARD_FAB2_LIB.BASEBOARD_FAB2(SCH_1):FM_ADR_COMPLETE_GHJ_N     I5 @BASEBOARD_FAB2_LIB.BASEBOARD_FAB2(SCH_1):PAGE89

R6F6 RES_0402-0.0,5%,1/16W,EMPTY,G2A
     1 CLK_322M_156M_CPU0_OSC_VRM_DN @BASEBOARD_FAB2_LIB.BASEBOARD_FAB2(SCH_1):CLK_322M_156M_CPU0_OSC_VRM_DN    I41 @BASEBOARD_FAB2_LIB.BASEBOARD_FAB2(SCH_1):PAGE104
     2 CLK_156M_OSC_CPU0_HFI_DN @BASEBOARD_FAB2_LIB.BASEBOARD_FAB2(SCH_1):CLK_156M_OSC_CPU0_HFI_DN    I41 @BASEBOARD_FAB2_LIB.BASEBOARD_FAB2(SCH_1):PAGE104

R6F7 RES_0402-0.0,5%,1/16W,CHIP,G21A
     1 CLK_156M_OSC_BRD_CPU0_DN @BASEBOARD_FAB2_LIB.BASEBOARD_FAB2(SCH_1):CLK_156M_OSC_BRD_CPU0_DN    I67 @BASEBOARD_FAB2_LIB.BASEBOARD_FAB2(SCH_1):PAGE104
     2 CLK_156M_OSC_CPU0_HFI_DN @BASEBOARD_FAB2_LIB.BASEBOARD_FAB2(SCH_1):CLK_156M_OSC_CPU0_HFI_DN    I67 @BASEBOARD_FAB2_LIB.BASEBOARD_FAB2(SCH_1):PAGE104

R6F8 RES_0402-0.0,5%,1/16W,EMPTY,G2A
     1 CLK_322M_156M_CPU0_OSC_VRM_DP @BASEBOARD_FAB2_LIB.BASEBOARD_FAB2(SCH_1):CLK_322M_156M_CPU0_OSC_VRM_DP    I37 @BASEBOARD_FAB2_LIB.BASEBOARD_FAB2(SCH_1):PAGE104
     2 CLK_156M_OSC_CPU0_HFI_DP @BASEBOARD_FAB2_LIB.BASEBOARD_FAB2(SCH_1):CLK_156M_OSC_CPU0_HFI_DP    I37 @BASEBOARD_FAB2_LIB.BASEBOARD_FAB2(SCH_1):PAGE104

R6F9 RES_0402-0.0,5%,1/16W,CHIP,G21A
     1 CLK_156M_OSC_BRD_CPU0_DP @BASEBOARD_FAB2_LIB.BASEBOARD_FAB2(SCH_1):CLK_156M_OSC_BRD_CPU0_DP    I68 @BASEBOARD_FAB2_LIB.BASEBOARD_FAB2(SCH_1):PAGE104
     2 CLK_156M_OSC_CPU0_HFI_DP @BASEBOARD_FAB2_LIB.BASEBOARD_FAB2(SCH_1):CLK_156M_OSC_CPU0_HFI_DP    I68 @BASEBOARD_FAB2_LIB.BASEBOARD_FAB2(SCH_1):PAGE104

R6F10 RES_0402-0.0,5%,1/16W,EMPTY,G2A
     1 CLK_322M_156M_CPU0_OSC_VRM_DN @BASEBOARD_FAB2_LIB.BASEBOARD_FAB2(SCH_1):CLK_322M_156M_CPU0_OSC_VRM_DN    I78 @BASEBOARD_FAB2_LIB.BASEBOARD_FAB2(SCH_1):PAGE104
     2 CLK_322M_OSC_CPU0_RC_DN @BASEBOARD_FAB2_LIB.BASEBOARD_FAB2(SCH_1):CLK_322M_OSC_CPU0_RC_DN    I78 @BASEBOARD_FAB2_LIB.BASEBOARD_FAB2(SCH_1):PAGE104

R6F11 RES_0402-0.0,5%,1/16W,EMPTY,G2A
     1 CLK_322M_156M_CPU0_OSC_VRM_DP @BASEBOARD_FAB2_LIB.BASEBOARD_FAB2(SCH_1):CLK_322M_156M_CPU0_OSC_VRM_DP    I79 @BASEBOARD_FAB2_LIB.BASEBOARD_FAB2(SCH_1):PAGE104
     2 CLK_322M_OSC_CPU0_RC_DP @BASEBOARD_FAB2_LIB.BASEBOARD_FAB2(SCH_1):CLK_322M_OSC_CPU0_RC_DP    I79 @BASEBOARD_FAB2_LIB.BASEBOARD_FAB2(SCH_1):PAGE104

R6L1 RES_0402-1.00K,1%,1/16W,CHIP,GA
     1 M_F_VREF @BASEBOARD_FAB2_LIB.BASEBOARD_FAB2(SCH_1):M_F_VREF    I64 @BASEBOARD_FAB2_LIB.BASEBOARD_FAB2(SCH_1):PAGE98
     2    GND @BASEBOARD_FAB2_LIB.BASEBOARD_FAB2(SCH_1):GND    I64 @BASEBOARD_FAB2_LIB.BASEBOARD_FAB2(SCH_1):PAGE98

R6L2 RES_0402-1.00K,1%,1/16W,CHIP,GA
     1 PVDDQ_DEF @BASEBOARD_FAB2_LIB.BASEBOARD_FAB2(SCH_1):PVDDQ_DEF    I62 @BASEBOARD_FAB2_LIB.BASEBOARD_FAB2(SCH_1):PAGE98
     2 M_F_VREF @BASEBOARD_FAB2_LIB.BASEBOARD_FAB2(SCH_1):M_F_VREF    I62 @BASEBOARD_FAB2_LIB.BASEBOARD_FAB2(SCH_1):PAGE98

R6L3 RES_0402-2,1.0%,1/16W,CHIP,G21A
     1 M_F_CPU_VREF @BASEBOARD_FAB2_LIB.BASEBOARD_FAB2(SCH_1):M_F_CPU_VREF    I66 @BASEBOARD_FAB2_LIB.BASEBOARD_FAB2(SCH_1):PAGE98
     2 M_F_VREF @BASEBOARD_FAB2_LIB.BASEBOARD_FAB2(SCH_1):M_F_VREF    I66 @BASEBOARD_FAB2_LIB.BASEBOARD_FAB2(SCH_1):PAGE98

R6L4 RES_0402-1.0M,1%,1/16W,EMPTY,GA
     1   P3V3 @BASEBOARD_FAB2_LIB.BASEBOARD_FAB2(SCH_1):P3V3    I37 @BASEBOARD_FAB2_LIB.BASEBOARD_FAB2(SCH_1):PAGE222
     2 FM_PVTT_DEF_EN_R @BASEBOARD_FAB2_LIB.BASEBOARD_FAB2(SCH_1):FM_PVTT_DEF_EN_R    I37 @BASEBOARD_FAB2_LIB.BASEBOARD_FAB2(SCH_1):PAGE222

R6L5 RES_0402-1.0M,1%,1/16W,EMPTY,GA
     1   P3V3 @BASEBOARD_FAB2_LIB.BASEBOARD_FAB2(SCH_1):P3V3    I37 @BASEBOARD_FAB2_LIB.BASEBOARD_FAB2(SCH_1):PAGE230
     2 FM_PVTT_KLM_EN_R @BASEBOARD_FAB2_LIB.BASEBOARD_FAB2(SCH_1):FM_PVTT_KLM_EN_R    I37 @BASEBOARD_FAB2_LIB.BASEBOARD_FAB2(SCH_1):PAGE230

R6L6 RES_0402-0.0,5%,1/16W,CHIP,G21A
     1 PVDDQ_KLM @BASEBOARD_FAB2_LIB.BASEBOARD_FAB2(SCH_1):PVDDQ_KLM    I34 @BASEBOARD_FAB2_LIB.BASEBOARD_FAB2(SCH_1):PAGE230
     2 VSENSE_PVDDQ_KLM_VTT @BASEBOARD_FAB2_LIB.BASEBOARD_FAB2(SCH_1):VSENSE_PVDDQ_KLM_VTT    I34 @BASEBOARD_FAB2_LIB.BASEBOARD_FAB2(SCH_1):PAGE230

R6L7 RES_0402-51.1,1.0%,1/16W,CHIP,A
     1    GND @BASEBOARD_FAB2_LIB.BASEBOARD_FAB2(SCH_1):GND    I52 @BASEBOARD_FAB2_LIB.BASEBOARD_FAB2(SCH_1):PAGE230
     2 PVTT_KLM @BASEBOARD_FAB2_LIB.BASEBOARD_FAB2(SCH_1):PVTT_KLM    I52 @BASEBOARD_FAB2_LIB.BASEBOARD_FAB2(SCH_1):PAGE230

R6L8 RES_0402-0.0,5%,1/16W,CHIP,G21A
     1   P3V3 @BASEBOARD_FAB2_LIB.BASEBOARD_FAB2(SCH_1):P3V3    I30 @BASEBOARD_FAB2_LIB.BASEBOARD_FAB2(SCH_1):PAGE230
     2 VR_PVTT_KLM_BIAS @BASEBOARD_FAB2_LIB.BASEBOARD_FAB2(SCH_1):VR_PVTT_KLM_BIAS    I30 @BASEBOARD_FAB2_LIB.BASEBOARD_FAB2(SCH_1):PAGE230

R6L9 RES_0402-10.0K,1%,1/16W,CHIP,GA
     1   P3V3 @BASEBOARD_FAB2_LIB.BASEBOARD_FAB2(SCH_1):P3V3    I19 @BASEBOARD_FAB2_LIB.BASEBOARD_FAB2(SCH_1):PAGE222
     2 PWRGD_PVTT_DEF_CPU0_R @BASEBOARD_FAB2_LIB.BASEBOARD_FAB2(SCH_1):PWRGD_PVTT_DEF_CPU0_R    I19 @BASEBOARD_FAB2_LIB.BASEBOARD_FAB2(SCH_1):PAGE222

R6L10 RES_0402-0.0,5%,1/16W,CHIP,G21A
     1 PVDDQ_DEF @BASEBOARD_FAB2_LIB.BASEBOARD_FAB2(SCH_1):PVDDQ_DEF    I34 @BASEBOARD_FAB2_LIB.BASEBOARD_FAB2(SCH_1):PAGE222
     2 VSENSE_PVDDQ_DEF_VTT @BASEBOARD_FAB2_LIB.BASEBOARD_FAB2(SCH_1):VSENSE_PVDDQ_DEF_VTT    I34 @BASEBOARD_FAB2_LIB.BASEBOARD_FAB2(SCH_1):PAGE222

R6L11 RES_0402-0.0,5%,1/16W,CHIP,G21A
     1   P3V3 @BASEBOARD_FAB2_LIB.BASEBOARD_FAB2(SCH_1):P3V3    I30 @BASEBOARD_FAB2_LIB.BASEBOARD_FAB2(SCH_1):PAGE222
     2 VR_PVTT_DEF_BIAS @BASEBOARD_FAB2_LIB.BASEBOARD_FAB2(SCH_1):VR_PVTT_DEF_BIAS    I30 @BASEBOARD_FAB2_LIB.BASEBOARD_FAB2(SCH_1):PAGE222

R6L12 RES_0402-1.00K,1%,1/16W,CHIP,GA
     1 M_E_VREF @BASEBOARD_FAB2_LIB.BASEBOARD_FAB2(SCH_1):M_E_VREF    I56 @BASEBOARD_FAB2_LIB.BASEBOARD_FAB2(SCH_1):PAGE98
     2    GND @BASEBOARD_FAB2_LIB.BASEBOARD_FAB2(SCH_1):GND    I56 @BASEBOARD_FAB2_LIB.BASEBOARD_FAB2(SCH_1):PAGE98

R6L13 RES_0402-1.00K,1%,1/16W,CHIP,GA
     1 PVDDQ_DEF @BASEBOARD_FAB2_LIB.BASEBOARD_FAB2(SCH_1):PVDDQ_DEF    I54 @BASEBOARD_FAB2_LIB.BASEBOARD_FAB2(SCH_1):PAGE98
     2 M_E_VREF @BASEBOARD_FAB2_LIB.BASEBOARD_FAB2(SCH_1):M_E_VREF    I54 @BASEBOARD_FAB2_LIB.BASEBOARD_FAB2(SCH_1):PAGE98

R6L14 RES_0402-2,1.0%,1/16W,CHIP,G21A
     1 M_E_CPU_VREF @BASEBOARD_FAB2_LIB.BASEBOARD_FAB2(SCH_1):M_E_CPU_VREF    I58 @BASEBOARD_FAB2_LIB.BASEBOARD_FAB2(SCH_1):PAGE98
     2 M_E_VREF @BASEBOARD_FAB2_LIB.BASEBOARD_FAB2(SCH_1):M_E_VREF    I58 @BASEBOARD_FAB2_LIB.BASEBOARD_FAB2(SCH_1):PAGE98

R6L16 RES_0402-1.00K,1%,1/16W,CHIP,GA
     1 M_D_VREF @BASEBOARD_FAB2_LIB.BASEBOARD_FAB2(SCH_1):M_D_VREF    I12 @BASEBOARD_FAB2_LIB.BASEBOARD_FAB2(SCH_1):PAGE98
     2    GND @BASEBOARD_FAB2_LIB.BASEBOARD_FAB2(SCH_1):GND    I12 @BASEBOARD_FAB2_LIB.BASEBOARD_FAB2(SCH_1):PAGE98

R6M1 RES_0402-1.00K,1%,1/16W,CHIP,GA
     1 PVDDQ_DEF @BASEBOARD_FAB2_LIB.BASEBOARD_FAB2(SCH_1):PVDDQ_DEF     I9 @BASEBOARD_FAB2_LIB.BASEBOARD_FAB2(SCH_1):PAGE98
     2 M_D_VREF @BASEBOARD_FAB2_LIB.BASEBOARD_FAB2(SCH_1):M_D_VREF     I9 @BASEBOARD_FAB2_LIB.BASEBOARD_FAB2(SCH_1):PAGE98

R6M2 RES_0402-2,1.0%,1/16W,CHIP,G21A
     1 M_D_CPU_VREF @BASEBOARD_FAB2_LIB.BASEBOARD_FAB2(SCH_1):M_D_CPU_VREF    I14 @BASEBOARD_FAB2_LIB.BASEBOARD_FAB2(SCH_1):PAGE98
     2 M_D_VREF @BASEBOARD_FAB2_LIB.BASEBOARD_FAB2(SCH_1):M_D_VREF    I14 @BASEBOARD_FAB2_LIB.BASEBOARD_FAB2(SCH_1):PAGE98

R6M4 RES_0402-4.75K,1%,1/16W,CHIP,GA
     1   P3V3 @BASEBOARD_FAB2_LIB.BASEBOARD_FAB2(SCH_1):P3V3    I82 @BASEBOARD_FAB2_LIB.BASEBOARD_FAB2(SCH_1):PAGE94
     2 H_CPU1_MEMKLM_MEMHOT @BASEBOARD_FAB2_LIB.BASEBOARD_FAB2(SCH_1):H_CPU1_MEMKLM_MEMHOT    I82 @BASEBOARD_FAB2_LIB.BASEBOARD_FAB2(SCH_1):PAGE94

R6M8 RES_0402-49.9,1%,1/16W,CHIP,G2A
     1 JTAG_MCP_CPU1_TDI_R @BASEBOARD_FAB2_LIB.BASEBOARD_FAB2(SCH_1):JTAG_MCP_CPU1_TDI_R   I188 @BASEBOARD_FAB2_LIB.BASEBOARD_FAB2(SCH_1):PAGE113
     2 JTAG_MCP_CPU1_TDI @BASEBOARD_FAB2_LIB.BASEBOARD_FAB2(SCH_1):JTAG_MCP_CPU1_TDI   I188 @BASEBOARD_FAB2_LIB.BASEBOARD_FAB2(SCH_1):PAGE113

R6M9 RES_0402-4.75K,1%,1/16W,CHIP,GA
     1 PVPP_KLM @BASEBOARD_FAB2_LIB.BASEBOARD_FAB2(SCH_1):PVPP_KLM    I49 @BASEBOARD_FAB2_LIB.BASEBOARD_FAB2(SCH_1):PAGE192
     2 RST_CD_CPU1_POR_N @BASEBOARD_FAB2_LIB.BASEBOARD_FAB2(SCH_1):RST_CD_CPU1_POR_N    I49 @BASEBOARD_FAB2_LIB.BASEBOARD_FAB2(SCH_1):PAGE192

R6N1 RES_0402-49.9,1%,1/16W,CHIP,G2A
     1 SVID_ALERT0_CPU0_R_N @BASEBOARD_FAB2_LIB.BASEBOARD_FAB2(SCH_1):SVID_ALERT0_CPU0_R_N   I164 @BASEBOARD_FAB2_LIB.BASEBOARD_FAB2(SCH_1):PAGE21
     2 PVCCIO_CPU0 @BASEBOARD_FAB2_LIB.BASEBOARD_FAB2(SCH_1):PVCCIO_CPU0   I164 @BASEBOARD_FAB2_LIB.BASEBOARD_FAB2(SCH_1):PAGE21

R6N2 RES_0402-100.0,1%,1/16W,CHIP,GA
     1 SVID_DIO0_CPU0_R @BASEBOARD_FAB2_LIB.BASEBOARD_FAB2(SCH_1):SVID_DIO0_CPU0_R   I163 @BASEBOARD_FAB2_LIB.BASEBOARD_FAB2(SCH_1):PAGE21
     2 PVCCIO_CPU0 @BASEBOARD_FAB2_LIB.BASEBOARD_FAB2(SCH_1):PVCCIO_CPU0   I163 @BASEBOARD_FAB2_LIB.BASEBOARD_FAB2(SCH_1):PAGE21

R6N3 RES_0402-1.0,1%,1/16W,CHIP,G21A
     1 VR_PVSA_CPU0_VCIN @BASEBOARD_FAB2_LIB.BASEBOARD_FAB2(SCH_1):VR_PVSA_CPU0_VCIN    I19 @BASEBOARD_FAB2_LIB.BASEBOARD_FAB2(SCH_1):PAGE205
     2 P5V_STBY @BASEBOARD_FAB2_LIB.BASEBOARD_FAB2(SCH_1):P5V_STBY    I19 @BASEBOARD_FAB2_LIB.BASEBOARD_FAB2(SCH_1):PAGE205

R6N4 RES_0402-51.1,1.0%,1/16W,CHIP,A
     1 PVSA_CPU0 @BASEBOARD_FAB2_LIB.BASEBOARD_FAB2(SCH_1):PVSA_CPU0    I45 @BASEBOARD_FAB2_LIB.BASEBOARD_FAB2(SCH_1):PAGE205
     2    GND @BASEBOARD_FAB2_LIB.BASEBOARD_FAB2(SCH_1):GND    I45 @BASEBOARD_FAB2_LIB.BASEBOARD_FAB2(SCH_1):PAGE205

R6N8 RES_0402-10.0,1%,1/16W,CHIP,G2A
     1 SMB_CPU1_PE_HP_GTL_SCL @BASEBOARD_FAB2_LIB.BASEBOARD_FAB2(SCH_1):SMB_CPU1_PE_HP_GTL_SCL     I2 @BASEBOARD_FAB2_LIB.BASEBOARD_FAB2(SCH_1):PAGE163
     2 SMB_CPU1_PE_HP_GTL_R_SCL @BASEBOARD_FAB2_LIB.BASEBOARD_FAB2(SCH_1):SMB_CPU1_PE_HP_GTL_R_SCL     I2 @BASEBOARD_FAB2_LIB.BASEBOARD_FAB2(SCH_1):PAGE163

R6N9 RES_0402-10.0,1%,1/16W,CHIP,G2A
     1 SMB_CPU1_PE_HP_GTL_SDA @BASEBOARD_FAB2_LIB.BASEBOARD_FAB2(SCH_1):SMB_CPU1_PE_HP_GTL_SDA     I3 @BASEBOARD_FAB2_LIB.BASEBOARD_FAB2(SCH_1):PAGE163
     2 SMB_CPU1_PE_HP_GTL_R_SDA @BASEBOARD_FAB2_LIB.BASEBOARD_FAB2(SCH_1):SMB_CPU1_PE_HP_GTL_R_SDA     I3 @BASEBOARD_FAB2_LIB.BASEBOARD_FAB2(SCH_1):PAGE163

R6N10 RES_0402-221,1.0%,1/16W,CHIP,GA
     1 SVID_ALERT0_CPU0_N @BASEBOARD_FAB2_LIB.BASEBOARD_FAB2(SCH_1):SVID_ALERT0_CPU0_N   I149 @BASEBOARD_FAB2_LIB.BASEBOARD_FAB2(SCH_1):PAGE21
     2 SVID_ALERT0_CPU0_R_N @BASEBOARD_FAB2_LIB.BASEBOARD_FAB2(SCH_1):SVID_ALERT0_CPU0_R_N   I149 @BASEBOARD_FAB2_LIB.BASEBOARD_FAB2(SCH_1):PAGE21

R6N11 RES_0402-0.0,5%,1/16W,CHIP,G21A
     1 SVID_DIO0_CPU0 @BASEBOARD_FAB2_LIB.BASEBOARD_FAB2(SCH_1):SVID_DIO0_CPU0   I151 @BASEBOARD_FAB2_LIB.BASEBOARD_FAB2(SCH_1):PAGE21
     2 SVID_DIO0_CPU0_R @BASEBOARD_FAB2_LIB.BASEBOARD_FAB2(SCH_1):SVID_DIO0_CPU0_R   I151 @BASEBOARD_FAB2_LIB.BASEBOARD_FAB2(SCH_1):PAGE21

R6N12 RES_0402-0.0,5%,1/16W,CHIP,G21A
     1 SVID_CLK0_CPU0 @BASEBOARD_FAB2_LIB.BASEBOARD_FAB2(SCH_1):SVID_CLK0_CPU0   I150 @BASEBOARD_FAB2_LIB.BASEBOARD_FAB2(SCH_1):PAGE21
     2 SVID_CLK0_CPU0_R @BASEBOARD_FAB2_LIB.BASEBOARD_FAB2(SCH_1):SVID_CLK0_CPU0_R   I150 @BASEBOARD_FAB2_LIB.BASEBOARD_FAB2(SCH_1):PAGE21

R6N13 RES_0402-1.00K,1%,1/16W,CHIP,GA
     1    GND @BASEBOARD_FAB2_LIB.BASEBOARD_FAB2(SCH_1):GND   I303 @BASEBOARD_FAB2_LIB.BASEBOARD_FAB2(SCH_1):PAGE156
     2 PD_PIROM_CPU0_ADDR1 @BASEBOARD_FAB2_LIB.BASEBOARD_FAB2(SCH_1):PD_PIROM_CPU0_ADDR1   I303 @BASEBOARD_FAB2_LIB.BASEBOARD_FAB2(SCH_1):PAGE156

R6N14 RES_0402-1.00K,1%,1/16W,CHIP,GA
     1    GND @BASEBOARD_FAB2_LIB.BASEBOARD_FAB2(SCH_1):GND   I302 @BASEBOARD_FAB2_LIB.BASEBOARD_FAB2(SCH_1):PAGE156
     2 PD_PIROM_CPU0_ADDR0 @BASEBOARD_FAB2_LIB.BASEBOARD_FAB2(SCH_1):PD_PIROM_CPU0_ADDR0   I302 @BASEBOARD_FAB2_LIB.BASEBOARD_FAB2(SCH_1):PAGE156

R6N15 RES_0402-1.00K,1%,1/16W,CHIP,GA
     1    GND @BASEBOARD_FAB2_LIB.BASEBOARD_FAB2(SCH_1):GND   I304 @BASEBOARD_FAB2_LIB.BASEBOARD_FAB2(SCH_1):PAGE156
     2 PD_PIROM_CPU0_ADDR2 @BASEBOARD_FAB2_LIB.BASEBOARD_FAB2(SCH_1):PD_PIROM_CPU0_ADDR2   I304 @BASEBOARD_FAB2_LIB.BASEBOARD_FAB2(SCH_1):PAGE156

R6P1 RES_0402-42.2,1.0%,1/16W,EMPTYA
     1 CLK_100M_CPU0_RC_REFCLK0_DP @BASEBOARD_FAB2_LIB.BASEBOARD_FAB2(SCH_1):CLK_100M_CPU0_RC_REFCLK0_DP   I149 @BASEBOARD_FAB2_LIB.BASEBOARD_FAB2(SCH_1):PAGE103
     2    GND @BASEBOARD_FAB2_LIB.BASEBOARD_FAB2(SCH_1):GND   I149 @BASEBOARD_FAB2_LIB.BASEBOARD_FAB2(SCH_1):PAGE103

R6P2 RES_0402-42.2,1.0%,1/16W,EMPTYA
     1 CLK_100M_CPU0_RC_REFCLK0_DN @BASEBOARD_FAB2_LIB.BASEBOARD_FAB2(SCH_1):CLK_100M_CPU0_RC_REFCLK0_DN   I151 @BASEBOARD_FAB2_LIB.BASEBOARD_FAB2(SCH_1):PAGE103
     2    GND @BASEBOARD_FAB2_LIB.BASEBOARD_FAB2(SCH_1):GND   I151 @BASEBOARD_FAB2_LIB.BASEBOARD_FAB2(SCH_1):PAGE103

R6P3 RES_0402-42.2,1.0%,1/16W,EMPTYA
     1 CLK_100M_CPU0_RC_REFCLK1_DP @BASEBOARD_FAB2_LIB.BASEBOARD_FAB2(SCH_1):CLK_100M_CPU0_RC_REFCLK1_DP   I145 @BASEBOARD_FAB2_LIB.BASEBOARD_FAB2(SCH_1):PAGE103
     2    GND @BASEBOARD_FAB2_LIB.BASEBOARD_FAB2(SCH_1):GND   I145 @BASEBOARD_FAB2_LIB.BASEBOARD_FAB2(SCH_1):PAGE103

R6P4 RES_0402-42.2,1.0%,1/16W,EMPTYA
     1 CLK_100M_CPU0_RC_REFCLK1_DN @BASEBOARD_FAB2_LIB.BASEBOARD_FAB2(SCH_1):CLK_100M_CPU0_RC_REFCLK1_DN   I147 @BASEBOARD_FAB2_LIB.BASEBOARD_FAB2(SCH_1):PAGE103
     2    GND @BASEBOARD_FAB2_LIB.BASEBOARD_FAB2(SCH_1):GND   I147 @BASEBOARD_FAB2_LIB.BASEBOARD_FAB2(SCH_1):PAGE103

R6P5 RES_0402-42.2,1.0%,1/16W,EMPTYA
     1 CLK_100M_CPU1_BCLK0_DP @BASEBOARD_FAB2_LIB.BASEBOARD_FAB2(SCH_1):CLK_100M_CPU1_BCLK0_DP   I141 @BASEBOARD_FAB2_LIB.BASEBOARD_FAB2(SCH_1):PAGE103
     2    GND @BASEBOARD_FAB2_LIB.BASEBOARD_FAB2(SCH_1):GND   I141 @BASEBOARD_FAB2_LIB.BASEBOARD_FAB2(SCH_1):PAGE103

R6P6 RES_0402-42.2,1.0%,1/16W,EMPTYA
     1 CLK_100M_CPU1_BCLK0_DN @BASEBOARD_FAB2_LIB.BASEBOARD_FAB2(SCH_1):CLK_100M_CPU1_BCLK0_DN   I143 @BASEBOARD_FAB2_LIB.BASEBOARD_FAB2(SCH_1):PAGE103
     2    GND @BASEBOARD_FAB2_LIB.BASEBOARD_FAB2(SCH_1):GND   I143 @BASEBOARD_FAB2_LIB.BASEBOARD_FAB2(SCH_1):PAGE103

R6P7 RES_0402-42.2,1.0%,1/16W,EMPTYA
     1 CLK_100M_CPU1_BCLK1_DP @BASEBOARD_FAB2_LIB.BASEBOARD_FAB2(SCH_1):CLK_100M_CPU1_BCLK1_DP   I137 @BASEBOARD_FAB2_LIB.BASEBOARD_FAB2(SCH_1):PAGE103
     2    GND @BASEBOARD_FAB2_LIB.BASEBOARD_FAB2(SCH_1):GND   I137 @BASEBOARD_FAB2_LIB.BASEBOARD_FAB2(SCH_1):PAGE103

R6P8 RES_0402-42.2,1.0%,1/16W,EMPTYA
     1 CLK_100M_CPU1_BCLK1_DN @BASEBOARD_FAB2_LIB.BASEBOARD_FAB2(SCH_1):CLK_100M_CPU1_BCLK1_DN   I139 @BASEBOARD_FAB2_LIB.BASEBOARD_FAB2(SCH_1):PAGE103
     2    GND @BASEBOARD_FAB2_LIB.BASEBOARD_FAB2(SCH_1):GND   I139 @BASEBOARD_FAB2_LIB.BASEBOARD_FAB2(SCH_1):PAGE103

R6P9 RES_0402-42.2,1.0%,1/16W,EMPTYA
     1 CLK_100M_CPU0_PE_REFCLK_DN @BASEBOARD_FAB2_LIB.BASEBOARD_FAB2(SCH_1):CLK_100M_CPU0_PE_REFCLK_DN   I155 @BASEBOARD_FAB2_LIB.BASEBOARD_FAB2(SCH_1):PAGE103
     2    GND @BASEBOARD_FAB2_LIB.BASEBOARD_FAB2(SCH_1):GND   I155 @BASEBOARD_FAB2_LIB.BASEBOARD_FAB2(SCH_1):PAGE103

R6P10 RES_0402-1.0,1%,1/16W,CHIP,G21A
     1 VR_PVCCIN_CPU0_PH4_VCIN @BASEBOARD_FAB2_LIB.BASEBOARD_FAB2(SCH_1):VR_PVCCIN_CPU0_PH4_VCIN    I50 @BASEBOARD_FAB2_LIB.BASEBOARD_FAB2(SCH_1):PAGE203
     2 P5V_STBY @BASEBOARD_FAB2_LIB.BASEBOARD_FAB2(SCH_1):P5V_STBY    I50 @BASEBOARD_FAB2_LIB.BASEBOARD_FAB2(SCH_1):PAGE203

R6P11 RES_0402-42.2,1.0%,1/16W,EMPTYA
     1 CLK_100M_CPU0_PE_REFCLK_DP @BASEBOARD_FAB2_LIB.BASEBOARD_FAB2(SCH_1):CLK_100M_CPU0_PE_REFCLK_DP   I153 @BASEBOARD_FAB2_LIB.BASEBOARD_FAB2(SCH_1):PAGE103
     2    GND @BASEBOARD_FAB2_LIB.BASEBOARD_FAB2(SCH_1):GND   I153 @BASEBOARD_FAB2_LIB.BASEBOARD_FAB2(SCH_1):PAGE103

R6P12 RES_0402-42.2,1.0%,1/16W,EMPTYA
     1 CLK_100M_CPU0_BCLK2_DN @BASEBOARD_FAB2_LIB.BASEBOARD_FAB2(SCH_1):CLK_100M_CPU0_BCLK2_DN   I159 @BASEBOARD_FAB2_LIB.BASEBOARD_FAB2(SCH_1):PAGE103
     2    GND @BASEBOARD_FAB2_LIB.BASEBOARD_FAB2(SCH_1):GND   I159 @BASEBOARD_FAB2_LIB.BASEBOARD_FAB2(SCH_1):PAGE103

R6P13 RES_0402-42.2,1.0%,1/16W,EMPTYA
     1 CLK_100M_CPU0_BCLK2_DP @BASEBOARD_FAB2_LIB.BASEBOARD_FAB2(SCH_1):CLK_100M_CPU0_BCLK2_DP   I157 @BASEBOARD_FAB2_LIB.BASEBOARD_FAB2(SCH_1):PAGE103
     2    GND @BASEBOARD_FAB2_LIB.BASEBOARD_FAB2(SCH_1):GND   I157 @BASEBOARD_FAB2_LIB.BASEBOARD_FAB2(SCH_1):PAGE103

R6P15 RES_0402-42.2,1.0%,1/16W,EMPTYA
     1 CLK_100M_CPU0_BCLK0_DN @BASEBOARD_FAB2_LIB.BASEBOARD_FAB2(SCH_1):CLK_100M_CPU0_BCLK0_DN   I167 @BASEBOARD_FAB2_LIB.BASEBOARD_FAB2(SCH_1):PAGE103
     2    GND @BASEBOARD_FAB2_LIB.BASEBOARD_FAB2(SCH_1):GND   I167 @BASEBOARD_FAB2_LIB.BASEBOARD_FAB2(SCH_1):PAGE103

R6P16 RES_0402-1.00K,1%,1/16W,CHIP,GA
     1 PVCCIO_CPU0 @BASEBOARD_FAB2_LIB.BASEBOARD_FAB2(SCH_1):PVCCIO_CPU0   I132 @BASEBOARD_FAB2_LIB.BASEBOARD_FAB2(SCH_1):PAGE201
     2 VR_PVCCIN_CPU0_VREN @BASEBOARD_FAB2_LIB.BASEBOARD_FAB2(SCH_1):VR_PVCCIN_CPU0_VREN   I132 @BASEBOARD_FAB2_LIB.BASEBOARD_FAB2(SCH_1):PAGE201

R6P17 RES_0402-42.2,1.0%,1/16W,EMPTYA
     1 CLK_100M_CPU0_BCLK0_DP @BASEBOARD_FAB2_LIB.BASEBOARD_FAB2(SCH_1):CLK_100M_CPU0_BCLK0_DP   I165 @BASEBOARD_FAB2_LIB.BASEBOARD_FAB2(SCH_1):PAGE103
     2    GND @BASEBOARD_FAB2_LIB.BASEBOARD_FAB2(SCH_1):GND   I165 @BASEBOARD_FAB2_LIB.BASEBOARD_FAB2(SCH_1):PAGE103

R6P18 RES_0402-0.0,5%,1/16W,CHIP,G21A
     1 FM_PVCCIN_PVCCSA_CPU0_EN_LVC1 @BASEBOARD_FAB2_LIB.BASEBOARD_FAB2(SCH_1):FM_PVCCIN_PVCCSA_CPU0_EN_LVC1   I131 @BASEBOARD_FAB2_LIB.BASEBOARD_FAB2(SCH_1):PAGE201
     2 VR_PVCCIN_CPU0_VREN @BASEBOARD_FAB2_LIB.BASEBOARD_FAB2(SCH_1):VR_PVCCIN_CPU0_VREN   I131 @BASEBOARD_FAB2_LIB.BASEBOARD_FAB2(SCH_1):PAGE201

R6P19 RES_0402-1.0,1%,1/16W,CHIP,G21A
     1 VR_PVCCIN_CPU0_PH3_VCIN @BASEBOARD_FAB2_LIB.BASEBOARD_FAB2(SCH_1):VR_PVCCIN_CPU0_PH3_VCIN    I38 @BASEBOARD_FAB2_LIB.BASEBOARD_FAB2(SCH_1):PAGE203
     2 P5V_STBY @BASEBOARD_FAB2_LIB.BASEBOARD_FAB2(SCH_1):P5V_STBY    I38 @BASEBOARD_FAB2_LIB.BASEBOARD_FAB2(SCH_1):PAGE203

R6P20 RES_0402-1.00K,1%,1/16W,CHIP,GA
     1 FM_DB1200_SMB_SA1 @BASEBOARD_FAB2_LIB.BASEBOARD_FAB2(SCH_1):FM_DB1200_SMB_SA1    I81 @BASEBOARD_FAB2_LIB.BASEBOARD_FAB2(SCH_1):PAGE102
     2    GND @BASEBOARD_FAB2_LIB.BASEBOARD_FAB2(SCH_1):GND    I81 @BASEBOARD_FAB2_LIB.BASEBOARD_FAB2(SCH_1):PAGE102

R6P21 RES_0402-1.00K,1%,1/16W,CHIP,GA
     1 FM_DB1200_SMB_SA0 @BASEBOARD_FAB2_LIB.BASEBOARD_FAB2(SCH_1):FM_DB1200_SMB_SA0    I80 @BASEBOARD_FAB2_LIB.BASEBOARD_FAB2(SCH_1):PAGE102
     2    GND @BASEBOARD_FAB2_LIB.BASEBOARD_FAB2(SCH_1):GND    I80 @BASEBOARD_FAB2_LIB.BASEBOARD_FAB2(SCH_1):PAGE102

R6P22 RES_0402-4.75K,1%,1/16W,EMPTY,A
     1 FM_HBW_BYPASS_LOWBW_N @BASEBOARD_FAB2_LIB.BASEBOARD_FAB2(SCH_1):FM_HBW_BYPASS_LOWBW_N    I47 @BASEBOARD_FAB2_LIB.BASEBOARD_FAB2(SCH_1):PAGE102
     2    GND @BASEBOARD_FAB2_LIB.BASEBOARD_FAB2(SCH_1):GND    I47 @BASEBOARD_FAB2_LIB.BASEBOARD_FAB2(SCH_1):PAGE102

R6P23 RES_0402-4.75K,1%,1/16W,EMPTY,A
     1 FM_100M_N @BASEBOARD_FAB2_LIB.BASEBOARD_FAB2(SCH_1):FM_100M_N    I46 @BASEBOARD_FAB2_LIB.BASEBOARD_FAB2(SCH_1):PAGE102
     2    GND @BASEBOARD_FAB2_LIB.BASEBOARD_FAB2(SCH_1):GND    I46 @BASEBOARD_FAB2_LIB.BASEBOARD_FAB2(SCH_1):PAGE102

R6P25 RES_0603-2.2,1.0%,1/10W,CHIP,GA
     1 P3V3_DB1200 @BASEBOARD_FAB2_LIB.BASEBOARD_FAB2(SCH_1):P3V3_DB1200    I26 @BASEBOARD_FAB2_LIB.BASEBOARD_FAB2(SCH_1):PAGE102
     2 P3V3_DB1200_R @BASEBOARD_FAB2_LIB.BASEBOARD_FAB2(SCH_1):P3V3_DB1200_R    I26 @BASEBOARD_FAB2_LIB.BASEBOARD_FAB2(SCH_1):PAGE102

R6P27 RES_0402-4.02K,1%,1/16W,CHIP,GA
     1 VR_PVCCIN_CPU0_XADDR2 @BASEBOARD_FAB2_LIB.BASEBOARD_FAB2(SCH_1):VR_PVCCIN_CPU0_XADDR2   I120 @BASEBOARD_FAB2_LIB.BASEBOARD_FAB2(SCH_1):PAGE201
     2    GND @BASEBOARD_FAB2_LIB.BASEBOARD_FAB2(SCH_1):GND   I120 @BASEBOARD_FAB2_LIB.BASEBOARD_FAB2(SCH_1):PAGE201

R6P28 RES_0402-4.02K,1%,1/16W,CHIP,GA
     1 VR_PVCCIN_CPU0_XADDR1 @BASEBOARD_FAB2_LIB.BASEBOARD_FAB2(SCH_1):VR_PVCCIN_CPU0_XADDR1   I121 @BASEBOARD_FAB2_LIB.BASEBOARD_FAB2(SCH_1):PAGE201
     2    GND @BASEBOARD_FAB2_LIB.BASEBOARD_FAB2(SCH_1):GND   I121 @BASEBOARD_FAB2_LIB.BASEBOARD_FAB2(SCH_1):PAGE201

R6P29 RES_0402-0.0,5%,1/16W,CHIP,G21A
     1 VR_PVCCIN_CPU0_VD12 @BASEBOARD_FAB2_LIB.BASEBOARD_FAB2(SCH_1):VR_PVCCIN_CPU0_VD12   I154 @BASEBOARD_FAB2_LIB.BASEBOARD_FAB2(SCH_1):PAGE201
     2 VR_PVSA_CPU0_BIREF1 @BASEBOARD_FAB2_LIB.BASEBOARD_FAB2(SCH_1):VR_PVSA_CPU0_BIREF1   I154 @BASEBOARD_FAB2_LIB.BASEBOARD_FAB2(SCH_1):PAGE201

R6P30 RES_0402-0.0,5%,1/16W,CHIP,G21A
     1 VR_PVCCIN_CPU0_VD12 @BASEBOARD_FAB2_LIB.BASEBOARD_FAB2(SCH_1):VR_PVCCIN_CPU0_VD12   I149 @BASEBOARD_FAB2_LIB.BASEBOARD_FAB2(SCH_1):PAGE201
     2 VR_PVCCIN_CPU0_AIREF5 @BASEBOARD_FAB2_LIB.BASEBOARD_FAB2(SCH_1):VR_PVCCIN_CPU0_AIREF5   I149 @BASEBOARD_FAB2_LIB.BASEBOARD_FAB2(SCH_1):PAGE201

R6P32 RES_0402-2.0K,1%,1/16W,EMPTY,GA
     1 P3V3_STBY @BASEBOARD_FAB2_LIB.BASEBOARD_FAB2(SCH_1):P3V3_STBY   I102 @BASEBOARD_FAB2_LIB.BASEBOARD_FAB2(SCH_1):PAGE201
     2 SMB_VR_STBY_LVC3_SDA @BASEBOARD_FAB2_LIB.BASEBOARD_FAB2(SCH_1):SMB_VR_STBY_LVC3_SDA   I102 @BASEBOARD_FAB2_LIB.BASEBOARD_FAB2(SCH_1):PAGE201

R6P33 RES_0402-110,1%,1/16W,EMPTY,G2A
     1 PVCCIO_CPU1 @BASEBOARD_FAB2_LIB.BASEBOARD_FAB2(SCH_1):PVCCIO_CPU1    I30 @BASEBOARD_FAB2_LIB.BASEBOARD_FAB2(SCH_1):PAGE213
     2 SVID_CLK0_CPU1_R @BASEBOARD_FAB2_LIB.BASEBOARD_FAB2(SCH_1):SVID_CLK0_CPU1_R    I30 @BASEBOARD_FAB2_LIB.BASEBOARD_FAB2(SCH_1):PAGE213

R6P34 RES_0402-0.0,5%,1/16W,CHIP,G21A
     1 VR_PVCCIN_CPU0_VD12 @BASEBOARD_FAB2_LIB.BASEBOARD_FAB2(SCH_1):VR_PVCCIN_CPU0_VD12   I148 @BASEBOARD_FAB2_LIB.BASEBOARD_FAB2(SCH_1):PAGE201
     2 VR_PVCCIN_CPU0_AIREF4 @BASEBOARD_FAB2_LIB.BASEBOARD_FAB2(SCH_1):VR_PVCCIN_CPU0_AIREF4   I148 @BASEBOARD_FAB2_LIB.BASEBOARD_FAB2(SCH_1):PAGE201

R6P35 RES_0402-100.0,1%,1/16W,EMPTY,A
     1 PVCCIO_CPU1 @BASEBOARD_FAB2_LIB.BASEBOARD_FAB2(SCH_1):PVCCIO_CPU1    I27 @BASEBOARD_FAB2_LIB.BASEBOARD_FAB2(SCH_1):PAGE213
     2 SVID_DIO0_CPU1_R @BASEBOARD_FAB2_LIB.BASEBOARD_FAB2(SCH_1):SVID_DIO0_CPU1_R    I27 @BASEBOARD_FAB2_LIB.BASEBOARD_FAB2(SCH_1):PAGE213

R6P37 RES_0402-2.0K,1%,1/16W,EMPTY,GA
     1 P3V3_STBY @BASEBOARD_FAB2_LIB.BASEBOARD_FAB2(SCH_1):P3V3_STBY   I103 @BASEBOARD_FAB2_LIB.BASEBOARD_FAB2(SCH_1):PAGE201
     2 SMB_VR_STBY_LVC3_SCL @BASEBOARD_FAB2_LIB.BASEBOARD_FAB2(SCH_1):SMB_VR_STBY_LVC3_SCL   I103 @BASEBOARD_FAB2_LIB.BASEBOARD_FAB2(SCH_1):PAGE201

R6P38 RES_0402-0.0,5%,1/16W,CHIP,G21A
     1 VR_PVCCIN_CPU0_VD12 @BASEBOARD_FAB2_LIB.BASEBOARD_FAB2(SCH_1):VR_PVCCIN_CPU0_VD12   I147 @BASEBOARD_FAB2_LIB.BASEBOARD_FAB2(SCH_1):PAGE201
     2 VR_PVCCIN_CPU0_AIREF3 @BASEBOARD_FAB2_LIB.BASEBOARD_FAB2(SCH_1):VR_PVCCIN_CPU0_AIREF3   I147 @BASEBOARD_FAB2_LIB.BASEBOARD_FAB2(SCH_1):PAGE201

R6P39 RES_0402-4.75K,1%,1/16W,CHIP,GA
     1 P3V3_STBY @BASEBOARD_FAB2_LIB.BASEBOARD_FAB2(SCH_1):P3V3_STBY   I181 @BASEBOARD_FAB2_LIB.BASEBOARD_FAB2(SCH_1):PAGE55
     2 FM_CPU1_SKTOCC_LVT3_N @BASEBOARD_FAB2_LIB.BASEBOARD_FAB2(SCH_1):FM_CPU1_SKTOCC_LVT3_N   I181 @BASEBOARD_FAB2_LIB.BASEBOARD_FAB2(SCH_1):PAGE55

R6P40 RES_0402-100.0K,1%,1/16W,EMPTYA
     1 P3V3_STBY @BASEBOARD_FAB2_LIB.BASEBOARD_FAB2(SCH_1):P3V3_STBY    I91 @BASEBOARD_FAB2_LIB.BASEBOARD_FAB2(SCH_1):PAGE213
     2 VR_PVCCIO_CPU1_EN @BASEBOARD_FAB2_LIB.BASEBOARD_FAB2(SCH_1):VR_PVCCIO_CPU1_EN    I91 @BASEBOARD_FAB2_LIB.BASEBOARD_FAB2(SCH_1):PAGE213

R6P41 RES_0402-0.0,5%,1/16W,CHIP,G21A
     1 FM_PVCCIO_CPU1_EN @BASEBOARD_FAB2_LIB.BASEBOARD_FAB2(SCH_1):FM_PVCCIO_CPU1_EN    I90 @BASEBOARD_FAB2_LIB.BASEBOARD_FAB2(SCH_1):PAGE213
     2 VR_PVCCIO_CPU1_EN @BASEBOARD_FAB2_LIB.BASEBOARD_FAB2(SCH_1):VR_PVCCIO_CPU1_EN    I90 @BASEBOARD_FAB2_LIB.BASEBOARD_FAB2(SCH_1):PAGE213

R6P42 RES_0402-0.0,5%,1/16W,CHIP,G21A
     1 VR_PVCCIN_CPU0_VD12 @BASEBOARD_FAB2_LIB.BASEBOARD_FAB2(SCH_1):VR_PVCCIN_CPU0_VD12   I139 @BASEBOARD_FAB2_LIB.BASEBOARD_FAB2(SCH_1):PAGE201
     2 VR_PVCCIN_CPU0_AIREF2 @BASEBOARD_FAB2_LIB.BASEBOARD_FAB2(SCH_1):VR_PVCCIN_CPU0_AIREF2   I139 @BASEBOARD_FAB2_LIB.BASEBOARD_FAB2(SCH_1):PAGE201

R6P43 RES_0402-0.0,5%,1/16W,CHIP,G21A
     1 VR_PVCCIN_CPU0_VD12 @BASEBOARD_FAB2_LIB.BASEBOARD_FAB2(SCH_1):VR_PVCCIN_CPU0_VD12   I150 @BASEBOARD_FAB2_LIB.BASEBOARD_FAB2(SCH_1):PAGE201
     2 VR_PVCCIN_CPU0_AIREF1 @BASEBOARD_FAB2_LIB.BASEBOARD_FAB2(SCH_1):VR_PVCCIN_CPU0_AIREF1   I150 @BASEBOARD_FAB2_LIB.BASEBOARD_FAB2(SCH_1):PAGE201

R6P45 RES_0402-33.2,1%,1/16W,CHIP,G2A
     1 IRQ_PVCCIN_CPU0_VRHOT_LVC3_R_N @BASEBOARD_FAB2_LIB.BASEBOARD_FAB2(SCH_1):IRQ_PVCCIN_CPU0_VRHOT_LVC3_R_N   I128 @BASEBOARD_FAB2_LIB.BASEBOARD_FAB2(SCH_1):PAGE201
     2 IRQ_PVCCIN_CPU0_VRHOT_LVC3_N @BASEBOARD_FAB2_LIB.BASEBOARD_FAB2(SCH_1):IRQ_PVCCIN_CPU0_VRHOT_LVC3_N   I128 @BASEBOARD_FAB2_LIB.BASEBOARD_FAB2(SCH_1):PAGE201

R6P46 RES_0402-100.0,1%,1/16W,CHIP,GA
     1 PVCCIO_CPU0 @BASEBOARD_FAB2_LIB.BASEBOARD_FAB2(SCH_1):PVCCIO_CPU0    I49 @BASEBOARD_FAB2_LIB.BASEBOARD_FAB2(SCH_1):PAGE112
     2 XDP_CPU_MBP1_N @BASEBOARD_FAB2_LIB.BASEBOARD_FAB2(SCH_1):XDP_CPU_MBP1_N    I49 @BASEBOARD_FAB2_LIB.BASEBOARD_FAB2(SCH_1):PAGE112

R6P47 RES_0402-1.0,1%,1/16W,CHIP,G21A
     1 VR_PVCCIN_CPU0_PH5_VCIN @BASEBOARD_FAB2_LIB.BASEBOARD_FAB2(SCH_1):VR_PVCCIN_CPU0_PH5_VCIN    I33 @BASEBOARD_FAB2_LIB.BASEBOARD_FAB2(SCH_1):PAGE204
     2 P5V_STBY @BASEBOARD_FAB2_LIB.BASEBOARD_FAB2(SCH_1):P5V_STBY    I33 @BASEBOARD_FAB2_LIB.BASEBOARD_FAB2(SCH_1):PAGE204

R6P48 RES_0402-4.75K,1%,1/16W,CHIP,GA
     1   P3V3 @BASEBOARD_FAB2_LIB.BASEBOARD_FAB2(SCH_1):P3V3    I91 @BASEBOARD_FAB2_LIB.BASEBOARD_FAB2(SCH_1):PAGE102
     2 FM_DB1200ZL_BCLKS_EN_N @BASEBOARD_FAB2_LIB.BASEBOARD_FAB2(SCH_1):FM_DB1200ZL_BCLKS_EN_N    I91 @BASEBOARD_FAB2_LIB.BASEBOARD_FAB2(SCH_1):PAGE102

R6P49 RES_0402-2.26K,1.0%,1/16W,EMPTA
     1 P3V3_STBY @BASEBOARD_FAB2_LIB.BASEBOARD_FAB2(SCH_1):P3V3_STBY    I14 @BASEBOARD_FAB2_LIB.BASEBOARD_FAB2(SCH_1):PAGE213
     2 PU_VR_PVCCIO_CPU1_FAULT1 @BASEBOARD_FAB2_LIB.BASEBOARD_FAB2(SCH_1):PU_VR_PVCCIO_CPU1_FAULT1    I14 @BASEBOARD_FAB2_LIB.BASEBOARD_FAB2(SCH_1):PAGE213

R6R2 RES_0402-1.0,1%,1/16W,CHIP,G21A
     1 VR_PVCCIN_CPU0_PH1_VCIN @BASEBOARD_FAB2_LIB.BASEBOARD_FAB2(SCH_1):VR_PVCCIN_CPU0_PH1_VCIN    I33 @BASEBOARD_FAB2_LIB.BASEBOARD_FAB2(SCH_1):PAGE202
     2 P5V_STBY @BASEBOARD_FAB2_LIB.BASEBOARD_FAB2(SCH_1):P5V_STBY    I33 @BASEBOARD_FAB2_LIB.BASEBOARD_FAB2(SCH_1):PAGE202

R6R5 RES_0402-1.0,1%,1/16W,CHIP,G21A
     1 VR_PVCCIO_CPU1_PH1_VCIN @BASEBOARD_FAB2_LIB.BASEBOARD_FAB2(SCH_1):VR_PVCCIO_CPU1_PH1_VCIN    I71 @BASEBOARD_FAB2_LIB.BASEBOARD_FAB2(SCH_1):PAGE214
     2 P5V_STBY @BASEBOARD_FAB2_LIB.BASEBOARD_FAB2(SCH_1):P5V_STBY    I71 @BASEBOARD_FAB2_LIB.BASEBOARD_FAB2(SCH_1):PAGE214

R6R6 RES_0402-1.0,1%,1/16W,CHIP,G21A
     1 VR_PVCCIN_CPU0_PH2_VCIN @BASEBOARD_FAB2_LIB.BASEBOARD_FAB2(SCH_1):VR_PVCCIN_CPU0_PH2_VCIN    I39 @BASEBOARD_FAB2_LIB.BASEBOARD_FAB2(SCH_1):PAGE202
     2 P5V_STBY @BASEBOARD_FAB2_LIB.BASEBOARD_FAB2(SCH_1):P5V_STBY    I39 @BASEBOARD_FAB2_LIB.BASEBOARD_FAB2(SCH_1):PAGE202

R6T1 RES_0402-240,1.0%,1/16W,CHIP,GA
     1 PVCCIO_CPU1 @BASEBOARD_FAB2_LIB.BASEBOARD_FAB2(SCH_1):PVCCIO_CPU1    I70 @BASEBOARD_FAB2_LIB.BASEBOARD_FAB2(SCH_1):PAGE99
     2 SMB_DDR_GHJ_SDA_G @BASEBOARD_FAB2_LIB.BASEBOARD_FAB2(SCH_1):SMB_DDR_GHJ_SDA_G    I70 @BASEBOARD_FAB2_LIB.BASEBOARD_FAB2(SCH_1):PAGE99

R6T2 RES_0402-240,1.0%,1/16W,CHIP,GA
     1 PVCCIO_CPU1 @BASEBOARD_FAB2_LIB.BASEBOARD_FAB2(SCH_1):PVCCIO_CPU1    I72 @BASEBOARD_FAB2_LIB.BASEBOARD_FAB2(SCH_1):PAGE99
     2 SMB_DDR_GHJ_SCL_G @BASEBOARD_FAB2_LIB.BASEBOARD_FAB2(SCH_1):SMB_DDR_GHJ_SCL_G    I72 @BASEBOARD_FAB2_LIB.BASEBOARD_FAB2(SCH_1):PAGE99

R6T3 RES_0402-10.0,1%,1/16W,CHIP,G2A
     1 SMB_DDR_GHJ_SCL_G_R @BASEBOARD_FAB2_LIB.BASEBOARD_FAB2(SCH_1):SMB_DDR_GHJ_SCL_G_R    I92 @BASEBOARD_FAB2_LIB.BASEBOARD_FAB2(SCH_1):PAGE99
     2 SMB_DDR_GHJ_SCL_G @BASEBOARD_FAB2_LIB.BASEBOARD_FAB2(SCH_1):SMB_DDR_GHJ_SCL_G    I92 @BASEBOARD_FAB2_LIB.BASEBOARD_FAB2(SCH_1):PAGE99

R6T4 RES_0402-10.0,1%,1/16W,CHIP,G2A
     1 SMB_DDR_GHJ_SDA_G_R @BASEBOARD_FAB2_LIB.BASEBOARD_FAB2(SCH_1):SMB_DDR_GHJ_SDA_G_R   I111 @BASEBOARD_FAB2_LIB.BASEBOARD_FAB2(SCH_1):PAGE99
     2 SMB_DDR_GHJ_SDA_G @BASEBOARD_FAB2_LIB.BASEBOARD_FAB2(SCH_1):SMB_DDR_GHJ_SDA_G   I111 @BASEBOARD_FAB2_LIB.BASEBOARD_FAB2(SCH_1):PAGE99

R6T5 RES_0402-1.00K,1%,1/16W,CHIP,GA
     1 XDP_CPU_TRST_N @BASEBOARD_FAB2_LIB.BASEBOARD_FAB2(SCH_1):XDP_CPU_TRST_N    I62 @BASEBOARD_FAB2_LIB.BASEBOARD_FAB2(SCH_1):PAGE112
     2    GND @BASEBOARD_FAB2_LIB.BASEBOARD_FAB2(SCH_1):GND    I62 @BASEBOARD_FAB2_LIB.BASEBOARD_FAB2(SCH_1):PAGE112

R6T6 RES_0402-150.0,1%,1/16W,CHIP,GA
     1 PVCCIO_CPU1 @BASEBOARD_FAB2_LIB.BASEBOARD_FAB2(SCH_1):PVCCIO_CPU1    I56 @BASEBOARD_FAB2_LIB.BASEBOARD_FAB2(SCH_1):PAGE112
     2 XDP_CPU1_TDI @BASEBOARD_FAB2_LIB.BASEBOARD_FAB2(SCH_1):XDP_CPU1_TDI    I56 @BASEBOARD_FAB2_LIB.BASEBOARD_FAB2(SCH_1):PAGE112

R6T7 RES_0402-150.0,1%,1/16W,CHIP,GA
     1 PVCCIO_CPU1 @BASEBOARD_FAB2_LIB.BASEBOARD_FAB2(SCH_1):PVCCIO_CPU1    I55 @BASEBOARD_FAB2_LIB.BASEBOARD_FAB2(SCH_1):PAGE112
     2 XDP_CPU1_TDO @BASEBOARD_FAB2_LIB.BASEBOARD_FAB2(SCH_1):XDP_CPU1_TDO    I55 @BASEBOARD_FAB2_LIB.BASEBOARD_FAB2(SCH_1):PAGE112

R6T8 RES_0402-100.0,1%,1/16W,CHIP,GA
     1 PVCCIO_CPU0 @BASEBOARD_FAB2_LIB.BASEBOARD_FAB2(SCH_1):PVCCIO_CPU0   I121 @BASEBOARD_FAB2_LIB.BASEBOARD_FAB2(SCH_1):PAGE112
     2 XDP_CPU_OBSFN_B0_MBP6_N @BASEBOARD_FAB2_LIB.BASEBOARD_FAB2(SCH_1):XDP_CPU_OBSFN_B0_MBP6_N   I121 @BASEBOARD_FAB2_LIB.BASEBOARD_FAB2(SCH_1):PAGE112

R6T9 RES_0402-100.0,1%,1/16W,CHIP,GA
     1 PVCCIO_CPU0 @BASEBOARD_FAB2_LIB.BASEBOARD_FAB2(SCH_1):PVCCIO_CPU0   I120 @BASEBOARD_FAB2_LIB.BASEBOARD_FAB2(SCH_1):PAGE112
     2 XDP_CPU_OBSFN_B1_MBP7_N @BASEBOARD_FAB2_LIB.BASEBOARD_FAB2(SCH_1):XDP_CPU_OBSFN_B1_MBP7_N   I120 @BASEBOARD_FAB2_LIB.BASEBOARD_FAB2(SCH_1):PAGE112

R6U3 RES_0402-1.0M,1%,1/16W,EMPTY,GA
     1   P3V3 @BASEBOARD_FAB2_LIB.BASEBOARD_FAB2(SCH_1):P3V3    I34 @BASEBOARD_FAB2_LIB.BASEBOARD_FAB2(SCH_1):PAGE229
     2 FM_PVTT_GHJ_EN_R @BASEBOARD_FAB2_LIB.BASEBOARD_FAB2(SCH_1):FM_PVTT_GHJ_EN_R    I34 @BASEBOARD_FAB2_LIB.BASEBOARD_FAB2(SCH_1):PAGE229

R6U4 RES_0402-0.0,5%,1/16W,CHIP,G21A
     1   P3V3 @BASEBOARD_FAB2_LIB.BASEBOARD_FAB2(SCH_1):P3V3    I28 @BASEBOARD_FAB2_LIB.BASEBOARD_FAB2(SCH_1):PAGE221
     2 VR_PVTT_ABC_BIAS @BASEBOARD_FAB2_LIB.BASEBOARD_FAB2(SCH_1):VR_PVTT_ABC_BIAS    I28 @BASEBOARD_FAB2_LIB.BASEBOARD_FAB2(SCH_1):PAGE221

R6U5 RES_0402-0.0,5%,1/16W,CHIP,G21A
     1 PVDDQ_ABC @BASEBOARD_FAB2_LIB.BASEBOARD_FAB2(SCH_1):PVDDQ_ABC    I32 @BASEBOARD_FAB2_LIB.BASEBOARD_FAB2(SCH_1):PAGE221
     2 VSENSE_PVDDQ_ABC_VTT @BASEBOARD_FAB2_LIB.BASEBOARD_FAB2(SCH_1):VSENSE_PVDDQ_ABC_VTT    I32 @BASEBOARD_FAB2_LIB.BASEBOARD_FAB2(SCH_1):PAGE221

R6U6 RES_0402-0.0,5%,1/16W,CHIP,G21A
     1 PVDDQ_GHJ @BASEBOARD_FAB2_LIB.BASEBOARD_FAB2(SCH_1):PVDDQ_GHJ    I39 @BASEBOARD_FAB2_LIB.BASEBOARD_FAB2(SCH_1):PAGE229
     2 VSENSE_PVDDQ_GHJ_VTT @BASEBOARD_FAB2_LIB.BASEBOARD_FAB2(SCH_1):VSENSE_PVDDQ_GHJ_VTT    I39 @BASEBOARD_FAB2_LIB.BASEBOARD_FAB2(SCH_1):PAGE229

R6U7 RES_0402-0.0,5%,1/16W,CHIP,G21A
     1   P3V3 @BASEBOARD_FAB2_LIB.BASEBOARD_FAB2(SCH_1):P3V3    I32 @BASEBOARD_FAB2_LIB.BASEBOARD_FAB2(SCH_1):PAGE229
     2 VR_PVTT_GHJ_BIAS @BASEBOARD_FAB2_LIB.BASEBOARD_FAB2(SCH_1):VR_PVTT_GHJ_BIAS    I32 @BASEBOARD_FAB2_LIB.BASEBOARD_FAB2(SCH_1):PAGE229

R6U8 RES_0402-51.1,1.0%,1/16W,CHIP,A
     1    GND @BASEBOARD_FAB2_LIB.BASEBOARD_FAB2(SCH_1):GND    I52 @BASEBOARD_FAB2_LIB.BASEBOARD_FAB2(SCH_1):PAGE229
     2 PVTT_GHJ @BASEBOARD_FAB2_LIB.BASEBOARD_FAB2(SCH_1):PVTT_GHJ    I52 @BASEBOARD_FAB2_LIB.BASEBOARD_FAB2(SCH_1):PAGE229

R6U13 RES_0402-20.0,1%,1/16W,CHIP,G2A
     1 SMB_DDR_GHJ_VPP_SCL_R @BASEBOARD_FAB2_LIB.BASEBOARD_FAB2(SCH_1):SMB_DDR_GHJ_VPP_SCL_R    I42 @BASEBOARD_FAB2_LIB.BASEBOARD_FAB2(SCH_1):PAGE99
     2 SMB_DDR_GHJ_VPP_SCL @BASEBOARD_FAB2_LIB.BASEBOARD_FAB2(SCH_1):SMB_DDR_GHJ_VPP_SCL    I42 @BASEBOARD_FAB2_LIB.BASEBOARD_FAB2(SCH_1):PAGE99

R6U14 RES_0402-20.0,1%,1/16W,CHIP,G2A
     1 SMB_DDR_GHJ_VPP_SDA_R @BASEBOARD_FAB2_LIB.BASEBOARD_FAB2(SCH_1):SMB_DDR_GHJ_VPP_SDA_R    I43 @BASEBOARD_FAB2_LIB.BASEBOARD_FAB2(SCH_1):PAGE99
     2 SMB_DDR_GHJ_VPP_SDA @BASEBOARD_FAB2_LIB.BASEBOARD_FAB2(SCH_1):SMB_DDR_GHJ_VPP_SDA    I43 @BASEBOARD_FAB2_LIB.BASEBOARD_FAB2(SCH_1):PAGE99

R6U15 RES_0402-1.0M,1%,1/16W,EMPTY,GA
     1   P3V3 @BASEBOARD_FAB2_LIB.BASEBOARD_FAB2(SCH_1):P3V3    I37 @BASEBOARD_FAB2_LIB.BASEBOARD_FAB2(SCH_1):PAGE221
     2 FM_PVTT_ABC_EN_R @BASEBOARD_FAB2_LIB.BASEBOARD_FAB2(SCH_1):FM_PVTT_ABC_EN_R    I37 @BASEBOARD_FAB2_LIB.BASEBOARD_FAB2(SCH_1):PAGE221

R6U16 RES_0402-51.1,1.0%,1/16W,CHIP,A
     1    GND @BASEBOARD_FAB2_LIB.BASEBOARD_FAB2(SCH_1):GND    I55 @BASEBOARD_FAB2_LIB.BASEBOARD_FAB2(SCH_1):PAGE221
     2 PVTT_ABC @BASEBOARD_FAB2_LIB.BASEBOARD_FAB2(SCH_1):PVTT_ABC    I55 @BASEBOARD_FAB2_LIB.BASEBOARD_FAB2(SCH_1):PAGE221

R6U17 RES_0402-665,1.0%,1/16W,CHIP,GA
     1 PVPP_GHJ @BASEBOARD_FAB2_LIB.BASEBOARD_FAB2(SCH_1):PVPP_GHJ   I106 @BASEBOARD_FAB2_LIB.BASEBOARD_FAB2(SCH_1):PAGE99
     2 SMB_DDR_GHJ_VPP_SCL_R @BASEBOARD_FAB2_LIB.BASEBOARD_FAB2(SCH_1):SMB_DDR_GHJ_VPP_SCL_R   I106 @BASEBOARD_FAB2_LIB.BASEBOARD_FAB2(SCH_1):PAGE99

R6U18 RES_0402-665,1.0%,1/16W,CHIP,GA
     1 PVPP_GHJ @BASEBOARD_FAB2_LIB.BASEBOARD_FAB2(SCH_1):PVPP_GHJ   I104 @BASEBOARD_FAB2_LIB.BASEBOARD_FAB2(SCH_1):PAGE99
     2 SMB_DDR_GHJ_VPP_SDA_R @BASEBOARD_FAB2_LIB.BASEBOARD_FAB2(SCH_1):SMB_DDR_GHJ_VPP_SDA_R   I104 @BASEBOARD_FAB2_LIB.BASEBOARD_FAB2(SCH_1):PAGE99

R6W1 RES_0402-100.0K,1%,1/16W,CHIP,B
     1 P3V3_STBY @BASEBOARD_FAB2_LIB.BASEBOARD_FAB2(SCH_1):P3V3_STBY   I229 @BASEBOARD_FAB2_LIB.BASEBOARD_FAB2(SCH_1):PAGE200
     2 BMC_UV_HIGH_SET @BASEBOARD_FAB2_LIB.BASEBOARD_FAB2(SCH_1):BMC_UV_HIGH_SET   I229 @BASEBOARD_FAB2_LIB.BASEBOARD_FAB2(SCH_1):PAGE200

R6W2 RES_0402-10.0K,1%,1/16W,CHIP,GA
     1 BMC_UV_HIGH_SET @BASEBOARD_FAB2_LIB.BASEBOARD_FAB2(SCH_1):BMC_UV_HIGH_SET   I230 @BASEBOARD_FAB2_LIB.BASEBOARD_FAB2(SCH_1):PAGE200
     2    GND @BASEBOARD_FAB2_LIB.BASEBOARD_FAB2(SCH_1):GND   I230 @BASEBOARD_FAB2_LIB.BASEBOARD_FAB2(SCH_1):PAGE200

R6W3 232KR2F-2-GP_SMD-RG1-232KR2F-2A
     1 UV_HIGH_SET_N @BASEBOARD_FAB2_LIB.BASEBOARD_FAB2(SCH_1):UV_HIGH_SET_N   I239 @BASEBOARD_FAB2_LIB.BASEBOARD_FAB2(SCH_1):PAGE200
     2 A_P12V_STBY_FP_TRIGGER @BASEBOARD_FAB2_LIB.BASEBOARD_FAB2(SCH_1):A_P12V_STBY_FP_TRIGGER   I239 @BASEBOARD_FAB2_LIB.BASEBOARD_FAB2(SCH_1):PAGE200

R6W4 RES_0402-4.75K,1%,1/16W,EMPTY,A
     1 P3V3_STBY @BASEBOARD_FAB2_LIB.BASEBOARD_FAB2(SCH_1):P3V3_STBY     I5 @BASEBOARD_FAB2_LIB.BASEBOARD_FAB2(SCH_1):PAGE247
     2 PCA9555_A2 @BASEBOARD_FAB2_LIB.BASEBOARD_FAB2(SCH_1):PCA9555_A2     I5 @BASEBOARD_FAB2_LIB.BASEBOARD_FAB2(SCH_1):PAGE247

R6W5 RES_0402-4.75K,1%,1/16W,EMPTY,A
     1 P3V3_STBY @BASEBOARD_FAB2_LIB.BASEBOARD_FAB2(SCH_1):P3V3_STBY    I10 @BASEBOARD_FAB2_LIB.BASEBOARD_FAB2(SCH_1):PAGE247
     2 PCA9555_A1 @BASEBOARD_FAB2_LIB.BASEBOARD_FAB2(SCH_1):PCA9555_A1    I10 @BASEBOARD_FAB2_LIB.BASEBOARD_FAB2(SCH_1):PAGE247

R6W6 RES_0402-4.75K,1%,1/16W,EMPTY,A
     1 P3V3_STBY @BASEBOARD_FAB2_LIB.BASEBOARD_FAB2(SCH_1):P3V3_STBY    I11 @BASEBOARD_FAB2_LIB.BASEBOARD_FAB2(SCH_1):PAGE247
     2 PCA9555_A0 @BASEBOARD_FAB2_LIB.BASEBOARD_FAB2(SCH_1):PCA9555_A0    I11 @BASEBOARD_FAB2_LIB.BASEBOARD_FAB2(SCH_1):PAGE247

R6W7 RES_0402-4.75K,1%,1/16W,CHIP,GA
     1 PCA9555_A2 @BASEBOARD_FAB2_LIB.BASEBOARD_FAB2(SCH_1):PCA9555_A2     I3 @BASEBOARD_FAB2_LIB.BASEBOARD_FAB2(SCH_1):PAGE247
     2    GND @BASEBOARD_FAB2_LIB.BASEBOARD_FAB2(SCH_1):GND     I3 @BASEBOARD_FAB2_LIB.BASEBOARD_FAB2(SCH_1):PAGE247

R6W8 RES_0402-4.75K,1%,1/16W,CHIP,GA
     1 PCA9555_A1 @BASEBOARD_FAB2_LIB.BASEBOARD_FAB2(SCH_1):PCA9555_A1     I8 @BASEBOARD_FAB2_LIB.BASEBOARD_FAB2(SCH_1):PAGE247
     2    GND @BASEBOARD_FAB2_LIB.BASEBOARD_FAB2(SCH_1):GND     I8 @BASEBOARD_FAB2_LIB.BASEBOARD_FAB2(SCH_1):PAGE247

R6W9 RES_0402-4.75K,1%,1/16W,CHIP,GA
     1 PCA9555_A0 @BASEBOARD_FAB2_LIB.BASEBOARD_FAB2(SCH_1):PCA9555_A0     I9 @BASEBOARD_FAB2_LIB.BASEBOARD_FAB2(SCH_1):PAGE247
     2    GND @BASEBOARD_FAB2_LIB.BASEBOARD_FAB2(SCH_1):GND     I9 @BASEBOARD_FAB2_LIB.BASEBOARD_FAB2(SCH_1):PAGE247

R6W10 RES_0402-4.75K,1%,1/16W,CHIP,GA
     1 P3V3_STBY @BASEBOARD_FAB2_LIB.BASEBOARD_FAB2(SCH_1):P3V3_STBY     I1 @BASEBOARD_FAB2_LIB.BASEBOARD_FAB2(SCH_1):PAGE247
     2 PCA9555_INT_N @BASEBOARD_FAB2_LIB.BASEBOARD_FAB2(SCH_1):PCA9555_INT_N     I1 @BASEBOARD_FAB2_LIB.BASEBOARD_FAB2(SCH_1):PAGE247

R6W11 RES_0402-4.75K,1%,1/16W,EMPTY,A
     1 P3V3_STBY @BASEBOARD_FAB2_LIB.BASEBOARD_FAB2(SCH_1):P3V3_STBY    I67 @BASEBOARD_FAB2_LIB.BASEBOARD_FAB2(SCH_1):PAGE247
     2 SMB_IPMB_3V3AUX_SCL @BASEBOARD_FAB2_LIB.BASEBOARD_FAB2(SCH_1):SMB_IPMB_3V3AUX_SCL    I67 @BASEBOARD_FAB2_LIB.BASEBOARD_FAB2(SCH_1):PAGE247

R6W12 RES_0402-4.75K,1%,1/16W,EMPTY,A
     1 P3V3_STBY @BASEBOARD_FAB2_LIB.BASEBOARD_FAB2(SCH_1):P3V3_STBY    I68 @BASEBOARD_FAB2_LIB.BASEBOARD_FAB2(SCH_1):PAGE247
     2 SMB_IPMB_3V3AUX_SDA @BASEBOARD_FAB2_LIB.BASEBOARD_FAB2(SCH_1):SMB_IPMB_3V3AUX_SDA    I68 @BASEBOARD_FAB2_LIB.BASEBOARD_FAB2(SCH_1):PAGE247

R6W13 RES_0402-15.0K,1%,1/16W,CHIP,GA
     1 P5V_STBY @BASEBOARD_FAB2_LIB.BASEBOARD_FAB2(SCH_1):P5V_STBY    I34 @BASEBOARD_FAB2_LIB.BASEBOARD_FAB2(SCH_1):PAGE168
     2 UART_SELECT_Q @BASEBOARD_FAB2_LIB.BASEBOARD_FAB2(SCH_1):UART_SELECT_Q    I34 @BASEBOARD_FAB2_LIB.BASEBOARD_FAB2(SCH_1):PAGE168

R6W14 RES_0402-5.11K,1%,1/16W,CHIP,GA
     1 UART_SELECT_Q @BASEBOARD_FAB2_LIB.BASEBOARD_FAB2(SCH_1):UART_SELECT_Q    I33 @BASEBOARD_FAB2_LIB.BASEBOARD_FAB2(SCH_1):PAGE168
     2    GND @BASEBOARD_FAB2_LIB.BASEBOARD_FAB2(SCH_1):GND    I33 @BASEBOARD_FAB2_LIB.BASEBOARD_FAB2(SCH_1):PAGE168

R6W15 RES_0402-10.0K,1%,1/16W,CHIP,GA
     1 P3V3_STBY @BASEBOARD_FAB2_LIB.BASEBOARD_FAB2(SCH_1):P3V3_STBY    I40 @BASEBOARD_FAB2_LIB.BASEBOARD_FAB2(SCH_1):PAGE168
     2 FM_UART_SEL_N @BASEBOARD_FAB2_LIB.BASEBOARD_FAB2(SCH_1):FM_UART_SEL_N    I40 @BASEBOARD_FAB2_LIB.BASEBOARD_FAB2(SCH_1):PAGE168

R6W16 RES_0402-10.0K,1%,1/16W,CHIP,GA
     1 P3V3_STBY @BASEBOARD_FAB2_LIB.BASEBOARD_FAB2(SCH_1):P3V3_STBY    I39 @BASEBOARD_FAB2_LIB.BASEBOARD_FAB2(SCH_1):PAGE168
     2 FM_SOL_UART_CH_SEL @BASEBOARD_FAB2_LIB.BASEBOARD_FAB2(SCH_1):FM_SOL_UART_CH_SEL    I39 @BASEBOARD_FAB2_LIB.BASEBOARD_FAB2(SCH_1):PAGE168

R6W17 RES_0402-0.0,5%,1/16W,CHIP,G21A
     1 SMB_IPMB_3V3AUX_SCL @BASEBOARD_FAB2_LIB.BASEBOARD_FAB2(SCH_1):SMB_IPMB_3V3AUX_SCL    I89 @BASEBOARD_FAB2_LIB.BASEBOARD_FAB2(SCH_1):PAGE144
     2 SMB_IPMB_3V3AUX_SCL_R @BASEBOARD_FAB2_LIB.BASEBOARD_FAB2(SCH_1):SMB_IPMB_3V3AUX_SCL_R    I89 @BASEBOARD_FAB2_LIB.BASEBOARD_FAB2(SCH_1):PAGE144

R6W18 RES_0402-0.0,5%,1/16W,CHIP,G21A
     1 SMB_IPMB_3V3AUX_SDA @BASEBOARD_FAB2_LIB.BASEBOARD_FAB2(SCH_1):SMB_IPMB_3V3AUX_SDA    I90 @BASEBOARD_FAB2_LIB.BASEBOARD_FAB2(SCH_1):PAGE144
     2 SMB_IPMB_3V3AUX_SDA_R @BASEBOARD_FAB2_LIB.BASEBOARD_FAB2(SCH_1):SMB_IPMB_3V3AUX_SDA_R    I90 @BASEBOARD_FAB2_LIB.BASEBOARD_FAB2(SCH_1):PAGE144

R6W19 RES_0402-0.0,5%,1/16W,CHIP,G21A
     1 SPA_5V_SIN_SW @BASEBOARD_FAB2_LIB.BASEBOARD_FAB2(SCH_1):SPA_5V_SIN_SW   I196 @BASEBOARD_FAB2_LIB.BASEBOARD_FAB2(SCH_1):PAGE155
     2 SPA_SIN_SW_R @BASEBOARD_FAB2_LIB.BASEBOARD_FAB2(SCH_1):SPA_SIN_SW_R   I196 @BASEBOARD_FAB2_LIB.BASEBOARD_FAB2(SCH_1):PAGE155

R6W20 RES_0402-20.0,1%,1/16W,CHIP,G2A
     1 SMB_HOST_STBY_LVC3_SDA_R3 @BASEBOARD_FAB2_LIB.BASEBOARD_FAB2(SCH_1):SMB_HOST_STBY_LVC3_SDA_R3    I87 @BASEBOARD_FAB2_LIB.BASEBOARD_FAB2(SCH_1):PAGE247
     2 SMB_HOST_STBY_LVC3_SDA @BASEBOARD_FAB2_LIB.BASEBOARD_FAB2(SCH_1):SMB_HOST_STBY_LVC3_SDA    I87 @BASEBOARD_FAB2_LIB.BASEBOARD_FAB2(SCH_1):PAGE247

R6W21 RES_0402-1.00K,1%,1/16W,CHIP,GA
     1 P3V3_STBY @BASEBOARD_FAB2_LIB.BASEBOARD_FAB2(SCH_1):P3V3_STBY    I90 @BASEBOARD_FAB2_LIB.BASEBOARD_FAB2(SCH_1):PAGE247
     2 PU_ID_EEPROM_A2 @BASEBOARD_FAB2_LIB.BASEBOARD_FAB2(SCH_1):PU_ID_EEPROM_A2    I90 @BASEBOARD_FAB2_LIB.BASEBOARD_FAB2(SCH_1):PAGE247

R6W22 RES_0402-20.0,1%,1/16W,CHIP,G2A
     1 SMB_HOST_STBY_LVC3_SCL @BASEBOARD_FAB2_LIB.BASEBOARD_FAB2(SCH_1):SMB_HOST_STBY_LVC3_SCL    I94 @BASEBOARD_FAB2_LIB.BASEBOARD_FAB2(SCH_1):PAGE247
     2 SMB_HOST_STBY_LVC3_SCL_R3 @BASEBOARD_FAB2_LIB.BASEBOARD_FAB2(SCH_1):SMB_HOST_STBY_LVC3_SCL_R3    I94 @BASEBOARD_FAB2_LIB.BASEBOARD_FAB2(SCH_1):PAGE247

R6W23 RES_0402-1.00K,1%,1/16W,CHIP,GA
     1 PD_ID_EEPROM_WP @BASEBOARD_FAB2_LIB.BASEBOARD_FAB2(SCH_1):PD_ID_EEPROM_WP    I92 @BASEBOARD_FAB2_LIB.BASEBOARD_FAB2(SCH_1):PAGE247
     2    GND @BASEBOARD_FAB2_LIB.BASEBOARD_FAB2(SCH_1):GND    I92 @BASEBOARD_FAB2_LIB.BASEBOARD_FAB2(SCH_1):PAGE247

R7A7 RES_0402-10.0,1%,1/16W,CHIP,G2A
     1 VSENSE_PVDDQ_DEF_P @BASEBOARD_FAB2_LIB.BASEBOARD_FAB2(SCH_1):VSENSE_PVDDQ_DEF_P    I60 @BASEBOARD_FAB2_LIB.BASEBOARD_FAB2(SCH_1):PAGE218
     2 VR_PVDDQ_DEF_AVSP @BASEBOARD_FAB2_LIB.BASEBOARD_FAB2(SCH_1):VR_PVDDQ_DEF_AVSP    I60 @BASEBOARD_FAB2_LIB.BASEBOARD_FAB2(SCH_1):PAGE218

R7A8 RES_0402-8.06K,1%,1/16W,CHIP,GA
     1 VR_PVDDQ_DEF_XADDR2 @BASEBOARD_FAB2_LIB.BASEBOARD_FAB2(SCH_1):VR_PVDDQ_DEF_XADDR2    I37 @BASEBOARD_FAB2_LIB.BASEBOARD_FAB2(SCH_1):PAGE218
     2    GND @BASEBOARD_FAB2_LIB.BASEBOARD_FAB2(SCH_1):GND    I37 @BASEBOARD_FAB2_LIB.BASEBOARD_FAB2(SCH_1):PAGE218

R7A9 RES_0402-2.26K,1.0%,1/16W,EMPTA
     1 P3V3_STBY @BASEBOARD_FAB2_LIB.BASEBOARD_FAB2(SCH_1):P3V3_STBY    I14 @BASEBOARD_FAB2_LIB.BASEBOARD_FAB2(SCH_1):PAGE218
     2 PU_VR_PVDDQ_DEF_FAULT1 @BASEBOARD_FAB2_LIB.BASEBOARD_FAB2(SCH_1):PU_VR_PVDDQ_DEF_FAULT1    I14 @BASEBOARD_FAB2_LIB.BASEBOARD_FAB2(SCH_1):PAGE218

R7A10 RES_0402-3.16K,1%,1/16W,CHIP,GA
     1 VR_PVDDQ_DEF_XADDR1 @BASEBOARD_FAB2_LIB.BASEBOARD_FAB2(SCH_1):VR_PVDDQ_DEF_XADDR1    I40 @BASEBOARD_FAB2_LIB.BASEBOARD_FAB2(SCH_1):PAGE218
     2    GND @BASEBOARD_FAB2_LIB.BASEBOARD_FAB2(SCH_1):GND    I40 @BASEBOARD_FAB2_LIB.BASEBOARD_FAB2(SCH_1):PAGE218

R7A11 RES_0402-0.0,5%,1/16W,CHIP,G21A
     1 SVID_ALERT_PVDDQ_DEF @BASEBOARD_FAB2_LIB.BASEBOARD_FAB2(SCH_1):SVID_ALERT_PVDDQ_DEF    I15 @BASEBOARD_FAB2_LIB.BASEBOARD_FAB2(SCH_1):PAGE218
     2 SVID_ALERT1_CPU0_R_N @BASEBOARD_FAB2_LIB.BASEBOARD_FAB2(SCH_1):SVID_ALERT1_CPU0_R_N    I15 @BASEBOARD_FAB2_LIB.BASEBOARD_FAB2(SCH_1):PAGE218

R7A12 RES_0402-0.0,5%,1/16W,CHIP,G21A
     1 SVID_VDIO_PVDDQ_DEF @BASEBOARD_FAB2_LIB.BASEBOARD_FAB2(SCH_1):SVID_VDIO_PVDDQ_DEF    I25 @BASEBOARD_FAB2_LIB.BASEBOARD_FAB2(SCH_1):PAGE218
     2 SVID_DIO1_CPU0_R @BASEBOARD_FAB2_LIB.BASEBOARD_FAB2(SCH_1):SVID_DIO1_CPU0_R    I25 @BASEBOARD_FAB2_LIB.BASEBOARD_FAB2(SCH_1):PAGE218

R7A13 RES_0402-100.0,1%,1/16W,CHIP,GA
     1 VSENSE_PVNN_PCH_STBY_AVSP @BASEBOARD_FAB2_LIB.BASEBOARD_FAB2(SCH_1):VSENSE_PVNN_PCH_STBY_AVSP    I90 @BASEBOARD_FAB2_LIB.BASEBOARD_FAB2(SCH_1):PAGE236
     2 PVNN_PCH_STBY @BASEBOARD_FAB2_LIB.BASEBOARD_FAB2(SCH_1):PVNN_PCH_STBY    I90 @BASEBOARD_FAB2_LIB.BASEBOARD_FAB2(SCH_1):PAGE236

R7A14 RES_0402-10.0,1%,1/16W,CHIP,G2A
     1 VSENSE_PVNN_PCH_STBY_FPK @BASEBOARD_FAB2_LIB.BASEBOARD_FAB2(SCH_1):VSENSE_PVNN_PCH_STBY_FPK    I94 @BASEBOARD_FAB2_LIB.BASEBOARD_FAB2(SCH_1):PAGE236
     2 VSENSE_PVNN_PCH_STBY_AVSP @BASEBOARD_FAB2_LIB.BASEBOARD_FAB2(SCH_1):VSENSE_PVNN_PCH_STBY_AVSP    I94 @BASEBOARD_FAB2_LIB.BASEBOARD_FAB2(SCH_1):PAGE236

R7A15 RES_0402-2.2,5%,1/16W,EMPTY,G2A
     1 VR_PVPP_DEF_SNUB @BASEBOARD_FAB2_LIB.BASEBOARD_FAB2(SCH_1):VR_PVPP_DEF_SNUB   I218 @BASEBOARD_FAB2_LIB.BASEBOARD_FAB2(SCH_1):PAGE232
     2    GND @BASEBOARD_FAB2_LIB.BASEBOARD_FAB2(SCH_1):GND   I218 @BASEBOARD_FAB2_LIB.BASEBOARD_FAB2(SCH_1):PAGE232

R7A16 RES_0402-1.5K,1%,1/16W,CHIP,G2A
     1 VR_PVDDQ_DEF_VINSEN @BASEBOARD_FAB2_LIB.BASEBOARD_FAB2(SCH_1):VR_PVDDQ_DEF_VINSEN    I54 @BASEBOARD_FAB2_LIB.BASEBOARD_FAB2(SCH_1):PAGE218
     2    GND @BASEBOARD_FAB2_LIB.BASEBOARD_FAB2(SCH_1):GND    I54 @BASEBOARD_FAB2_LIB.BASEBOARD_FAB2(SCH_1):PAGE218

R7A17 RES_0402-150.0,1%,1/16W,CHIP,GA
     1 SVID_CLK1_CPU0_R @BASEBOARD_FAB2_LIB.BASEBOARD_FAB2(SCH_1):SVID_CLK1_CPU0_R    I48 @BASEBOARD_FAB2_LIB.BASEBOARD_FAB2(SCH_1):PAGE218
     2 SVID_CLK_PVDDQ_DEF @BASEBOARD_FAB2_LIB.BASEBOARD_FAB2(SCH_1):SVID_CLK_PVDDQ_DEF    I48 @BASEBOARD_FAB2_LIB.BASEBOARD_FAB2(SCH_1):PAGE218

R7A18 RES_0402-0.0,5%,1/16W,CHIP,G21A
     1    GND @BASEBOARD_FAB2_LIB.BASEBOARD_FAB2(SCH_1):GND    I92 @BASEBOARD_FAB2_LIB.BASEBOARD_FAB2(SCH_1):PAGE236
     2 VSENSE_PVNN_PCH_STBY_AVSN @BASEBOARD_FAB2_LIB.BASEBOARD_FAB2(SCH_1):VSENSE_PVNN_PCH_STBY_AVSN    I92 @BASEBOARD_FAB2_LIB.BASEBOARD_FAB2(SCH_1):PAGE236

R7A19 RES_0402-10.0,1%,1/16W,CHIP,G2A
     1 VSENSE_PVNN_PCH_STBY_QAT @BASEBOARD_FAB2_LIB.BASEBOARD_FAB2(SCH_1):VSENSE_PVNN_PCH_STBY_QAT    I93 @BASEBOARD_FAB2_LIB.BASEBOARD_FAB2(SCH_1):PAGE236
     2 VSENSE_PVNN_PCH_STBY_AVSP @BASEBOARD_FAB2_LIB.BASEBOARD_FAB2(SCH_1):VSENSE_PVNN_PCH_STBY_AVSP    I93 @BASEBOARD_FAB2_LIB.BASEBOARD_FAB2(SCH_1):PAGE236

R7A20 RES_0402-68.1K,1%,1/16W,EMPTY,A
     1 VR_PVDDQ_DEF_PH1_OCSET @BASEBOARD_FAB2_LIB.BASEBOARD_FAB2(SCH_1):VR_PVDDQ_DEF_PH1_OCSET   I108 @BASEBOARD_FAB2_LIB.BASEBOARD_FAB2(SCH_1):PAGE219
     2    GND @BASEBOARD_FAB2_LIB.BASEBOARD_FAB2(SCH_1):GND   I108 @BASEBOARD_FAB2_LIB.BASEBOARD_FAB2(SCH_1):PAGE219

R7A21 RES_0402-68.1K,1%,1/16W,EMPTY,A
     1 VR_PVDDQ_DEF_PH2_OCSET @BASEBOARD_FAB2_LIB.BASEBOARD_FAB2(SCH_1):VR_PVDDQ_DEF_PH2_OCSET   I110 @BASEBOARD_FAB2_LIB.BASEBOARD_FAB2(SCH_1):PAGE219
     2    GND @BASEBOARD_FAB2_LIB.BASEBOARD_FAB2(SCH_1):GND   I110 @BASEBOARD_FAB2_LIB.BASEBOARD_FAB2(SCH_1):PAGE219

R7B1 RES_0402-33.2,1%,1/16W,CHIP,G2A
     1 IRQ_PVDDQ_DEF_VRHOT_LVT3_R_N @BASEBOARD_FAB2_LIB.BASEBOARD_FAB2(SCH_1):IRQ_PVDDQ_DEF_VRHOT_LVT3_R_N    I12 @BASEBOARD_FAB2_LIB.BASEBOARD_FAB2(SCH_1):PAGE218
     2 IRQ_PVDDQ_DEF_VRHOT_LVT3_N @BASEBOARD_FAB2_LIB.BASEBOARD_FAB2(SCH_1):IRQ_PVDDQ_DEF_VRHOT_LVT3_N    I12 @BASEBOARD_FAB2_LIB.BASEBOARD_FAB2(SCH_1):PAGE218

R7B2 RES_0402-20.0,1%,1/16W,CHIP,G2A
     1 SMB_VR_SDA_VDDQ_DEF @BASEBOARD_FAB2_LIB.BASEBOARD_FAB2(SCH_1):SMB_VR_SDA_VDDQ_DEF    I24 @BASEBOARD_FAB2_LIB.BASEBOARD_FAB2(SCH_1):PAGE218
     2 SMB_VR_STBY_LVC3_SDA @BASEBOARD_FAB2_LIB.BASEBOARD_FAB2(SCH_1):SMB_VR_STBY_LVC3_SDA    I24 @BASEBOARD_FAB2_LIB.BASEBOARD_FAB2(SCH_1):PAGE218

R7B3 RES_0402-20.0,1%,1/16W,CHIP,G2A
     1 SMB_VR_SCL_VDDQ_DEF @BASEBOARD_FAB2_LIB.BASEBOARD_FAB2(SCH_1):SMB_VR_SCL_VDDQ_DEF    I21 @BASEBOARD_FAB2_LIB.BASEBOARD_FAB2(SCH_1):PAGE218
     2 SMB_VR_STBY_LVC3_SCL @BASEBOARD_FAB2_LIB.BASEBOARD_FAB2(SCH_1):SMB_VR_STBY_LVC3_SCL    I21 @BASEBOARD_FAB2_LIB.BASEBOARD_FAB2(SCH_1):PAGE218

R7B4 RES_0402-1.00K,1%,1/16W,CHIP,GA
     1 P3V3_STBY @BASEBOARD_FAB2_LIB.BASEBOARD_FAB2(SCH_1):P3V3_STBY    I17 @BASEBOARD_FAB2_LIB.BASEBOARD_FAB2(SCH_1):PAGE218
     2 IRQ_PVDDQ_DEF_VRHOT_LVT3_R_N @BASEBOARD_FAB2_LIB.BASEBOARD_FAB2(SCH_1):IRQ_PVDDQ_DEF_VRHOT_LVT3_R_N    I17 @BASEBOARD_FAB2_LIB.BASEBOARD_FAB2(SCH_1):PAGE218

R7B5 RES_0402-1.00K,1%,1/16W,CHIP,GA
     1 P3V3_STBY @BASEBOARD_FAB2_LIB.BASEBOARD_FAB2(SCH_1):P3V3_STBY    I16 @BASEBOARD_FAB2_LIB.BASEBOARD_FAB2(SCH_1):PAGE218
     2 PWRGD_PVDDQ_DEF_R @BASEBOARD_FAB2_LIB.BASEBOARD_FAB2(SCH_1):PWRGD_PVDDQ_DEF_R    I16 @BASEBOARD_FAB2_LIB.BASEBOARD_FAB2(SCH_1):PAGE218

R7B6 RES_0402-10.0K,1%,1/16W,CHIP,GA
     1 P3V3_STBY @BASEBOARD_FAB2_LIB.BASEBOARD_FAB2(SCH_1):P3V3_STBY   I295 @BASEBOARD_FAB2_LIB.BASEBOARD_FAB2(SCH_1):PAGE133
     2 FM_PCH_PRSNT_N @BASEBOARD_FAB2_LIB.BASEBOARD_FAB2(SCH_1):FM_PCH_PRSNT_N   I295 @BASEBOARD_FAB2_LIB.BASEBOARD_FAB2(SCH_1):PAGE133

R7B7 RES_0402-10.0K,1%,1/16W,EMPTY,A
     1 A_EXTCLKP @BASEBOARD_FAB2_LIB.BASEBOARD_FAB2(SCH_1):A_EXTCLKP   I230 @BASEBOARD_FAB2_LIB.BASEBOARD_FAB2(SCH_1):PAGE116
     2    GND @BASEBOARD_FAB2_LIB.BASEBOARD_FAB2(SCH_1):GND   I230 @BASEBOARD_FAB2_LIB.BASEBOARD_FAB2(SCH_1):PAGE116

R7B8 RES_0402-10.0K,1%,1/16W,EMPTY,A
     1 A_EXTCLKN @BASEBOARD_FAB2_LIB.BASEBOARD_FAB2(SCH_1):A_EXTCLKN   I229 @BASEBOARD_FAB2_LIB.BASEBOARD_FAB2(SCH_1):PAGE116
     2    GND @BASEBOARD_FAB2_LIB.BASEBOARD_FAB2(SCH_1):GND   I229 @BASEBOARD_FAB2_LIB.BASEBOARD_FAB2(SCH_1):PAGE116

R7B9 RES_0402-0.0,5%,1/16W,CHIP,G21A
     1 FM_PVPP_CPU0_EN @BASEBOARD_FAB2_LIB.BASEBOARD_FAB2(SCH_1):FM_PVPP_CPU0_EN   I307 @BASEBOARD_FAB2_LIB.BASEBOARD_FAB2(SCH_1):PAGE232
     2 FM_PVPP_PVDDQ_CPU0_EN_DEF @BASEBOARD_FAB2_LIB.BASEBOARD_FAB2(SCH_1):FM_PVPP_PVDDQ_CPU0_EN_DEF   I307 @BASEBOARD_FAB2_LIB.BASEBOARD_FAB2(SCH_1):PAGE232

R7B10 RES_0603-120.0,1%,1/10W,CHIP,GA
     1 PVPP_DEF @BASEBOARD_FAB2_LIB.BASEBOARD_FAB2(SCH_1):PVPP_DEF   I227 @BASEBOARD_FAB2_LIB.BASEBOARD_FAB2(SCH_1):PAGE232
     2    GND @BASEBOARD_FAB2_LIB.BASEBOARD_FAB2(SCH_1):GND   I227 @BASEBOARD_FAB2_LIB.BASEBOARD_FAB2(SCH_1):PAGE232

R7B11 RES_0402-0.0,5%,1/16W,CHIP,G21A
     1 PVPP_DEF @BASEBOARD_FAB2_LIB.BASEBOARD_FAB2(SCH_1):PVPP_DEF   I299 @BASEBOARD_FAB2_LIB.BASEBOARD_FAB2(SCH_1):PAGE232
     2 VSENSE_PVPP_DEF @BASEBOARD_FAB2_LIB.BASEBOARD_FAB2(SCH_1):VSENSE_PVPP_DEF   I299 @BASEBOARD_FAB2_LIB.BASEBOARD_FAB2(SCH_1):PAGE232

R7B12 RES_0402-22.1,1.0%,1/16W,CHIP,A
     1 PWRGD_PVPP_DEF_R @BASEBOARD_FAB2_LIB.BASEBOARD_FAB2(SCH_1):PWRGD_PVPP_DEF_R   I257 @BASEBOARD_FAB2_LIB.BASEBOARD_FAB2(SCH_1):PAGE232
     2 PWRGD_PVPP_DEF @BASEBOARD_FAB2_LIB.BASEBOARD_FAB2(SCH_1):PWRGD_PVPP_DEF   I257 @BASEBOARD_FAB2_LIB.BASEBOARD_FAB2(SCH_1):PAGE232

R7B13 RES_0402-6.34K,1%,1/16W,CHIP,GA
     1 VR_FB_PVPP_DEF @BASEBOARD_FAB2_LIB.BASEBOARD_FAB2(SCH_1):VR_FB_PVPP_DEF   I304 @BASEBOARD_FAB2_LIB.BASEBOARD_FAB2(SCH_1):PAGE232
     2 AGND_PVPP_DEF @BASEBOARD_FAB2_LIB.BASEBOARD_FAB2(SCH_1):AGND_PVPP_DEF   I304 @BASEBOARD_FAB2_LIB.BASEBOARD_FAB2(SCH_1):PAGE232

R7B14 RES_0402-7.87K,1.0%,1/16W,CHIPA
     1 VR_PVPP_DEF_ISET @BASEBOARD_FAB2_LIB.BASEBOARD_FAB2(SCH_1):VR_PVPP_DEF_ISET   I193 @BASEBOARD_FAB2_LIB.BASEBOARD_FAB2(SCH_1):PAGE232
     2 AGND_PVPP_DEF @BASEBOARD_FAB2_LIB.BASEBOARD_FAB2(SCH_1):AGND_PVPP_DEF   I193 @BASEBOARD_FAB2_LIB.BASEBOARD_FAB2(SCH_1):PAGE232

R7B15 RES_0402-20.0K,1%,1/16W,CHIP,GA
     1 VSENSE_PVPP_DEF @BASEBOARD_FAB2_LIB.BASEBOARD_FAB2(SCH_1):VSENSE_PVPP_DEF   I303 @BASEBOARD_FAB2_LIB.BASEBOARD_FAB2(SCH_1):PAGE232
     2 VR_FB_PVPP_DEF @BASEBOARD_FAB2_LIB.BASEBOARD_FAB2(SCH_1):VR_FB_PVPP_DEF   I303 @BASEBOARD_FAB2_LIB.BASEBOARD_FAB2(SCH_1):PAGE232

R7B16 RES_0402-7.87K,1.0%,1/16W,CHIPA
     1 VR_COMP_RC_PVPP_DEF @BASEBOARD_FAB2_LIB.BASEBOARD_FAB2(SCH_1):VR_COMP_RC_PVPP_DEF   I300 @BASEBOARD_FAB2_LIB.BASEBOARD_FAB2(SCH_1):PAGE232
     2 VR_FB_PVPP_DEF @BASEBOARD_FAB2_LIB.BASEBOARD_FAB2(SCH_1):VR_FB_PVPP_DEF   I300 @BASEBOARD_FAB2_LIB.BASEBOARD_FAB2(SCH_1):PAGE232

R7B17 RES_0402-1.00K,1%,1/16W,CHIP,GA
     1 P3V3_STBY @BASEBOARD_FAB2_LIB.BASEBOARD_FAB2(SCH_1):P3V3_STBY   I210 @BASEBOARD_FAB2_LIB.BASEBOARD_FAB2(SCH_1):PAGE232
     2 PWRGD_PVPP_DEF_R @BASEBOARD_FAB2_LIB.BASEBOARD_FAB2(SCH_1):PWRGD_PVPP_DEF_R   I210 @BASEBOARD_FAB2_LIB.BASEBOARD_FAB2(SCH_1):PAGE232

R7B18 RES_0402-1.0K,0.1%,1/16W,CHIP,A
     1 VSENSE_PVPP_DEF @BASEBOARD_FAB2_LIB.BASEBOARD_FAB2(SCH_1):VSENSE_PVPP_DEF   I298 @BASEBOARD_FAB2_LIB.BASEBOARD_FAB2(SCH_1):PAGE232
     2 VR_COMP_PVPP_DEF @BASEBOARD_FAB2_LIB.BASEBOARD_FAB2(SCH_1):VR_COMP_PVPP_DEF   I298 @BASEBOARD_FAB2_LIB.BASEBOARD_FAB2(SCH_1):PAGE232

R7B19 RES_0402-0.0,5%,1/16W,CHIP,G21A
     1 VR_PVPP_DEF_BOOT @BASEBOARD_FAB2_LIB.BASEBOARD_FAB2(SCH_1):VR_PVPP_DEF_BOOT   I240 @BASEBOARD_FAB2_LIB.BASEBOARD_FAB2(SCH_1):PAGE232
     2 VR_PVPP_DEF_BOOT_R @BASEBOARD_FAB2_LIB.BASEBOARD_FAB2(SCH_1):VR_PVPP_DEF_BOOT_R   I240 @BASEBOARD_FAB2_LIB.BASEBOARD_FAB2(SCH_1):PAGE232

R7B20 RES_0402-0.0,5%,1/16W,CHIP,G21A
     1    GND @BASEBOARD_FAB2_LIB.BASEBOARD_FAB2(SCH_1):GND   I150 @BASEBOARD_FAB2_LIB.BASEBOARD_FAB2(SCH_1):PAGE232
     2 AGND_PVPP_DEF @BASEBOARD_FAB2_LIB.BASEBOARD_FAB2(SCH_1):AGND_PVPP_DEF   I150 @BASEBOARD_FAB2_LIB.BASEBOARD_FAB2(SCH_1):PAGE232

R7C1 RES_0603-200K,0.1%,1/10W,CHIP,A
     1 XTAL_PCH_48M_IN @BASEBOARD_FAB2_LIB.BASEBOARD_FAB2(SCH_1):XTAL_PCH_48M_IN    I48 @BASEBOARD_FAB2_LIB.BASEBOARD_FAB2(SCH_1):PAGE114
     2 XTAL_PCH_48M_OUT @BASEBOARD_FAB2_LIB.BASEBOARD_FAB2(SCH_1):XTAL_PCH_48M_OUT    I48 @BASEBOARD_FAB2_LIB.BASEBOARD_FAB2(SCH_1):PAGE114

R7C2 RES_0402-0.0,5%,1/16W,EMPTY,G2A
     1 CLK_100M_BMC_PE_R_DN @BASEBOARD_FAB2_LIB.BASEBOARD_FAB2(SCH_1):CLK_100M_BMC_PE_R_DN   I141 @BASEBOARD_FAB2_LIB.BASEBOARD_FAB2(SCH_1):PAGE114
     2 CLK_100M_BMC_PE_DN @BASEBOARD_FAB2_LIB.BASEBOARD_FAB2(SCH_1):CLK_100M_BMC_PE_DN   I141 @BASEBOARD_FAB2_LIB.BASEBOARD_FAB2(SCH_1):PAGE114

R7C3 RES_0402-51.1,1.0%,1/16W,CHIP,A
     1 PVCCIO_CPU0 @BASEBOARD_FAB2_LIB.BASEBOARD_FAB2(SCH_1):PVCCIO_CPU0    I78 @BASEBOARD_FAB2_LIB.BASEBOARD_FAB2(SCH_1):PAGE212
     2    GND @BASEBOARD_FAB2_LIB.BASEBOARD_FAB2(SCH_1):GND    I78 @BASEBOARD_FAB2_LIB.BASEBOARD_FAB2(SCH_1):PAGE212

R7C4 RES_0402-0.0,5%,1/16W,EMPTY,G2A
     1 CLK_100M_BMC_PE_R_DP @BASEBOARD_FAB2_LIB.BASEBOARD_FAB2(SCH_1):CLK_100M_BMC_PE_R_DP   I142 @BASEBOARD_FAB2_LIB.BASEBOARD_FAB2(SCH_1):PAGE114
     2 CLK_100M_BMC_PE_DP @BASEBOARD_FAB2_LIB.BASEBOARD_FAB2(SCH_1):CLK_100M_BMC_PE_DP   I142 @BASEBOARD_FAB2_LIB.BASEBOARD_FAB2(SCH_1):PAGE114

R7C5 RES_0402-10.0K,1%,1/16W,CHIP,GA
     1 P3V3_STBY @BASEBOARD_FAB2_LIB.BASEBOARD_FAB2(SCH_1):P3V3_STBY   I297 @BASEBOARD_FAB2_LIB.BASEBOARD_FAB2(SCH_1):PAGE133
     2 FM_SINT_PRSNT_N @BASEBOARD_FAB2_LIB.BASEBOARD_FAB2(SCH_1):FM_SINT_PRSNT_N   I297 @BASEBOARD_FAB2_LIB.BASEBOARD_FAB2(SCH_1):PAGE133

R7C6 RES_0603-10M,1.0%,1/10W,CHIP,GA
     1 XTAL_33K_RTC1 @BASEBOARD_FAB2_LIB.BASEBOARD_FAB2(SCH_1):XTAL_33K_RTC1    I54 @BASEBOARD_FAB2_LIB.BASEBOARD_FAB2(SCH_1):PAGE114
     2 XTAL_33K_RTC2 @BASEBOARD_FAB2_LIB.BASEBOARD_FAB2(SCH_1):XTAL_33K_RTC2    I54 @BASEBOARD_FAB2_LIB.BASEBOARD_FAB2(SCH_1):PAGE114

R7C8 RES_0402-10.0K,1%,1/16W,CHIP,GA
     1 P3V3_STBY @BASEBOARD_FAB2_LIB.BASEBOARD_FAB2(SCH_1):P3V3_STBY   I296 @BASEBOARD_FAB2_LIB.BASEBOARD_FAB2(SCH_1):PAGE133
     2 FM_WBG_PRSNT_N @BASEBOARD_FAB2_LIB.BASEBOARD_FAB2(SCH_1):FM_WBG_PRSNT_N   I296 @BASEBOARD_FAB2_LIB.BASEBOARD_FAB2(SCH_1):PAGE133

R7C10 RES_0402-20.0K,1%,1/16W,CHIP,GA
     1 P3V3_RTC_STBY @BASEBOARD_FAB2_LIB.BASEBOARD_FAB2(SCH_1):P3V3_RTC_STBY    I13 @BASEBOARD_FAB2_LIB.BASEBOARD_FAB2(SCH_1):PAGE137
     2 RST_RTCRST_N @BASEBOARD_FAB2_LIB.BASEBOARD_FAB2(SCH_1):RST_RTCRST_N    I13 @BASEBOARD_FAB2_LIB.BASEBOARD_FAB2(SCH_1):PAGE137

R7C11 RES_0402-1.0M,1%,1/16W,EMPTY,GA
     1    GND @BASEBOARD_FAB2_LIB.BASEBOARD_FAB2(SCH_1):GND    I11 @BASEBOARD_FAB2_LIB.BASEBOARD_FAB2(SCH_1):PAGE137
     2 RST_RTCRST_N @BASEBOARD_FAB2_LIB.BASEBOARD_FAB2(SCH_1):RST_RTCRST_N    I11 @BASEBOARD_FAB2_LIB.BASEBOARD_FAB2(SCH_1):PAGE137

R7C13 RES_0402-10.0K,1%,1/16W,CHIP,GA
     1 P3V3_STBY @BASEBOARD_FAB2_LIB.BASEBOARD_FAB2(SCH_1):P3V3_STBY    I67 @BASEBOARD_FAB2_LIB.BASEBOARD_FAB2(SCH_1):PAGE137
     2 FM_UART_PRES_N @BASEBOARD_FAB2_LIB.BASEBOARD_FAB2(SCH_1):FM_UART_PRES_N    I67 @BASEBOARD_FAB2_LIB.BASEBOARD_FAB2(SCH_1):PAGE137

R7C14 RES_0402-33.2,1%,1/16W,CHIP,G2A
     1 RMII_BMC_PCH_SPRNGVLLE_RXER @BASEBOARD_FAB2_LIB.BASEBOARD_FAB2(SCH_1):RMII_BMC_PCH_SPRNGVLLE_RXER    I98 @BASEBOARD_FAB2_LIB.BASEBOARD_FAB2(SCH_1):PAGE121
     2 RMII_BMC_PCH_SPRNGVLLE_RXER_R @BASEBOARD_FAB2_LIB.BASEBOARD_FAB2(SCH_1):RMII_BMC_PCH_SPRNGVLLE_RXER_R    I98 @BASEBOARD_FAB2_LIB.BASEBOARD_FAB2(SCH_1):PAGE121

R7C15 RES_0402-0.0,5%,1/16W,CHIP,G21A
     1 SPI_PCH_MOSI_R @BASEBOARD_FAB2_LIB.BASEBOARD_FAB2(SCH_1):SPI_PCH_MOSI_R    I31 @BASEBOARD_FAB2_LIB.BASEBOARD_FAB2(SCH_1):PAGE121
     2 SPI_PCH_MOSI @BASEBOARD_FAB2_LIB.BASEBOARD_FAB2(SCH_1):SPI_PCH_MOSI    I31 @BASEBOARD_FAB2_LIB.BASEBOARD_FAB2(SCH_1):PAGE121

R7C16 RES_0402-33.2,1%,1/16W,CHIP,G2A
     1 SPI_PCH_CS0_R_N @BASEBOARD_FAB2_LIB.BASEBOARD_FAB2(SCH_1):SPI_PCH_CS0_R_N    I33 @BASEBOARD_FAB2_LIB.BASEBOARD_FAB2(SCH_1):PAGE121
     2 SPI_PCH_CS0_N @BASEBOARD_FAB2_LIB.BASEBOARD_FAB2(SCH_1):SPI_PCH_CS0_N    I33 @BASEBOARD_FAB2_LIB.BASEBOARD_FAB2(SCH_1):PAGE121

R7C17 RES_0402-4.75K,1%,1/16W,CHIP,GA
     1 PVCCIO_CPU0 @BASEBOARD_FAB2_LIB.BASEBOARD_FAB2(SCH_1):PVCCIO_CPU0    I28 @BASEBOARD_FAB2_LIB.BASEBOARD_FAB2(SCH_1):PAGE166
     2 PECI_BMC @BASEBOARD_FAB2_LIB.BASEBOARD_FAB2(SCH_1):PECI_BMC    I28 @BASEBOARD_FAB2_LIB.BASEBOARD_FAB2(SCH_1):PAGE166

R7C18 RES_0402-0.0,5%,1/16W,EMPTY,G2A
     1 PECI_BMC @BASEBOARD_FAB2_LIB.BASEBOARD_FAB2(SCH_1):PECI_BMC    I11 @BASEBOARD_FAB2_LIB.BASEBOARD_FAB2(SCH_1):PAGE166
     2 PECI_CPU_G @BASEBOARD_FAB2_LIB.BASEBOARD_FAB2(SCH_1):PECI_CPU_G    I11 @BASEBOARD_FAB2_LIB.BASEBOARD_FAB2(SCH_1):PAGE166

R7C19 RES_0402-0.0,5%,1/16W,CHIP,G21A
     1 PECI_PCH @BASEBOARD_FAB2_LIB.BASEBOARD_FAB2(SCH_1):PECI_PCH    I15 @BASEBOARD_FAB2_LIB.BASEBOARD_FAB2(SCH_1):PAGE166
     2 PECI_CPU_G @BASEBOARD_FAB2_LIB.BASEBOARD_FAB2(SCH_1):PECI_CPU_G    I15 @BASEBOARD_FAB2_LIB.BASEBOARD_FAB2(SCH_1):PAGE166

R7C20 RES_0402-10.0K,1%,1/16W,CHIP,GA
     1 CLK_50M_CKMNG_PCH_10GBE @BASEBOARD_FAB2_LIB.BASEBOARD_FAB2(SCH_1):CLK_50M_CKMNG_PCH_10GBE    I73 @BASEBOARD_FAB2_LIB.BASEBOARD_FAB2(SCH_1):PAGE121
     2    GND @BASEBOARD_FAB2_LIB.BASEBOARD_FAB2(SCH_1):GND    I73 @BASEBOARD_FAB2_LIB.BASEBOARD_FAB2(SCH_1):PAGE121

R7C21 RES_0402-10.0K,1%,1/16W,CHIP,GA
     1 P1V05_PCH_STBY @BASEBOARD_FAB2_LIB.BASEBOARD_FAB2(SCH_1):P1V05_PCH_STBY     I9 @BASEBOARD_FAB2_LIB.BASEBOARD_FAB2(SCH_1):PAGE134
     2 FM_PCH_LVC1_THERMTRIP_N @BASEBOARD_FAB2_LIB.BASEBOARD_FAB2(SCH_1):FM_PCH_LVC1_THERMTRIP_N     I9 @BASEBOARD_FAB2_LIB.BASEBOARD_FAB2(SCH_1):PAGE134

R7C22 RES_0402-4.75K,1%,1/16W,EMPTY,A
     1 PVCCIO_CPU0 @BASEBOARD_FAB2_LIB.BASEBOARD_FAB2(SCH_1):PVCCIO_CPU0    I14 @BASEBOARD_FAB2_LIB.BASEBOARD_FAB2(SCH_1):PAGE166
     2 PECI_PCH @BASEBOARD_FAB2_LIB.BASEBOARD_FAB2(SCH_1):PECI_PCH    I14 @BASEBOARD_FAB2_LIB.BASEBOARD_FAB2(SCH_1):PAGE166

R7C23 RES_0402-10.0K,1%,1/16W,CHIP,GA
     1 P3V3_STBY @BASEBOARD_FAB2_LIB.BASEBOARD_FAB2(SCH_1):P3V3_STBY   I144 @BASEBOARD_FAB2_LIB.BASEBOARD_FAB2(SCH_1):PAGE118
     2 XDP_PCH_PWR_DEBUG_N @BASEBOARD_FAB2_LIB.BASEBOARD_FAB2(SCH_1):XDP_PCH_PWR_DEBUG_N   I144 @BASEBOARD_FAB2_LIB.BASEBOARD_FAB2(SCH_1):PAGE118

R7C24 RES_0402-4.02K,1%,1/16W,CHIP,GA
     1 VR_PVCCMCP_CPU0_XADDR2 @BASEBOARD_FAB2_LIB.BASEBOARD_FAB2(SCH_1):VR_PVCCMCP_CPU0_XADDR2   I155 @BASEBOARD_FAB2_LIB.BASEBOARD_FAB2(SCH_1):PAGE194
     2    GND @BASEBOARD_FAB2_LIB.BASEBOARD_FAB2(SCH_1):GND   I155 @BASEBOARD_FAB2_LIB.BASEBOARD_FAB2(SCH_1):PAGE194

R7C25 RES_0402-68.1K,1%,1/16W,EMPTY,A
     1 VR_PVCCIO_CPU0_OCSET @BASEBOARD_FAB2_LIB.BASEBOARD_FAB2(SCH_1):VR_PVCCIO_CPU0_OCSET   I103 @BASEBOARD_FAB2_LIB.BASEBOARD_FAB2(SCH_1):PAGE212
     2    GND @BASEBOARD_FAB2_LIB.BASEBOARD_FAB2(SCH_1):GND   I103 @BASEBOARD_FAB2_LIB.BASEBOARD_FAB2(SCH_1):PAGE212

R7C26 RES_0402-33.2,1%,1/16W,CHIP,G2A
     1 CLK_24M_BMC_LPC @BASEBOARD_FAB2_LIB.BASEBOARD_FAB2(SCH_1):CLK_24M_BMC_LPC   I189 @BASEBOARD_FAB2_LIB.BASEBOARD_FAB2(SCH_1):PAGE119
     2 CLK_24M_BMC_LPC_R @BASEBOARD_FAB2_LIB.BASEBOARD_FAB2(SCH_1):CLK_24M_BMC_LPC_R   I189 @BASEBOARD_FAB2_LIB.BASEBOARD_FAB2(SCH_1):PAGE119

R7D1 RES_0402-1.00K,1%,1/16W,CHIP,GA
     1 RMII_PCH_SPRNGVLLE_ARB_OUT @BASEBOARD_FAB2_LIB.BASEBOARD_FAB2(SCH_1):RMII_PCH_SPRNGVLLE_ARB_OUT    I70 @BASEBOARD_FAB2_LIB.BASEBOARD_FAB2(SCH_1):PAGE125
     2    GND @BASEBOARD_FAB2_LIB.BASEBOARD_FAB2(SCH_1):GND    I70 @BASEBOARD_FAB2_LIB.BASEBOARD_FAB2(SCH_1):PAGE125

R7D2 RES_0402-1.00K,1%,1/16W,CHIP,GA
     1 P3V3_STBY @BASEBOARD_FAB2_LIB.BASEBOARD_FAB2(SCH_1):P3V3_STBY   I332 @BASEBOARD_FAB2_LIB.BASEBOARD_FAB2(SCH_1):PAGE133
     2 PU_FM_RCIN_N @BASEBOARD_FAB2_LIB.BASEBOARD_FAB2(SCH_1):PU_FM_RCIN_N   I332 @BASEBOARD_FAB2_LIB.BASEBOARD_FAB2(SCH_1):PAGE133

R7D3 RES_0402-4.75K,1%,1/16W,CHIP,GA
     1 P3V3_STBY @BASEBOARD_FAB2_LIB.BASEBOARD_FAB2(SCH_1):P3V3_STBY   I243 @BASEBOARD_FAB2_LIB.BASEBOARD_FAB2(SCH_1):PAGE133
     2 IRQ_LPC_SERIRQ_N @BASEBOARD_FAB2_LIB.BASEBOARD_FAB2(SCH_1):IRQ_LPC_SERIRQ_N   I243 @BASEBOARD_FAB2_LIB.BASEBOARD_FAB2(SCH_1):PAGE133

R7D4 RES_0402-10.0K,1%,1/16W,CHIP,GA
     1 P3V3_STBY @BASEBOARD_FAB2_LIB.BASEBOARD_FAB2(SCH_1):P3V3_STBY   I245 @BASEBOARD_FAB2_LIB.BASEBOARD_FAB2(SCH_1):PAGE133
     2 PU_IRQ_PCH_SCI_WHEA_N @BASEBOARD_FAB2_LIB.BASEBOARD_FAB2(SCH_1):PU_IRQ_PCH_SCI_WHEA_N   I245 @BASEBOARD_FAB2_LIB.BASEBOARD_FAB2(SCH_1):PAGE133

R7D5 RES_0402-2.26K,1.0%,1/16W,CHIPA
     1 P3V3_STBY @BASEBOARD_FAB2_LIB.BASEBOARD_FAB2(SCH_1):P3V3_STBY   I199 @BASEBOARD_FAB2_LIB.BASEBOARD_FAB2(SCH_1):PAGE181
     2 FM_MB_SLOT_ID0 @BASEBOARD_FAB2_LIB.BASEBOARD_FAB2(SCH_1):FM_MB_SLOT_ID0   I199 @BASEBOARD_FAB2_LIB.BASEBOARD_FAB2(SCH_1):PAGE181

R7D6 RES_0402-4.75K,1%,1/16W,CHIP,GA
     1 P3V3_STBY @BASEBOARD_FAB2_LIB.BASEBOARD_FAB2(SCH_1):P3V3_STBY   I306 @BASEBOARD_FAB2_LIB.BASEBOARD_FAB2(SCH_1):PAGE133
     2 FM_BMC_READY_N @BASEBOARD_FAB2_LIB.BASEBOARD_FAB2(SCH_1):FM_BMC_READY_N   I306 @BASEBOARD_FAB2_LIB.BASEBOARD_FAB2(SCH_1):PAGE133

R7D7 RES_0402-1.00K,1%,1/16W,CHIP,GA
     1 P3V3_STBY @BASEBOARD_FAB2_LIB.BASEBOARD_FAB2(SCH_1):P3V3_STBY   I331 @BASEBOARD_FAB2_LIB.BASEBOARD_FAB2(SCH_1):PAGE133
     2 IRQ_PIRQA_SPI_TPM_N @BASEBOARD_FAB2_LIB.BASEBOARD_FAB2(SCH_1):IRQ_PIRQA_SPI_TPM_N   I331 @BASEBOARD_FAB2_LIB.BASEBOARD_FAB2(SCH_1):PAGE133

R7D8 RES_0402-10.0K,1%,1/16W,CHIP,GA
     1 P3V3_STBY @BASEBOARD_FAB2_LIB.BASEBOARD_FAB2(SCH_1):P3V3_STBY   I200 @BASEBOARD_FAB2_LIB.BASEBOARD_FAB2(SCH_1):PAGE133
     2 PU_LPC_CLKRUN_N @BASEBOARD_FAB2_LIB.BASEBOARD_FAB2(SCH_1):PU_LPC_CLKRUN_N   I200 @BASEBOARD_FAB2_LIB.BASEBOARD_FAB2(SCH_1):PAGE133

R7D9 RES_0402-2.26K,1.0%,1/16W,CHIPA
     1 P3V3_STBY @BASEBOARD_FAB2_LIB.BASEBOARD_FAB2(SCH_1):P3V3_STBY   I200 @BASEBOARD_FAB2_LIB.BASEBOARD_FAB2(SCH_1):PAGE181
     2 FM_MB_SLOT_ID1 @BASEBOARD_FAB2_LIB.BASEBOARD_FAB2(SCH_1):FM_MB_SLOT_ID1   I200 @BASEBOARD_FAB2_LIB.BASEBOARD_FAB2(SCH_1):PAGE181

R7D10 RES_0402-10.0K,1%,1/16W,CHIP,GA
     1 P3V3_STBY @BASEBOARD_FAB2_LIB.BASEBOARD_FAB2(SCH_1):P3V3_STBY   I202 @BASEBOARD_FAB2_LIB.BASEBOARD_FAB2(SCH_1):PAGE133
     2 PU_LPC_PME_N @BASEBOARD_FAB2_LIB.BASEBOARD_FAB2(SCH_1):PU_LPC_PME_N   I202 @BASEBOARD_FAB2_LIB.BASEBOARD_FAB2(SCH_1):PAGE133

R7D12 RES_0402-10.0K,1%,1/16W,CHIP,GA
     1 P3V3_STBY @BASEBOARD_FAB2_LIB.BASEBOARD_FAB2(SCH_1):P3V3_STBY   I237 @BASEBOARD_FAB2_LIB.BASEBOARD_FAB2(SCH_1):PAGE133
     2 FM_OCP_MEZZA_PRES_N @BASEBOARD_FAB2_LIB.BASEBOARD_FAB2(SCH_1):FM_OCP_MEZZA_PRES_N   I237 @BASEBOARD_FAB2_LIB.BASEBOARD_FAB2(SCH_1):PAGE133

R7D13 RES_0402-8.2K,1%,1/16W,EMPTY,GA
     1 P3V3_STBY @BASEBOARD_FAB2_LIB.BASEBOARD_FAB2(SCH_1):P3V3_STBY    I60 @BASEBOARD_FAB2_LIB.BASEBOARD_FAB2(SCH_1):PAGE125
     2 RMII_BMC_PCH_SPRNGVLLE_RXER @BASEBOARD_FAB2_LIB.BASEBOARD_FAB2(SCH_1):RMII_BMC_PCH_SPRNGVLLE_RXER    I60 @BASEBOARD_FAB2_LIB.BASEBOARD_FAB2(SCH_1):PAGE125

R7D15 RES_0402-348,1%,1/16W,CHIP,G21A
     1 PECI_CPU_G @BASEBOARD_FAB2_LIB.BASEBOARD_FAB2(SCH_1):PECI_CPU_G    I32 @BASEBOARD_FAB2_LIB.BASEBOARD_FAB2(SCH_1):PAGE166
     2    GND @BASEBOARD_FAB2_LIB.BASEBOARD_FAB2(SCH_1):GND    I32 @BASEBOARD_FAB2_LIB.BASEBOARD_FAB2(SCH_1):PAGE166

R7D18 RES_0402-1.00K,1%,1/16W,CHIP,GA
     1 FM_THERMTRIP_DLY @BASEBOARD_FAB2_LIB.BASEBOARD_FAB2(SCH_1):FM_THERMTRIP_DLY    I11 @BASEBOARD_FAB2_LIB.BASEBOARD_FAB2(SCH_1):PAGE134
     2 FM_THERMTRIP_DLY_R @BASEBOARD_FAB2_LIB.BASEBOARD_FAB2(SCH_1):FM_THERMTRIP_DLY_R    I11 @BASEBOARD_FAB2_LIB.BASEBOARD_FAB2(SCH_1):PAGE134

R7D19 RES_0402-1.00K,1%,1/16W,EMPTY,A
     1 FM_OC_DETECT_EN_N @BASEBOARD_FAB2_LIB.BASEBOARD_FAB2(SCH_1):FM_OC_DETECT_EN_N     I6 @BASEBOARD_FAB2_LIB.BASEBOARD_FAB2(SCH_1):PAGE126
     2    GND @BASEBOARD_FAB2_LIB.BASEBOARD_FAB2(SCH_1):GND     I6 @BASEBOARD_FAB2_LIB.BASEBOARD_FAB2(SCH_1):PAGE126

R7D23 RES_0402-0.0,5%,1/16W,CHIP,G21A
     1 RST_BMC_SRST_N @BASEBOARD_FAB2_LIB.BASEBOARD_FAB2(SCH_1):RST_BMC_SRST_N   I131 @BASEBOARD_FAB2_LIB.BASEBOARD_FAB2(SCH_1):PAGE118
     2 RST_BMC_SRST_R_N @BASEBOARD_FAB2_LIB.BASEBOARD_FAB2(SCH_1):RST_BMC_SRST_R_N   I131 @BASEBOARD_FAB2_LIB.BASEBOARD_FAB2(SCH_1):PAGE118

R7D24 RES_0402-33.2,1%,1/16W,CHIP,G2A
     1 FM_CPU1_PROCHOT_LVT3_K_N @BASEBOARD_FAB2_LIB.BASEBOARD_FAB2(SCH_1):FM_CPU1_PROCHOT_LVT3_K_N    I62 @BASEBOARD_FAB2_LIB.BASEBOARD_FAB2(SCH_1):PAGE93
     2 FM_CPU1_PROCHOT_LVT3_N @BASEBOARD_FAB2_LIB.BASEBOARD_FAB2(SCH_1):FM_CPU1_PROCHOT_LVT3_N    I62 @BASEBOARD_FAB2_LIB.BASEBOARD_FAB2(SCH_1):PAGE93

R7D25 RES_0402-33.2,1%,1/16W,CHIP,G2A
     1 FM_CPU_MSMI_LVT3_R_N @BASEBOARD_FAB2_LIB.BASEBOARD_FAB2(SCH_1):FM_CPU_MSMI_LVT3_R_N    I70 @BASEBOARD_FAB2_LIB.BASEBOARD_FAB2(SCH_1):PAGE92
     2 FM_CPU_MSMI_LVT3_N @BASEBOARD_FAB2_LIB.BASEBOARD_FAB2(SCH_1):FM_CPU_MSMI_LVT3_N    I70 @BASEBOARD_FAB2_LIB.BASEBOARD_FAB2(SCH_1):PAGE92

R7D26 RES_0402-1.00K,1%,1/16W,CHIP,GA
     1 PD_GTL2104_DIR_0 @BASEBOARD_FAB2_LIB.BASEBOARD_FAB2(SCH_1):PD_GTL2104_DIR_0    I54 @BASEBOARD_FAB2_LIB.BASEBOARD_FAB2(SCH_1):PAGE92
     2    GND @BASEBOARD_FAB2_LIB.BASEBOARD_FAB2(SCH_1):GND    I54 @BASEBOARD_FAB2_LIB.BASEBOARD_FAB2(SCH_1):PAGE92

R7D27 RES_0402-0.0,5%,1/16W,CHIP,G21A
     1 H_CPU0_MSMI_G_N @BASEBOARD_FAB2_LIB.BASEBOARD_FAB2(SCH_1):H_CPU0_MSMI_G_N    I68 @BASEBOARD_FAB2_LIB.BASEBOARD_FAB2(SCH_1):PAGE92
     2 H_CPU_MSMI_G_N @BASEBOARD_FAB2_LIB.BASEBOARD_FAB2(SCH_1):H_CPU_MSMI_G_N    I68 @BASEBOARD_FAB2_LIB.BASEBOARD_FAB2(SCH_1):PAGE92

R7D28 RES_0402-0.0,5%,1/16W,CHIP,G21A
     1 H_CPU1_MSMI_G_N @BASEBOARD_FAB2_LIB.BASEBOARD_FAB2(SCH_1):H_CPU1_MSMI_G_N    I67 @BASEBOARD_FAB2_LIB.BASEBOARD_FAB2(SCH_1):PAGE92
     2 H_CPU_MSMI_G_N @BASEBOARD_FAB2_LIB.BASEBOARD_FAB2(SCH_1):H_CPU_MSMI_G_N    I67 @BASEBOARD_FAB2_LIB.BASEBOARD_FAB2(SCH_1):PAGE92

R7D29 RES_0402-33.2,1%,1/16W,CHIP,G2A
     1 FM_CPU0_FIVR_FAULT_R_LVT3 @BASEBOARD_FAB2_LIB.BASEBOARD_FAB2(SCH_1):FM_CPU0_FIVR_FAULT_R_LVT3    I30 @BASEBOARD_FAB2_LIB.BASEBOARD_FAB2(SCH_1):PAGE92
     2 FM_CPU0_FIVR_FAULT_LVT3 @BASEBOARD_FAB2_LIB.BASEBOARD_FAB2(SCH_1):FM_CPU0_FIVR_FAULT_LVT3    I30 @BASEBOARD_FAB2_LIB.BASEBOARD_FAB2(SCH_1):PAGE92

R7D30 RES_0402-4.75K,1%,1/16W,CHIP,GA
     1 P3V3_STBY @BASEBOARD_FAB2_LIB.BASEBOARD_FAB2(SCH_1):P3V3_STBY   I121 @BASEBOARD_FAB2_LIB.BASEBOARD_FAB2(SCH_1):PAGE135
     2 FM_CPLD_UART_CH_LOCK_N @BASEBOARD_FAB2_LIB.BASEBOARD_FAB2(SCH_1):FM_CPLD_UART_CH_LOCK_N   I121 @BASEBOARD_FAB2_LIB.BASEBOARD_FAB2(SCH_1):PAGE135

R7D31 RES_0402-33.2,1%,1/16W,CHIP,G2A
     1 FM_CPU_ERR2_LVT3_R_N @BASEBOARD_FAB2_LIB.BASEBOARD_FAB2(SCH_1):FM_CPU_ERR2_LVT3_R_N    I29 @BASEBOARD_FAB2_LIB.BASEBOARD_FAB2(SCH_1):PAGE92
     2 FM_CPU_ERR2_LVT3_N @BASEBOARD_FAB2_LIB.BASEBOARD_FAB2(SCH_1):FM_CPU_ERR2_LVT3_N    I29 @BASEBOARD_FAB2_LIB.BASEBOARD_FAB2(SCH_1):PAGE92

R7D32 RES_0402-100.0,1%,1/16W,CHIP,GA
     1 P0V7_GTL2104_VREF_0 @BASEBOARD_FAB2_LIB.BASEBOARD_FAB2(SCH_1):P0V7_GTL2104_VREF_0    I48 @BASEBOARD_FAB2_LIB.BASEBOARD_FAB2(SCH_1):PAGE92
     2    GND @BASEBOARD_FAB2_LIB.BASEBOARD_FAB2(SCH_1):GND    I48 @BASEBOARD_FAB2_LIB.BASEBOARD_FAB2(SCH_1):PAGE92

R7D33 RES_0402-49.9,1%,1/16W,CHIP,G2A
     1 PVCCIO_CPU0 @BASEBOARD_FAB2_LIB.BASEBOARD_FAB2(SCH_1):PVCCIO_CPU0    I51 @BASEBOARD_FAB2_LIB.BASEBOARD_FAB2(SCH_1):PAGE92
     2 P0V7_GTL2104_VREF_0 @BASEBOARD_FAB2_LIB.BASEBOARD_FAB2(SCH_1):P0V7_GTL2104_VREF_0    I51 @BASEBOARD_FAB2_LIB.BASEBOARD_FAB2(SCH_1):PAGE92

R7D34 RES_0402-33.2,1%,1/16W,CHIP,G2A
     1 FM_CPU0_THERMTRIP_LVT3_R_N @BASEBOARD_FAB2_LIB.BASEBOARD_FAB2(SCH_1):FM_CPU0_THERMTRIP_LVT3_R_N    I24 @BASEBOARD_FAB2_LIB.BASEBOARD_FAB2(SCH_1):PAGE92
     2 FM_CPU0_THERMTRIP_LVT3_N @BASEBOARD_FAB2_LIB.BASEBOARD_FAB2(SCH_1):FM_CPU0_THERMTRIP_LVT3_N    I24 @BASEBOARD_FAB2_LIB.BASEBOARD_FAB2(SCH_1):PAGE92

R7D36 RES_0402-0.0,5%,1/16W,CHIP,G21A
     1 FM_156M_CPU1_BRD_OSC_EN @BASEBOARD_FAB2_LIB.BASEBOARD_FAB2(SCH_1):FM_156M_CPU1_BRD_OSC_EN    I96 @BASEBOARD_FAB2_LIB.BASEBOARD_FAB2(SCH_1):PAGE104
     2 FM_CPU1_STL_BRD_OSC_EN @BASEBOARD_FAB2_LIB.BASEBOARD_FAB2(SCH_1):FM_CPU1_STL_BRD_OSC_EN    I96 @BASEBOARD_FAB2_LIB.BASEBOARD_FAB2(SCH_1):PAGE104

R7D37 RES_0402-0.0,5%,1/16W,EMPTY,G2A
     1 FM_CPU1_VRM_OSC_EN @BASEBOARD_FAB2_LIB.BASEBOARD_FAB2(SCH_1):FM_CPU1_VRM_OSC_EN    I98 @BASEBOARD_FAB2_LIB.BASEBOARD_FAB2(SCH_1):PAGE104
     2 FM_CPU1_VRM_322M_156M_OSC_EN @BASEBOARD_FAB2_LIB.BASEBOARD_FAB2(SCH_1):FM_CPU1_VRM_322M_156M_OSC_EN    I98 @BASEBOARD_FAB2_LIB.BASEBOARD_FAB2(SCH_1):PAGE104

R7D38 RES_0402-0.0,5%,1/16W,EMPTY,G2A
     1 FM_CPU1_VRM_OSC_EN @BASEBOARD_FAB2_LIB.BASEBOARD_FAB2(SCH_1):FM_CPU1_VRM_OSC_EN    I97 @BASEBOARD_FAB2_LIB.BASEBOARD_FAB2(SCH_1):PAGE104
     2 FM_CPU1_STL_BRD_OSC_EN @BASEBOARD_FAB2_LIB.BASEBOARD_FAB2(SCH_1):FM_CPU1_STL_BRD_OSC_EN    I97 @BASEBOARD_FAB2_LIB.BASEBOARD_FAB2(SCH_1):PAGE104

R7D39 RES_0402-0.0,5%,1/16W,EMPTY,G2A
     1 FM_CPU0_VRM_OSC_EN @BASEBOARD_FAB2_LIB.BASEBOARD_FAB2(SCH_1):FM_CPU0_VRM_OSC_EN    I95 @BASEBOARD_FAB2_LIB.BASEBOARD_FAB2(SCH_1):PAGE104
     2 FM_CPU0_VRM_322M_156M_OSC_EN @BASEBOARD_FAB2_LIB.BASEBOARD_FAB2(SCH_1):FM_CPU0_VRM_322M_156M_OSC_EN    I95 @BASEBOARD_FAB2_LIB.BASEBOARD_FAB2(SCH_1):PAGE104

R7D40 RES_0402-0.0,5%,1/16W,EMPTY,G2A
     1 FM_CPU0_VRM_OSC_EN @BASEBOARD_FAB2_LIB.BASEBOARD_FAB2(SCH_1):FM_CPU0_VRM_OSC_EN    I94 @BASEBOARD_FAB2_LIB.BASEBOARD_FAB2(SCH_1):PAGE104
     2 FM_CPU0_STL_BRD_OSC_EN @BASEBOARD_FAB2_LIB.BASEBOARD_FAB2(SCH_1):FM_CPU0_STL_BRD_OSC_EN    I94 @BASEBOARD_FAB2_LIB.BASEBOARD_FAB2(SCH_1):PAGE104

R7D41 RES_0402-0.0,5%,1/16W,CHIP,G21A
     1 FM_CPU1_PROCHOT_LVT3_R_N @BASEBOARD_FAB2_LIB.BASEBOARD_FAB2(SCH_1):FM_CPU1_PROCHOT_LVT3_R_N   I114 @BASEBOARD_FAB2_LIB.BASEBOARD_FAB2(SCH_1):PAGE93
     2 FM_CPU1_PROCHOT_LVT3_K_N @BASEBOARD_FAB2_LIB.BASEBOARD_FAB2(SCH_1):FM_CPU1_PROCHOT_LVT3_K_N   I114 @BASEBOARD_FAB2_LIB.BASEBOARD_FAB2(SCH_1):PAGE93

R7D42 RES_0402-4.75K,1%,1/16W,CHIP,GA
     1 P3V3_STBY @BASEBOARD_FAB2_LIB.BASEBOARD_FAB2(SCH_1):P3V3_STBY   I193 @BASEBOARD_FAB2_LIB.BASEBOARD_FAB2(SCH_1):PAGE191
     2 PU_FAB2_MARKER_CPLD @BASEBOARD_FAB2_LIB.BASEBOARD_FAB2(SCH_1):PU_FAB2_MARKER_CPLD   I193 @BASEBOARD_FAB2_LIB.BASEBOARD_FAB2(SCH_1):PAGE191

R7D43 RES_0402-0.0,5%,1/16W,EMPTY,G2A
     1 FM_CPU1_PROCHOT_LVT3_K_N @BASEBOARD_FAB2_LIB.BASEBOARD_FAB2(SCH_1):FM_CPU1_PROCHOT_LVT3_K_N   I110 @BASEBOARD_FAB2_LIB.BASEBOARD_FAB2(SCH_1):PAGE93
     2 H_CPU1_PROCHOT_G_PCH_N @BASEBOARD_FAB2_LIB.BASEBOARD_FAB2(SCH_1):H_CPU1_PROCHOT_G_PCH_N   I110 @BASEBOARD_FAB2_LIB.BASEBOARD_FAB2(SCH_1):PAGE93

R7D44 RES_0402-4.75K,1%,1/16W,CHIP,GA
     1 P1V05_PCH_STBY @BASEBOARD_FAB2_LIB.BASEBOARD_FAB2(SCH_1):P1V05_PCH_STBY   I356 @BASEBOARD_FAB2_LIB.BASEBOARD_FAB2(SCH_1):PAGE133
     2 FM_OCP_MEZZB_PRES_N @BASEBOARD_FAB2_LIB.BASEBOARD_FAB2(SCH_1):FM_OCP_MEZZB_PRES_N   I356 @BASEBOARD_FAB2_LIB.BASEBOARD_FAB2(SCH_1):PAGE133

R7E2 RES_0402-75,1.0%,1/16W,CHIP,G2A
     1 PVCCIO_CPU0 @BASEBOARD_FAB2_LIB.BASEBOARD_FAB2(SCH_1):PVCCIO_CPU0    I19 @BASEBOARD_FAB2_LIB.BASEBOARD_FAB2(SCH_1):PAGE92
     2 H_CPU0_THERMTRIP_G_N @BASEBOARD_FAB2_LIB.BASEBOARD_FAB2(SCH_1):H_CPU0_THERMTRIP_G_N    I19 @BASEBOARD_FAB2_LIB.BASEBOARD_FAB2(SCH_1):PAGE92

R7E5 RES_0402-10.0K,1%,1/16W,CHIP,GA
     1 P3V3_STBY @BASEBOARD_FAB2_LIB.BASEBOARD_FAB2(SCH_1):P3V3_STBY    I38 @BASEBOARD_FAB2_LIB.BASEBOARD_FAB2(SCH_1):PAGE192
     2 PU_THERMTRIP_FORCE_N @BASEBOARD_FAB2_LIB.BASEBOARD_FAB2(SCH_1):PU_THERMTRIP_FORCE_N    I38 @BASEBOARD_FAB2_LIB.BASEBOARD_FAB2(SCH_1):PAGE192

R7E6 RES_0402-10.0K,1%,1/16W,CHIP,GA
     1 P3V3_STBY @BASEBOARD_FAB2_LIB.BASEBOARD_FAB2(SCH_1):P3V3_STBY    I33 @BASEBOARD_FAB2_LIB.BASEBOARD_FAB2(SCH_1):PAGE192
     2 PU_RST_PERST_BIT1 @BASEBOARD_FAB2_LIB.BASEBOARD_FAB2(SCH_1):PU_RST_PERST_BIT1    I33 @BASEBOARD_FAB2_LIB.BASEBOARD_FAB2(SCH_1):PAGE192

R7E7 RES_0402-4.75K,1%,1/16W,CHIP,GA
     1   P3V3 @BASEBOARD_FAB2_LIB.BASEBOARD_FAB2(SCH_1):P3V3   I106 @BASEBOARD_FAB2_LIB.BASEBOARD_FAB2(SCH_1):PAGE95
     2 FM_SYS_THROTTLE_LVC3 @BASEBOARD_FAB2_LIB.BASEBOARD_FAB2(SCH_1):FM_SYS_THROTTLE_LVC3   I106 @BASEBOARD_FAB2_LIB.BASEBOARD_FAB2(SCH_1):PAGE95

R7E9 RES_0402-0.0,5%,1/16W,CHIP,G21A
     1 FM_THROTTLE_N @BASEBOARD_FAB2_LIB.BASEBOARD_FAB2(SCH_1):FM_THROTTLE_N   I108 @BASEBOARD_FAB2_LIB.BASEBOARD_FAB2(SCH_1):PAGE95
     2 FM_THROTTLE_R_N @BASEBOARD_FAB2_LIB.BASEBOARD_FAB2(SCH_1):FM_THROTTLE_R_N   I108 @BASEBOARD_FAB2_LIB.BASEBOARD_FAB2(SCH_1):PAGE95

R7E10 RES_0402-4.75K,1%,1/16W,CHIP,GA
     1   P3V3 @BASEBOARD_FAB2_LIB.BASEBOARD_FAB2(SCH_1):P3V3    I62 @BASEBOARD_FAB2_LIB.BASEBOARD_FAB2(SCH_1):PAGE95
     2 IRQ_CPU0_VRHOT @BASEBOARD_FAB2_LIB.BASEBOARD_FAB2(SCH_1):IRQ_CPU0_VRHOT    I62 @BASEBOARD_FAB2_LIB.BASEBOARD_FAB2(SCH_1):PAGE95

R7E11 RES_0402-4.75K,1%,1/16W,CHIP,GA
     1   P3V3 @BASEBOARD_FAB2_LIB.BASEBOARD_FAB2(SCH_1):P3V3    I72 @BASEBOARD_FAB2_LIB.BASEBOARD_FAB2(SCH_1):PAGE95
     2 IRQ_CPU1_VRHOT @BASEBOARD_FAB2_LIB.BASEBOARD_FAB2(SCH_1):IRQ_CPU1_VRHOT    I72 @BASEBOARD_FAB2_LIB.BASEBOARD_FAB2(SCH_1):PAGE95

R7E12 RES_0402-1.00K,1%,1/16W,CHIP,GA
     1 P5V_STBY @BASEBOARD_FAB2_LIB.BASEBOARD_FAB2(SCH_1):P5V_STBY    I11 @BASEBOARD_FAB2_LIB.BASEBOARD_FAB2(SCH_1):PAGE241
     2 PWRGD_P5V_STBY_R @BASEBOARD_FAB2_LIB.BASEBOARD_FAB2(SCH_1):PWRGD_P5V_STBY_R    I11 @BASEBOARD_FAB2_LIB.BASEBOARD_FAB2(SCH_1):PAGE241

R7E13 RES_0402-0.0,5%,1/16W,CHIP,G21A
     1    GND @BASEBOARD_FAB2_LIB.BASEBOARD_FAB2(SCH_1):GND    I58 @BASEBOARD_FAB2_LIB.BASEBOARD_FAB2(SCH_1):PAGE241
     2 AGND_P5V_STBY @BASEBOARD_FAB2_LIB.BASEBOARD_FAB2(SCH_1):AGND_P5V_STBY    I58 @BASEBOARD_FAB2_LIB.BASEBOARD_FAB2(SCH_1):PAGE241

R7E14 RES_0402-75K,1%,1/16W,CHIP,G21A
     1 VR_P5V_STBY_RT @BASEBOARD_FAB2_LIB.BASEBOARD_FAB2(SCH_1):VR_P5V_STBY_RT    I18 @BASEBOARD_FAB2_LIB.BASEBOARD_FAB2(SCH_1):PAGE241
     2 AGND_P5V_STBY @BASEBOARD_FAB2_LIB.BASEBOARD_FAB2(SCH_1):AGND_P5V_STBY    I18 @BASEBOARD_FAB2_LIB.BASEBOARD_FAB2(SCH_1):PAGE241

R7E15 RES_0402-22.1,1.0%,1/16W,CHIP,A
     1 PWRGD_P5V_STBY_R @BASEBOARD_FAB2_LIB.BASEBOARD_FAB2(SCH_1):PWRGD_P5V_STBY_R    I89 @BASEBOARD_FAB2_LIB.BASEBOARD_FAB2(SCH_1):PAGE241
     2 PWRGD_P5V_STBY @BASEBOARD_FAB2_LIB.BASEBOARD_FAB2(SCH_1):PWRGD_P5V_STBY    I89 @BASEBOARD_FAB2_LIB.BASEBOARD_FAB2(SCH_1):PAGE241

R7E16 RES_0402-1.37K,1%,1/16W,CHIP,GA
     1 VR_P5V_STBY_VSENSE @BASEBOARD_FAB2_LIB.BASEBOARD_FAB2(SCH_1):VR_P5V_STBY_VSENSE    I51 @BASEBOARD_FAB2_LIB.BASEBOARD_FAB2(SCH_1):PAGE241
     2 AGND_P5V_STBY @BASEBOARD_FAB2_LIB.BASEBOARD_FAB2(SCH_1):AGND_P5V_STBY    I51 @BASEBOARD_FAB2_LIB.BASEBOARD_FAB2(SCH_1):PAGE241

R7E17 RES_0402-0.0,5%,1/16W,CHIP,G21A
     1 VR_FET_SW_P5V_STBY_PVIN @BASEBOARD_FAB2_LIB.BASEBOARD_FAB2(SCH_1):VR_FET_SW_P5V_STBY_PVIN    I37 @BASEBOARD_FAB2_LIB.BASEBOARD_FAB2(SCH_1):PAGE241
     2 VR_P5V_STBY_VIN @BASEBOARD_FAB2_LIB.BASEBOARD_FAB2(SCH_1):VR_P5V_STBY_VIN    I37 @BASEBOARD_FAB2_LIB.BASEBOARD_FAB2(SCH_1):PAGE241

R7E18 RES_0402-4.75K,1%,1/16W,CHIP,GA
     1 P3V3_STBY @BASEBOARD_FAB2_LIB.BASEBOARD_FAB2(SCH_1):P3V3_STBY    I55 @BASEBOARD_FAB2_LIB.BASEBOARD_FAB2(SCH_1):PAGE192
     2 RST_RSMRST_N @BASEBOARD_FAB2_LIB.BASEBOARD_FAB2(SCH_1):RST_RSMRST_N    I55 @BASEBOARD_FAB2_LIB.BASEBOARD_FAB2(SCH_1):PAGE192

R7E19 RES_0402-1.00K,1%,1/16W,EMPTY,A
     1 P3V3_STBY @BASEBOARD_FAB2_LIB.BASEBOARD_FAB2(SCH_1):P3V3_STBY    I57 @BASEBOARD_FAB2_LIB.BASEBOARD_FAB2(SCH_1):PAGE192
     2 FM_MEM_EVENT_FUNC @BASEBOARD_FAB2_LIB.BASEBOARD_FAB2(SCH_1):FM_MEM_EVENT_FUNC    I57 @BASEBOARD_FAB2_LIB.BASEBOARD_FAB2(SCH_1):PAGE192

R7E20 RES_0402-1.00K,1%,1/16W,CHIP,GA
     1 FM_MEM_EVENT_FUNC @BASEBOARD_FAB2_LIB.BASEBOARD_FAB2(SCH_1):FM_MEM_EVENT_FUNC    I59 @BASEBOARD_FAB2_LIB.BASEBOARD_FAB2(SCH_1):PAGE192
     2    GND @BASEBOARD_FAB2_LIB.BASEBOARD_FAB2(SCH_1):GND    I59 @BASEBOARD_FAB2_LIB.BASEBOARD_FAB2(SCH_1):PAGE192

R7E21 RES_0402-4.75K,1%,1/16W,CHIP,GA
     1   P3V3 @BASEBOARD_FAB2_LIB.BASEBOARD_FAB2(SCH_1):P3V3   I343 @BASEBOARD_FAB2_LIB.BASEBOARD_FAB2(SCH_1):PAGE108
     2 FM_PWRBRK_N @BASEBOARD_FAB2_LIB.BASEBOARD_FAB2(SCH_1):FM_PWRBRK_N   I343 @BASEBOARD_FAB2_LIB.BASEBOARD_FAB2(SCH_1):PAGE108

R7E22 RES_0402-0.0,5%,1/16W,CHIP,G21A
     1 FM_PWRBRK_N @BASEBOARD_FAB2_LIB.BASEBOARD_FAB2(SCH_1):FM_PWRBRK_N   I341 @BASEBOARD_FAB2_LIB.BASEBOARD_FAB2(SCH_1):PAGE108
     2 FM_PWRBRK_SLOT_N @BASEBOARD_FAB2_LIB.BASEBOARD_FAB2(SCH_1):FM_PWRBRK_SLOT_N   I341 @BASEBOARD_FAB2_LIB.BASEBOARD_FAB2(SCH_1):PAGE108

R7F1 RES_0402-10.0K,1%,1/16W,CHIP,GA
     1 VR_P5V_STBY_VSENSE_R @BASEBOARD_FAB2_LIB.BASEBOARD_FAB2(SCH_1):VR_P5V_STBY_VSENSE_R    I50 @BASEBOARD_FAB2_LIB.BASEBOARD_FAB2(SCH_1):PAGE241
     2 VR_P5V_STBY_VSENSE @BASEBOARD_FAB2_LIB.BASEBOARD_FAB2(SCH_1):VR_P5V_STBY_VSENSE    I50 @BASEBOARD_FAB2_LIB.BASEBOARD_FAB2(SCH_1):PAGE241

R7F3 RES_0402-33.2,1%,1/16W,CHIP,G2A
     1 SPI_BIOS_SOCKET_IO3 @BASEBOARD_FAB2_LIB.BASEBOARD_FAB2(SCH_1):SPI_BIOS_SOCKET_IO3   I109 @BASEBOARD_FAB2_LIB.BASEBOARD_FAB2(SCH_1):PAGE153
     2 PU_BIOS_SPI_HOLD0_N @BASEBOARD_FAB2_LIB.BASEBOARD_FAB2(SCH_1):PU_BIOS_SPI_HOLD0_N   I109 @BASEBOARD_FAB2_LIB.BASEBOARD_FAB2(SCH_1):PAGE153

R7F4 RES_0402-33.2,1%,1/16W,CHIP,G2A
     1 SPI_SWITCH_MISO @BASEBOARD_FAB2_LIB.BASEBOARD_FAB2(SCH_1):SPI_SWITCH_MISO    I98 @BASEBOARD_FAB2_LIB.BASEBOARD_FAB2(SCH_1):PAGE153
     2 SPI_MISO_R0 @BASEBOARD_FAB2_LIB.BASEBOARD_FAB2(SCH_1):SPI_MISO_R0    I98 @BASEBOARD_FAB2_LIB.BASEBOARD_FAB2(SCH_1):PAGE153

R7F5 RES_0402-4.75K,1%,1/16W,CHIP,GA
     1 P3V3_STBY @BASEBOARD_FAB2_LIB.BASEBOARD_FAB2(SCH_1):P3V3_STBY    I94 @BASEBOARD_FAB2_LIB.BASEBOARD_FAB2(SCH_1):PAGE153
     2 SPI_CS0_PRIMARY_R_N @BASEBOARD_FAB2_LIB.BASEBOARD_FAB2(SCH_1):SPI_CS0_PRIMARY_R_N    I94 @BASEBOARD_FAB2_LIB.BASEBOARD_FAB2(SCH_1):PAGE153

R7F6 RES_0402-4.75K,1%,1/16W,EMPTY,A
     1 P3V3_STBY @BASEBOARD_FAB2_LIB.BASEBOARD_FAB2(SCH_1):P3V3_STBY    I90 @BASEBOARD_FAB2_LIB.BASEBOARD_FAB2(SCH_1):PAGE153
     2 PU_SPI0_RST @BASEBOARD_FAB2_LIB.BASEBOARD_FAB2(SCH_1):PU_SPI0_RST    I90 @BASEBOARD_FAB2_LIB.BASEBOARD_FAB2(SCH_1):PAGE153

R7F7 RES_0402-2.2,5%,1/16W,EMPTY,G2A
     1 VR_PVPP_ABC_SNUB @BASEBOARD_FAB2_LIB.BASEBOARD_FAB2(SCH_1):VR_PVPP_ABC_SNUB   I174 @BASEBOARD_FAB2_LIB.BASEBOARD_FAB2(SCH_1):PAGE231
     2    GND @BASEBOARD_FAB2_LIB.BASEBOARD_FAB2(SCH_1):GND   I174 @BASEBOARD_FAB2_LIB.BASEBOARD_FAB2(SCH_1):PAGE231

R7F8 RES_0402-0.0,5%,1/16W,CHIP,G21A
     1 VR_PVPP_ABC_BOOT @BASEBOARD_FAB2_LIB.BASEBOARD_FAB2(SCH_1):VR_PVPP_ABC_BOOT   I154 @BASEBOARD_FAB2_LIB.BASEBOARD_FAB2(SCH_1):PAGE231
     2 VR_PVPP_ABC_BOOT_R @BASEBOARD_FAB2_LIB.BASEBOARD_FAB2(SCH_1):VR_PVPP_ABC_BOOT_R   I154 @BASEBOARD_FAB2_LIB.BASEBOARD_FAB2(SCH_1):PAGE231

R7F9 RES_0402-0.0,5%,1/16W,CHIP,G21A
     1 FM_PVPP_CPU0_EN @BASEBOARD_FAB2_LIB.BASEBOARD_FAB2(SCH_1):FM_PVPP_CPU0_EN   I220 @BASEBOARD_FAB2_LIB.BASEBOARD_FAB2(SCH_1):PAGE231
     2 FM_PVPP_PVDDQ_CPU0_EN_ABC @BASEBOARD_FAB2_LIB.BASEBOARD_FAB2(SCH_1):FM_PVPP_PVDDQ_CPU0_EN_ABC   I220 @BASEBOARD_FAB2_LIB.BASEBOARD_FAB2(SCH_1):PAGE231

R7F10 RES_0603-120.0,1%,1/10W,CHIP,GA
     1 PVPP_ABC @BASEBOARD_FAB2_LIB.BASEBOARD_FAB2(SCH_1):PVPP_ABC   I177 @BASEBOARD_FAB2_LIB.BASEBOARD_FAB2(SCH_1):PAGE231
     2    GND @BASEBOARD_FAB2_LIB.BASEBOARD_FAB2(SCH_1):GND   I177 @BASEBOARD_FAB2_LIB.BASEBOARD_FAB2(SCH_1):PAGE231

R7F11 RES_0402-6.34K,1%,1/16W,CHIP,GA
     1 VR_FB_PVPP_ABC @BASEBOARD_FAB2_LIB.BASEBOARD_FAB2(SCH_1):VR_FB_PVPP_ABC   I166 @BASEBOARD_FAB2_LIB.BASEBOARD_FAB2(SCH_1):PAGE231
     2 AGND_PVPP_ABC @BASEBOARD_FAB2_LIB.BASEBOARD_FAB2(SCH_1):AGND_PVPP_ABC   I166 @BASEBOARD_FAB2_LIB.BASEBOARD_FAB2(SCH_1):PAGE231

R7F12 RES_0402-0.0,5%,1/16W,CHIP,G21A
     1 PVPP_ABC @BASEBOARD_FAB2_LIB.BASEBOARD_FAB2(SCH_1):PVPP_ABC   I168 @BASEBOARD_FAB2_LIB.BASEBOARD_FAB2(SCH_1):PAGE231
     2 VSENSE_PVPP_ABC @BASEBOARD_FAB2_LIB.BASEBOARD_FAB2(SCH_1):VSENSE_PVPP_ABC   I168 @BASEBOARD_FAB2_LIB.BASEBOARD_FAB2(SCH_1):PAGE231

R7F13 RES_0402-20.0K,1%,1/16W,CHIP,GA
     1 VSENSE_PVPP_ABC @BASEBOARD_FAB2_LIB.BASEBOARD_FAB2(SCH_1):VSENSE_PVPP_ABC   I167 @BASEBOARD_FAB2_LIB.BASEBOARD_FAB2(SCH_1):PAGE231
     2 VR_FB_PVPP_ABC @BASEBOARD_FAB2_LIB.BASEBOARD_FAB2(SCH_1):VR_FB_PVPP_ABC   I167 @BASEBOARD_FAB2_LIB.BASEBOARD_FAB2(SCH_1):PAGE231

R7F14 RES_0402-10.0K,1%,1/16W,CHIP,GA
     1 FM_PVPP_CPU0_EN @BASEBOARD_FAB2_LIB.BASEBOARD_FAB2(SCH_1):FM_PVPP_CPU0_EN   I136 @BASEBOARD_FAB2_LIB.BASEBOARD_FAB2(SCH_1):PAGE231
     2    GND @BASEBOARD_FAB2_LIB.BASEBOARD_FAB2(SCH_1):GND   I136 @BASEBOARD_FAB2_LIB.BASEBOARD_FAB2(SCH_1):PAGE231

R7F15 RES_0402-7.87K,1.0%,1/16W,CHIPA
     1 VR_PVPP_ABC_ISET @BASEBOARD_FAB2_LIB.BASEBOARD_FAB2(SCH_1):VR_PVPP_ABC_ISET   I134 @BASEBOARD_FAB2_LIB.BASEBOARD_FAB2(SCH_1):PAGE231
     2 AGND_PVPP_ABC @BASEBOARD_FAB2_LIB.BASEBOARD_FAB2(SCH_1):AGND_PVPP_ABC   I134 @BASEBOARD_FAB2_LIB.BASEBOARD_FAB2(SCH_1):PAGE231

R7F16 RES_0402-22.1,1.0%,1/16W,CHIP,A
     1 PWRGD_PVPP_ABC_R @BASEBOARD_FAB2_LIB.BASEBOARD_FAB2(SCH_1):PWRGD_PVPP_ABC_R   I208 @BASEBOARD_FAB2_LIB.BASEBOARD_FAB2(SCH_1):PAGE231
     2 PWRGD_PVPP_ABC @BASEBOARD_FAB2_LIB.BASEBOARD_FAB2(SCH_1):PWRGD_PVPP_ABC   I208 @BASEBOARD_FAB2_LIB.BASEBOARD_FAB2(SCH_1):PAGE231

R7F17 RES_0402-1.0K,0.1%,1/16W,CHIP,A
     1 VSENSE_PVPP_ABC @BASEBOARD_FAB2_LIB.BASEBOARD_FAB2(SCH_1):VSENSE_PVPP_ABC   I218 @BASEBOARD_FAB2_LIB.BASEBOARD_FAB2(SCH_1):PAGE231
     2 VR_COMP_PVPP_ABC @BASEBOARD_FAB2_LIB.BASEBOARD_FAB2(SCH_1):VR_COMP_PVPP_ABC   I218 @BASEBOARD_FAB2_LIB.BASEBOARD_FAB2(SCH_1):PAGE231

R7F18 RES_0402-7.87K,1.0%,1/16W,CHIPA
     1 VR_COMP_RC_PVPP_ABC @BASEBOARD_FAB2_LIB.BASEBOARD_FAB2(SCH_1):VR_COMP_RC_PVPP_ABC   I201 @BASEBOARD_FAB2_LIB.BASEBOARD_FAB2(SCH_1):PAGE231
     2 VR_FB_PVPP_ABC @BASEBOARD_FAB2_LIB.BASEBOARD_FAB2(SCH_1):VR_FB_PVPP_ABC   I201 @BASEBOARD_FAB2_LIB.BASEBOARD_FAB2(SCH_1):PAGE231

R7F19 RES_0402-1.00K,1%,1/16W,CHIP,GA
     1 P3V3_STBY @BASEBOARD_FAB2_LIB.BASEBOARD_FAB2(SCH_1):P3V3_STBY   I143 @BASEBOARD_FAB2_LIB.BASEBOARD_FAB2(SCH_1):PAGE231
     2 PWRGD_PVPP_ABC_R @BASEBOARD_FAB2_LIB.BASEBOARD_FAB2(SCH_1):PWRGD_PVPP_ABC_R   I143 @BASEBOARD_FAB2_LIB.BASEBOARD_FAB2(SCH_1):PAGE231

R7F20 RES_0402-100.0K,1%,1/16W,EMPTYA
     1 P3V3_STBY @BASEBOARD_FAB2_LIB.BASEBOARD_FAB2(SCH_1):P3V3_STBY   I315 @BASEBOARD_FAB2_LIB.BASEBOARD_FAB2(SCH_1):PAGE215
     2 VR_PVDDQ_ABC_VREN @BASEBOARD_FAB2_LIB.BASEBOARD_FAB2(SCH_1):VR_PVDDQ_ABC_VREN   I315 @BASEBOARD_FAB2_LIB.BASEBOARD_FAB2(SCH_1):PAGE215

R7F21 RES_0402-0.0,5%,1/16W,CHIP,G21A
     1 FM_PVDDQ_ABC_EN @BASEBOARD_FAB2_LIB.BASEBOARD_FAB2(SCH_1):FM_PVDDQ_ABC_EN   I343 @BASEBOARD_FAB2_LIB.BASEBOARD_FAB2(SCH_1):PAGE215
     2 VR_PVDDQ_ABC_VREN @BASEBOARD_FAB2_LIB.BASEBOARD_FAB2(SCH_1):VR_PVDDQ_ABC_VREN   I343 @BASEBOARD_FAB2_LIB.BASEBOARD_FAB2(SCH_1):PAGE215

R7F22 RES_0402-1.00K,1%,1/16W,CHIP,GA
     1 P3V3_STBY @BASEBOARD_FAB2_LIB.BASEBOARD_FAB2(SCH_1):P3V3_STBY   I301 @BASEBOARD_FAB2_LIB.BASEBOARD_FAB2(SCH_1):PAGE215
     2 PWRGD_PVDDQ_ABC_R @BASEBOARD_FAB2_LIB.BASEBOARD_FAB2(SCH_1):PWRGD_PVDDQ_ABC_R   I301 @BASEBOARD_FAB2_LIB.BASEBOARD_FAB2(SCH_1):PAGE215

R7F23 RES_0402-33.2,1%,1/16W,CHIP,G2A
     1 IRQ_PVDDQ_ABC_VRHOT_LVT3_R_N @BASEBOARD_FAB2_LIB.BASEBOARD_FAB2(SCH_1):IRQ_PVDDQ_ABC_VRHOT_LVT3_R_N   I297 @BASEBOARD_FAB2_LIB.BASEBOARD_FAB2(SCH_1):PAGE215
     2 IRQ_PVDDQ_ABC_VRHOT_LVT3_N @BASEBOARD_FAB2_LIB.BASEBOARD_FAB2(SCH_1):IRQ_PVDDQ_ABC_VRHOT_LVT3_N   I297 @BASEBOARD_FAB2_LIB.BASEBOARD_FAB2(SCH_1):PAGE215

R7F24 RES_0402-22.1,1.0%,1/16W,CHIP,A
     1 PWRGD_PVDDQ_ABC_R @BASEBOARD_FAB2_LIB.BASEBOARD_FAB2(SCH_1):PWRGD_PVDDQ_ABC_R   I296 @BASEBOARD_FAB2_LIB.BASEBOARD_FAB2(SCH_1):PAGE215
     2 PWRGD_PVDDQ_ABC @BASEBOARD_FAB2_LIB.BASEBOARD_FAB2(SCH_1):PWRGD_PVDDQ_ABC   I296 @BASEBOARD_FAB2_LIB.BASEBOARD_FAB2(SCH_1):PAGE215

R7F25 RES_0402-20.0,1%,1/16W,CHIP,G2A
     1 SMB_VR_SCL_VDDQ_ABC @BASEBOARD_FAB2_LIB.BASEBOARD_FAB2(SCH_1):SMB_VR_SCL_VDDQ_ABC   I298 @BASEBOARD_FAB2_LIB.BASEBOARD_FAB2(SCH_1):PAGE215
     2 SMB_VR_STBY_LVC3_SCL @BASEBOARD_FAB2_LIB.BASEBOARD_FAB2(SCH_1):SMB_VR_STBY_LVC3_SCL   I298 @BASEBOARD_FAB2_LIB.BASEBOARD_FAB2(SCH_1):PAGE215

R7F26 RES_0402-20.0,1%,1/16W,CHIP,G2A
     1 SMB_VR_SDA_VDDQ_ABC @BASEBOARD_FAB2_LIB.BASEBOARD_FAB2(SCH_1):SMB_VR_SDA_VDDQ_ABC   I304 @BASEBOARD_FAB2_LIB.BASEBOARD_FAB2(SCH_1):PAGE215
     2 SMB_VR_STBY_LVC3_SDA @BASEBOARD_FAB2_LIB.BASEBOARD_FAB2(SCH_1):SMB_VR_STBY_LVC3_SDA   I304 @BASEBOARD_FAB2_LIB.BASEBOARD_FAB2(SCH_1):PAGE215

R7F27 RES_0402-1.00K,1%,1/16W,CHIP,GA
     1 P3V3_STBY @BASEBOARD_FAB2_LIB.BASEBOARD_FAB2(SCH_1):P3V3_STBY   I303 @BASEBOARD_FAB2_LIB.BASEBOARD_FAB2(SCH_1):PAGE215
     2 IRQ_PVDDQ_ABC_VRHOT_LVT3_R_N @BASEBOARD_FAB2_LIB.BASEBOARD_FAB2(SCH_1):IRQ_PVDDQ_ABC_VRHOT_LVT3_R_N   I303 @BASEBOARD_FAB2_LIB.BASEBOARD_FAB2(SCH_1):PAGE215

R7F28 RES_0402-10.0K,1%,1/16W,CHIP,GA
     1 P3V3_STBY @BASEBOARD_FAB2_LIB.BASEBOARD_FAB2(SCH_1):P3V3_STBY   I168 @BASEBOARD_FAB2_LIB.BASEBOARD_FAB2(SCH_1):PAGE153
     2 PU_BIOS_SPI_WP0_N @BASEBOARD_FAB2_LIB.BASEBOARD_FAB2(SCH_1):PU_BIOS_SPI_WP0_N   I168 @BASEBOARD_FAB2_LIB.BASEBOARD_FAB2(SCH_1):PAGE153

R7F29 RES_0402-33.2,1%,1/16W,CHIP,G2A
     1 SPI_SWITCH_MOSI @BASEBOARD_FAB2_LIB.BASEBOARD_FAB2(SCH_1):SPI_SWITCH_MOSI   I181 @BASEBOARD_FAB2_LIB.BASEBOARD_FAB2(SCH_1):PAGE153
     2 SPI_SWITCH_MOSI_R0 @BASEBOARD_FAB2_LIB.BASEBOARD_FAB2(SCH_1):SPI_SWITCH_MOSI_R0   I181 @BASEBOARD_FAB2_LIB.BASEBOARD_FAB2(SCH_1):PAGE153

R7F30 RES_0402-10.0K,1%,1/16W,EMPTY,A
     1 PU_BIOS_SPI_WP0_N @BASEBOARD_FAB2_LIB.BASEBOARD_FAB2(SCH_1):PU_BIOS_SPI_WP0_N   I170 @BASEBOARD_FAB2_LIB.BASEBOARD_FAB2(SCH_1):PAGE153
     2    GND @BASEBOARD_FAB2_LIB.BASEBOARD_FAB2(SCH_1):GND   I170 @BASEBOARD_FAB2_LIB.BASEBOARD_FAB2(SCH_1):PAGE153

R7F32 RES_0402-10.0K,1%,1/16W,CHIP,GA
     1 P3V3_STBY @BASEBOARD_FAB2_LIB.BASEBOARD_FAB2(SCH_1):P3V3_STBY   I140 @BASEBOARD_FAB2_LIB.BASEBOARD_FAB2(SCH_1):PAGE153
     2 PU_BIOS_SPI_HOLD0_N @BASEBOARD_FAB2_LIB.BASEBOARD_FAB2(SCH_1):PU_BIOS_SPI_HOLD0_N   I140 @BASEBOARD_FAB2_LIB.BASEBOARD_FAB2(SCH_1):PAGE153

R7F33 RES_0402-4.75K,1%,1/16W,CHIP,GA
     1 P5V_STBY @BASEBOARD_FAB2_LIB.BASEBOARD_FAB2(SCH_1):P5V_STBY    I65 @BASEBOARD_FAB2_LIB.BASEBOARD_FAB2(SCH_1):PAGE161
     2 FAN_PWM_OUT_SYS1_R @BASEBOARD_FAB2_LIB.BASEBOARD_FAB2(SCH_1):FAN_PWM_OUT_SYS1_R    I65 @BASEBOARD_FAB2_LIB.BASEBOARD_FAB2(SCH_1):PAGE161

R7F34 RES_0402-100.0K,1%,1/16W,CHIP,B
     1 VR_FET_SW_P12V_STBY_PVDDQ_ABC @BASEBOARD_FAB2_LIB.BASEBOARD_FAB2(SCH_1):VR_FET_SW_P12V_STBY_PVDDQ_ABC   I336 @BASEBOARD_FAB2_LIB.BASEBOARD_FAB2(SCH_1):PAGE215
     2 VR_PVDDQ_ABC_VINSEN @BASEBOARD_FAB2_LIB.BASEBOARD_FAB2(SCH_1):VR_PVDDQ_ABC_VINSEN   I336 @BASEBOARD_FAB2_LIB.BASEBOARD_FAB2(SCH_1):PAGE215

R7F35 RES_0402-0.0,5%,1/16W,CHIP,G21A
     1    GND @BASEBOARD_FAB2_LIB.BASEBOARD_FAB2(SCH_1):GND   I170 @BASEBOARD_FAB2_LIB.BASEBOARD_FAB2(SCH_1):PAGE231
     2 AGND_PVPP_ABC @BASEBOARD_FAB2_LIB.BASEBOARD_FAB2(SCH_1):AGND_PVPP_ABC   I170 @BASEBOARD_FAB2_LIB.BASEBOARD_FAB2(SCH_1):PAGE231

R7F36 RES_0402-2.26K,1.0%,1/16W,EMPTA
     1 P3V3_STBY @BASEBOARD_FAB2_LIB.BASEBOARD_FAB2(SCH_1):P3V3_STBY   I300 @BASEBOARD_FAB2_LIB.BASEBOARD_FAB2(SCH_1):PAGE215
     2 PU_VR_PVDDQ_ABC_FAULT1 @BASEBOARD_FAB2_LIB.BASEBOARD_FAB2(SCH_1):PU_VR_PVDDQ_ABC_FAULT1   I300 @BASEBOARD_FAB2_LIB.BASEBOARD_FAB2(SCH_1):PAGE215

R7F37 RES_0402-33.2,1%,1/16W,CHIP,G2A
     1 SPI_BIOS_SOCKET_IO2 @BASEBOARD_FAB2_LIB.BASEBOARD_FAB2(SCH_1):SPI_BIOS_SOCKET_IO2   I108 @BASEBOARD_FAB2_LIB.BASEBOARD_FAB2(SCH_1):PAGE153
     2 PU_BIOS_SPI_WP0_N @BASEBOARD_FAB2_LIB.BASEBOARD_FAB2(SCH_1):PU_BIOS_SPI_WP0_N   I108 @BASEBOARD_FAB2_LIB.BASEBOARD_FAB2(SCH_1):PAGE153

R7G2 RES_0402-0.0,5%,1/16W,CHIP,G21A
     1 SVID_VDIO_PVDDQ_ABC @BASEBOARD_FAB2_LIB.BASEBOARD_FAB2(SCH_1):SVID_VDIO_PVDDQ_ABC   I307 @BASEBOARD_FAB2_LIB.BASEBOARD_FAB2(SCH_1):PAGE215
     2 SVID_DIO1_CPU0_R @BASEBOARD_FAB2_LIB.BASEBOARD_FAB2(SCH_1):SVID_DIO1_CPU0_R   I307 @BASEBOARD_FAB2_LIB.BASEBOARD_FAB2(SCH_1):PAGE215

R7G3 RES_0402-1.5K,1%,1/16W,CHIP,G2A
     1 VR_PVDDQ_ABC_VINSEN @BASEBOARD_FAB2_LIB.BASEBOARD_FAB2(SCH_1):VR_PVDDQ_ABC_VINSEN   I337 @BASEBOARD_FAB2_LIB.BASEBOARD_FAB2(SCH_1):PAGE215
     2    GND @BASEBOARD_FAB2_LIB.BASEBOARD_FAB2(SCH_1):GND   I337 @BASEBOARD_FAB2_LIB.BASEBOARD_FAB2(SCH_1):PAGE215

R7G4 RES_0402-0.0,5%,1/16W,CHIP,G21A
     1 SVID_ALERT_PVDDQ_ABC @BASEBOARD_FAB2_LIB.BASEBOARD_FAB2(SCH_1):SVID_ALERT_PVDDQ_ABC   I302 @BASEBOARD_FAB2_LIB.BASEBOARD_FAB2(SCH_1):PAGE215
     2 SVID_ALERT1_CPU0_R_N @BASEBOARD_FAB2_LIB.BASEBOARD_FAB2(SCH_1):SVID_ALERT1_CPU0_R_N   I302 @BASEBOARD_FAB2_LIB.BASEBOARD_FAB2(SCH_1):PAGE215

R7G7 RES_0402-4.75K,1%,1/16W,CHIP,GA
     1   P3V3 @BASEBOARD_FAB2_LIB.BASEBOARD_FAB2(SCH_1):P3V3    I51 @BASEBOARD_FAB2_LIB.BASEBOARD_FAB2(SCH_1):PAGE94
     2 H_CPU0_MEMABC_MEMHOT @BASEBOARD_FAB2_LIB.BASEBOARD_FAB2(SCH_1):H_CPU0_MEMABC_MEMHOT    I51 @BASEBOARD_FAB2_LIB.BASEBOARD_FAB2(SCH_1):PAGE94

R7G8 RES_0402-4.02K,1%,1/16W,CHIP,GA
     1 VR_PVDDQ_ABC_XADDR1 @BASEBOARD_FAB2_LIB.BASEBOARD_FAB2(SCH_1):VR_PVDDQ_ABC_XADDR1   I321 @BASEBOARD_FAB2_LIB.BASEBOARD_FAB2(SCH_1):PAGE215
     2    GND @BASEBOARD_FAB2_LIB.BASEBOARD_FAB2(SCH_1):GND   I321 @BASEBOARD_FAB2_LIB.BASEBOARD_FAB2(SCH_1):PAGE215

R7G9 RES_0402-10.0,1%,1/16W,CHIP,G2A
     1 VSENSE_PVDDQ_ABC_P @BASEBOARD_FAB2_LIB.BASEBOARD_FAB2(SCH_1):VSENSE_PVDDQ_ABC_P   I344 @BASEBOARD_FAB2_LIB.BASEBOARD_FAB2(SCH_1):PAGE215
     2 VR_PVDDQ_ABC_AVSP @BASEBOARD_FAB2_LIB.BASEBOARD_FAB2(SCH_1):VR_PVDDQ_ABC_AVSP   I344 @BASEBOARD_FAB2_LIB.BASEBOARD_FAB2(SCH_1):PAGE215

R7G10 RES_0402-8.06K,1%,1/16W,CHIP,GA
     1 VR_PVDDQ_ABC_XADDR2 @BASEBOARD_FAB2_LIB.BASEBOARD_FAB2(SCH_1):VR_PVDDQ_ABC_XADDR2   I317 @BASEBOARD_FAB2_LIB.BASEBOARD_FAB2(SCH_1):PAGE215
     2    GND @BASEBOARD_FAB2_LIB.BASEBOARD_FAB2(SCH_1):GND   I317 @BASEBOARD_FAB2_LIB.BASEBOARD_FAB2(SCH_1):PAGE215

R7G14 RES_0402-0.0,5%,1/16W,CHIP,G21A
     1 JTAG_PLD_TDO @BASEBOARD_FAB2_LIB.BASEBOARD_FAB2(SCH_1):JTAG_PLD_TDO    I38 @BASEBOARD_FAB2_LIB.BASEBOARD_FAB2(SCH_1):PAGE189
     2 JTAG_TDO @BASEBOARD_FAB2_LIB.BASEBOARD_FAB2(SCH_1):JTAG_TDO    I38 @BASEBOARD_FAB2_LIB.BASEBOARD_FAB2(SCH_1):PAGE189

R7G15 RES_0402-0.0,5%,1/16W,EMPTY,G2A
     1 JTAG_PCH_PLD_TDO @BASEBOARD_FAB2_LIB.BASEBOARD_FAB2(SCH_1):JTAG_PCH_PLD_TDO    I36 @BASEBOARD_FAB2_LIB.BASEBOARD_FAB2(SCH_1):PAGE189
     2 JTAG_TDO @BASEBOARD_FAB2_LIB.BASEBOARD_FAB2(SCH_1):JTAG_TDO    I36 @BASEBOARD_FAB2_LIB.BASEBOARD_FAB2(SCH_1):PAGE189

R7G16 RES_0402-0.0,5%,1/16W,EMPTY,G2A
     1 JTAG_PCH_GBE_TDO @BASEBOARD_FAB2_LIB.BASEBOARD_FAB2(SCH_1):JTAG_PCH_GBE_TDO    I27 @BASEBOARD_FAB2_LIB.BASEBOARD_FAB2(SCH_1):PAGE189
     2 JTAG_TDO @BASEBOARD_FAB2_LIB.BASEBOARD_FAB2(SCH_1):JTAG_TDO    I27 @BASEBOARD_FAB2_LIB.BASEBOARD_FAB2(SCH_1):PAGE189

R7G17 RES_0402-0.0,5%,1/16W,CHIP,G21A
     1 JTAG_BMC_TDO @BASEBOARD_FAB2_LIB.BASEBOARD_FAB2(SCH_1):JTAG_BMC_TDO    I37 @BASEBOARD_FAB2_LIB.BASEBOARD_FAB2(SCH_1):PAGE189
     2 JTAG_TDO @BASEBOARD_FAB2_LIB.BASEBOARD_FAB2(SCH_1):JTAG_TDO    I37 @BASEBOARD_FAB2_LIB.BASEBOARD_FAB2(SCH_1):PAGE189

R7G18 RES_0402-0.0,5%,1/16W,EMPTY,G2A
     1 JTAG_PCH_PLD_TDI @BASEBOARD_FAB2_LIB.BASEBOARD_FAB2(SCH_1):JTAG_PCH_PLD_TDI    I13 @BASEBOARD_FAB2_LIB.BASEBOARD_FAB2(SCH_1):PAGE189
     2 JTAG_TDI @BASEBOARD_FAB2_LIB.BASEBOARD_FAB2(SCH_1):JTAG_TDI    I13 @BASEBOARD_FAB2_LIB.BASEBOARD_FAB2(SCH_1):PAGE189

R7G19 RES_0402-0.0,5%,1/16W,EMPTY,G2A
     1 JTAG_PCH_GBE_TDI @BASEBOARD_FAB2_LIB.BASEBOARD_FAB2(SCH_1):JTAG_PCH_GBE_TDI     I8 @BASEBOARD_FAB2_LIB.BASEBOARD_FAB2(SCH_1):PAGE189
     2 JTAG_TDI @BASEBOARD_FAB2_LIB.BASEBOARD_FAB2(SCH_1):JTAG_TDI     I8 @BASEBOARD_FAB2_LIB.BASEBOARD_FAB2(SCH_1):PAGE189

R7G21 RES_0402-0.0,5%,1/16W,CHIP,G21A
     1 JTAG_TDO @BASEBOARD_FAB2_LIB.BASEBOARD_FAB2(SCH_1):JTAG_TDO    I63 @BASEBOARD_FAB2_LIB.BASEBOARD_FAB2(SCH_1):PAGE189
     2 JTAG_TDO_R @BASEBOARD_FAB2_LIB.BASEBOARD_FAB2(SCH_1):JTAG_TDO_R    I63 @BASEBOARD_FAB2_LIB.BASEBOARD_FAB2(SCH_1):PAGE189

R7G22 RES_0402-10.0K,1%,1/16W,CHIP,GA
     1 P3V3_STBY @BASEBOARD_FAB2_LIB.BASEBOARD_FAB2(SCH_1):P3V3_STBY    I53 @BASEBOARD_FAB2_LIB.BASEBOARD_FAB2(SCH_1):PAGE189
     2 JTAG_TDO_R @BASEBOARD_FAB2_LIB.BASEBOARD_FAB2(SCH_1):JTAG_TDO_R    I53 @BASEBOARD_FAB2_LIB.BASEBOARD_FAB2(SCH_1):PAGE189

R7G23 RES_0402-10.0K,1%,1/16W,CHIP,GA
     1 P3V3_STBY @BASEBOARD_FAB2_LIB.BASEBOARD_FAB2(SCH_1):P3V3_STBY    I51 @BASEBOARD_FAB2_LIB.BASEBOARD_FAB2(SCH_1):PAGE189
     2 JTAG_TDI_R @BASEBOARD_FAB2_LIB.BASEBOARD_FAB2(SCH_1):JTAG_TDI_R    I51 @BASEBOARD_FAB2_LIB.BASEBOARD_FAB2(SCH_1):PAGE189

R7G24 RES_0402-150.0,1%,1/16W,CHIP,GA
     1 SVID_CLK1_CPU0_R @BASEBOARD_FAB2_LIB.BASEBOARD_FAB2(SCH_1):SVID_CLK1_CPU0_R   I331 @BASEBOARD_FAB2_LIB.BASEBOARD_FAB2(SCH_1):PAGE215
     2 SVID_CLK_PVDDQ_ABC @BASEBOARD_FAB2_LIB.BASEBOARD_FAB2(SCH_1):SVID_CLK_PVDDQ_ABC   I331 @BASEBOARD_FAB2_LIB.BASEBOARD_FAB2(SCH_1):PAGE215

R7G25 RES_0402-68.1K,1%,1/16W,EMPTY,A
     1 VR_PVDDQ_ABC_PH1_OCSET @BASEBOARD_FAB2_LIB.BASEBOARD_FAB2(SCH_1):VR_PVDDQ_ABC_PH1_OCSET   I104 @BASEBOARD_FAB2_LIB.BASEBOARD_FAB2(SCH_1):PAGE216
     2    GND @BASEBOARD_FAB2_LIB.BASEBOARD_FAB2(SCH_1):GND   I104 @BASEBOARD_FAB2_LIB.BASEBOARD_FAB2(SCH_1):PAGE216

R7G26 RES_0402-10.0K,1%,1/16W,CHIP,GA
     1 P3V3_STBY @BASEBOARD_FAB2_LIB.BASEBOARD_FAB2(SCH_1):P3V3_STBY   I101 @BASEBOARD_FAB2_LIB.BASEBOARD_FAB2(SCH_1):PAGE136
     2 FM_ME_RECOVER_N @BASEBOARD_FAB2_LIB.BASEBOARD_FAB2(SCH_1):FM_ME_RECOVER_N   I101 @BASEBOARD_FAB2_LIB.BASEBOARD_FAB2(SCH_1):PAGE136

R7G27 RES_0402-1.00K,1%,1/16W,CHIP,GA
     1 P3V3_STBY @BASEBOARD_FAB2_LIB.BASEBOARD_FAB2(SCH_1):P3V3_STBY   I155 @BASEBOARD_FAB2_LIB.BASEBOARD_FAB2(SCH_1):PAGE136
     2 PU_BIOS_USB_RECOVERY @BASEBOARD_FAB2_LIB.BASEBOARD_FAB2(SCH_1):PU_BIOS_USB_RECOVERY   I155 @BASEBOARD_FAB2_LIB.BASEBOARD_FAB2(SCH_1):PAGE136

R7G28 RES_0402-1.00K,1%,1/16W,CHIP,GA
     1 PD_ME_RCVR_N @BASEBOARD_FAB2_LIB.BASEBOARD_FAB2(SCH_1):PD_ME_RCVR_N   I102 @BASEBOARD_FAB2_LIB.BASEBOARD_FAB2(SCH_1):PAGE136
     2    GND @BASEBOARD_FAB2_LIB.BASEBOARD_FAB2(SCH_1):GND   I102 @BASEBOARD_FAB2_LIB.BASEBOARD_FAB2(SCH_1):PAGE136

R7G29 RES_0402-1.00K,1%,1/16W,CHIP,GA
     1 PD_PASSWORD_CLEAR @BASEBOARD_FAB2_LIB.BASEBOARD_FAB2(SCH_1):PD_PASSWORD_CLEAR   I148 @BASEBOARD_FAB2_LIB.BASEBOARD_FAB2(SCH_1):PAGE136
     2    GND @BASEBOARD_FAB2_LIB.BASEBOARD_FAB2(SCH_1):GND   I148 @BASEBOARD_FAB2_LIB.BASEBOARD_FAB2(SCH_1):PAGE136

R7G30 RES_0402-68.1K,1%,1/16W,EMPTY,A
     1 VR_PVDDQ_ABC_PH2_OCSET @BASEBOARD_FAB2_LIB.BASEBOARD_FAB2(SCH_1):VR_PVDDQ_ABC_PH2_OCSET   I106 @BASEBOARD_FAB2_LIB.BASEBOARD_FAB2(SCH_1):PAGE216
     2    GND @BASEBOARD_FAB2_LIB.BASEBOARD_FAB2(SCH_1):GND   I106 @BASEBOARD_FAB2_LIB.BASEBOARD_FAB2(SCH_1):PAGE216

R7G31 RES_0402-1.00K,1%,1/16W,CHIP,GA
     1 P3V3_STBY @BASEBOARD_FAB2_LIB.BASEBOARD_FAB2(SCH_1):P3V3_STBY   I139 @BASEBOARD_FAB2_LIB.BASEBOARD_FAB2(SCH_1):PAGE136
     2 PU_BIOS_RECOVER_BOOT @BASEBOARD_FAB2_LIB.BASEBOARD_FAB2(SCH_1):PU_BIOS_RECOVER_BOOT   I139 @BASEBOARD_FAB2_LIB.BASEBOARD_FAB2(SCH_1):PAGE136

R7L2 RES_0402-100.0,1%,1/16W,EMPTY,A
     1 VSENSE_PVDDQ_KLM_P @BASEBOARD_FAB2_LIB.BASEBOARD_FAB2(SCH_1):VSENSE_PVDDQ_KLM_P    I74 @BASEBOARD_FAB2_LIB.BASEBOARD_FAB2(SCH_1):PAGE228
     2 VSENSE_PVDDQ_KLM_N @BASEBOARD_FAB2_LIB.BASEBOARD_FAB2(SCH_1):VSENSE_PVDDQ_KLM_N    I74 @BASEBOARD_FAB2_LIB.BASEBOARD_FAB2(SCH_1):PAGE228

R7M1 RES_0402-665,1.0%,1/16W,CHIP,GA
     1 PVPP_KLM @BASEBOARD_FAB2_LIB.BASEBOARD_FAB2(SCH_1):PVPP_KLM   I109 @BASEBOARD_FAB2_LIB.BASEBOARD_FAB2(SCH_1):PAGE99
     2 SMB_DDR_KLM_VPP_SCL_R @BASEBOARD_FAB2_LIB.BASEBOARD_FAB2(SCH_1):SMB_DDR_KLM_VPP_SCL_R   I109 @BASEBOARD_FAB2_LIB.BASEBOARD_FAB2(SCH_1):PAGE99

R7M2 RES_0402-240,1.0%,1/16W,CHIP,GA
     1 PVCCIO_CPU1 @BASEBOARD_FAB2_LIB.BASEBOARD_FAB2(SCH_1):PVCCIO_CPU1    I79 @BASEBOARD_FAB2_LIB.BASEBOARD_FAB2(SCH_1):PAGE99
     2 SMB_DDR_KLM_SCL_G @BASEBOARD_FAB2_LIB.BASEBOARD_FAB2(SCH_1):SMB_DDR_KLM_SCL_G    I79 @BASEBOARD_FAB2_LIB.BASEBOARD_FAB2(SCH_1):PAGE99

R7M3 RES_0402-10.0,1%,1/16W,CHIP,G2A
     1 SMB_DDR_KLM_SCL_G_R @BASEBOARD_FAB2_LIB.BASEBOARD_FAB2(SCH_1):SMB_DDR_KLM_SCL_G_R    I98 @BASEBOARD_FAB2_LIB.BASEBOARD_FAB2(SCH_1):PAGE99
     2 SMB_DDR_KLM_SCL_G @BASEBOARD_FAB2_LIB.BASEBOARD_FAB2(SCH_1):SMB_DDR_KLM_SCL_G    I98 @BASEBOARD_FAB2_LIB.BASEBOARD_FAB2(SCH_1):PAGE99

R7M4 RES_0402-20.0,1%,1/16W,CHIP,G2A
     1 SMB_DDR_KLM_VPP_SCL_R @BASEBOARD_FAB2_LIB.BASEBOARD_FAB2(SCH_1):SMB_DDR_KLM_VPP_SCL_R    I56 @BASEBOARD_FAB2_LIB.BASEBOARD_FAB2(SCH_1):PAGE99
     2 SMB_DDR_KLM_VPP_SCL @BASEBOARD_FAB2_LIB.BASEBOARD_FAB2(SCH_1):SMB_DDR_KLM_VPP_SCL    I56 @BASEBOARD_FAB2_LIB.BASEBOARD_FAB2(SCH_1):PAGE99

R7M5 RES_0402-20.0,1%,1/16W,CHIP,G2A
     1 SMB_DDR_KLM_VPP_SDA_R @BASEBOARD_FAB2_LIB.BASEBOARD_FAB2(SCH_1):SMB_DDR_KLM_VPP_SDA_R    I55 @BASEBOARD_FAB2_LIB.BASEBOARD_FAB2(SCH_1):PAGE99
     2 SMB_DDR_KLM_VPP_SDA @BASEBOARD_FAB2_LIB.BASEBOARD_FAB2(SCH_1):SMB_DDR_KLM_VPP_SDA    I55 @BASEBOARD_FAB2_LIB.BASEBOARD_FAB2(SCH_1):PAGE99

R7M6 RES_0402-665,1.0%,1/16W,CHIP,GA
     1 PVPP_KLM @BASEBOARD_FAB2_LIB.BASEBOARD_FAB2(SCH_1):PVPP_KLM   I107 @BASEBOARD_FAB2_LIB.BASEBOARD_FAB2(SCH_1):PAGE99
     2 SMB_DDR_KLM_VPP_SDA_R @BASEBOARD_FAB2_LIB.BASEBOARD_FAB2(SCH_1):SMB_DDR_KLM_VPP_SDA_R   I107 @BASEBOARD_FAB2_LIB.BASEBOARD_FAB2(SCH_1):PAGE99

R7M7 RES_0402-240,1.0%,1/16W,CHIP,GA
     1 PVCCIO_CPU1 @BASEBOARD_FAB2_LIB.BASEBOARD_FAB2(SCH_1):PVCCIO_CPU1    I77 @BASEBOARD_FAB2_LIB.BASEBOARD_FAB2(SCH_1):PAGE99
     2 SMB_DDR_KLM_SDA_G @BASEBOARD_FAB2_LIB.BASEBOARD_FAB2(SCH_1):SMB_DDR_KLM_SDA_G    I77 @BASEBOARD_FAB2_LIB.BASEBOARD_FAB2(SCH_1):PAGE99

R7M8 RES_0402-10.0,1%,1/16W,CHIP,G2A
     1 SMB_DDR_KLM_SDA_G_R @BASEBOARD_FAB2_LIB.BASEBOARD_FAB2(SCH_1):SMB_DDR_KLM_SDA_G_R   I112 @BASEBOARD_FAB2_LIB.BASEBOARD_FAB2(SCH_1):PAGE99
     2 SMB_DDR_KLM_SDA_G @BASEBOARD_FAB2_LIB.BASEBOARD_FAB2(SCH_1):SMB_DDR_KLM_SDA_G   I112 @BASEBOARD_FAB2_LIB.BASEBOARD_FAB2(SCH_1):PAGE99

R7M9 RES_0402-64.9,1.0%,1/16W,CHIP,A
     1 PVDDQ_KLM @BASEBOARD_FAB2_LIB.BASEBOARD_FAB2(SCH_1):PVDDQ_KLM    I28 @BASEBOARD_FAB2_LIB.BASEBOARD_FAB2(SCH_1):PAGE96
     2 PWRGD_CPU1_DRAMPWROK_KLM_G @BASEBOARD_FAB2_LIB.BASEBOARD_FAB2(SCH_1):PWRGD_CPU1_DRAMPWROK_KLM_G    I28 @BASEBOARD_FAB2_LIB.BASEBOARD_FAB2(SCH_1):PAGE96

R7P1 RES_0402-42.2,1.0%,1/16W,EMPTYA
     1 CLK_100M_CPU1_BCLK2_DP @BASEBOARD_FAB2_LIB.BASEBOARD_FAB2(SCH_1):CLK_100M_CPU1_BCLK2_DP   I133 @BASEBOARD_FAB2_LIB.BASEBOARD_FAB2(SCH_1):PAGE103
     2    GND @BASEBOARD_FAB2_LIB.BASEBOARD_FAB2(SCH_1):GND   I133 @BASEBOARD_FAB2_LIB.BASEBOARD_FAB2(SCH_1):PAGE103

R7P2 RES_0402-42.2,1.0%,1/16W,EMPTYA
     1 CLK_100M_CPU1_BCLK2_DN @BASEBOARD_FAB2_LIB.BASEBOARD_FAB2(SCH_1):CLK_100M_CPU1_BCLK2_DN   I135 @BASEBOARD_FAB2_LIB.BASEBOARD_FAB2(SCH_1):PAGE103
     2    GND @BASEBOARD_FAB2_LIB.BASEBOARD_FAB2(SCH_1):GND   I135 @BASEBOARD_FAB2_LIB.BASEBOARD_FAB2(SCH_1):PAGE103

R7P3 RES_0402-42.2,1.0%,1/16W,EMPTYA
     1 CLK_100M_CPU1_PE_REFCLK_DP @BASEBOARD_FAB2_LIB.BASEBOARD_FAB2(SCH_1):CLK_100M_CPU1_PE_REFCLK_DP   I129 @BASEBOARD_FAB2_LIB.BASEBOARD_FAB2(SCH_1):PAGE103
     2    GND @BASEBOARD_FAB2_LIB.BASEBOARD_FAB2(SCH_1):GND   I129 @BASEBOARD_FAB2_LIB.BASEBOARD_FAB2(SCH_1):PAGE103

R7P4 RES_0402-42.2,1.0%,1/16W,EMPTYA
     1 CLK_100M_CPU1_PE_REFCLK_DN @BASEBOARD_FAB2_LIB.BASEBOARD_FAB2(SCH_1):CLK_100M_CPU1_PE_REFCLK_DN   I131 @BASEBOARD_FAB2_LIB.BASEBOARD_FAB2(SCH_1):PAGE103
     2    GND @BASEBOARD_FAB2_LIB.BASEBOARD_FAB2(SCH_1):GND   I131 @BASEBOARD_FAB2_LIB.BASEBOARD_FAB2(SCH_1):PAGE103

R7P5 RES_0402-150.0,1%,1/16W,CHIP,GA
     1 H_CPU1_MEMGHJ_MEMHOT_G_N @BASEBOARD_FAB2_LIB.BASEBOARD_FAB2(SCH_1):H_CPU1_MEMGHJ_MEMHOT_G_N    I61 @BASEBOARD_FAB2_LIB.BASEBOARD_FAB2(SCH_1):PAGE152
     2 PVCCIO_CPU1 @BASEBOARD_FAB2_LIB.BASEBOARD_FAB2(SCH_1):PVCCIO_CPU1    I61 @BASEBOARD_FAB2_LIB.BASEBOARD_FAB2(SCH_1):PAGE152

R7P6 RES_0402-42.2,1.0%,1/16W,EMPTYA
     1 CLK_100M_CPU1_RC_REFCLK0_DP @BASEBOARD_FAB2_LIB.BASEBOARD_FAB2(SCH_1):CLK_100M_CPU1_RC_REFCLK0_DP   I125 @BASEBOARD_FAB2_LIB.BASEBOARD_FAB2(SCH_1):PAGE103
     2    GND @BASEBOARD_FAB2_LIB.BASEBOARD_FAB2(SCH_1):GND   I125 @BASEBOARD_FAB2_LIB.BASEBOARD_FAB2(SCH_1):PAGE103

R7P7 RES_0402-42.2,1.0%,1/16W,EMPTYA
     1 CLK_100M_CPU1_RC_REFCLK0_DN @BASEBOARD_FAB2_LIB.BASEBOARD_FAB2(SCH_1):CLK_100M_CPU1_RC_REFCLK0_DN   I127 @BASEBOARD_FAB2_LIB.BASEBOARD_FAB2(SCH_1):PAGE103
     2    GND @BASEBOARD_FAB2_LIB.BASEBOARD_FAB2(SCH_1):GND   I127 @BASEBOARD_FAB2_LIB.BASEBOARD_FAB2(SCH_1):PAGE103

R7P8 RES_0402-49.9,1%,1/16W,CHIP,G2A
     1 A_CPU1_PE3_RBIAS @BASEBOARD_FAB2_LIB.BASEBOARD_FAB2(SCH_1):A_CPU1_PE3_RBIAS   I123 @BASEBOARD_FAB2_LIB.BASEBOARD_FAB2(SCH_1):PAGE55
     2    GND @BASEBOARD_FAB2_LIB.BASEBOARD_FAB2(SCH_1):GND   I123 @BASEBOARD_FAB2_LIB.BASEBOARD_FAB2(SCH_1):PAGE55

R7P9 RES_0402-42.2,1.0%,1/16W,EMPTYA
     1 CLK_100M_CPU1_RC_REFCLK1_DP @BASEBOARD_FAB2_LIB.BASEBOARD_FAB2(SCH_1):CLK_100M_CPU1_RC_REFCLK1_DP   I121 @BASEBOARD_FAB2_LIB.BASEBOARD_FAB2(SCH_1):PAGE103
     2    GND @BASEBOARD_FAB2_LIB.BASEBOARD_FAB2(SCH_1):GND   I121 @BASEBOARD_FAB2_LIB.BASEBOARD_FAB2(SCH_1):PAGE103

R7P10 RES_0402-49.9,1%,1/16W,CHIP,G2A
     1 A_CPU1_PE012_RBIAS @BASEBOARD_FAB2_LIB.BASEBOARD_FAB2(SCH_1):A_CPU1_PE012_RBIAS   I124 @BASEBOARD_FAB2_LIB.BASEBOARD_FAB2(SCH_1):PAGE55
     2    GND @BASEBOARD_FAB2_LIB.BASEBOARD_FAB2(SCH_1):GND   I124 @BASEBOARD_FAB2_LIB.BASEBOARD_FAB2(SCH_1):PAGE55

R7P11 RES_0402-49.9,1%,1/16W,CHIP,G2A
     1 A_CPU1_UPI2_RBIAS @BASEBOARD_FAB2_LIB.BASEBOARD_FAB2(SCH_1):A_CPU1_UPI2_RBIAS   I126 @BASEBOARD_FAB2_LIB.BASEBOARD_FAB2(SCH_1):PAGE55
     2    GND @BASEBOARD_FAB2_LIB.BASEBOARD_FAB2(SCH_1):GND   I126 @BASEBOARD_FAB2_LIB.BASEBOARD_FAB2(SCH_1):PAGE55

R7P12 RES_0402-42.2,1.0%,1/16W,EMPTYA
     1 CLK_100M_CPU1_RC_REFCLK1_DN @BASEBOARD_FAB2_LIB.BASEBOARD_FAB2(SCH_1):CLK_100M_CPU1_RC_REFCLK1_DN   I123 @BASEBOARD_FAB2_LIB.BASEBOARD_FAB2(SCH_1):PAGE103
     2    GND @BASEBOARD_FAB2_LIB.BASEBOARD_FAB2(SCH_1):GND   I123 @BASEBOARD_FAB2_LIB.BASEBOARD_FAB2(SCH_1):PAGE103

R7P13 RES_0402-10.0K,1%,1/16W,CHIP,GA
     1    GND @BASEBOARD_FAB2_LIB.BASEBOARD_FAB2(SCH_1):GND    I81 @BASEBOARD_FAB2_LIB.BASEBOARD_FAB2(SCH_1):PAGE97
     2 PD_CPU1_MCP01_DMON @BASEBOARD_FAB2_LIB.BASEBOARD_FAB2(SCH_1):PD_CPU1_MCP01_DMON    I81 @BASEBOARD_FAB2_LIB.BASEBOARD_FAB2(SCH_1):PAGE97

R7P14 RES_0402-240,1.0%,1/16W,CHIP,GA
     1    GND @BASEBOARD_FAB2_LIB.BASEBOARD_FAB2(SCH_1):GND    I70 @BASEBOARD_FAB2_LIB.BASEBOARD_FAB2(SCH_1):PAGE90
     2 PD_CPU1_DMIMODE_OVERRIDE @BASEBOARD_FAB2_LIB.BASEBOARD_FAB2(SCH_1):PD_CPU1_DMIMODE_OVERRIDE    I70 @BASEBOARD_FAB2_LIB.BASEBOARD_FAB2(SCH_1):PAGE90

R7P15 RES_0402-240,1.0%,1/16W,EMPTY,A
     1    GND @BASEBOARD_FAB2_LIB.BASEBOARD_FAB2(SCH_1):GND    I74 @BASEBOARD_FAB2_LIB.BASEBOARD_FAB2(SCH_1):PAGE90
     2 PD_CPU1_KSFC_DIS @BASEBOARD_FAB2_LIB.BASEBOARD_FAB2(SCH_1):PD_CPU1_KSFC_DIS    I74 @BASEBOARD_FAB2_LIB.BASEBOARD_FAB2(SCH_1):PAGE90

R7P16 RES_0402-90.9,1%,1/16W,CHIP,G2A
     1 A_CPU1_GHJ_RCOMP0 @BASEBOARD_FAB2_LIB.BASEBOARD_FAB2(SCH_1):A_CPU1_GHJ_RCOMP0   I119 @BASEBOARD_FAB2_LIB.BASEBOARD_FAB2(SCH_1):PAGE55
     2    GND @BASEBOARD_FAB2_LIB.BASEBOARD_FAB2(SCH_1):GND   I119 @BASEBOARD_FAB2_LIB.BASEBOARD_FAB2(SCH_1):PAGE55

R7P17 RES_0402-90.9,1%,1/16W,CHIP,G2A
     1 A_CPU1_GHJ_RCOMP1 @BASEBOARD_FAB2_LIB.BASEBOARD_FAB2(SCH_1):A_CPU1_GHJ_RCOMP1   I140 @BASEBOARD_FAB2_LIB.BASEBOARD_FAB2(SCH_1):PAGE55
     2    GND @BASEBOARD_FAB2_LIB.BASEBOARD_FAB2(SCH_1):GND   I140 @BASEBOARD_FAB2_LIB.BASEBOARD_FAB2(SCH_1):PAGE55

R7P18 RES_0402-150.0,1%,1/16W,CHIP,GA
     1 PVCCIO_CPU0 @BASEBOARD_FAB2_LIB.BASEBOARD_FAB2(SCH_1):PVCCIO_CPU0   I100 @BASEBOARD_FAB2_LIB.BASEBOARD_FAB2(SCH_1):PAGE92
     2 H_CPU1_CATERR_G_N @BASEBOARD_FAB2_LIB.BASEBOARD_FAB2(SCH_1):H_CPU1_CATERR_G_N   I100 @BASEBOARD_FAB2_LIB.BASEBOARD_FAB2(SCH_1):PAGE92

R7P19 RES_0402-100.0,1%,1/16W,CHIP,GA
     1 A_CPU1_GHJ_RCOMP2 @BASEBOARD_FAB2_LIB.BASEBOARD_FAB2(SCH_1):A_CPU1_GHJ_RCOMP2   I115 @BASEBOARD_FAB2_LIB.BASEBOARD_FAB2(SCH_1):PAGE55
     2    GND @BASEBOARD_FAB2_LIB.BASEBOARD_FAB2(SCH_1):GND   I115 @BASEBOARD_FAB2_LIB.BASEBOARD_FAB2(SCH_1):PAGE55

R7P20 RES_0402-150.0,1%,1/16W,CHIP,GA
     1 PVCCIO_CPU0 @BASEBOARD_FAB2_LIB.BASEBOARD_FAB2(SCH_1):PVCCIO_CPU0    I44 @BASEBOARD_FAB2_LIB.BASEBOARD_FAB2(SCH_1):PAGE97
     2 H_CPU1_FAST_WAKE_N @BASEBOARD_FAB2_LIB.BASEBOARD_FAB2(SCH_1):H_CPU1_FAST_WAKE_N    I44 @BASEBOARD_FAB2_LIB.BASEBOARD_FAB2(SCH_1):PAGE97

R7P21 RES_0402-150.0,1%,1/16W,CHIP,GA
     1 H_CPU1_MEMKLM_MEMHOT_G_N @BASEBOARD_FAB2_LIB.BASEBOARD_FAB2(SCH_1):H_CPU1_MEMKLM_MEMHOT_G_N    I62 @BASEBOARD_FAB2_LIB.BASEBOARD_FAB2(SCH_1):PAGE152
     2 PVCCIO_CPU1 @BASEBOARD_FAB2_LIB.BASEBOARD_FAB2(SCH_1):PVCCIO_CPU1    I62 @BASEBOARD_FAB2_LIB.BASEBOARD_FAB2(SCH_1):PAGE152

R7P22 RES_0402-240,1.0%,1/16W,EMPTY,A
     1 PVCCIO_CPU1 @BASEBOARD_FAB2_LIB.BASEBOARD_FAB2(SCH_1):PVCCIO_CPU1    I76 @BASEBOARD_FAB2_LIB.BASEBOARD_FAB2(SCH_1):PAGE90
     2 PU_CPU1_LEGACY_SKT @BASEBOARD_FAB2_LIB.BASEBOARD_FAB2(SCH_1):PU_CPU1_LEGACY_SKT    I76 @BASEBOARD_FAB2_LIB.BASEBOARD_FAB2(SCH_1):PAGE90

R7P25 RES_0402-49.9,1%,1/16W,CHIP,G2A
     1 H_PM_SYNC_GTL_R2 @BASEBOARD_FAB2_LIB.BASEBOARD_FAB2(SCH_1):H_PM_SYNC_GTL_R2   I170 @BASEBOARD_FAB2_LIB.BASEBOARD_FAB2(SCH_1):PAGE55
     2 H_PM_SYNC_GTL @BASEBOARD_FAB2_LIB.BASEBOARD_FAB2(SCH_1):H_PM_SYNC_GTL   I170 @BASEBOARD_FAB2_LIB.BASEBOARD_FAB2(SCH_1):PAGE55

R7P26 RES_0402-49.9,1%,1/16W,CHIP,G2A
     1 H_PMSYNC_CLK_24M_CPU1 @BASEBOARD_FAB2_LIB.BASEBOARD_FAB2(SCH_1):H_PMSYNC_CLK_24M_CPU1   I156 @BASEBOARD_FAB2_LIB.BASEBOARD_FAB2(SCH_1):PAGE55
     2 H_PMSYNC_CLK_24M @BASEBOARD_FAB2_LIB.BASEBOARD_FAB2(SCH_1):H_PMSYNC_CLK_24M   I156 @BASEBOARD_FAB2_LIB.BASEBOARD_FAB2(SCH_1):PAGE55

R7P27 RES_0402-150.0,1%,1/16W,CHIP,GA
     1 PVCCIO_CPU0 @BASEBOARD_FAB2_LIB.BASEBOARD_FAB2(SCH_1):PVCCIO_CPU0    I65 @BASEBOARD_FAB2_LIB.BASEBOARD_FAB2(SCH_1):PAGE92
     2 H_CPU1_MSMI_G_N @BASEBOARD_FAB2_LIB.BASEBOARD_FAB2(SCH_1):H_CPU1_MSMI_G_N    I65 @BASEBOARD_FAB2_LIB.BASEBOARD_FAB2(SCH_1):PAGE92

R7P28 RES_0402-150.0,1%,1/16W,CHIP,GA
     1 PVCCIO_CPU1 @BASEBOARD_FAB2_LIB.BASEBOARD_FAB2(SCH_1):PVCCIO_CPU1   I106 @BASEBOARD_FAB2_LIB.BASEBOARD_FAB2(SCH_1):PAGE93
     2 H_CPU1_PROCHOT_G_N @BASEBOARD_FAB2_LIB.BASEBOARD_FAB2(SCH_1):H_CPU1_PROCHOT_G_N   I106 @BASEBOARD_FAB2_LIB.BASEBOARD_FAB2(SCH_1):PAGE93

R7P29 RES_0402-51.1,1.0%,1/16W,CHIP,A
     1 XDP_CPU_TCK0 @BASEBOARD_FAB2_LIB.BASEBOARD_FAB2(SCH_1):XDP_CPU_TCK0    I61 @BASEBOARD_FAB2_LIB.BASEBOARD_FAB2(SCH_1):PAGE112
     2    GND @BASEBOARD_FAB2_LIB.BASEBOARD_FAB2(SCH_1):GND    I61 @BASEBOARD_FAB2_LIB.BASEBOARD_FAB2(SCH_1):PAGE112

R7P30 RES_0402-100.0,1%,1/16W,CHIP,GA
     1 PVCCIO_CPU0 @BASEBOARD_FAB2_LIB.BASEBOARD_FAB2(SCH_1):PVCCIO_CPU0    I50 @BASEBOARD_FAB2_LIB.BASEBOARD_FAB2(SCH_1):PAGE112
     2 XDP_CPU_MBP0_N @BASEBOARD_FAB2_LIB.BASEBOARD_FAB2(SCH_1):XDP_CPU_MBP0_N    I50 @BASEBOARD_FAB2_LIB.BASEBOARD_FAB2(SCH_1):PAGE112

R7R1 RES_0402-51.1,1.0%,1/16W,CHIP,A
     1 PVCCIO_CPU1 @BASEBOARD_FAB2_LIB.BASEBOARD_FAB2(SCH_1):PVCCIO_CPU1   I109 @BASEBOARD_FAB2_LIB.BASEBOARD_FAB2(SCH_1):PAGE214
     2    GND @BASEBOARD_FAB2_LIB.BASEBOARD_FAB2(SCH_1):GND   I109 @BASEBOARD_FAB2_LIB.BASEBOARD_FAB2(SCH_1):PAGE214

R7U2 RES_0402-100.0,1%,1/16W,EMPTY,A
     1 VSENSE_PVDDQ_GHJ_P @BASEBOARD_FAB2_LIB.BASEBOARD_FAB2(SCH_1):VSENSE_PVDDQ_GHJ_P    I74 @BASEBOARD_FAB2_LIB.BASEBOARD_FAB2(SCH_1):PAGE225
     2 VSENSE_PVDDQ_GHJ_N @BASEBOARD_FAB2_LIB.BASEBOARD_FAB2(SCH_1):VSENSE_PVDDQ_GHJ_N    I74 @BASEBOARD_FAB2_LIB.BASEBOARD_FAB2(SCH_1):PAGE225

R8A1 RES_0402-10.0,1%,1/16W,CHIP,G2A
     1 VSENSE_PVNN_PCH_STBY_AVSP @BASEBOARD_FAB2_LIB.BASEBOARD_FAB2(SCH_1):VSENSE_PVNN_PCH_STBY_AVSP   I210 @BASEBOARD_FAB2_LIB.BASEBOARD_FAB2(SCH_1):PAGE235
     2 VR_PVNN_PCH_AVSP @BASEBOARD_FAB2_LIB.BASEBOARD_FAB2(SCH_1):VR_PVNN_PCH_AVSP   I210 @BASEBOARD_FAB2_LIB.BASEBOARD_FAB2(SCH_1):PAGE235

R8A2 RES_0402-2.67K,1%,1/16W,CHIP,GA
     1 VR_PVNN_PCH_XADDR2 @BASEBOARD_FAB2_LIB.BASEBOARD_FAB2(SCH_1):VR_PVNN_PCH_XADDR2   I217 @BASEBOARD_FAB2_LIB.BASEBOARD_FAB2(SCH_1):PAGE235
     2    GND @BASEBOARD_FAB2_LIB.BASEBOARD_FAB2(SCH_1):GND   I217 @BASEBOARD_FAB2_LIB.BASEBOARD_FAB2(SCH_1):PAGE235

R8A4 RES_0402-100.0K,1%,1/16W,CHIP,B
     1 VR_FET_SW_P12V_STBY_PVDDQ_DEF @BASEBOARD_FAB2_LIB.BASEBOARD_FAB2(SCH_1):VR_FET_SW_P12V_STBY_PVDDQ_DEF   I165 @BASEBOARD_FAB2_LIB.BASEBOARD_FAB2(SCH_1):PAGE235
     2 VR_PVNN_PCH_VINSEN @BASEBOARD_FAB2_LIB.BASEBOARD_FAB2(SCH_1):VR_PVNN_PCH_VINSEN   I165 @BASEBOARD_FAB2_LIB.BASEBOARD_FAB2(SCH_1):PAGE235

R8A5 RES_0402-1.00K,1%,1/16W,CHIP,GA
     1 P3V3_STBY @BASEBOARD_FAB2_LIB.BASEBOARD_FAB2(SCH_1):P3V3_STBY   I216 @BASEBOARD_FAB2_LIB.BASEBOARD_FAB2(SCH_1):PAGE235
     2 IRQ_PVNN_PCH_VRHOT_N @BASEBOARD_FAB2_LIB.BASEBOARD_FAB2(SCH_1):IRQ_PVNN_PCH_VRHOT_N   I216 @BASEBOARD_FAB2_LIB.BASEBOARD_FAB2(SCH_1):PAGE235

R8A6 RES_0402-1.00K,1%,1/16W,CHIP,GA
     1 P3V3_STBY @BASEBOARD_FAB2_LIB.BASEBOARD_FAB2(SCH_1):P3V3_STBY   I149 @BASEBOARD_FAB2_LIB.BASEBOARD_FAB2(SCH_1):PAGE235
     2 PWRGD_PVNN_PCH_R @BASEBOARD_FAB2_LIB.BASEBOARD_FAB2(SCH_1):PWRGD_PVNN_PCH_R   I149 @BASEBOARD_FAB2_LIB.BASEBOARD_FAB2(SCH_1):PAGE235

R8A7 RES_0402-100.0K,1%,1/16W,EMPTYA
     1 P3V3_STBY @BASEBOARD_FAB2_LIB.BASEBOARD_FAB2(SCH_1):P3V3_STBY   I222 @BASEBOARD_FAB2_LIB.BASEBOARD_FAB2(SCH_1):PAGE235
     2 VR_PVNN_PCH_VREN @BASEBOARD_FAB2_LIB.BASEBOARD_FAB2(SCH_1):VR_PVNN_PCH_VREN   I222 @BASEBOARD_FAB2_LIB.BASEBOARD_FAB2(SCH_1):PAGE235

R8A8 RES_0402-20.0,1%,1/16W,CHIP,G2A
     1 SMB_VR_STBY_LVC3_SDA @BASEBOARD_FAB2_LIB.BASEBOARD_FAB2(SCH_1):SMB_VR_STBY_LVC3_SDA   I172 @BASEBOARD_FAB2_LIB.BASEBOARD_FAB2(SCH_1):PAGE235
     2 SMB_VR_SDA_PVNN_PCH @BASEBOARD_FAB2_LIB.BASEBOARD_FAB2(SCH_1):SMB_VR_SDA_PVNN_PCH   I172 @BASEBOARD_FAB2_LIB.BASEBOARD_FAB2(SCH_1):PAGE235

R8A9 RES_0402-20.0,1%,1/16W,CHIP,G2A
     1 SMB_VR_STBY_LVC3_SCL @BASEBOARD_FAB2_LIB.BASEBOARD_FAB2(SCH_1):SMB_VR_STBY_LVC3_SCL   I173 @BASEBOARD_FAB2_LIB.BASEBOARD_FAB2(SCH_1):PAGE235
     2 SMB_VR_SCL_PVNN_PCH @BASEBOARD_FAB2_LIB.BASEBOARD_FAB2(SCH_1):SMB_VR_SCL_PVNN_PCH   I173 @BASEBOARD_FAB2_LIB.BASEBOARD_FAB2(SCH_1):PAGE235

R8A10 RES_0402-5.11K,1%,1/16W,CHIP,GA
     1 P3V3_STBY @BASEBOARD_FAB2_LIB.BASEBOARD_FAB2(SCH_1):P3V3_STBY     I3 @BASEBOARD_FAB2_LIB.BASEBOARD_FAB2(SCH_1):PAGE237
     2 PWRGD_P1V8_PCH_STBY_R @BASEBOARD_FAB2_LIB.BASEBOARD_FAB2(SCH_1):PWRGD_P1V8_PCH_STBY_R     I3 @BASEBOARD_FAB2_LIB.BASEBOARD_FAB2(SCH_1):PAGE237

R8A11 RES_0402-22.1,1.0%,1/16W,CHIP,A
     1 PWRGD_P1V8_PCH_STBY_R @BASEBOARD_FAB2_LIB.BASEBOARD_FAB2(SCH_1):PWRGD_P1V8_PCH_STBY_R    I90 @BASEBOARD_FAB2_LIB.BASEBOARD_FAB2(SCH_1):PAGE237
     2 PWRGD_P1V8_PCH_STBY @BASEBOARD_FAB2_LIB.BASEBOARD_FAB2(SCH_1):PWRGD_P1V8_PCH_STBY    I90 @BASEBOARD_FAB2_LIB.BASEBOARD_FAB2(SCH_1):PAGE237

R8A12 RES_0603-475.0,1%,1/10W,CHIP,GA
     1 P1V8_PCH_STBY @BASEBOARD_FAB2_LIB.BASEBOARD_FAB2(SCH_1):P1V8_PCH_STBY    I15 @BASEBOARD_FAB2_LIB.BASEBOARD_FAB2(SCH_1):PAGE237
     2    GND @BASEBOARD_FAB2_LIB.BASEBOARD_FAB2(SCH_1):GND    I15 @BASEBOARD_FAB2_LIB.BASEBOARD_FAB2(SCH_1):PAGE237

R8A13 RES_0402-150.0,1%,1/16W,CHIP,GA
     1 P1V05_PCH_STBY @BASEBOARD_FAB2_LIB.BASEBOARD_FAB2(SCH_1):P1V05_PCH_STBY    I79 @BASEBOARD_FAB2_LIB.BASEBOARD_FAB2(SCH_1):PAGE112
     2 XDP_TDI @BASEBOARD_FAB2_LIB.BASEBOARD_FAB2(SCH_1):XDP_TDI    I79 @BASEBOARD_FAB2_LIB.BASEBOARD_FAB2(SCH_1):PAGE112

R8A14 RES_0402-150.0,1%,1/16W,CHIP,GA
     1 P1V05_PCH_STBY @BASEBOARD_FAB2_LIB.BASEBOARD_FAB2(SCH_1):P1V05_PCH_STBY    I80 @BASEBOARD_FAB2_LIB.BASEBOARD_FAB2(SCH_1):PAGE112
     2 XDP_TMS @BASEBOARD_FAB2_LIB.BASEBOARD_FAB2(SCH_1):XDP_TMS    I80 @BASEBOARD_FAB2_LIB.BASEBOARD_FAB2(SCH_1):PAGE112

R8B1 RES_0402-51.1,1.0%,1/16W,CHIP,A
     1 XDP_PCH_TCK1 @BASEBOARD_FAB2_LIB.BASEBOARD_FAB2(SCH_1):XDP_PCH_TCK1    I95 @BASEBOARD_FAB2_LIB.BASEBOARD_FAB2(SCH_1):PAGE112
     2    GND @BASEBOARD_FAB2_LIB.BASEBOARD_FAB2(SCH_1):GND    I95 @BASEBOARD_FAB2_LIB.BASEBOARD_FAB2(SCH_1):PAGE112

R8B2 RES_0402-1.00K,1%,1/16W,CHIP,GA
     1 XDP_TRST_N @BASEBOARD_FAB2_LIB.BASEBOARD_FAB2(SCH_1):XDP_TRST_N    I94 @BASEBOARD_FAB2_LIB.BASEBOARD_FAB2(SCH_1):PAGE112
     2    GND @BASEBOARD_FAB2_LIB.BASEBOARD_FAB2(SCH_1):GND    I94 @BASEBOARD_FAB2_LIB.BASEBOARD_FAB2(SCH_1):PAGE112

R8B3 RES_0402-4.75K,1%,1/16W,CHIP,GA
     1 PVPP_ABC @BASEBOARD_FAB2_LIB.BASEBOARD_FAB2(SCH_1):PVPP_ABC    I24 @BASEBOARD_FAB2_LIB.BASEBOARD_FAB2(SCH_1):PAGE91
     2 FM_MODPRST_HFI0_CPU0_LVT2_N @BASEBOARD_FAB2_LIB.BASEBOARD_FAB2(SCH_1):FM_MODPRST_HFI0_CPU0_LVT2_N    I24 @BASEBOARD_FAB2_LIB.BASEBOARD_FAB2(SCH_1):PAGE91

R8B4 RES_0402-100.0K,1%,1/16W,CHIP,A
     1 FM_CTNR_PS_ON @BASEBOARD_FAB2_LIB.BASEBOARD_FAB2(SCH_1):FM_CTNR_PS_ON    I83 @BASEBOARD_FAB2_LIB.BASEBOARD_FAB2(SCH_1):PAGE198
     2    GND @BASEBOARD_FAB2_LIB.BASEBOARD_FAB2(SCH_1):GND    I83 @BASEBOARD_FAB2_LIB.BASEBOARD_FAB2(SCH_1):PAGE198

R8B5 RES_0402-4.75K,1%,1/16W,CHIP,GA
     1 PVPP_ABC @BASEBOARD_FAB2_LIB.BASEBOARD_FAB2(SCH_1):PVPP_ABC    I22 @BASEBOARD_FAB2_LIB.BASEBOARD_FAB2(SCH_1):PAGE91
     2 LED_HFI0_CPU0_N @BASEBOARD_FAB2_LIB.BASEBOARD_FAB2(SCH_1):LED_HFI0_CPU0_N    I22 @BASEBOARD_FAB2_LIB.BASEBOARD_FAB2(SCH_1):PAGE91

R8B6 RES_0402-1.8K,1%,1/16W,CHIP,G2A
     1 PVPP_ABC @BASEBOARD_FAB2_LIB.BASEBOARD_FAB2(SCH_1):PVPP_ABC    I37 @BASEBOARD_FAB2_LIB.BASEBOARD_FAB2(SCH_1):PAGE91
     2 SMB_HFI0_CPU0_LVC2_SCL @BASEBOARD_FAB2_LIB.BASEBOARD_FAB2(SCH_1):SMB_HFI0_CPU0_LVC2_SCL    I37 @BASEBOARD_FAB2_LIB.BASEBOARD_FAB2(SCH_1):PAGE91

R8B7 RES_0402-1.8K,1%,1/16W,CHIP,G2A
     1 PVPP_ABC @BASEBOARD_FAB2_LIB.BASEBOARD_FAB2(SCH_1):PVPP_ABC    I36 @BASEBOARD_FAB2_LIB.BASEBOARD_FAB2(SCH_1):PAGE91
     2 SMB_HFI0_CPU0_LVC2_SDA @BASEBOARD_FAB2_LIB.BASEBOARD_FAB2(SCH_1):SMB_HFI0_CPU0_LVC2_SDA    I36 @BASEBOARD_FAB2_LIB.BASEBOARD_FAB2(SCH_1):PAGE91

R8B8 RES_0402-4.75K,1%,1/16W,CHIP,GA
     1 PVPP_ABC @BASEBOARD_FAB2_LIB.BASEBOARD_FAB2(SCH_1):PVPP_ABC    I14 @BASEBOARD_FAB2_LIB.BASEBOARD_FAB2(SCH_1):PAGE91
     2 RST_HFI0_CPU0_LVT2_N @BASEBOARD_FAB2_LIB.BASEBOARD_FAB2(SCH_1):RST_HFI0_CPU0_LVT2_N    I14 @BASEBOARD_FAB2_LIB.BASEBOARD_FAB2(SCH_1):PAGE91

R8B9 RES_0402-113,1%,1/16W,CHIP,G21A
     1 A_USB2_COMP @BASEBOARD_FAB2_LIB.BASEBOARD_FAB2(SCH_1):A_USB2_COMP    I90 @BASEBOARD_FAB2_LIB.BASEBOARD_FAB2(SCH_1):PAGE115
     2    GND @BASEBOARD_FAB2_LIB.BASEBOARD_FAB2(SCH_1):GND    I90 @BASEBOARD_FAB2_LIB.BASEBOARD_FAB2(SCH_1):PAGE115

R8B10 RES_0402-4.75K,1%,1/16W,CHIP,GA
     1 PVPP_ABC @BASEBOARD_FAB2_LIB.BASEBOARD_FAB2(SCH_1):PVPP_ABC    I16 @BASEBOARD_FAB2_LIB.BASEBOARD_FAB2(SCH_1):PAGE91
     2 IRQ_HFI0_CPU0_LVT2_N @BASEBOARD_FAB2_LIB.BASEBOARD_FAB2(SCH_1):IRQ_HFI0_CPU0_LVT2_N    I16 @BASEBOARD_FAB2_LIB.BASEBOARD_FAB2(SCH_1):PAGE91

R8B11 RES_0402-1.8K,1%,1/16W,CHIP,G2A
     1 PVPP_ABC @BASEBOARD_FAB2_LIB.BASEBOARD_FAB2(SCH_1):PVPP_ABC    I35 @BASEBOARD_FAB2_LIB.BASEBOARD_FAB2(SCH_1):PAGE91
     2 SMB_HFI1_CPU0_LVC2_SCL @BASEBOARD_FAB2_LIB.BASEBOARD_FAB2(SCH_1):SMB_HFI1_CPU0_LVC2_SCL    I35 @BASEBOARD_FAB2_LIB.BASEBOARD_FAB2(SCH_1):PAGE91

R8B12 RES_0402-0.0,5%,1/16W,CHIP,G21A
     1 VSENSE_P1V05_PCH_STBY_AVSN @BASEBOARD_FAB2_LIB.BASEBOARD_FAB2(SCH_1):VSENSE_P1V05_PCH_STBY_AVSN    I59 @BASEBOARD_FAB2_LIB.BASEBOARD_FAB2(SCH_1):PAGE236
     2    GND @BASEBOARD_FAB2_LIB.BASEBOARD_FAB2(SCH_1):GND    I59 @BASEBOARD_FAB2_LIB.BASEBOARD_FAB2(SCH_1):PAGE236

R8B13 RES_0402-1.8K,1%,1/16W,CHIP,G2A
     1 PVPP_ABC @BASEBOARD_FAB2_LIB.BASEBOARD_FAB2(SCH_1):PVPP_ABC    I34 @BASEBOARD_FAB2_LIB.BASEBOARD_FAB2(SCH_1):PAGE91
     2 SMB_HFI1_CPU0_LVC2_SDA @BASEBOARD_FAB2_LIB.BASEBOARD_FAB2(SCH_1):SMB_HFI1_CPU0_LVC2_SDA    I34 @BASEBOARD_FAB2_LIB.BASEBOARD_FAB2(SCH_1):PAGE91

R8B14 RES_0402-0.0,5%,1/16W,CHIP,G21A
     1 VSENSE_P1V05_PCH_STBY_AVSP @BASEBOARD_FAB2_LIB.BASEBOARD_FAB2(SCH_1):VSENSE_P1V05_PCH_STBY_AVSP    I56 @BASEBOARD_FAB2_LIB.BASEBOARD_FAB2(SCH_1):PAGE236
     2 P1V05_PCH_STBY @BASEBOARD_FAB2_LIB.BASEBOARD_FAB2(SCH_1):P1V05_PCH_STBY    I56 @BASEBOARD_FAB2_LIB.BASEBOARD_FAB2(SCH_1):PAGE236

R8B15 RES_0402-100.0,1%,1/16W,EMPTY,A
     1 VSENSE_P1V05_PCH_STBY_AVSP @BASEBOARD_FAB2_LIB.BASEBOARD_FAB2(SCH_1):VSENSE_P1V05_PCH_STBY_AVSP    I57 @BASEBOARD_FAB2_LIB.BASEBOARD_FAB2(SCH_1):PAGE236
     2 VSENSE_P1V05_PCH_STBY_AVSN @BASEBOARD_FAB2_LIB.BASEBOARD_FAB2(SCH_1):VSENSE_P1V05_PCH_STBY_AVSN    I57 @BASEBOARD_FAB2_LIB.BASEBOARD_FAB2(SCH_1):PAGE236

R8B16 RES_0402-4.75K,1%,1/16W,CHIP,GA
     1 PVPP_ABC @BASEBOARD_FAB2_LIB.BASEBOARD_FAB2(SCH_1):PVPP_ABC    I17 @BASEBOARD_FAB2_LIB.BASEBOARD_FAB2(SCH_1):PAGE91
     2 RST_HFI1_CPU0_LVT2_N @BASEBOARD_FAB2_LIB.BASEBOARD_FAB2(SCH_1):RST_HFI1_CPU0_LVT2_N    I17 @BASEBOARD_FAB2_LIB.BASEBOARD_FAB2(SCH_1):PAGE91

R8B17 RES_0402-4.75K,1%,1/16W,CHIP,GA
     1 PVPP_ABC @BASEBOARD_FAB2_LIB.BASEBOARD_FAB2(SCH_1):PVPP_ABC    I18 @BASEBOARD_FAB2_LIB.BASEBOARD_FAB2(SCH_1):PAGE91
     2 IRQ_HFI1_CPU0_LVT2_N @BASEBOARD_FAB2_LIB.BASEBOARD_FAB2(SCH_1):IRQ_HFI1_CPU0_LVT2_N    I18 @BASEBOARD_FAB2_LIB.BASEBOARD_FAB2(SCH_1):PAGE91

R8B18 RES_0402-4.75K,1%,1/16W,CHIP,GA
     1 PVPP_ABC @BASEBOARD_FAB2_LIB.BASEBOARD_FAB2(SCH_1):PVPP_ABC    I20 @BASEBOARD_FAB2_LIB.BASEBOARD_FAB2(SCH_1):PAGE91
     2 LED_HFI1_CPU0_N @BASEBOARD_FAB2_LIB.BASEBOARD_FAB2(SCH_1):LED_HFI1_CPU0_N    I20 @BASEBOARD_FAB2_LIB.BASEBOARD_FAB2(SCH_1):PAGE91

R8B19 RES_0402-4.75K,1%,1/16W,CHIP,GA
     1 PVPP_ABC @BASEBOARD_FAB2_LIB.BASEBOARD_FAB2(SCH_1):PVPP_ABC    I21 @BASEBOARD_FAB2_LIB.BASEBOARD_FAB2(SCH_1):PAGE91
     2 FM_MODPRST_HFI1_CPU0_LVT2_N @BASEBOARD_FAB2_LIB.BASEBOARD_FAB2(SCH_1):FM_MODPRST_HFI1_CPU0_LVT2_N    I21 @BASEBOARD_FAB2_LIB.BASEBOARD_FAB2(SCH_1):PAGE91

R8B20 RES_0402-10.0,1%,1/16W,CHIP,G2A
     1 H_PMSYNC_CLK_24M_R @BASEBOARD_FAB2_LIB.BASEBOARD_FAB2(SCH_1):H_PMSYNC_CLK_24M_R   I110 @BASEBOARD_FAB2_LIB.BASEBOARD_FAB2(SCH_1):PAGE114
     2 H_PMSYNC_CLK_24M @BASEBOARD_FAB2_LIB.BASEBOARD_FAB2(SCH_1):H_PMSYNC_CLK_24M   I110 @BASEBOARD_FAB2_LIB.BASEBOARD_FAB2(SCH_1):PAGE114

R8B21 RES_0402-49.9,1%,1/16W,EMPTY,GA
     1 H_PMSYNC_CLK_24M @BASEBOARD_FAB2_LIB.BASEBOARD_FAB2(SCH_1):H_PMSYNC_CLK_24M   I124 @BASEBOARD_FAB2_LIB.BASEBOARD_FAB2(SCH_1):PAGE114
     2    GND @BASEBOARD_FAB2_LIB.BASEBOARD_FAB2(SCH_1):GND   I124 @BASEBOARD_FAB2_LIB.BASEBOARD_FAB2(SCH_1):PAGE114

R8B23 RES_0402-1.00K,1%,1/16W,CHIP,GA
     1 P3V3_STBY @BASEBOARD_FAB2_LIB.BASEBOARD_FAB2(SCH_1):P3V3_STBY   I280 @BASEBOARD_FAB2_LIB.BASEBOARD_FAB2(SCH_1):PAGE133
     2 FM_XRC_PRESENT_N @BASEBOARD_FAB2_LIB.BASEBOARD_FAB2(SCH_1):FM_XRC_PRESENT_N   I280 @BASEBOARD_FAB2_LIB.BASEBOARD_FAB2(SCH_1):PAGE133

R8B24 RES_0402-3.3K,5%,1/16W,CHIP,G2A
     1 P3V3_STBY @BASEBOARD_FAB2_LIB.BASEBOARD_FAB2(SCH_1):P3V3_STBY    I95 @BASEBOARD_FAB2_LIB.BASEBOARD_FAB2(SCH_1):PAGE138
     2 SMB_SLOTX24_PCH_STBY_LVC3_SDA @BASEBOARD_FAB2_LIB.BASEBOARD_FAB2(SCH_1):SMB_SLOTX24_PCH_STBY_LVC3_SDA    I95 @BASEBOARD_FAB2_LIB.BASEBOARD_FAB2(SCH_1):PAGE138

R8B25 RES_0402-4.75K,1%,1/16W,CHIP,GA
     1 P3V3_STBY @BASEBOARD_FAB2_LIB.BASEBOARD_FAB2(SCH_1):P3V3_STBY   I156 @BASEBOARD_FAB2_LIB.BASEBOARD_FAB2(SCH_1):PAGE149
     2 FM_BMC_HEARTBEAT_N @BASEBOARD_FAB2_LIB.BASEBOARD_FAB2(SCH_1):FM_BMC_HEARTBEAT_N   I156 @BASEBOARD_FAB2_LIB.BASEBOARD_FAB2(SCH_1):PAGE149

R8B26 RES_0402-3.3K,5%,1/16W,CHIP,G2A
     1 P3V3_STBY @BASEBOARD_FAB2_LIB.BASEBOARD_FAB2(SCH_1):P3V3_STBY    I96 @BASEBOARD_FAB2_LIB.BASEBOARD_FAB2(SCH_1):PAGE138
     2 SMB_SLOTX24_PCH_STBY_LVC3_SCL @BASEBOARD_FAB2_LIB.BASEBOARD_FAB2(SCH_1):SMB_SLOTX24_PCH_STBY_LVC3_SCL    I96 @BASEBOARD_FAB2_LIB.BASEBOARD_FAB2(SCH_1):PAGE138

R8B27 RES_0402-20.0,1%,1/16W,CHIP,G2A
     1 SMB_SLOTX24_STBY_LVC3_SDA_R1 @BASEBOARD_FAB2_LIB.BASEBOARD_FAB2(SCH_1):SMB_SLOTX24_STBY_LVC3_SDA_R1   I173 @BASEBOARD_FAB2_LIB.BASEBOARD_FAB2(SCH_1):PAGE138
     2 SMB_SLOTX24_PCH_STBY_LVC3_SDA @BASEBOARD_FAB2_LIB.BASEBOARD_FAB2(SCH_1):SMB_SLOTX24_PCH_STBY_LVC3_SDA   I173 @BASEBOARD_FAB2_LIB.BASEBOARD_FAB2(SCH_1):PAGE138

R8B28 RES_0402-20.0,1%,1/16W,CHIP,G2A
     1 SMB_SLOTX24_STBY_LVC3_SCL_R1 @BASEBOARD_FAB2_LIB.BASEBOARD_FAB2(SCH_1):SMB_SLOTX24_STBY_LVC3_SCL_R1   I174 @BASEBOARD_FAB2_LIB.BASEBOARD_FAB2(SCH_1):PAGE138
     2 SMB_SLOTX24_PCH_STBY_LVC3_SCL @BASEBOARD_FAB2_LIB.BASEBOARD_FAB2(SCH_1):SMB_SLOTX24_PCH_STBY_LVC3_SCL   I174 @BASEBOARD_FAB2_LIB.BASEBOARD_FAB2(SCH_1):PAGE138

R8B29 RES_0402-49.9,1%,1/16W,CHIP,G2A
     1 SGPIO_PCH_SSATA_DOUT0 @BASEBOARD_FAB2_LIB.BASEBOARD_FAB2(SCH_1):SGPIO_PCH_SSATA_DOUT0    I21 @BASEBOARD_FAB2_LIB.BASEBOARD_FAB2(SCH_1):PAGE178
     2 SGPIO_PCH_SSATA_DOUT0_R @BASEBOARD_FAB2_LIB.BASEBOARD_FAB2(SCH_1):SGPIO_PCH_SSATA_DOUT0_R    I21 @BASEBOARD_FAB2_LIB.BASEBOARD_FAB2(SCH_1):PAGE178

R8B30 RES_0402-1.00K,1%,1/16W,CHIP,GA
     1 P3V3_STBY @BASEBOARD_FAB2_LIB.BASEBOARD_FAB2(SCH_1):P3V3_STBY   I282 @BASEBOARD_FAB2_LIB.BASEBOARD_FAB2(SCH_1):PAGE133
     2 FM_XRC_READY_N @BASEBOARD_FAB2_LIB.BASEBOARD_FAB2(SCH_1):FM_XRC_READY_N   I282 @BASEBOARD_FAB2_LIB.BASEBOARD_FAB2(SCH_1):PAGE133

R8B31 RES_0402-4.75K,1%,1/16W,CHIP,GA
     1 P3V3_STBY @BASEBOARD_FAB2_LIB.BASEBOARD_FAB2(SCH_1):P3V3_STBY   I307 @BASEBOARD_FAB2_LIB.BASEBOARD_FAB2(SCH_1):PAGE133
     2 FM_THROTTLE_N @BASEBOARD_FAB2_LIB.BASEBOARD_FAB2(SCH_1):FM_THROTTLE_N   I307 @BASEBOARD_FAB2_LIB.BASEBOARD_FAB2(SCH_1):PAGE133

R8B32 RES_0402-10.0K,1%,1/16W,CHIP,GA
     1 A_USB2_VBUS @BASEBOARD_FAB2_LIB.BASEBOARD_FAB2(SCH_1):A_USB2_VBUS   I114 @BASEBOARD_FAB2_LIB.BASEBOARD_FAB2(SCH_1):PAGE115
     2    GND @BASEBOARD_FAB2_LIB.BASEBOARD_FAB2(SCH_1):GND   I114 @BASEBOARD_FAB2_LIB.BASEBOARD_FAB2(SCH_1):PAGE115

R8C1 RES_0402-4.75K,1%,1/16W,CHIP,GA
     1 P3V3_STBY @BASEBOARD_FAB2_LIB.BASEBOARD_FAB2(SCH_1):P3V3_STBY   I326 @BASEBOARD_FAB2_LIB.BASEBOARD_FAB2(SCH_1):PAGE133
     2 FM_SLT_CFG1 @BASEBOARD_FAB2_LIB.BASEBOARD_FAB2(SCH_1):FM_SLT_CFG1   I326 @BASEBOARD_FAB2_LIB.BASEBOARD_FAB2(SCH_1):PAGE133

R8C2 RES_0402-4.75K,1%,1/16W,CHIP,GA
     1 P3V3_STBY @BASEBOARD_FAB2_LIB.BASEBOARD_FAB2(SCH_1):P3V3_STBY   I304 @BASEBOARD_FAB2_LIB.BASEBOARD_FAB2(SCH_1):PAGE133
     2 IRQ_BMC_PCH_SCI_LPC_N @BASEBOARD_FAB2_LIB.BASEBOARD_FAB2(SCH_1):IRQ_BMC_PCH_SCI_LPC_N   I304 @BASEBOARD_FAB2_LIB.BASEBOARD_FAB2(SCH_1):PAGE133

R8C4 RES_0402-1.00K,1%,1/16W,CHIP,GA
     1 P3V3_STBY @BASEBOARD_FAB2_LIB.BASEBOARD_FAB2(SCH_1):P3V3_STBY   I286 @BASEBOARD_FAB2_LIB.BASEBOARD_FAB2(SCH_1):PAGE133
     2 IRQ_BMC_PCH_SMI_LPC_N @BASEBOARD_FAB2_LIB.BASEBOARD_FAB2(SCH_1):IRQ_BMC_PCH_SMI_LPC_N   I286 @BASEBOARD_FAB2_LIB.BASEBOARD_FAB2(SCH_1):PAGE133

R8C6 RES_0402-4.75K,1%,1/16W,CHIP,GA
     1 P3V3_STBY @BASEBOARD_FAB2_LIB.BASEBOARD_FAB2(SCH_1):P3V3_STBY   I303 @BASEBOARD_FAB2_LIB.BASEBOARD_FAB2(SCH_1):PAGE133
     2 FM_BIOS_POST_CMPLT_N @BASEBOARD_FAB2_LIB.BASEBOARD_FAB2(SCH_1):FM_BIOS_POST_CMPLT_N   I303 @BASEBOARD_FAB2_LIB.BASEBOARD_FAB2(SCH_1):PAGE133

R8C7 RES_0402-4.75K,1%,1/16W,CHIP,GA
     1 P3V3_STBY @BASEBOARD_FAB2_LIB.BASEBOARD_FAB2(SCH_1):P3V3_STBY   I327 @BASEBOARD_FAB2_LIB.BASEBOARD_FAB2(SCH_1):PAGE133
     2 FM_SLT_CFG0 @BASEBOARD_FAB2_LIB.BASEBOARD_FAB2(SCH_1):FM_SLT_CFG0   I327 @BASEBOARD_FAB2_LIB.BASEBOARD_FAB2(SCH_1):PAGE133

R8C9 RES_0402-4.75K,1%,1/16W,CHIP,GA
     1 P3V3_STBY @BASEBOARD_FAB2_LIB.BASEBOARD_FAB2(SCH_1):P3V3_STBY    I20 @BASEBOARD_FAB2_LIB.BASEBOARD_FAB2(SCH_1):PAGE126
     2 IRQ_SML0_ALERT_N @BASEBOARD_FAB2_LIB.BASEBOARD_FAB2(SCH_1):IRQ_SML0_ALERT_N    I20 @BASEBOARD_FAB2_LIB.BASEBOARD_FAB2(SCH_1):PAGE126

R8C11 RES_0402-20.0,1%,1/16W,CHIP,G2A
     1 SMB_SMLINK0_STBY_LVC3_SDA_R1 @BASEBOARD_FAB2_LIB.BASEBOARD_FAB2(SCH_1):SMB_SMLINK0_STBY_LVC3_SDA_R1   I169 @BASEBOARD_FAB2_LIB.BASEBOARD_FAB2(SCH_1):PAGE138
     2 SMB_SMLINK0_STBY_LVC3_SDA @BASEBOARD_FAB2_LIB.BASEBOARD_FAB2(SCH_1):SMB_SMLINK0_STBY_LVC3_SDA   I169 @BASEBOARD_FAB2_LIB.BASEBOARD_FAB2(SCH_1):PAGE138

R8C12 RES_0402-20.0,1%,1/16W,CHIP,G2A
     1 SMB_SMLINK0_STBY_LVC3_SCL_R1 @BASEBOARD_FAB2_LIB.BASEBOARD_FAB2(SCH_1):SMB_SMLINK0_STBY_LVC3_SCL_R1   I170 @BASEBOARD_FAB2_LIB.BASEBOARD_FAB2(SCH_1):PAGE138
     2 SMB_SMLINK0_STBY_LVC3_SCL @BASEBOARD_FAB2_LIB.BASEBOARD_FAB2(SCH_1):SMB_SMLINK0_STBY_LVC3_SCL   I170 @BASEBOARD_FAB2_LIB.BASEBOARD_FAB2(SCH_1):PAGE138

R8C14 RES_0402-20.0,1%,1/16W,CHIP,G2A
     1 SMB_HOST_STBY_LVC3_SCL_R1 @BASEBOARD_FAB2_LIB.BASEBOARD_FAB2(SCH_1):SMB_HOST_STBY_LVC3_SCL_R1   I168 @BASEBOARD_FAB2_LIB.BASEBOARD_FAB2(SCH_1):PAGE138
     2 SMB_HOST_STBY_LVC3_SCL @BASEBOARD_FAB2_LIB.BASEBOARD_FAB2(SCH_1):SMB_HOST_STBY_LVC3_SCL   I168 @BASEBOARD_FAB2_LIB.BASEBOARD_FAB2(SCH_1):PAGE138

R8C15 RES_0402-2.0K,1%,1/16W,CHIP,G2A
     1 P3V3_STBY @BASEBOARD_FAB2_LIB.BASEBOARD_FAB2(SCH_1):P3V3_STBY    I92 @BASEBOARD_FAB2_LIB.BASEBOARD_FAB2(SCH_1):PAGE138
     2 SMB_HOST_STBY_LVC3_SCL @BASEBOARD_FAB2_LIB.BASEBOARD_FAB2(SCH_1):SMB_HOST_STBY_LVC3_SCL    I92 @BASEBOARD_FAB2_LIB.BASEBOARD_FAB2(SCH_1):PAGE138

R8C16 RES_0402-2.0K,1%,1/16W,CHIP,G2A
     1 P3V3_STBY @BASEBOARD_FAB2_LIB.BASEBOARD_FAB2(SCH_1):P3V3_STBY    I91 @BASEBOARD_FAB2_LIB.BASEBOARD_FAB2(SCH_1):PAGE138
     2 SMB_HOST_STBY_LVC3_SDA @BASEBOARD_FAB2_LIB.BASEBOARD_FAB2(SCH_1):SMB_HOST_STBY_LVC3_SDA    I91 @BASEBOARD_FAB2_LIB.BASEBOARD_FAB2(SCH_1):PAGE138

R8C17 RES_0402-1.00K,1%,1/16W,EMPTY,A
     1 PU_PCH_TLS_ENABLE_STRAP @BASEBOARD_FAB2_LIB.BASEBOARD_FAB2(SCH_1):PU_PCH_TLS_ENABLE_STRAP    I41 @BASEBOARD_FAB2_LIB.BASEBOARD_FAB2(SCH_1):PAGE125
     2    GND @BASEBOARD_FAB2_LIB.BASEBOARD_FAB2(SCH_1):GND    I41 @BASEBOARD_FAB2_LIB.BASEBOARD_FAB2(SCH_1):PAGE125

R8C18 RES_0402-1.00K,1%,1/16W,CHIP,GA
     1 P3V3_STBY @BASEBOARD_FAB2_LIB.BASEBOARD_FAB2(SCH_1):P3V3_STBY    I40 @BASEBOARD_FAB2_LIB.BASEBOARD_FAB2(SCH_1):PAGE125
     2 PU_PCH_TLS_ENABLE_STRAP @BASEBOARD_FAB2_LIB.BASEBOARD_FAB2(SCH_1):PU_PCH_TLS_ENABLE_STRAP    I40 @BASEBOARD_FAB2_LIB.BASEBOARD_FAB2(SCH_1):PAGE125

R8C20 RES_0402-20.0,1%,1/16W,CHIP,G2A
     1 SMB_HOST_STBY_LVC3_SDA_R1 @BASEBOARD_FAB2_LIB.BASEBOARD_FAB2(SCH_1):SMB_HOST_STBY_LVC3_SDA_R1   I167 @BASEBOARD_FAB2_LIB.BASEBOARD_FAB2(SCH_1):PAGE138
     2 SMB_HOST_STBY_LVC3_SDA @BASEBOARD_FAB2_LIB.BASEBOARD_FAB2(SCH_1):SMB_HOST_STBY_LVC3_SDA   I167 @BASEBOARD_FAB2_LIB.BASEBOARD_FAB2(SCH_1):PAGE138

R8C21 RES_0402-100.0,1%,1/16W,CHIP,GA
     1 A_RCOMP_3P3 @BASEBOARD_FAB2_LIB.BASEBOARD_FAB2(SCH_1):A_RCOMP_3P3   I148 @BASEBOARD_FAB2_LIB.BASEBOARD_FAB2(SCH_1):PAGE120
     2    GND @BASEBOARD_FAB2_LIB.BASEBOARD_FAB2(SCH_1):GND   I148 @BASEBOARD_FAB2_LIB.BASEBOARD_FAB2(SCH_1):PAGE120

R8C23 RES_0402-0.0,5%,1/16W,EMPTY,G2A
     1 FM_GBE_LOM_DISABLE_N @BASEBOARD_FAB2_LIB.BASEBOARD_FAB2(SCH_1):FM_GBE_LOM_DISABLE_N   I125 @BASEBOARD_FAB2_LIB.BASEBOARD_FAB2(SCH_1):PAGE118
     2 FM_10GBE_LOM_DISABLE_N @BASEBOARD_FAB2_LIB.BASEBOARD_FAB2(SCH_1):FM_10GBE_LOM_DISABLE_N   I125 @BASEBOARD_FAB2_LIB.BASEBOARD_FAB2(SCH_1):PAGE118

R8C24 RES_0402-0.0,5%,1/16W,CHIP,G21A
     1 FM_GBE_LOM_DISABLE_N @BASEBOARD_FAB2_LIB.BASEBOARD_FAB2(SCH_1):FM_GBE_LOM_DISABLE_N   I120 @BASEBOARD_FAB2_LIB.BASEBOARD_FAB2(SCH_1):PAGE118
     2 FM_1GB_LOM_DISABLE_N @BASEBOARD_FAB2_LIB.BASEBOARD_FAB2(SCH_1):FM_1GB_LOM_DISABLE_N   I120 @BASEBOARD_FAB2_LIB.BASEBOARD_FAB2(SCH_1):PAGE118

R8C25 RES_0402-4.75K,1%,1/16W,CHIP,GA
     1 P3V3_STBY @BASEBOARD_FAB2_LIB.BASEBOARD_FAB2(SCH_1):P3V3_STBY   I333 @BASEBOARD_FAB2_LIB.BASEBOARD_FAB2(SCH_1):PAGE133
     2 IRQ_PCH_NIC_ALERT_N @BASEBOARD_FAB2_LIB.BASEBOARD_FAB2(SCH_1):IRQ_PCH_NIC_ALERT_N   I333 @BASEBOARD_FAB2_LIB.BASEBOARD_FAB2(SCH_1):PAGE133

R8C26 RES_0402-100.0,1%,1/16W,CHIP,GA
     1 A_1P8_3P3_RCOMP @BASEBOARD_FAB2_LIB.BASEBOARD_FAB2(SCH_1):A_1P8_3P3_RCOMP    I35 @BASEBOARD_FAB2_LIB.BASEBOARD_FAB2(SCH_1):PAGE121
     2    GND @BASEBOARD_FAB2_LIB.BASEBOARD_FAB2(SCH_1):GND    I35 @BASEBOARD_FAB2_LIB.BASEBOARD_FAB2(SCH_1):PAGE121

R8D3 RES_0402-20.0,1%,1/16W,CHIP,G2A
     1 SMB_SENSOR_STBY_LVC3_SCL_R1 @BASEBOARD_FAB2_LIB.BASEBOARD_FAB2(SCH_1):SMB_SENSOR_STBY_LVC3_SCL_R1   I161 @BASEBOARD_FAB2_LIB.BASEBOARD_FAB2(SCH_1):PAGE138
     2 SMB_SENSOR_PCH_STBY_LVC3_SCL @BASEBOARD_FAB2_LIB.BASEBOARD_FAB2(SCH_1):SMB_SENSOR_PCH_STBY_LVC3_SCL   I161 @BASEBOARD_FAB2_LIB.BASEBOARD_FAB2(SCH_1):PAGE138

R8D4 RES_0402-20.0,1%,1/16W,CHIP,G2A
     1 SMB_VR_STBY_LVC3_SCL_R1 @BASEBOARD_FAB2_LIB.BASEBOARD_FAB2(SCH_1):SMB_VR_STBY_LVC3_SCL_R1   I164 @BASEBOARD_FAB2_LIB.BASEBOARD_FAB2(SCH_1):PAGE138
     2 SMB_VR_STBY_LVC3_SCL @BASEBOARD_FAB2_LIB.BASEBOARD_FAB2(SCH_1):SMB_VR_STBY_LVC3_SCL   I164 @BASEBOARD_FAB2_LIB.BASEBOARD_FAB2(SCH_1):PAGE138

R8D5 RES_0402-1.00K,1%,1/16W,EMPTY,A
     1 PU_ADR_TIMER_HOLD_OFF_N @BASEBOARD_FAB2_LIB.BASEBOARD_FAB2(SCH_1):PU_ADR_TIMER_HOLD_OFF_N    I50 @BASEBOARD_FAB2_LIB.BASEBOARD_FAB2(SCH_1):PAGE125
     2    GND @BASEBOARD_FAB2_LIB.BASEBOARD_FAB2(SCH_1):GND    I50 @BASEBOARD_FAB2_LIB.BASEBOARD_FAB2(SCH_1):PAGE125

R8D6 RES_0402-20.0,1%,1/16W,CHIP,G2A
     1 SMB_SENSOR_STBY_LVC3_SDA_R1 @BASEBOARD_FAB2_LIB.BASEBOARD_FAB2(SCH_1):SMB_SENSOR_STBY_LVC3_SDA_R1   I162 @BASEBOARD_FAB2_LIB.BASEBOARD_FAB2(SCH_1):PAGE138
     2 SMB_SENSOR_PCH_STBY_LVC3_SDA @BASEBOARD_FAB2_LIB.BASEBOARD_FAB2(SCH_1):SMB_SENSOR_PCH_STBY_LVC3_SDA   I162 @BASEBOARD_FAB2_LIB.BASEBOARD_FAB2(SCH_1):PAGE138

R8D7 RES_0402-20.0,1%,1/16W,CHIP,G2A
     1 SMB_VR_STBY_LVC3_SDA_R1 @BASEBOARD_FAB2_LIB.BASEBOARD_FAB2(SCH_1):SMB_VR_STBY_LVC3_SDA_R1   I163 @BASEBOARD_FAB2_LIB.BASEBOARD_FAB2(SCH_1):PAGE138
     2 SMB_VR_STBY_LVC3_SDA @BASEBOARD_FAB2_LIB.BASEBOARD_FAB2(SCH_1):SMB_VR_STBY_LVC3_SDA   I163 @BASEBOARD_FAB2_LIB.BASEBOARD_FAB2(SCH_1):PAGE138

R8D11 RES_0402-33.2,1%,1/16W,CHIP,G2A
     1 RMII_PCH_SPRNGVLLE_ARB_OUT @BASEBOARD_FAB2_LIB.BASEBOARD_FAB2(SCH_1):RMII_PCH_SPRNGVLLE_ARB_OUT   I101 @BASEBOARD_FAB2_LIB.BASEBOARD_FAB2(SCH_1):PAGE121
     2 RMII_PCH_SPRNGVLLE_ARB_OUT_R @BASEBOARD_FAB2_LIB.BASEBOARD_FAB2(SCH_1):RMII_PCH_SPRNGVLLE_ARB_OUT_R   I101 @BASEBOARD_FAB2_LIB.BASEBOARD_FAB2(SCH_1):PAGE121

R8D13 RES_0402-10.0K,1%,1/16W,CHIP,GA
     1 P3V3_STBY @BASEBOARD_FAB2_LIB.BASEBOARD_FAB2(SCH_1):P3V3_STBY    I52 @BASEBOARD_FAB2_LIB.BASEBOARD_FAB2(SCH_1):PAGE125
     2 PU_ADR_TIMER_HOLD_OFF_N @BASEBOARD_FAB2_LIB.BASEBOARD_FAB2(SCH_1):PU_ADR_TIMER_HOLD_OFF_N    I52 @BASEBOARD_FAB2_LIB.BASEBOARD_FAB2(SCH_1):PAGE125

R8D14 RES_0402-4.75K,1%,1/16W,CHIP,GA
     1 P3V3_STBY @BASEBOARD_FAB2_LIB.BASEBOARD_FAB2(SCH_1):P3V3_STBY   I301 @BASEBOARD_FAB2_LIB.BASEBOARD_FAB2(SCH_1):PAGE133
     2 FP_PWR_ID_LED_N @BASEBOARD_FAB2_LIB.BASEBOARD_FAB2(SCH_1):FP_PWR_ID_LED_N   I301 @BASEBOARD_FAB2_LIB.BASEBOARD_FAB2(SCH_1):PAGE133

R8D15 RES_0402-1.37K,1%,1/16W,CHIP,GA
     1 P3V3_STBY @BASEBOARD_FAB2_LIB.BASEBOARD_FAB2(SCH_1):P3V3_STBY    I88 @BASEBOARD_FAB2_LIB.BASEBOARD_FAB2(SCH_1):PAGE138
     2 SMB_VR_STBY_LVC3_SCL @BASEBOARD_FAB2_LIB.BASEBOARD_FAB2(SCH_1):SMB_VR_STBY_LVC3_SCL    I88 @BASEBOARD_FAB2_LIB.BASEBOARD_FAB2(SCH_1):PAGE138

R8D16 RES_0402-10.0K,1%,1/16W,EMPTY,A
     1 P3V3_STBY @BASEBOARD_FAB2_LIB.BASEBOARD_FAB2(SCH_1):P3V3_STBY    I71 @BASEBOARD_FAB2_LIB.BASEBOARD_FAB2(SCH_1):PAGE125
     2 RMII_PCH_SPRNGVLLE_ARB_OUT @BASEBOARD_FAB2_LIB.BASEBOARD_FAB2(SCH_1):RMII_PCH_SPRNGVLLE_ARB_OUT    I71 @BASEBOARD_FAB2_LIB.BASEBOARD_FAB2(SCH_1):PAGE125

R8D17 RES_0402-1.37K,1%,1/16W,CHIP,GA
     1 P3V3_STBY @BASEBOARD_FAB2_LIB.BASEBOARD_FAB2(SCH_1):P3V3_STBY    I87 @BASEBOARD_FAB2_LIB.BASEBOARD_FAB2(SCH_1):PAGE138
     2 SMB_VR_STBY_LVC3_SDA @BASEBOARD_FAB2_LIB.BASEBOARD_FAB2(SCH_1):SMB_VR_STBY_LVC3_SDA    I87 @BASEBOARD_FAB2_LIB.BASEBOARD_FAB2(SCH_1):PAGE138

R8D19 RES_0402-49.9,1%,1/16W,CHIP,G2A
     1 SGPIO_PCH_SATA_DOUT0 @BASEBOARD_FAB2_LIB.BASEBOARD_FAB2(SCH_1):SGPIO_PCH_SATA_DOUT0     I8 @BASEBOARD_FAB2_LIB.BASEBOARD_FAB2(SCH_1):PAGE178
     2 SGPIO_PCH_SATA_DOUT0_R @BASEBOARD_FAB2_LIB.BASEBOARD_FAB2(SCH_1):SGPIO_PCH_SATA_DOUT0_R     I8 @BASEBOARD_FAB2_LIB.BASEBOARD_FAB2(SCH_1):PAGE178

R8D20 RES_0402-49.9,1%,1/16W,CHIP,G2A
     1 SGPIO_PCH_SATA_LOAD @BASEBOARD_FAB2_LIB.BASEBOARD_FAB2(SCH_1):SGPIO_PCH_SATA_LOAD     I1 @BASEBOARD_FAB2_LIB.BASEBOARD_FAB2(SCH_1):PAGE178
     2 SGPIO_PCH_SATA_LOAD_R @BASEBOARD_FAB2_LIB.BASEBOARD_FAB2(SCH_1):SGPIO_PCH_SATA_LOAD_R     I1 @BASEBOARD_FAB2_LIB.BASEBOARD_FAB2(SCH_1):PAGE178

R8D21 RES_0402-1.00K,1%,1/16W,CHIP,GA
     1 P3V3_STBY @BASEBOARD_FAB2_LIB.BASEBOARD_FAB2(SCH_1):P3V3_STBY   I120 @BASEBOARD_FAB2_LIB.BASEBOARD_FAB2(SCH_1):PAGE135
     2 FM_IE_DISABLE_N @BASEBOARD_FAB2_LIB.BASEBOARD_FAB2(SCH_1):FM_IE_DISABLE_N   I120 @BASEBOARD_FAB2_LIB.BASEBOARD_FAB2(SCH_1):PAGE135

R8D22 RES_0402-33.2,1%,1/16W,CHIP,G2A
     1 RST_BMC_SRST_R2_N @BASEBOARD_FAB2_LIB.BASEBOARD_FAB2(SCH_1):RST_BMC_SRST_R2_N   I386 @BASEBOARD_FAB2_LIB.BASEBOARD_FAB2(SCH_1):PAGE157
     2 FM_TPM_PRES_RST_N @BASEBOARD_FAB2_LIB.BASEBOARD_FAB2(SCH_1):FM_TPM_PRES_RST_N   I386 @BASEBOARD_FAB2_LIB.BASEBOARD_FAB2(SCH_1):PAGE157

R8D23 RES_0402-20.0,1%,1/16W,CHIP,G2A
     1 SMB_SENSOR_STBY_LVC3_SDA_R2 @BASEBOARD_FAB2_LIB.BASEBOARD_FAB2(SCH_1):SMB_SENSOR_STBY_LVC3_SDA_R2    I85 @BASEBOARD_FAB2_LIB.BASEBOARD_FAB2(SCH_1):PAGE167
     2 SMB_SENSOR_STBY_LVC3_SDA @BASEBOARD_FAB2_LIB.BASEBOARD_FAB2(SCH_1):SMB_SENSOR_STBY_LVC3_SDA    I85 @BASEBOARD_FAB2_LIB.BASEBOARD_FAB2(SCH_1):PAGE167

R8D24 RES_0402-20.0,1%,1/16W,CHIP,G2A
     1 SMB_SENSOR_STBY_LVC3_SCL @BASEBOARD_FAB2_LIB.BASEBOARD_FAB2(SCH_1):SMB_SENSOR_STBY_LVC3_SCL    I84 @BASEBOARD_FAB2_LIB.BASEBOARD_FAB2(SCH_1):PAGE167
     2 SMB_SENSOR_STBY_LVC3_SCL_R2 @BASEBOARD_FAB2_LIB.BASEBOARD_FAB2(SCH_1):SMB_SENSOR_STBY_LVC3_SCL_R2    I84 @BASEBOARD_FAB2_LIB.BASEBOARD_FAB2(SCH_1):PAGE167

R8D25 RES_0402-4.75K,1%,1/16W,CHIP,GA
     1 P3V3_STBY @BASEBOARD_FAB2_LIB.BASEBOARD_FAB2(SCH_1):P3V3_STBY   I335 @BASEBOARD_FAB2_LIB.BASEBOARD_FAB2(SCH_1):PAGE157
     2 RST_BMC_SRST_R2_N @BASEBOARD_FAB2_LIB.BASEBOARD_FAB2(SCH_1):RST_BMC_SRST_R2_N   I335 @BASEBOARD_FAB2_LIB.BASEBOARD_FAB2(SCH_1):PAGE157

R8D26 RES_0402-4.75K,1%,1/16W,CHIP,GA
     1 P3V3_STBY @BASEBOARD_FAB2_LIB.BASEBOARD_FAB2(SCH_1):P3V3_STBY    I71 @BASEBOARD_FAB2_LIB.BASEBOARD_FAB2(SCH_1):PAGE170
     2 IRQ_SML1_PMBUS_ALERT_BUF_N @BASEBOARD_FAB2_LIB.BASEBOARD_FAB2(SCH_1):IRQ_SML1_PMBUS_ALERT_BUF_N    I71 @BASEBOARD_FAB2_LIB.BASEBOARD_FAB2(SCH_1):PAGE170

R8D27 RES_0402-1.00K,1%,1/16W,CHIP,GA
     1 PD_FRU_WP @BASEBOARD_FAB2_LIB.BASEBOARD_FAB2(SCH_1):PD_FRU_WP    I50 @BASEBOARD_FAB2_LIB.BASEBOARD_FAB2(SCH_1):PAGE167
     2    GND @BASEBOARD_FAB2_LIB.BASEBOARD_FAB2(SCH_1):GND    I50 @BASEBOARD_FAB2_LIB.BASEBOARD_FAB2(SCH_1):PAGE167

R8D28 RES_0402-1.00K,1%,1/16W,CHIP,GA
     1 P3V3_STBY @BASEBOARD_FAB2_LIB.BASEBOARD_FAB2(SCH_1):P3V3_STBY    I70 @BASEBOARD_FAB2_LIB.BASEBOARD_FAB2(SCH_1):PAGE167
     2 PU_AT24C64_A2 @BASEBOARD_FAB2_LIB.BASEBOARD_FAB2(SCH_1):PU_AT24C64_A2    I70 @BASEBOARD_FAB2_LIB.BASEBOARD_FAB2(SCH_1):PAGE167

R8D29 RES_0402-4.75K,1%,1/16W,CHIP,GA
     1 P3V3_STBY @BASEBOARD_FAB2_LIB.BASEBOARD_FAB2(SCH_1):P3V3_STBY    I26 @BASEBOARD_FAB2_LIB.BASEBOARD_FAB2(SCH_1):PAGE89
     2 IRQ_DIMM_SAVE_LVT3 @BASEBOARD_FAB2_LIB.BASEBOARD_FAB2(SCH_1):IRQ_DIMM_SAVE_LVT3    I26 @BASEBOARD_FAB2_LIB.BASEBOARD_FAB2(SCH_1):PAGE89

R8D30 RES_0402-10.0K,1%,1/16W,CHIP,GA
     1 IRQ_DIMM_SAVE_N @BASEBOARD_FAB2_LIB.BASEBOARD_FAB2(SCH_1):IRQ_DIMM_SAVE_N    I34 @BASEBOARD_FAB2_LIB.BASEBOARD_FAB2(SCH_1):PAGE89
     2 IRQ_DIMM_SAVE_R_N @BASEBOARD_FAB2_LIB.BASEBOARD_FAB2(SCH_1):IRQ_DIMM_SAVE_R_N    I34 @BASEBOARD_FAB2_LIB.BASEBOARD_FAB2(SCH_1):PAGE89

R8D31 RES_0402-4.75K,1%,1/16W,CHIP,GA
     1 P3V3_STBY @BASEBOARD_FAB2_LIB.BASEBOARD_FAB2(SCH_1):P3V3_STBY    I27 @BASEBOARD_FAB2_LIB.BASEBOARD_FAB2(SCH_1):PAGE89
     2 IRQ_DIMM_SAVE_LVT3_N @BASEBOARD_FAB2_LIB.BASEBOARD_FAB2(SCH_1):IRQ_DIMM_SAVE_LVT3_N    I27 @BASEBOARD_FAB2_LIB.BASEBOARD_FAB2(SCH_1):PAGE89

R8D35 RES_0402-0.0,5%,1/16W,CHIP,G21A
     1 SPI_PCH_TPM_CS_N @BASEBOARD_FAB2_LIB.BASEBOARD_FAB2(SCH_1):SPI_PCH_TPM_CS_N    I92 @BASEBOARD_FAB2_LIB.BASEBOARD_FAB2(SCH_1):PAGE184
     2 SPI_PCH_TPM_CS_R_N @BASEBOARD_FAB2_LIB.BASEBOARD_FAB2(SCH_1):SPI_PCH_TPM_CS_R_N    I92 @BASEBOARD_FAB2_LIB.BASEBOARD_FAB2(SCH_1):PAGE184

R8D36 RES_0402-33.2,1%,1/16W,CHIP,G2A
     1 RST_BMC_SRST_R2_N @BASEBOARD_FAB2_LIB.BASEBOARD_FAB2(SCH_1):RST_BMC_SRST_R2_N   I388 @BASEBOARD_FAB2_LIB.BASEBOARD_FAB2(SCH_1):PAGE157
     2 RST_BMC_DDR3_BUF_IN_N @BASEBOARD_FAB2_LIB.BASEBOARD_FAB2(SCH_1):RST_BMC_DDR3_BUF_IN_N   I388 @BASEBOARD_FAB2_LIB.BASEBOARD_FAB2(SCH_1):PAGE157

R8D37 RES_0402-4.75K,1%,1/16W,CHIP,GA
     1 A_PG_P5V @BASEBOARD_FAB2_LIB.BASEBOARD_FAB2(SCH_1):A_PG_P5V   I115 @BASEBOARD_FAB2_LIB.BASEBOARD_FAB2(SCH_1):PAGE196
     2    GND @BASEBOARD_FAB2_LIB.BASEBOARD_FAB2(SCH_1):GND   I115 @BASEBOARD_FAB2_LIB.BASEBOARD_FAB2(SCH_1):PAGE196

R8D38 RES_0402-100.0K,1%,1/16W,CHIP,A
     1   P12V @BASEBOARD_FAB2_LIB.BASEBOARD_FAB2(SCH_1):P12V   I112 @BASEBOARD_FAB2_LIB.BASEBOARD_FAB2(SCH_1):PAGE196
     2 A_PG_P12V_MAIN @BASEBOARD_FAB2_LIB.BASEBOARD_FAB2(SCH_1):A_PG_P12V_MAIN   I112 @BASEBOARD_FAB2_LIB.BASEBOARD_FAB2(SCH_1):PAGE196

R8D39 RES_0402-49.9K,1%,1/16W,CHIP,GA
     1    P5V @BASEBOARD_FAB2_LIB.BASEBOARD_FAB2(SCH_1):P5V   I114 @BASEBOARD_FAB2_LIB.BASEBOARD_FAB2(SCH_1):PAGE196
     2 A_PG_P5V @BASEBOARD_FAB2_LIB.BASEBOARD_FAB2(SCH_1):A_PG_P5V   I114 @BASEBOARD_FAB2_LIB.BASEBOARD_FAB2(SCH_1):PAGE196

R8D40 RES_0402-3.74K,1%,1/16W,CHIP,GA
     1 A_PG_P12V_MAIN @BASEBOARD_FAB2_LIB.BASEBOARD_FAB2(SCH_1):A_PG_P12V_MAIN   I113 @BASEBOARD_FAB2_LIB.BASEBOARD_FAB2(SCH_1):PAGE196
     2    GND @BASEBOARD_FAB2_LIB.BASEBOARD_FAB2(SCH_1):GND   I113 @BASEBOARD_FAB2_LIB.BASEBOARD_FAB2(SCH_1):PAGE196

R8D41 RES_0402-10.0K,1%,1/16W,CHIP,GA
     1 P3V3_STBY @BASEBOARD_FAB2_LIB.BASEBOARD_FAB2(SCH_1):P3V3_STBY   I120 @BASEBOARD_FAB2_LIB.BASEBOARD_FAB2(SCH_1):PAGE196
     2 PWRGD_P12V_MAIN_R @BASEBOARD_FAB2_LIB.BASEBOARD_FAB2(SCH_1):PWRGD_P12V_MAIN_R   I120 @BASEBOARD_FAB2_LIB.BASEBOARD_FAB2(SCH_1):PAGE196

R8D42 RES_0402-100.0,1%,1/16W,CHIP,GA
     1 PWRGD_P12V_MAIN_R @BASEBOARD_FAB2_LIB.BASEBOARD_FAB2(SCH_1):PWRGD_P12V_MAIN_R   I106 @BASEBOARD_FAB2_LIB.BASEBOARD_FAB2(SCH_1):PAGE196
     2 PWRGD_P12V_MAIN @BASEBOARD_FAB2_LIB.BASEBOARD_FAB2(SCH_1):PWRGD_P12V_MAIN   I106 @BASEBOARD_FAB2_LIB.BASEBOARD_FAB2(SCH_1):PAGE196

R8D43 RES_0402-0.0,5%,1/16W,CHIP,G21A
     1 FM_156M_CPU0_BRD_OSC_EN @BASEBOARD_FAB2_LIB.BASEBOARD_FAB2(SCH_1):FM_156M_CPU0_BRD_OSC_EN    I93 @BASEBOARD_FAB2_LIB.BASEBOARD_FAB2(SCH_1):PAGE104
     2 FM_CPU0_STL_BRD_OSC_EN @BASEBOARD_FAB2_LIB.BASEBOARD_FAB2(SCH_1):FM_CPU0_STL_BRD_OSC_EN    I93 @BASEBOARD_FAB2_LIB.BASEBOARD_FAB2(SCH_1):PAGE104

R8D44 RES_0402-10.0K,1%,1/16W,CHIP,GA
     1 P3V3_STBY @BASEBOARD_FAB2_LIB.BASEBOARD_FAB2(SCH_1):P3V3_STBY   I362 @BASEBOARD_FAB2_LIB.BASEBOARD_FAB2(SCH_1):PAGE133
     2 FM_CPU0_RC_EN @BASEBOARD_FAB2_LIB.BASEBOARD_FAB2(SCH_1):FM_CPU0_RC_EN   I362 @BASEBOARD_FAB2_LIB.BASEBOARD_FAB2(SCH_1):PAGE133

R8E1 RES_0402-0.0,5%,1/16W,CHIP,G21A
     1 IRQ_SPI_TPM_N_R @BASEBOARD_FAB2_LIB.BASEBOARD_FAB2(SCH_1):IRQ_SPI_TPM_N_R    I99 @BASEBOARD_FAB2_LIB.BASEBOARD_FAB2(SCH_1):PAGE184
     2 IRQ_PIRQA_SPI_TPM_N @BASEBOARD_FAB2_LIB.BASEBOARD_FAB2(SCH_1):IRQ_PIRQA_SPI_TPM_N    I99 @BASEBOARD_FAB2_LIB.BASEBOARD_FAB2(SCH_1):PAGE184

R8E2 RES_0402-1.00K,1%,1/16W,CHIP,GA
     1 XDP_SPI_PCH_MOSI_BOOT_HALT_N @BASEBOARD_FAB2_LIB.BASEBOARD_FAB2(SCH_1):XDP_SPI_PCH_MOSI_BOOT_HALT_N    I89 @BASEBOARD_FAB2_LIB.BASEBOARD_FAB2(SCH_1):PAGE111
     2 SPI_PCH_MOSI @BASEBOARD_FAB2_LIB.BASEBOARD_FAB2(SCH_1):SPI_PCH_MOSI    I89 @BASEBOARD_FAB2_LIB.BASEBOARD_FAB2(SCH_1):PAGE111

R8E3 RES_0402-10.0K,1%,1/16W,CHIP,GA
     1 P3V3_STBY @BASEBOARD_FAB2_LIB.BASEBOARD_FAB2(SCH_1):P3V3_STBY   I355 @BASEBOARD_FAB2_LIB.BASEBOARD_FAB2(SCH_1):PAGE133
     2 FM_TPM_PRES_N @BASEBOARD_FAB2_LIB.BASEBOARD_FAB2(SCH_1):FM_TPM_PRES_N   I355 @BASEBOARD_FAB2_LIB.BASEBOARD_FAB2(SCH_1):PAGE133

R8E4 RES_0402-1.00K,1%,1/16W,EMPTY,A
     1 SPI_PCH_MOSI @BASEBOARD_FAB2_LIB.BASEBOARD_FAB2(SCH_1):SPI_PCH_MOSI    I24 @BASEBOARD_FAB2_LIB.BASEBOARD_FAB2(SCH_1):PAGE125
     2    GND @BASEBOARD_FAB2_LIB.BASEBOARD_FAB2(SCH_1):GND    I24 @BASEBOARD_FAB2_LIB.BASEBOARD_FAB2(SCH_1):PAGE125

R8E5 RES_0402-33.2,1%,1/16W,CHIP,G2A
     1 FM_CTNR_PS_ON_R @BASEBOARD_FAB2_LIB.BASEBOARD_FAB2(SCH_1):FM_CTNR_PS_ON_R   I218 @BASEBOARD_FAB2_LIB.BASEBOARD_FAB2(SCH_1):PAGE181
     2 FM_CTNR_PS_ON @BASEBOARD_FAB2_LIB.BASEBOARD_FAB2(SCH_1):FM_CTNR_PS_ON   I218 @BASEBOARD_FAB2_LIB.BASEBOARD_FAB2(SCH_1):PAGE181

R8E6 RES_0402-1.00K,1%,1/16W,EMPTY,A
     1 P3V3_STBY @BASEBOARD_FAB2_LIB.BASEBOARD_FAB2(SCH_1):P3V3_STBY    I21 @BASEBOARD_FAB2_LIB.BASEBOARD_FAB2(SCH_1):PAGE125
     2 SPI_PCH_MOSI @BASEBOARD_FAB2_LIB.BASEBOARD_FAB2(SCH_1):SPI_PCH_MOSI    I21 @BASEBOARD_FAB2_LIB.BASEBOARD_FAB2(SCH_1):PAGE125

R8E7 RES_0402-22.1,1.0%,1/16W,CHIP,A
     1 PWRGD_P12V_HSC_DLY_R @BASEBOARD_FAB2_LIB.BASEBOARD_FAB2(SCH_1):PWRGD_P12V_HSC_DLY_R    I90 @BASEBOARD_FAB2_LIB.BASEBOARD_FAB2(SCH_1):PAGE196
     2 PWRGD_P12V_HSC_DLY @BASEBOARD_FAB2_LIB.BASEBOARD_FAB2(SCH_1):PWRGD_P12V_HSC_DLY    I90 @BASEBOARD_FAB2_LIB.BASEBOARD_FAB2(SCH_1):PAGE196

R8E9 RES_0402-33.2,1%,1/16W,CHIP,G2A
     1 SPI_PCH_CLK @BASEBOARD_FAB2_LIB.BASEBOARD_FAB2(SCH_1):SPI_PCH_CLK    I88 @BASEBOARD_FAB2_LIB.BASEBOARD_FAB2(SCH_1):PAGE184
     2 SPI_PCH_TPM_CLK_R @BASEBOARD_FAB2_LIB.BASEBOARD_FAB2(SCH_1):SPI_PCH_TPM_CLK_R    I88 @BASEBOARD_FAB2_LIB.BASEBOARD_FAB2(SCH_1):PAGE184

R8E10 RES_0402-33.2,1%,1/16W,CHIP,G2A
     1 SPI_PCH_MOSI @BASEBOARD_FAB2_LIB.BASEBOARD_FAB2(SCH_1):SPI_PCH_MOSI    I95 @BASEBOARD_FAB2_LIB.BASEBOARD_FAB2(SCH_1):PAGE184
     2 SPI_PCH_TPM_MOSI_R @BASEBOARD_FAB2_LIB.BASEBOARD_FAB2(SCH_1):SPI_PCH_TPM_MOSI_R    I95 @BASEBOARD_FAB2_LIB.BASEBOARD_FAB2(SCH_1):PAGE184

R8E11 RES_0402-0.0,5%,1/16W,EMPTY,G2A
     1 FM_MEM_THERM_EVENT_LVT3_N @BASEBOARD_FAB2_LIB.BASEBOARD_FAB2(SCH_1):FM_MEM_THERM_EVENT_LVT3_N   I279 @BASEBOARD_FAB2_LIB.BASEBOARD_FAB2(SCH_1):PAGE156
     2 FM_ADR_SMI_GPIO_N @BASEBOARD_FAB2_LIB.BASEBOARD_FAB2(SCH_1):FM_ADR_SMI_GPIO_N   I279 @BASEBOARD_FAB2_LIB.BASEBOARD_FAB2(SCH_1):PAGE156

R8E12 RES_0402-4.75K,1%,1/16W,EMPTY,A
     1 P3V3_STBY @BASEBOARD_FAB2_LIB.BASEBOARD_FAB2(SCH_1):P3V3_STBY    I78 @BASEBOARD_FAB2_LIB.BASEBOARD_FAB2(SCH_1):PAGE198
     2 FM_CTNR_PS_ON @BASEBOARD_FAB2_LIB.BASEBOARD_FAB2(SCH_1):FM_CTNR_PS_ON    I78 @BASEBOARD_FAB2_LIB.BASEBOARD_FAB2(SCH_1):PAGE198

R8E13 RES_0402-33.2,1%,1/16W,CHIP,G2A
     1 SPI_PCH_MISO @BASEBOARD_FAB2_LIB.BASEBOARD_FAB2(SCH_1):SPI_PCH_MISO    I93 @BASEBOARD_FAB2_LIB.BASEBOARD_FAB2(SCH_1):PAGE184
     2 SPI_PCH_TPM_MISO_R @BASEBOARD_FAB2_LIB.BASEBOARD_FAB2(SCH_1):SPI_PCH_TPM_MISO_R    I93 @BASEBOARD_FAB2_LIB.BASEBOARD_FAB2(SCH_1):PAGE184

R8E14 RES_0402-4.75K,1%,1/16W,CHIP,GA
     1 P3V3_STBY @BASEBOARD_FAB2_LIB.BASEBOARD_FAB2(SCH_1):P3V3_STBY   I133 @BASEBOARD_FAB2_LIB.BASEBOARD_FAB2(SCH_1):PAGE136
     2 RST_PLTRST_TOP_SWAP @BASEBOARD_FAB2_LIB.BASEBOARD_FAB2(SCH_1):RST_PLTRST_TOP_SWAP   I133 @BASEBOARD_FAB2_LIB.BASEBOARD_FAB2(SCH_1):PAGE136

R8E16 RES_0402-20.0K,1%,1/16W,CHIP,GA
     1 FM_BIOS_TOP_SWAP @BASEBOARD_FAB2_LIB.BASEBOARD_FAB2(SCH_1):FM_BIOS_TOP_SWAP   I140 @BASEBOARD_FAB2_LIB.BASEBOARD_FAB2(SCH_1):PAGE136
     2    GND @BASEBOARD_FAB2_LIB.BASEBOARD_FAB2(SCH_1):GND   I140 @BASEBOARD_FAB2_LIB.BASEBOARD_FAB2(SCH_1):PAGE136

R8E17 RES_0402-33.2,1%,1/16W,CHIP,G2A
     1 IRQ_LVC3_WAKE_R_N @BASEBOARD_FAB2_LIB.BASEBOARD_FAB2(SCH_1):IRQ_LVC3_WAKE_R_N     I2 @BASEBOARD_FAB2_LIB.BASEBOARD_FAB2(SCH_1):PAGE142
     2 IRQ_LVC3_WAKE_N @BASEBOARD_FAB2_LIB.BASEBOARD_FAB2(SCH_1):IRQ_LVC3_WAKE_N     I2 @BASEBOARD_FAB2_LIB.BASEBOARD_FAB2(SCH_1):PAGE142

R8E18 RES_0402-1.0K,0.1%,1/16W,CHIP,A
     1 P5V_STBY @BASEBOARD_FAB2_LIB.BASEBOARD_FAB2(SCH_1):P5V_STBY     I9 @BASEBOARD_FAB2_LIB.BASEBOARD_FAB2(SCH_1):PAGE241
     2    GND @BASEBOARD_FAB2_LIB.BASEBOARD_FAB2(SCH_1):GND     I9 @BASEBOARD_FAB2_LIB.BASEBOARD_FAB2(SCH_1):PAGE241

R8E19 RES_0402-4.75K,1%,1/16W,EMPTY,A
     1 P3V3_STBY @BASEBOARD_FAB2_LIB.BASEBOARD_FAB2(SCH_1):P3V3_STBY   I361 @BASEBOARD_FAB2_LIB.BASEBOARD_FAB2(SCH_1):PAGE157
     2 FM_BIOS_TOP_SWAP @BASEBOARD_FAB2_LIB.BASEBOARD_FAB2(SCH_1):FM_BIOS_TOP_SWAP   I361 @BASEBOARD_FAB2_LIB.BASEBOARD_FAB2(SCH_1):PAGE157

R8E20 RES_0402-33.2,1%,1/16W,CHIP,G2A
     1 FM_BIOS_TOP_SWAP_SPKR_R @BASEBOARD_FAB2_LIB.BASEBOARD_FAB2(SCH_1):FM_BIOS_TOP_SWAP_SPKR_R   I126 @BASEBOARD_FAB2_LIB.BASEBOARD_FAB2(SCH_1):PAGE136
     2 FM_BIOS_TOP_SWAP_SPKR @BASEBOARD_FAB2_LIB.BASEBOARD_FAB2(SCH_1):FM_BIOS_TOP_SWAP_SPKR   I126 @BASEBOARD_FAB2_LIB.BASEBOARD_FAB2(SCH_1):PAGE136

R8E21 RES_0402-0.0,5%,1/16W,CHIP,G21A
     1 FM_PE_SPRV_WAKE_N @BASEBOARD_FAB2_LIB.BASEBOARD_FAB2(SCH_1):FM_PE_SPRV_WAKE_N    I33 @BASEBOARD_FAB2_LIB.BASEBOARD_FAB2(SCH_1):PAGE142
     2 FM_ALL_WAKE_N @BASEBOARD_FAB2_LIB.BASEBOARD_FAB2(SCH_1):FM_ALL_WAKE_N    I33 @BASEBOARD_FAB2_LIB.BASEBOARD_FAB2(SCH_1):PAGE142

R8E22 RES_0402-4.75K,1%,1/16W,CHIP,GA
     1 P3V3_STBY @BASEBOARD_FAB2_LIB.BASEBOARD_FAB2(SCH_1):P3V3_STBY   I215 @BASEBOARD_FAB2_LIB.BASEBOARD_FAB2(SCH_1):PAGE156
     2 IRQ_BMC_PCH_NMI_STBY_N @BASEBOARD_FAB2_LIB.BASEBOARD_FAB2(SCH_1):IRQ_BMC_PCH_NMI_STBY_N   I215 @BASEBOARD_FAB2_LIB.BASEBOARD_FAB2(SCH_1):PAGE156

R8E23 RES_0402-4.75K,1%,1/16W,CHIP,GA
     1 PU_TRI_STATE_EN @BASEBOARD_FAB2_LIB.BASEBOARD_FAB2(SCH_1):PU_TRI_STATE_EN     I3 @BASEBOARD_FAB2_LIB.BASEBOARD_FAB2(SCH_1):PAGE142
     2 P3V3_STBY @BASEBOARD_FAB2_LIB.BASEBOARD_FAB2(SCH_1):P3V3_STBY     I3 @BASEBOARD_FAB2_LIB.BASEBOARD_FAB2(SCH_1):PAGE142

R8E24 RES_0402-33.2,1%,1/16W,CHIP,G2A
     1 IRQ_BMC_PCH_NMI_STBY_N @BASEBOARD_FAB2_LIB.BASEBOARD_FAB2(SCH_1):IRQ_BMC_PCH_NMI_STBY_N   I214 @BASEBOARD_FAB2_LIB.BASEBOARD_FAB2(SCH_1):PAGE156
     2 IRQ_BMC_PCH_NMI_STBY_R_N @BASEBOARD_FAB2_LIB.BASEBOARD_FAB2(SCH_1):IRQ_BMC_PCH_NMI_STBY_R_N   I214 @BASEBOARD_FAB2_LIB.BASEBOARD_FAB2(SCH_1):PAGE156

R8E25 RES_0402-0.0,5%,1/16W,CHIP,G21A
     1 P3V3_STBY @BASEBOARD_FAB2_LIB.BASEBOARD_FAB2(SCH_1):P3V3_STBY   I144 @BASEBOARD_FAB2_LIB.BASEBOARD_FAB2(SCH_1):PAGE240
     2 VSENSE_P3V3_STBY @BASEBOARD_FAB2_LIB.BASEBOARD_FAB2(SCH_1):VSENSE_P3V3_STBY   I144 @BASEBOARD_FAB2_LIB.BASEBOARD_FAB2(SCH_1):PAGE240

R8E26 RES_0402-0.0,5%,1/16W,CHIP,G21A
     1 FM_PE_OCP_WAKE_N @BASEBOARD_FAB2_LIB.BASEBOARD_FAB2(SCH_1):FM_PE_OCP_WAKE_N    I30 @BASEBOARD_FAB2_LIB.BASEBOARD_FAB2(SCH_1):PAGE142
     2 FM_ALL_WAKE_N @BASEBOARD_FAB2_LIB.BASEBOARD_FAB2(SCH_1):FM_ALL_WAKE_N    I30 @BASEBOARD_FAB2_LIB.BASEBOARD_FAB2(SCH_1):PAGE142

R8E27 RES_0402-0.0,5%,1/16W,CHIP,G21A
     1 FM_PE_M2_WAKE_N @BASEBOARD_FAB2_LIB.BASEBOARD_FAB2(SCH_1):FM_PE_M2_WAKE_N    I32 @BASEBOARD_FAB2_LIB.BASEBOARD_FAB2(SCH_1):PAGE142
     2 FM_ALL_WAKE_N @BASEBOARD_FAB2_LIB.BASEBOARD_FAB2(SCH_1):FM_ALL_WAKE_N    I32 @BASEBOARD_FAB2_LIB.BASEBOARD_FAB2(SCH_1):PAGE142

R8E28 RES_0402-0.0,5%,1/16W,CHIP,G21A
     1 FM_PE_SLOTX24_WAKE_N @BASEBOARD_FAB2_LIB.BASEBOARD_FAB2(SCH_1):FM_PE_SLOTX24_WAKE_N    I31 @BASEBOARD_FAB2_LIB.BASEBOARD_FAB2(SCH_1):PAGE142
     2 FM_ALL_WAKE_N @BASEBOARD_FAB2_LIB.BASEBOARD_FAB2(SCH_1):FM_ALL_WAKE_N    I31 @BASEBOARD_FAB2_LIB.BASEBOARD_FAB2(SCH_1):PAGE142

R8E29 RES_0402-0.0,5%,1/16W,EMPTY,G2A
     1 FM_PE_BMC_WAKE_N @BASEBOARD_FAB2_LIB.BASEBOARD_FAB2(SCH_1):FM_PE_BMC_WAKE_N    I18 @BASEBOARD_FAB2_LIB.BASEBOARD_FAB2(SCH_1):PAGE142
     2 FM_ALL_WAKE_N @BASEBOARD_FAB2_LIB.BASEBOARD_FAB2(SCH_1):FM_ALL_WAKE_N    I18 @BASEBOARD_FAB2_LIB.BASEBOARD_FAB2(SCH_1):PAGE142

R8E30 RES_0402-10.0K,1%,1/16W,CHIP,GA
     1 P3V3_STBY @BASEBOARD_FAB2_LIB.BASEBOARD_FAB2(SCH_1):P3V3_STBY    I23 @BASEBOARD_FAB2_LIB.BASEBOARD_FAB2(SCH_1):PAGE142
     2 FM_ALL_WAKE_N @BASEBOARD_FAB2_LIB.BASEBOARD_FAB2(SCH_1):FM_ALL_WAKE_N    I23 @BASEBOARD_FAB2_LIB.BASEBOARD_FAB2(SCH_1):PAGE142

R8E31 RES_0402-23.2K,1%,1/16W,CHIP,GA
     1 VSENSE_P3V3_STBY @BASEBOARD_FAB2_LIB.BASEBOARD_FAB2(SCH_1):VSENSE_P3V3_STBY   I143 @BASEBOARD_FAB2_LIB.BASEBOARD_FAB2(SCH_1):PAGE240
     2 VSENSE_VOUT_P3V3_STBY @BASEBOARD_FAB2_LIB.BASEBOARD_FAB2(SCH_1):VSENSE_VOUT_P3V3_STBY   I143 @BASEBOARD_FAB2_LIB.BASEBOARD_FAB2(SCH_1):PAGE240

R8E32 RES_0402-4.75K,1%,1/16W,CHIP,GA
     1 P3V3_STBY @BASEBOARD_FAB2_LIB.BASEBOARD_FAB2(SCH_1):P3V3_STBY   I385 @BASEBOARD_FAB2_LIB.BASEBOARD_FAB2(SCH_1):PAGE157
     2 FP_NMI_BTN_OUT_R_N @BASEBOARD_FAB2_LIB.BASEBOARD_FAB2(SCH_1):FP_NMI_BTN_OUT_R_N   I385 @BASEBOARD_FAB2_LIB.BASEBOARD_FAB2(SCH_1):PAGE157

R8E33 RES_0402-0.0,5%,1/16W,CHIP,G21A
     1 PWRGD_P12V_HSC_DLY @BASEBOARD_FAB2_LIB.BASEBOARD_FAB2(SCH_1):PWRGD_P12V_HSC_DLY    I91 @BASEBOARD_FAB2_LIB.BASEBOARD_FAB2(SCH_1):PAGE241
     2 VR_P5V_STBY_EN @BASEBOARD_FAB2_LIB.BASEBOARD_FAB2(SCH_1):VR_P5V_STBY_EN    I91 @BASEBOARD_FAB2_LIB.BASEBOARD_FAB2(SCH_1):PAGE241

R8E34 RES_0402-10.0K,1%,1/16W,CHIP,GA
     1 VSENSE_VOUT_P3V3_STBY @BASEBOARD_FAB2_LIB.BASEBOARD_FAB2(SCH_1):VSENSE_VOUT_P3V3_STBY   I142 @BASEBOARD_FAB2_LIB.BASEBOARD_FAB2(SCH_1):PAGE240
     2 AGND_P3V3_STBY @BASEBOARD_FAB2_LIB.BASEBOARD_FAB2(SCH_1):AGND_P3V3_STBY   I142 @BASEBOARD_FAB2_LIB.BASEBOARD_FAB2(SCH_1):PAGE240

R8E35 RES_0402-0.0,5%,1/16W,CHIP,G21A
     1 VR_P3V3_STBY_BOOT @BASEBOARD_FAB2_LIB.BASEBOARD_FAB2(SCH_1):VR_P3V3_STBY_BOOT   I127 @BASEBOARD_FAB2_LIB.BASEBOARD_FAB2(SCH_1):PAGE240
     2 VR_P3V3_STBY_BOOT_R @BASEBOARD_FAB2_LIB.BASEBOARD_FAB2(SCH_1):VR_P3V3_STBY_BOOT_R   I127 @BASEBOARD_FAB2_LIB.BASEBOARD_FAB2(SCH_1):PAGE240

R8E36 RES_0402-10.0K,1%,1/16W,CHIP,GA
     1 P3V3_STBY @BASEBOARD_FAB2_LIB.BASEBOARD_FAB2(SCH_1):P3V3_STBY    I28 @BASEBOARD_FAB2_LIB.BASEBOARD_FAB2(SCH_1):PAGE142
     2 FM_PE_SLOTX24_WAKE_N @BASEBOARD_FAB2_LIB.BASEBOARD_FAB2(SCH_1):FM_PE_SLOTX24_WAKE_N    I28 @BASEBOARD_FAB2_LIB.BASEBOARD_FAB2(SCH_1):PAGE142

R8E37 RES_0402-0.0,5%,1/16W,CHIP,G21A
     1 VR_P5V_STBY_VSENSE_R @BASEBOARD_FAB2_LIB.BASEBOARD_FAB2(SCH_1):VR_P5V_STBY_VSENSE_R    I78 @BASEBOARD_FAB2_LIB.BASEBOARD_FAB2(SCH_1):PAGE241
     2 P5V_STBY @BASEBOARD_FAB2_LIB.BASEBOARD_FAB2(SCH_1):P5V_STBY    I78 @BASEBOARD_FAB2_LIB.BASEBOARD_FAB2(SCH_1):PAGE241

R8E38 RES_0402-0.0,5%,1/16W,CHIP,G21A
     1 VSENSE_RGND_P3V3_STBY @BASEBOARD_FAB2_LIB.BASEBOARD_FAB2(SCH_1):VSENSE_RGND_P3V3_STBY   I140 @BASEBOARD_FAB2_LIB.BASEBOARD_FAB2(SCH_1):PAGE240
     2 AGND_P3V3_STBY @BASEBOARD_FAB2_LIB.BASEBOARD_FAB2(SCH_1):AGND_P3V3_STBY   I140 @BASEBOARD_FAB2_LIB.BASEBOARD_FAB2(SCH_1):PAGE240

R8E39 RES_0402-24.9K,1%,1/16W,CHIP,GA
     1 VR_P5V_STBY_COMP @BASEBOARD_FAB2_LIB.BASEBOARD_FAB2(SCH_1):VR_P5V_STBY_COMP    I54 @BASEBOARD_FAB2_LIB.BASEBOARD_FAB2(SCH_1):PAGE241
     2 VR_P5V_STBY_RC_COMP @BASEBOARD_FAB2_LIB.BASEBOARD_FAB2(SCH_1):VR_P5V_STBY_RC_COMP    I54 @BASEBOARD_FAB2_LIB.BASEBOARD_FAB2(SCH_1):PAGE241

R8E40 RES_0402-100.0K,1%,1/16W,EMPTYA
     1 P3V3_STBY @BASEBOARD_FAB2_LIB.BASEBOARD_FAB2(SCH_1):P3V3_STBY   I177 @BASEBOARD_FAB2_LIB.BASEBOARD_FAB2(SCH_1):PAGE240
     2 VR_P3V3_STBY_EN @BASEBOARD_FAB2_LIB.BASEBOARD_FAB2(SCH_1):VR_P3V3_STBY_EN   I177 @BASEBOARD_FAB2_LIB.BASEBOARD_FAB2(SCH_1):PAGE240

R8F1 RES_0402-10.0K,1%,1/16W,EMPTY,A
     1 PWRGD_P5V_STBY @BASEBOARD_FAB2_LIB.BASEBOARD_FAB2(SCH_1):PWRGD_P5V_STBY   I111 @BASEBOARD_FAB2_LIB.BASEBOARD_FAB2(SCH_1):PAGE240
     2    GND @BASEBOARD_FAB2_LIB.BASEBOARD_FAB2(SCH_1):GND   I111 @BASEBOARD_FAB2_LIB.BASEBOARD_FAB2(SCH_1):PAGE240

R8F2 RES_0402-0.0,5%,1/16W,CHIP,G21A
     1 PWRGD_P5V_STBY @BASEBOARD_FAB2_LIB.BASEBOARD_FAB2(SCH_1):PWRGD_P5V_STBY   I176 @BASEBOARD_FAB2_LIB.BASEBOARD_FAB2(SCH_1):PAGE240
     2 VR_P3V3_STBY_EN @BASEBOARD_FAB2_LIB.BASEBOARD_FAB2(SCH_1):VR_P3V3_STBY_EN   I176 @BASEBOARD_FAB2_LIB.BASEBOARD_FAB2(SCH_1):PAGE240

R8F3 RES_0402-2.2,5%,1/16W,EMPTY,G2A
     1 VR_P3V3_STBY_SNUB @BASEBOARD_FAB2_LIB.BASEBOARD_FAB2(SCH_1):VR_P3V3_STBY_SNUB   I148 @BASEBOARD_FAB2_LIB.BASEBOARD_FAB2(SCH_1):PAGE240
     2    GND @BASEBOARD_FAB2_LIB.BASEBOARD_FAB2(SCH_1):GND   I148 @BASEBOARD_FAB2_LIB.BASEBOARD_FAB2(SCH_1):PAGE240

R8F5 RES_0402-1.00K,1%,1/16W,CHIP,GA
     1 P3V3_STBY @BASEBOARD_FAB2_LIB.BASEBOARD_FAB2(SCH_1):P3V3_STBY   I117 @BASEBOARD_FAB2_LIB.BASEBOARD_FAB2(SCH_1):PAGE240
     2 PWRGD_P3V3_STBY_R @BASEBOARD_FAB2_LIB.BASEBOARD_FAB2(SCH_1):PWRGD_P3V3_STBY_R   I117 @BASEBOARD_FAB2_LIB.BASEBOARD_FAB2(SCH_1):PAGE240

R8F6 RES_0402-0.0,5%,1/16W,CHIP,G21A
     1 SPI_PCH_MISO @BASEBOARD_FAB2_LIB.BASEBOARD_FAB2(SCH_1):SPI_PCH_MISO   I119 @BASEBOARD_FAB2_LIB.BASEBOARD_FAB2(SCH_1):PAGE154
     2 SPI_PCH_MISO_R @BASEBOARD_FAB2_LIB.BASEBOARD_FAB2(SCH_1):SPI_PCH_MISO_R   I119 @BASEBOARD_FAB2_LIB.BASEBOARD_FAB2(SCH_1):PAGE154

R8F7 RES_0402-33.2,1%,1/16W,CHIP,G2A
     1 SPI_SWITCH_CLK @BASEBOARD_FAB2_LIB.BASEBOARD_FAB2(SCH_1):SPI_SWITCH_CLK   I167 @BASEBOARD_FAB2_LIB.BASEBOARD_FAB2(SCH_1):PAGE153
     2 SPI_CLK_R1 @BASEBOARD_FAB2_LIB.BASEBOARD_FAB2(SCH_1):SPI_CLK_R1   I167 @BASEBOARD_FAB2_LIB.BASEBOARD_FAB2(SCH_1):PAGE153

R8F8 RES_0402-33.2,1%,1/16W,CHIP,G2A
     1 SPI_SWITCH_CLK @BASEBOARD_FAB2_LIB.BASEBOARD_FAB2(SCH_1):SPI_SWITCH_CLK   I166 @BASEBOARD_FAB2_LIB.BASEBOARD_FAB2(SCH_1):PAGE153
     2 SPI_CLK_R0 @BASEBOARD_FAB2_LIB.BASEBOARD_FAB2(SCH_1):SPI_CLK_R0   I166 @BASEBOARD_FAB2_LIB.BASEBOARD_FAB2(SCH_1):PAGE153

R8F9 RES_0402-64.9K,1%,1/16W,CHIP,GA
     1 VR_P3V3_STBY_OCSELECT @BASEBOARD_FAB2_LIB.BASEBOARD_FAB2(SCH_1):VR_P3V3_STBY_OCSELECT   I106 @BASEBOARD_FAB2_LIB.BASEBOARD_FAB2(SCH_1):PAGE240
     2 AGND_P3V3_STBY @BASEBOARD_FAB2_LIB.BASEBOARD_FAB2(SCH_1):AGND_P3V3_STBY   I106 @BASEBOARD_FAB2_LIB.BASEBOARD_FAB2(SCH_1):PAGE240

R8F10 RES_0402-22.1,1.0%,1/16W,CHIP,A
     1 PWRGD_P3V3_STBY_R @BASEBOARD_FAB2_LIB.BASEBOARD_FAB2(SCH_1):PWRGD_P3V3_STBY_R   I171 @BASEBOARD_FAB2_LIB.BASEBOARD_FAB2(SCH_1):PAGE240
     2 PWRGD_P3V3_STBY @BASEBOARD_FAB2_LIB.BASEBOARD_FAB2(SCH_1):PWRGD_P3V3_STBY   I171 @BASEBOARD_FAB2_LIB.BASEBOARD_FAB2(SCH_1):PAGE240

R8F11 RES_0402-0.0,5%,1/16W,CHIP,G21A
     1    GND @BASEBOARD_FAB2_LIB.BASEBOARD_FAB2(SCH_1):GND   I146 @BASEBOARD_FAB2_LIB.BASEBOARD_FAB2(SCH_1):PAGE240
     2 AGND_P3V3_STBY @BASEBOARD_FAB2_LIB.BASEBOARD_FAB2(SCH_1):AGND_P3V3_STBY   I146 @BASEBOARD_FAB2_LIB.BASEBOARD_FAB2(SCH_1):PAGE240

R8F12 RES_0402-33.2,1%,1/16W,CHIP,G2A
     1 SPI_BMC_BT_DI @BASEBOARD_FAB2_LIB.BASEBOARD_FAB2(SCH_1):SPI_BMC_BT_DI    I13 @BASEBOARD_FAB2_LIB.BASEBOARD_FAB2(SCH_1):PAGE162
     2 SPI_BMC_BT_DI_R @BASEBOARD_FAB2_LIB.BASEBOARD_FAB2(SCH_1):SPI_BMC_BT_DI_R    I13 @BASEBOARD_FAB2_LIB.BASEBOARD_FAB2(SCH_1):PAGE162

R8F13 RES_0402-4.75K,1%,1/16W,CHIP,GA
     1 P3V3_STBY @BASEBOARD_FAB2_LIB.BASEBOARD_FAB2(SCH_1):P3V3_STBY    I23 @BASEBOARD_FAB2_LIB.BASEBOARD_FAB2(SCH_1):PAGE162
     2 SPI_BMC_BT_CS_N @BASEBOARD_FAB2_LIB.BASEBOARD_FAB2(SCH_1):SPI_BMC_BT_CS_N    I23 @BASEBOARD_FAB2_LIB.BASEBOARD_FAB2(SCH_1):PAGE162

R8F14 RES_0402-4.75K,1%,1/16W,CHIP,GA
     1 P3V3_STBY @BASEBOARD_FAB2_LIB.BASEBOARD_FAB2(SCH_1):P3V3_STBY     I9 @BASEBOARD_FAB2_LIB.BASEBOARD_FAB2(SCH_1):PAGE162
     2 PU_SPI_BMC_BT_HOLD_N @BASEBOARD_FAB2_LIB.BASEBOARD_FAB2(SCH_1):PU_SPI_BMC_BT_HOLD_N     I9 @BASEBOARD_FAB2_LIB.BASEBOARD_FAB2(SCH_1):PAGE162

R8F16 RES_0402-4.75K,1%,1/16W,EMPTY,A
     1 P3V3_STBY @BASEBOARD_FAB2_LIB.BASEBOARD_FAB2(SCH_1):P3V3_STBY     I8 @BASEBOARD_FAB2_LIB.BASEBOARD_FAB2(SCH_1):PAGE162
     2 PU_SPI_FLASH_RESET_2_N @BASEBOARD_FAB2_LIB.BASEBOARD_FAB2(SCH_1):PU_SPI_FLASH_RESET_2_N     I8 @BASEBOARD_FAB2_LIB.BASEBOARD_FAB2(SCH_1):PAGE162

R8F18 RES_0402-0.0,5%,1/16W,CHIP,G21A
     1 P3E_PCH_RX_0_DP @BASEBOARD_FAB2_LIB.BASEBOARD_FAB2(SCH_1):P3E_PCH_RX_0_DP   I105 @BASEBOARD_FAB2_LIB.BASEBOARD_FAB2(SCH_1):PAGE185
     2 P3E_PCH_M2_SATA6G_RX_R_DP @BASEBOARD_FAB2_LIB.BASEBOARD_FAB2(SCH_1):P3E_PCH_M2_SATA6G_RX_R_DP   I105 @BASEBOARD_FAB2_LIB.BASEBOARD_FAB2(SCH_1):PAGE185

R8F21 RES_0402-0.0,5%,1/16W,CHIP,G21A
     1 P3E_PCH_RX_0_DN @BASEBOARD_FAB2_LIB.BASEBOARD_FAB2(SCH_1):P3E_PCH_RX_0_DN   I106 @BASEBOARD_FAB2_LIB.BASEBOARD_FAB2(SCH_1):PAGE185
     2 P3E_PCH_M2_SATA6G_RX_R_DN @BASEBOARD_FAB2_LIB.BASEBOARD_FAB2(SCH_1):P3E_PCH_M2_SATA6G_RX_R_DN   I106 @BASEBOARD_FAB2_LIB.BASEBOARD_FAB2(SCH_1):PAGE185

R8F23 RES_0402-2.21K,1%,1/16W,CHIP,GA
     1 P3V3_STBY @BASEBOARD_FAB2_LIB.BASEBOARD_FAB2(SCH_1):P3V3_STBY   I296 @BASEBOARD_FAB2_LIB.BASEBOARD_FAB2(SCH_1):PAGE157
     2 IRQ_MEZZ_LAN_ALERT_N @BASEBOARD_FAB2_LIB.BASEBOARD_FAB2(SCH_1):IRQ_MEZZ_LAN_ALERT_N   I296 @BASEBOARD_FAB2_LIB.BASEBOARD_FAB2(SCH_1):PAGE157

R8F24 RES_0402-4.75K,1%,1/16W,CHIP,GA
     1 P3V3_STBY @BASEBOARD_FAB2_LIB.BASEBOARD_FAB2(SCH_1):P3V3_STBY   I316 @BASEBOARD_FAB2_LIB.BASEBOARD_FAB2(SCH_1):PAGE157
     2 FP_NMI_BTN_N @BASEBOARD_FAB2_LIB.BASEBOARD_FAB2(SCH_1):FP_NMI_BTN_N   I316 @BASEBOARD_FAB2_LIB.BASEBOARD_FAB2(SCH_1):PAGE157

R8F25 RES_0402-475.0,1%,1/16W,CHIP,GA
     1 A_COMP_CKMNG @BASEBOARD_FAB2_LIB.BASEBOARD_FAB2(SCH_1):A_COMP_CKMNG    I28 @BASEBOARD_FAB2_LIB.BASEBOARD_FAB2(SCH_1):PAGE101
     2    GND @BASEBOARD_FAB2_LIB.BASEBOARD_FAB2(SCH_1):GND    I28 @BASEBOARD_FAB2_LIB.BASEBOARD_FAB2(SCH_1):PAGE101

R8F26 RES_0402-10.0K,1%,1/16W,CHIP,GA
     1 P3V3_STBY @BASEBOARD_FAB2_LIB.BASEBOARD_FAB2(SCH_1):P3V3_STBY   I211 @BASEBOARD_FAB2_LIB.BASEBOARD_FAB2(SCH_1):PAGE156
     2 FM_PCH_PWRBTN_R_N @BASEBOARD_FAB2_LIB.BASEBOARD_FAB2(SCH_1):FM_PCH_PWRBTN_R_N   I211 @BASEBOARD_FAB2_LIB.BASEBOARD_FAB2(SCH_1):PAGE156

R8F27 RES_0402-22.1,1.0%,1/16W,CHIP,A
     1 CLK_32K_SUSCLK_PLD_R @BASEBOARD_FAB2_LIB.BASEBOARD_FAB2(SCH_1):CLK_32K_SUSCLK_PLD_R   I129 @BASEBOARD_FAB2_LIB.BASEBOARD_FAB2(SCH_1):PAGE101
     2 CLK_32K_SUSCLK_PLD @BASEBOARD_FAB2_LIB.BASEBOARD_FAB2(SCH_1):CLK_32K_SUSCLK_PLD   I129 @BASEBOARD_FAB2_LIB.BASEBOARD_FAB2(SCH_1):PAGE101

R8F29 RES_0402-33.2,1%,1/16W,CHIP,G2A
     1 CLK_25M_BMC_R @BASEBOARD_FAB2_LIB.BASEBOARD_FAB2(SCH_1):CLK_25M_BMC_R    I20 @BASEBOARD_FAB2_LIB.BASEBOARD_FAB2(SCH_1):PAGE101
     2 CLK_25M_BMC @BASEBOARD_FAB2_LIB.BASEBOARD_FAB2(SCH_1):CLK_25M_BMC    I20 @BASEBOARD_FAB2_LIB.BASEBOARD_FAB2(SCH_1):PAGE101

R8F34 RES_0402-4.75K,1%,1/16W,CHIP,GA
     1 P3V3_STBY @BASEBOARD_FAB2_LIB.BASEBOARD_FAB2(SCH_1):P3V3_STBY    I22 @BASEBOARD_FAB2_LIB.BASEBOARD_FAB2(SCH_1):PAGE162
     2 PU_SPI_BMC_BT_WP_N @BASEBOARD_FAB2_LIB.BASEBOARD_FAB2(SCH_1):PU_SPI_BMC_BT_WP_N    I22 @BASEBOARD_FAB2_LIB.BASEBOARD_FAB2(SCH_1):PAGE162

R8F35 RES_0402-1.00K,1%,1/16W,EMPTY,A
     1 PU_SPI_BMC_BT_WP_N @BASEBOARD_FAB2_LIB.BASEBOARD_FAB2(SCH_1):PU_SPI_BMC_BT_WP_N    I24 @BASEBOARD_FAB2_LIB.BASEBOARD_FAB2(SCH_1):PAGE162
     2    GND @BASEBOARD_FAB2_LIB.BASEBOARD_FAB2(SCH_1):GND    I24 @BASEBOARD_FAB2_LIB.BASEBOARD_FAB2(SCH_1):PAGE162

R8F36 RES_0402-10.0K,1%,1/16W,CHIP,GA
     1   P3V3 @BASEBOARD_FAB2_LIB.BASEBOARD_FAB2(SCH_1):P3V3   I136 @BASEBOARD_FAB2_LIB.BASEBOARD_FAB2(SCH_1):PAGE185
     2 PU_M2_CLK_REQ_N @BASEBOARD_FAB2_LIB.BASEBOARD_FAB2(SCH_1):PU_M2_CLK_REQ_N   I136 @BASEBOARD_FAB2_LIB.BASEBOARD_FAB2(SCH_1):PAGE185

R8F37 RES_0402-0.0,5%,1/16W,EMPTY,G2A
     1 FM_CPU_ERR0_LVT3_N @BASEBOARD_FAB2_LIB.BASEBOARD_FAB2(SCH_1):FM_CPU_ERR0_LVT3_N   I131 @BASEBOARD_FAB2_LIB.BASEBOARD_FAB2(SCH_1):PAGE93
     2 FM_CPU_ERR0_PCH_N @BASEBOARD_FAB2_LIB.BASEBOARD_FAB2(SCH_1):FM_CPU_ERR0_PCH_N   I131 @BASEBOARD_FAB2_LIB.BASEBOARD_FAB2(SCH_1):PAGE93

R8F38 RES_0402-0.0,5%,1/16W,CHIP,G21A
     1 FM_CPU_ERR0_LVT3_N @BASEBOARD_FAB2_LIB.BASEBOARD_FAB2(SCH_1):FM_CPU_ERR0_LVT3_N   I119 @BASEBOARD_FAB2_LIB.BASEBOARD_FAB2(SCH_1):PAGE93
     2 FM_CPU_ERR0_LVT3_BMC_N @BASEBOARD_FAB2_LIB.BASEBOARD_FAB2(SCH_1):FM_CPU_ERR0_LVT3_BMC_N   I119 @BASEBOARD_FAB2_LIB.BASEBOARD_FAB2(SCH_1):PAGE93

R8G1 RES_0402-33.2,1%,1/16W,CHIP,G2A
     1 CLK_50M_CKMNG_BMC_2_R @BASEBOARD_FAB2_LIB.BASEBOARD_FAB2(SCH_1):CLK_50M_CKMNG_BMC_2_R   I133 @BASEBOARD_FAB2_LIB.BASEBOARD_FAB2(SCH_1):PAGE101
     2 CLK_50M_CKMNG_BMC_2 @BASEBOARD_FAB2_LIB.BASEBOARD_FAB2(SCH_1):CLK_50M_CKMNG_BMC_2   I133 @BASEBOARD_FAB2_LIB.BASEBOARD_FAB2(SCH_1):PAGE101

R8G2 RES_0402-4.75K,1%,1/16W,CHIP,GA
     1 P3V3_STBY @BASEBOARD_FAB2_LIB.BASEBOARD_FAB2(SCH_1):P3V3_STBY   I267 @BASEBOARD_FAB2_LIB.BASEBOARD_FAB2(SCH_1):PAGE156
     2 FM_PCH_PWRBTN_OUT_N @BASEBOARD_FAB2_LIB.BASEBOARD_FAB2(SCH_1):FM_PCH_PWRBTN_OUT_N   I267 @BASEBOARD_FAB2_LIB.BASEBOARD_FAB2(SCH_1):PAGE156

R8G3 RES_0402-2.26K,1.0%,1/16W,EMPTA
     1 P3V3_STBY @BASEBOARD_FAB2_LIB.BASEBOARD_FAB2(SCH_1):P3V3_STBY   I210 @BASEBOARD_FAB2_LIB.BASEBOARD_FAB2(SCH_1):PAGE159
     2 SMB_OCP_LAN_STBY_LVC3_SCL_R @BASEBOARD_FAB2_LIB.BASEBOARD_FAB2(SCH_1):SMB_OCP_LAN_STBY_LVC3_SCL_R   I210 @BASEBOARD_FAB2_LIB.BASEBOARD_FAB2(SCH_1):PAGE159

R8G4 RES_0402-20.0,1%,1/16W,CHIP,G2A
     1 SMB_OCP_LAN_STBY_LVC3_SCL_R @BASEBOARD_FAB2_LIB.BASEBOARD_FAB2(SCH_1):SMB_OCP_LAN_STBY_LVC3_SCL_R   I229 @BASEBOARD_FAB2_LIB.BASEBOARD_FAB2(SCH_1):PAGE159
     2 SMB_OCP_LAN_STBY_LVC3_SCL @BASEBOARD_FAB2_LIB.BASEBOARD_FAB2(SCH_1):SMB_OCP_LAN_STBY_LVC3_SCL   I229 @BASEBOARD_FAB2_LIB.BASEBOARD_FAB2(SCH_1):PAGE159

R8G5 RES_0402-20.0,1%,1/16W,CHIP,G2A
     1 SMB_OCP_LAN_STBY_LVC3_SDA_R @BASEBOARD_FAB2_LIB.BASEBOARD_FAB2(SCH_1):SMB_OCP_LAN_STBY_LVC3_SDA_R   I228 @BASEBOARD_FAB2_LIB.BASEBOARD_FAB2(SCH_1):PAGE159
     2 SMB_OCP_LAN_STBY_LVC3_SDA @BASEBOARD_FAB2_LIB.BASEBOARD_FAB2(SCH_1):SMB_OCP_LAN_STBY_LVC3_SDA   I228 @BASEBOARD_FAB2_LIB.BASEBOARD_FAB2(SCH_1):PAGE159

R8G6 RES_0402-2.26K,1.0%,1/16W,EMPTA
     1 P3V3_STBY @BASEBOARD_FAB2_LIB.BASEBOARD_FAB2(SCH_1):P3V3_STBY   I212 @BASEBOARD_FAB2_LIB.BASEBOARD_FAB2(SCH_1):PAGE159
     2 SMB_OCP_LAN_STBY_LVC3_SDA_R @BASEBOARD_FAB2_LIB.BASEBOARD_FAB2(SCH_1):SMB_OCP_LAN_STBY_LVC3_SDA_R   I212 @BASEBOARD_FAB2_LIB.BASEBOARD_FAB2(SCH_1):PAGE159

R8G7 RES_0402-0.0,5%,1/16W,CHIP,G21A
     1 JTAG_PLD_TDI @BASEBOARD_FAB2_LIB.BASEBOARD_FAB2(SCH_1):JTAG_PLD_TDI    I18 @BASEBOARD_FAB2_LIB.BASEBOARD_FAB2(SCH_1):PAGE189
     2 JTAG_TDI @BASEBOARD_FAB2_LIB.BASEBOARD_FAB2(SCH_1):JTAG_TDI    I18 @BASEBOARD_FAB2_LIB.BASEBOARD_FAB2(SCH_1):PAGE189

R8G8 RES_0402-0.0,5%,1/16W,CHIP,G21A
     1 JTAG_BMC_TDI @BASEBOARD_FAB2_LIB.BASEBOARD_FAB2(SCH_1):JTAG_BMC_TDI    I17 @BASEBOARD_FAB2_LIB.BASEBOARD_FAB2(SCH_1):PAGE189
     2 JTAG_TDI @BASEBOARD_FAB2_LIB.BASEBOARD_FAB2(SCH_1):JTAG_TDI    I17 @BASEBOARD_FAB2_LIB.BASEBOARD_FAB2(SCH_1):PAGE189

R8G9 RES_0402-0.0,5%,1/16W,EMPTY,G2A
     1 JTAG_PCH_GBE_TRST_N @BASEBOARD_FAB2_LIB.BASEBOARD_FAB2(SCH_1):JTAG_PCH_GBE_TRST_N     I9 @BASEBOARD_FAB2_LIB.BASEBOARD_FAB2(SCH_1):PAGE189
     2 JTAG_TRST_N @BASEBOARD_FAB2_LIB.BASEBOARD_FAB2(SCH_1):JTAG_TRST_N     I9 @BASEBOARD_FAB2_LIB.BASEBOARD_FAB2(SCH_1):PAGE189

R8G10 RES_0402-0.0,5%,1/16W,CHIP,G21A
     1 JTAG_BMC_TRST_N @BASEBOARD_FAB2_LIB.BASEBOARD_FAB2(SCH_1):JTAG_BMC_TRST_N     I7 @BASEBOARD_FAB2_LIB.BASEBOARD_FAB2(SCH_1):PAGE189
     2 JTAG_TRST_N @BASEBOARD_FAB2_LIB.BASEBOARD_FAB2(SCH_1):JTAG_TRST_N     I7 @BASEBOARD_FAB2_LIB.BASEBOARD_FAB2(SCH_1):PAGE189

R8G11 RES_0402-0.0,5%,1/16W,EMPTY,G2A
     1 JTAG_PCH_PLD_TMS @BASEBOARD_FAB2_LIB.BASEBOARD_FAB2(SCH_1):JTAG_PCH_PLD_TMS    I19 @BASEBOARD_FAB2_LIB.BASEBOARD_FAB2(SCH_1):PAGE189
     2 JTAG_TMS @BASEBOARD_FAB2_LIB.BASEBOARD_FAB2(SCH_1):JTAG_TMS    I19 @BASEBOARD_FAB2_LIB.BASEBOARD_FAB2(SCH_1):PAGE189

R8G12 RES_0402-0.0,5%,1/16W,EMPTY,G2A
     1 JTAG_PCH_GBE_TMS @BASEBOARD_FAB2_LIB.BASEBOARD_FAB2(SCH_1):JTAG_PCH_GBE_TMS    I21 @BASEBOARD_FAB2_LIB.BASEBOARD_FAB2(SCH_1):PAGE189
     2 JTAG_TMS @BASEBOARD_FAB2_LIB.BASEBOARD_FAB2(SCH_1):JTAG_TMS    I21 @BASEBOARD_FAB2_LIB.BASEBOARD_FAB2(SCH_1):PAGE189

R8G13 RES_0402-0.0,5%,1/16W,CHIP,G21A
     1 JTAG_PLD_TMS @BASEBOARD_FAB2_LIB.BASEBOARD_FAB2(SCH_1):JTAG_PLD_TMS    I23 @BASEBOARD_FAB2_LIB.BASEBOARD_FAB2(SCH_1):PAGE189
     2 JTAG_TMS @BASEBOARD_FAB2_LIB.BASEBOARD_FAB2(SCH_1):JTAG_TMS    I23 @BASEBOARD_FAB2_LIB.BASEBOARD_FAB2(SCH_1):PAGE189

R8G14 RES_0402-0.0,5%,1/16W,CHIP,G21A
     1 JTAG_BMC_TMS @BASEBOARD_FAB2_LIB.BASEBOARD_FAB2(SCH_1):JTAG_BMC_TMS    I20 @BASEBOARD_FAB2_LIB.BASEBOARD_FAB2(SCH_1):PAGE189
     2 JTAG_TMS @BASEBOARD_FAB2_LIB.BASEBOARD_FAB2(SCH_1):JTAG_TMS    I20 @BASEBOARD_FAB2_LIB.BASEBOARD_FAB2(SCH_1):PAGE189

R8G15 RES_0402-0.0,5%,1/16W,EMPTY,G2A
     1 JTAG_PCH_GBE_CLK @BASEBOARD_FAB2_LIB.BASEBOARD_FAB2(SCH_1):JTAG_PCH_GBE_CLK    I24 @BASEBOARD_FAB2_LIB.BASEBOARD_FAB2(SCH_1):PAGE189
     2 JTAG_TCK @BASEBOARD_FAB2_LIB.BASEBOARD_FAB2(SCH_1):JTAG_TCK    I24 @BASEBOARD_FAB2_LIB.BASEBOARD_FAB2(SCH_1):PAGE189

R8G16 RES_0402-0.0,5%,1/16W,EMPTY,G2A
     1 JTAG_PCH_PLD_TCK @BASEBOARD_FAB2_LIB.BASEBOARD_FAB2(SCH_1):JTAG_PCH_PLD_TCK    I22 @BASEBOARD_FAB2_LIB.BASEBOARD_FAB2(SCH_1):PAGE189
     2 JTAG_TCK @BASEBOARD_FAB2_LIB.BASEBOARD_FAB2(SCH_1):JTAG_TCK    I22 @BASEBOARD_FAB2_LIB.BASEBOARD_FAB2(SCH_1):PAGE189

R8G17 RES_0402-0.0,5%,1/16W,CHIP,G21A
     1 JTAG_BMC_TCK @BASEBOARD_FAB2_LIB.BASEBOARD_FAB2(SCH_1):JTAG_BMC_TCK    I25 @BASEBOARD_FAB2_LIB.BASEBOARD_FAB2(SCH_1):PAGE189
     2 JTAG_TCK @BASEBOARD_FAB2_LIB.BASEBOARD_FAB2(SCH_1):JTAG_TCK    I25 @BASEBOARD_FAB2_LIB.BASEBOARD_FAB2(SCH_1):PAGE189

R8G18 RES_0402-0.0,5%,1/16W,CHIP,G21A
     1 JTAG_PLD_TCK @BASEBOARD_FAB2_LIB.BASEBOARD_FAB2(SCH_1):JTAG_PLD_TCK    I26 @BASEBOARD_FAB2_LIB.BASEBOARD_FAB2(SCH_1):PAGE189
     2 JTAG_TCK @BASEBOARD_FAB2_LIB.BASEBOARD_FAB2(SCH_1):JTAG_TCK    I26 @BASEBOARD_FAB2_LIB.BASEBOARD_FAB2(SCH_1):PAGE189

R8G19 RES_0402-0.0,5%,1/16W,CHIP,G21A
     1 JTAG_TDI @BASEBOARD_FAB2_LIB.BASEBOARD_FAB2(SCH_1):JTAG_TDI    I64 @BASEBOARD_FAB2_LIB.BASEBOARD_FAB2(SCH_1):PAGE189
     2 JTAG_TDI_R @BASEBOARD_FAB2_LIB.BASEBOARD_FAB2(SCH_1):JTAG_TDI_R    I64 @BASEBOARD_FAB2_LIB.BASEBOARD_FAB2(SCH_1):PAGE189

R8G20 RES_0402-10.0K,1%,1/16W,CHIP,GA
     1 P3V3_STBY @BASEBOARD_FAB2_LIB.BASEBOARD_FAB2(SCH_1):P3V3_STBY    I50 @BASEBOARD_FAB2_LIB.BASEBOARD_FAB2(SCH_1):PAGE189
     2 JTAG_TMS_R @BASEBOARD_FAB2_LIB.BASEBOARD_FAB2(SCH_1):JTAG_TMS_R    I50 @BASEBOARD_FAB2_LIB.BASEBOARD_FAB2(SCH_1):PAGE189

R8G21 RES_0402-0.0,5%,1/16W,CHIP,G21A
     1 JTAG_TMS @BASEBOARD_FAB2_LIB.BASEBOARD_FAB2(SCH_1):JTAG_TMS    I65 @BASEBOARD_FAB2_LIB.BASEBOARD_FAB2(SCH_1):PAGE189
     2 JTAG_TMS_R @BASEBOARD_FAB2_LIB.BASEBOARD_FAB2(SCH_1):JTAG_TMS_R    I65 @BASEBOARD_FAB2_LIB.BASEBOARD_FAB2(SCH_1):PAGE189

R8G22 RES_0402-0.0,5%,1/16W,CHIP,G21A
     1 JTAG_TCK @BASEBOARD_FAB2_LIB.BASEBOARD_FAB2(SCH_1):JTAG_TCK    I66 @BASEBOARD_FAB2_LIB.BASEBOARD_FAB2(SCH_1):PAGE189
     2 JTAG_TCK_R @BASEBOARD_FAB2_LIB.BASEBOARD_FAB2(SCH_1):JTAG_TCK_R    I66 @BASEBOARD_FAB2_LIB.BASEBOARD_FAB2(SCH_1):PAGE189

R8G23 RES_0402-4.75K,1%,1/16W,CHIP,GA
     1 JTAG_TCK_R @BASEBOARD_FAB2_LIB.BASEBOARD_FAB2(SCH_1):JTAG_TCK_R    I56 @BASEBOARD_FAB2_LIB.BASEBOARD_FAB2(SCH_1):PAGE189
     2    GND @BASEBOARD_FAB2_LIB.BASEBOARD_FAB2(SCH_1):GND    I56 @BASEBOARD_FAB2_LIB.BASEBOARD_FAB2(SCH_1):PAGE189

R8G24 RES_0402-33.2,1%,1/16W,CHIP,G2A
     1 CLK_50M_CKMNG_PCH_10GBE_R @BASEBOARD_FAB2_LIB.BASEBOARD_FAB2(SCH_1):CLK_50M_CKMNG_PCH_10GBE_R   I132 @BASEBOARD_FAB2_LIB.BASEBOARD_FAB2(SCH_1):PAGE101
     2 CLK_50M_CKMNG_PCH_10GBE @BASEBOARD_FAB2_LIB.BASEBOARD_FAB2(SCH_1):CLK_50M_CKMNG_PCH_10GBE   I132 @BASEBOARD_FAB2_LIB.BASEBOARD_FAB2(SCH_1):PAGE101

R8G25 RES_0402-33.2,1%,1/16W,CHIP,G2A
     1 CLK_50M_CKMNG_SPRVLLE_R @BASEBOARD_FAB2_LIB.BASEBOARD_FAB2(SCH_1):CLK_50M_CKMNG_SPRVLLE_R   I131 @BASEBOARD_FAB2_LIB.BASEBOARD_FAB2(SCH_1):PAGE101
     2 CLK_50M_CKMNG_SPRVLLE @BASEBOARD_FAB2_LIB.BASEBOARD_FAB2(SCH_1):CLK_50M_CKMNG_SPRVLLE   I131 @BASEBOARD_FAB2_LIB.BASEBOARD_FAB2(SCH_1):PAGE101

R8N1 RES_0402-1.8K,1%,1/16W,CHIP,G2A
     1 P3V3_STBY @BASEBOARD_FAB2_LIB.BASEBOARD_FAB2(SCH_1):P3V3_STBY   I157 @BASEBOARD_FAB2_LIB.BASEBOARD_FAB2(SCH_1):PAGE55
     2 FM_CPU1_PROC_ID1 @BASEBOARD_FAB2_LIB.BASEBOARD_FAB2(SCH_1):FM_CPU1_PROC_ID1   I157 @BASEBOARD_FAB2_LIB.BASEBOARD_FAB2(SCH_1):PAGE55

R8N2 RES_0402-10.0K,1%,1/16W,CHIP,GA
     1 P3V3_STBY @BASEBOARD_FAB2_LIB.BASEBOARD_FAB2(SCH_1):P3V3_STBY   I161 @BASEBOARD_FAB2_LIB.BASEBOARD_FAB2(SCH_1):PAGE55
     2 FM_CPU1_PKGID0 @BASEBOARD_FAB2_LIB.BASEBOARD_FAB2(SCH_1):FM_CPU1_PKGID0   I161 @BASEBOARD_FAB2_LIB.BASEBOARD_FAB2(SCH_1):PAGE55

R8N3 RES_0402-10.0K,1%,1/16W,CHIP,GA
     1 P3V3_STBY @BASEBOARD_FAB2_LIB.BASEBOARD_FAB2(SCH_1):P3V3_STBY   I159 @BASEBOARD_FAB2_LIB.BASEBOARD_FAB2(SCH_1):PAGE55
     2 FM_CPU1_PKGID2 @BASEBOARD_FAB2_LIB.BASEBOARD_FAB2(SCH_1):FM_CPU1_PKGID2   I159 @BASEBOARD_FAB2_LIB.BASEBOARD_FAB2(SCH_1):PAGE55

R8N4 RES_0402-1.8K,1%,1/16W,CHIP,G2A
     1 P3V3_STBY @BASEBOARD_FAB2_LIB.BASEBOARD_FAB2(SCH_1):P3V3_STBY   I158 @BASEBOARD_FAB2_LIB.BASEBOARD_FAB2(SCH_1):PAGE55
     2 FM_CPU1_PROC_ID0 @BASEBOARD_FAB2_LIB.BASEBOARD_FAB2(SCH_1):FM_CPU1_PROC_ID0   I158 @BASEBOARD_FAB2_LIB.BASEBOARD_FAB2(SCH_1):PAGE55

R8N5 RES_0402-10.0K,1%,1/16W,CHIP,GA
     1 P3V3_STBY @BASEBOARD_FAB2_LIB.BASEBOARD_FAB2(SCH_1):P3V3_STBY   I160 @BASEBOARD_FAB2_LIB.BASEBOARD_FAB2(SCH_1):PAGE55
     2 FM_CPU1_PKGID1 @BASEBOARD_FAB2_LIB.BASEBOARD_FAB2(SCH_1):FM_CPU1_PKGID1   I160 @BASEBOARD_FAB2_LIB.BASEBOARD_FAB2(SCH_1):PAGE55

R8P1 RES_0402-49.9,1%,1/16W,CHIP,G2A
     1 PD_CPU1_TEST14 @BASEBOARD_FAB2_LIB.BASEBOARD_FAB2(SCH_1):PD_CPU1_TEST14    I85 @BASEBOARD_FAB2_LIB.BASEBOARD_FAB2(SCH_1):PAGE90
     2    GND @BASEBOARD_FAB2_LIB.BASEBOARD_FAB2(SCH_1):GND    I85 @BASEBOARD_FAB2_LIB.BASEBOARD_FAB2(SCH_1):PAGE90

R8P2 RES_0402-49.9,1%,1/16W,CHIP,G2A
     1 PD_CPU1_TEST13 @BASEBOARD_FAB2_LIB.BASEBOARD_FAB2(SCH_1):PD_CPU1_TEST13    I86 @BASEBOARD_FAB2_LIB.BASEBOARD_FAB2(SCH_1):PAGE90
     2    GND @BASEBOARD_FAB2_LIB.BASEBOARD_FAB2(SCH_1):GND    I86 @BASEBOARD_FAB2_LIB.BASEBOARD_FAB2(SCH_1):PAGE90

R8P3 RES_0402-49.9,1%,1/16W,CHIP,G2A
     1 PD_CPU1_RSVD_TEST_2 @BASEBOARD_FAB2_LIB.BASEBOARD_FAB2(SCH_1):PD_CPU1_RSVD_TEST_2   I173 @BASEBOARD_FAB2_LIB.BASEBOARD_FAB2(SCH_1):PAGE56
     2    GND @BASEBOARD_FAB2_LIB.BASEBOARD_FAB2(SCH_1):GND   I173 @BASEBOARD_FAB2_LIB.BASEBOARD_FAB2(SCH_1):PAGE56

R8R1 RES_0402-49.9,1%,1/16W,CHIP,G2A
     1 PD_CPU1_RSVD_TEST_1 @BASEBOARD_FAB2_LIB.BASEBOARD_FAB2(SCH_1):PD_CPU1_RSVD_TEST_1   I174 @BASEBOARD_FAB2_LIB.BASEBOARD_FAB2(SCH_1):PAGE56
     2    GND @BASEBOARD_FAB2_LIB.BASEBOARD_FAB2(SCH_1):GND   I174 @BASEBOARD_FAB2_LIB.BASEBOARD_FAB2(SCH_1):PAGE56

R9A1 RES_0402-1.00K,1%,1/16W,EMPTY,A
     1   P3V3 @BASEBOARD_FAB2_LIB.BASEBOARD_FAB2(SCH_1):P3V3    I95 @BASEBOARD_FAB2_LIB.BASEBOARD_FAB2(SCH_1):PAGE111
     2 XDP_CPU_TCK_BUF @BASEBOARD_FAB2_LIB.BASEBOARD_FAB2(SCH_1):XDP_CPU_TCK_BUF    I95 @BASEBOARD_FAB2_LIB.BASEBOARD_FAB2(SCH_1):PAGE111

R9A2 RES_0402-33.2,1%,1/16W,EMPTY,GA
     1 XDP_PCH_CPU_TCK0 @BASEBOARD_FAB2_LIB.BASEBOARD_FAB2(SCH_1):XDP_PCH_CPU_TCK0    I83 @BASEBOARD_FAB2_LIB.BASEBOARD_FAB2(SCH_1):PAGE111
     2 XDP_CPU_GTL_TCK_R2 @BASEBOARD_FAB2_LIB.BASEBOARD_FAB2(SCH_1):XDP_CPU_GTL_TCK_R2    I83 @BASEBOARD_FAB2_LIB.BASEBOARD_FAB2(SCH_1):PAGE111

R9A3 RES_0402-0.0,5%,1/16W,CHIP,G21A
     1 XDP_PCH_CPU_TCK0 @BASEBOARD_FAB2_LIB.BASEBOARD_FAB2(SCH_1):XDP_PCH_CPU_TCK0    I74 @BASEBOARD_FAB2_LIB.BASEBOARD_FAB2(SCH_1):PAGE111
     2 XDP_CPU_TCK0 @BASEBOARD_FAB2_LIB.BASEBOARD_FAB2(SCH_1):XDP_CPU_TCK0    I74 @BASEBOARD_FAB2_LIB.BASEBOARD_FAB2(SCH_1):PAGE111

R9A4 RES_0402-475.0,1%,1/16W,CHIP,GA
     1 XDP_PRESENT_N @BASEBOARD_FAB2_LIB.BASEBOARD_FAB2(SCH_1):XDP_PRESENT_N    I55 @BASEBOARD_FAB2_LIB.BASEBOARD_FAB2(SCH_1):PAGE111
     2 PVCCIO_CPU0 @BASEBOARD_FAB2_LIB.BASEBOARD_FAB2(SCH_1):PVCCIO_CPU0    I55 @BASEBOARD_FAB2_LIB.BASEBOARD_FAB2(SCH_1):PAGE111

R9A5 RES_0402-15.0K,1%,1/16W,CHIP,GA
     1 P5V_STBY @BASEBOARD_FAB2_LIB.BASEBOARD_FAB2(SCH_1):P5V_STBY   I195 @BASEBOARD_FAB2_LIB.BASEBOARD_FAB2(SCH_1):PAGE155
     2 FM_UART_SWITCH_N @BASEBOARD_FAB2_LIB.BASEBOARD_FAB2(SCH_1):FM_UART_SWITCH_N   I195 @BASEBOARD_FAB2_LIB.BASEBOARD_FAB2(SCH_1):PAGE155

R9A6 RES_0402-20.0K,1%,1/16W,EMPTY,A
     1 P5V_STBY @BASEBOARD_FAB2_LIB.BASEBOARD_FAB2(SCH_1):P5V_STBY   I191 @BASEBOARD_FAB2_LIB.BASEBOARD_FAB2(SCH_1):PAGE155
     2 SPA_5V_SIN_SW @BASEBOARD_FAB2_LIB.BASEBOARD_FAB2(SCH_1):SPA_5V_SIN_SW   I191 @BASEBOARD_FAB2_LIB.BASEBOARD_FAB2(SCH_1):PAGE155

R9A7 RES_0402-2.21K,1%,1/16W,CHIP,GA
     1 P3V3_STBY @BASEBOARD_FAB2_LIB.BASEBOARD_FAB2(SCH_1):P3V3_STBY    I80 @BASEBOARD_FAB2_LIB.BASEBOARD_FAB2(SCH_1):PAGE155
     2 SPA_SIN_SW_R @BASEBOARD_FAB2_LIB.BASEBOARD_FAB2(SCH_1):SPA_SIN_SW_R    I80 @BASEBOARD_FAB2_LIB.BASEBOARD_FAB2(SCH_1):PAGE155

R9A8 RES_0402-0.0,5%,1/16W,CHIP,G21A
     1 SPA_SIN_SW_R @BASEBOARD_FAB2_LIB.BASEBOARD_FAB2(SCH_1):SPA_SIN_SW_R    I53 @BASEBOARD_FAB2_LIB.BASEBOARD_FAB2(SCH_1):PAGE155
     2 SPA_MID_DBG1__RX @BASEBOARD_FAB2_LIB.BASEBOARD_FAB2(SCH_1):SPA_MID_DBG1__RX    I53 @BASEBOARD_FAB2_LIB.BASEBOARD_FAB2(SCH_1):PAGE155

R9A9 RES_0402-100.0,1%,1/16W,CHIP,GA
     1 RST_SYSTEM_BTN_BUF_N @BASEBOARD_FAB2_LIB.BASEBOARD_FAB2(SCH_1):RST_SYSTEM_BTN_BUF_N    I35 @BASEBOARD_FAB2_LIB.BASEBOARD_FAB2(SCH_1):PAGE175
     2 RST_SYSTEM_BTN_N @BASEBOARD_FAB2_LIB.BASEBOARD_FAB2(SCH_1):RST_SYSTEM_BTN_N    I35 @BASEBOARD_FAB2_LIB.BASEBOARD_FAB2(SCH_1):PAGE175

R9A11 RES_0402-150.0,1%,1/16W,CHIP,GA
     1 P1V05_PCH_STBY @BASEBOARD_FAB2_LIB.BASEBOARD_FAB2(SCH_1):P1V05_PCH_STBY    I78 @BASEBOARD_FAB2_LIB.BASEBOARD_FAB2(SCH_1):PAGE112
     2 XDP_TDO @BASEBOARD_FAB2_LIB.BASEBOARD_FAB2(SCH_1):XDP_TDO    I78 @BASEBOARD_FAB2_LIB.BASEBOARD_FAB2(SCH_1):PAGE112

R9A12 RES_0402-2.21K,1%,1/16W,CHIP,GA
     1 FM_PCH_SATA_RAID_KEY_R @BASEBOARD_FAB2_LIB.BASEBOARD_FAB2(SCH_1):FM_PCH_SATA_RAID_KEY_R   I117 @BASEBOARD_FAB2_LIB.BASEBOARD_FAB2(SCH_1):PAGE135
     2 P3V3_STBY @BASEBOARD_FAB2_LIB.BASEBOARD_FAB2(SCH_1):P3V3_STBY   I117 @BASEBOARD_FAB2_LIB.BASEBOARD_FAB2(SCH_1):PAGE135

R9A13 RES_0402-33.2,1%,1/16W,CHIP,G2A
     1 FM_PCH_SATA_RAID_KEY_R @BASEBOARD_FAB2_LIB.BASEBOARD_FAB2(SCH_1):FM_PCH_SATA_RAID_KEY_R   I118 @BASEBOARD_FAB2_LIB.BASEBOARD_FAB2(SCH_1):PAGE135
     2 FM_PCH_SATA_RAID_KEY @BASEBOARD_FAB2_LIB.BASEBOARD_FAB2(SCH_1):FM_PCH_SATA_RAID_KEY   I118 @BASEBOARD_FAB2_LIB.BASEBOARD_FAB2(SCH_1):PAGE135

R9A14 RES_0402-1.00K,1%,1/16W,CHIP,GA
     1 XDP_RST_CO_N @BASEBOARD_FAB2_LIB.BASEBOARD_FAB2(SCH_1):XDP_RST_CO_N    I11 @BASEBOARD_FAB2_LIB.BASEBOARD_FAB2(SCH_1):PAGE111
     2 P3V3_STBY @BASEBOARD_FAB2_LIB.BASEBOARD_FAB2(SCH_1):P3V3_STBY    I11 @BASEBOARD_FAB2_LIB.BASEBOARD_FAB2(SCH_1):PAGE111

R9A15 RES_0402-1.00K,1%,1/16W,CHIP,GA
     1 RST_RSMRST_N @BASEBOARD_FAB2_LIB.BASEBOARD_FAB2(SCH_1):RST_RSMRST_N    I60 @BASEBOARD_FAB2_LIB.BASEBOARD_FAB2(SCH_1):PAGE111
     2 XDP_RSMRST_N @BASEBOARD_FAB2_LIB.BASEBOARD_FAB2(SCH_1):XDP_RSMRST_N    I60 @BASEBOARD_FAB2_LIB.BASEBOARD_FAB2(SCH_1):PAGE111

R9A16 RES_0402-2.21K,1%,1/16W,CHIP,GA
     1 PU_KEY_CONN_PIN2_R @BASEBOARD_FAB2_LIB.BASEBOARD_FAB2(SCH_1):PU_KEY_CONN_PIN2_R   I129 @BASEBOARD_FAB2_LIB.BASEBOARD_FAB2(SCH_1):PAGE135
     2 P3V3_STBY @BASEBOARD_FAB2_LIB.BASEBOARD_FAB2(SCH_1):P3V3_STBY   I129 @BASEBOARD_FAB2_LIB.BASEBOARD_FAB2(SCH_1):PAGE135

R9A17 RES_0402-1.00K,1%,1/16W,CHIP,GA
     1 XDP_ITP_PMODE @BASEBOARD_FAB2_LIB.BASEBOARD_FAB2(SCH_1):XDP_ITP_PMODE    I57 @BASEBOARD_FAB2_LIB.BASEBOARD_FAB2(SCH_1):PAGE111
     2 P1V05_PCH_STBY @BASEBOARD_FAB2_LIB.BASEBOARD_FAB2(SCH_1):P1V05_PCH_STBY    I57 @BASEBOARD_FAB2_LIB.BASEBOARD_FAB2(SCH_1):PAGE111

R9A18 RES_0402-4.75K,1%,1/16W,CHIP,GA
     1 P3V3_STBY @BASEBOARD_FAB2_LIB.BASEBOARD_FAB2(SCH_1):P3V3_STBY   I183 @BASEBOARD_FAB2_LIB.BASEBOARD_FAB2(SCH_1):PAGE119
     2 FM_PWR_LED @BASEBOARD_FAB2_LIB.BASEBOARD_FAB2(SCH_1):FM_PWR_LED   I183 @BASEBOARD_FAB2_LIB.BASEBOARD_FAB2(SCH_1):PAGE119

R9A20 RES_0402-221,1.0%,1/16W,CHIP,GA
     1 FM_PWR_LED_A @BASEBOARD_FAB2_LIB.BASEBOARD_FAB2(SCH_1):FM_PWR_LED_A   I178 @BASEBOARD_FAB2_LIB.BASEBOARD_FAB2(SCH_1):PAGE119
     2 P3V3_STBY @BASEBOARD_FAB2_LIB.BASEBOARD_FAB2(SCH_1):P3V3_STBY   I178 @BASEBOARD_FAB2_LIB.BASEBOARD_FAB2(SCH_1):PAGE119

R9A21 RES_0402-4.75K,1%,1/16W,CHIP,GA
     1 P3V3_STBY @BASEBOARD_FAB2_LIB.BASEBOARD_FAB2(SCH_1):P3V3_STBY   I186 @BASEBOARD_FAB2_LIB.BASEBOARD_FAB2(SCH_1):PAGE119
     2 FM_PWR_LED_N @BASEBOARD_FAB2_LIB.BASEBOARD_FAB2(SCH_1):FM_PWR_LED_N   I186 @BASEBOARD_FAB2_LIB.BASEBOARD_FAB2(SCH_1):PAGE119

R9B4 RES_0402-49.9,1%,1/16W,CHIP,G2A
     1 ISENSE_TMP421_1_E @BASEBOARD_FAB2_LIB.BASEBOARD_FAB2(SCH_1):ISENSE_TMP421_1_E     I6 @BASEBOARD_FAB2_LIB.BASEBOARD_FAB2(SCH_1):PAGE167
     2 ISENSE_TMP421_1_DXP @BASEBOARD_FAB2_LIB.BASEBOARD_FAB2(SCH_1):ISENSE_TMP421_1_DXP     I6 @BASEBOARD_FAB2_LIB.BASEBOARD_FAB2(SCH_1):PAGE167

R9B5 RES_0402-49.9,1%,1/16W,CHIP,G2A
     1 ISENSE_TMP421_1_BC @BASEBOARD_FAB2_LIB.BASEBOARD_FAB2(SCH_1):ISENSE_TMP421_1_BC     I5 @BASEBOARD_FAB2_LIB.BASEBOARD_FAB2(SCH_1):PAGE167
     2 ISENSE_TMP421_1_DXN @BASEBOARD_FAB2_LIB.BASEBOARD_FAB2(SCH_1):ISENSE_TMP421_1_DXN     I5 @BASEBOARD_FAB2_LIB.BASEBOARD_FAB2(SCH_1):PAGE167

R9B6 RES_0402-1.00K,1%,1/16W,CHIP,GA
     1 P3V3_STBY @BASEBOARD_FAB2_LIB.BASEBOARD_FAB2(SCH_1):P3V3_STBY    I35 @BASEBOARD_FAB2_LIB.BASEBOARD_FAB2(SCH_1):PAGE167
     2 PU_TMP421_1_A1 @BASEBOARD_FAB2_LIB.BASEBOARD_FAB2(SCH_1):PU_TMP421_1_A1    I35 @BASEBOARD_FAB2_LIB.BASEBOARD_FAB2(SCH_1):PAGE167

R9B7 RES_0402-100.0,1%,1/16W,CHIP,GA
     1    GND @BASEBOARD_FAB2_LIB.BASEBOARD_FAB2(SCH_1):GND   I222 @BASEBOARD_FAB2_LIB.BASEBOARD_FAB2(SCH_1):PAGE186
     2 FM_MEZZA_PRSNT1_N @BASEBOARD_FAB2_LIB.BASEBOARD_FAB2(SCH_1):FM_MEZZA_PRSNT1_N   I222 @BASEBOARD_FAB2_LIB.BASEBOARD_FAB2(SCH_1):PAGE186

R9B8 RES_0402-1.00K,1%,1/16W,CHIP,GA
     1 PD_TMP421_1_A0 @BASEBOARD_FAB2_LIB.BASEBOARD_FAB2(SCH_1):PD_TMP421_1_A0    I10 @BASEBOARD_FAB2_LIB.BASEBOARD_FAB2(SCH_1):PAGE167
     2    GND @BASEBOARD_FAB2_LIB.BASEBOARD_FAB2(SCH_1):GND    I10 @BASEBOARD_FAB2_LIB.BASEBOARD_FAB2(SCH_1):PAGE167

R9B9 RES_0402-1.00K,1%,1/16W,CHIP,GA
     1 JTAG_MCP_TCK @BASEBOARD_FAB2_LIB.BASEBOARD_FAB2(SCH_1):JTAG_MCP_TCK   I179 @BASEBOARD_FAB2_LIB.BASEBOARD_FAB2(SCH_1):PAGE113
     2    GND @BASEBOARD_FAB2_LIB.BASEBOARD_FAB2(SCH_1):GND   I179 @BASEBOARD_FAB2_LIB.BASEBOARD_FAB2(SCH_1):PAGE113

R9B10 RES_0402-49.9,1%,1/16W,CHIP,G2A
     1 JTAG_MCP_TCK @BASEBOARD_FAB2_LIB.BASEBOARD_FAB2(SCH_1):JTAG_MCP_TCK   I180 @BASEBOARD_FAB2_LIB.BASEBOARD_FAB2(SCH_1):PAGE113
     2 JTAG_MCP_TCK_R @BASEBOARD_FAB2_LIB.BASEBOARD_FAB2(SCH_1):JTAG_MCP_TCK_R   I180 @BASEBOARD_FAB2_LIB.BASEBOARD_FAB2(SCH_1):PAGE113

R9B11 RES_0402-0.0,5%,1/16W,CHIP,G21A
     1 JTAG_MCP_TCK @BASEBOARD_FAB2_LIB.BASEBOARD_FAB2(SCH_1):JTAG_MCP_TCK   I239 @BASEBOARD_FAB2_LIB.BASEBOARD_FAB2(SCH_1):PAGE113
     2 JTAG_MCP_TCK_R @BASEBOARD_FAB2_LIB.BASEBOARD_FAB2(SCH_1):JTAG_MCP_TCK_R   I239 @BASEBOARD_FAB2_LIB.BASEBOARD_FAB2(SCH_1):PAGE113

R9B12 RES_0402-1.00K,1%,1/16W,CHIP,GA
     1 P1V8_MCP_CPU0 @BASEBOARD_FAB2_LIB.BASEBOARD_FAB2(SCH_1):P1V8_MCP_CPU0   I203 @BASEBOARD_FAB2_LIB.BASEBOARD_FAB2(SCH_1):PAGE113
     2 JTAG_MCP_MUX_TDO @BASEBOARD_FAB2_LIB.BASEBOARD_FAB2(SCH_1):JTAG_MCP_MUX_TDO   I203 @BASEBOARD_FAB2_LIB.BASEBOARD_FAB2(SCH_1):PAGE113

R9B13 RES_0402-0.0,5%,1/16W,CHIP,G21A
     1 JTAG_MCP_TMS @BASEBOARD_FAB2_LIB.BASEBOARD_FAB2(SCH_1):JTAG_MCP_TMS   I240 @BASEBOARD_FAB2_LIB.BASEBOARD_FAB2(SCH_1):PAGE113
     2 JTAG_MCP_TMS_R @BASEBOARD_FAB2_LIB.BASEBOARD_FAB2(SCH_1):JTAG_MCP_TMS_R   I240 @BASEBOARD_FAB2_LIB.BASEBOARD_FAB2(SCH_1):PAGE113

R9B14 RES_0402-1.00K,1%,1/16W,CHIP,GA
     1 PWRGD_CPU0_G @BASEBOARD_FAB2_LIB.BASEBOARD_FAB2(SCH_1):PWRGD_CPU0_G   I168 @BASEBOARD_FAB2_LIB.BASEBOARD_FAB2(SCH_1):PAGE113
     2 PWRGD_CPU0_G_R @BASEBOARD_FAB2_LIB.BASEBOARD_FAB2(SCH_1):PWRGD_CPU0_G_R   I168 @BASEBOARD_FAB2_LIB.BASEBOARD_FAB2(SCH_1):PAGE113

R9E1 RES_0402-10.0K,1%,1/16W,CHIP,GA
     1 P3V3_STBY @BASEBOARD_FAB2_LIB.BASEBOARD_FAB2(SCH_1):P3V3_STBY   I179 @BASEBOARD_FAB2_LIB.BASEBOARD_FAB2(SCH_1):PAGE139
     2 PU_JTAG_SPRV_TDI @BASEBOARD_FAB2_LIB.BASEBOARD_FAB2(SCH_1):PU_JTAG_SPRV_TDI   I179 @BASEBOARD_FAB2_LIB.BASEBOARD_FAB2(SCH_1):PAGE139

R9E2 RES_0402-10.0K,1%,1/16W,CHIP,GA
     1 P3V3_STBY @BASEBOARD_FAB2_LIB.BASEBOARD_FAB2(SCH_1):P3V3_STBY   I177 @BASEBOARD_FAB2_LIB.BASEBOARD_FAB2(SCH_1):PAGE139
     2 PU_JTAG_SPRV_TCK @BASEBOARD_FAB2_LIB.BASEBOARD_FAB2(SCH_1):PU_JTAG_SPRV_TCK   I177 @BASEBOARD_FAB2_LIB.BASEBOARD_FAB2(SCH_1):PAGE139

R9E3 RES_0402-10.0K,1%,1/16W,CHIP,GA
     1 P3V3_STBY @BASEBOARD_FAB2_LIB.BASEBOARD_FAB2(SCH_1):P3V3_STBY   I178 @BASEBOARD_FAB2_LIB.BASEBOARD_FAB2(SCH_1):PAGE139
     2 PU_JTAG_SPRV_TMS @BASEBOARD_FAB2_LIB.BASEBOARD_FAB2(SCH_1):PU_JTAG_SPRV_TMS   I178 @BASEBOARD_FAB2_LIB.BASEBOARD_FAB2(SCH_1):PAGE139

R9E4 RES_0402-10.0K,1%,1/16W,CHIP,GA
     1 P3V3_STBY @BASEBOARD_FAB2_LIB.BASEBOARD_FAB2(SCH_1):P3V3_STBY   I200 @BASEBOARD_FAB2_LIB.BASEBOARD_FAB2(SCH_1):PAGE139
     2 RST_PLTRST_SPRV_R_N @BASEBOARD_FAB2_LIB.BASEBOARD_FAB2(SCH_1):RST_PLTRST_SPRV_R_N   I200 @BASEBOARD_FAB2_LIB.BASEBOARD_FAB2(SCH_1):PAGE139

R9E5 RES_0402-33.2,1%,1/16W,CHIP,G2A
     1 SPI_NIC_CS_R_N @BASEBOARD_FAB2_LIB.BASEBOARD_FAB2(SCH_1):SPI_NIC_CS_R_N   I129 @BASEBOARD_FAB2_LIB.BASEBOARD_FAB2(SCH_1):PAGE139
     2 SPI_NIC_CS_N @BASEBOARD_FAB2_LIB.BASEBOARD_FAB2(SCH_1):SPI_NIC_CS_N   I129 @BASEBOARD_FAB2_LIB.BASEBOARD_FAB2(SCH_1):PAGE139

R9E6 RES_0402-33.2,1%,1/16W,CHIP,G2A
     1 SPI_NIC_MISO_R @BASEBOARD_FAB2_LIB.BASEBOARD_FAB2(SCH_1):SPI_NIC_MISO_R    I17 @BASEBOARD_FAB2_LIB.BASEBOARD_FAB2(SCH_1):PAGE140
     2 SPI_NIC_MISO @BASEBOARD_FAB2_LIB.BASEBOARD_FAB2(SCH_1):SPI_NIC_MISO    I17 @BASEBOARD_FAB2_LIB.BASEBOARD_FAB2(SCH_1):PAGE140

R9E7 RES_0402-3.32K,1%,1/16W,CHIP,GA
     1 P3V3_STBY @BASEBOARD_FAB2_LIB.BASEBOARD_FAB2(SCH_1):P3V3_STBY   I193 @BASEBOARD_FAB2_LIB.BASEBOARD_FAB2(SCH_1):PAGE139
     2 IRQ_LOM_ALERT_N @BASEBOARD_FAB2_LIB.BASEBOARD_FAB2(SCH_1):IRQ_LOM_ALERT_N   I193 @BASEBOARD_FAB2_LIB.BASEBOARD_FAB2(SCH_1):PAGE139

R9E8 RES_0402-33.2,1%,1/16W,CHIP,G2A
     1 SPI_NIC_SCLK_R @BASEBOARD_FAB2_LIB.BASEBOARD_FAB2(SCH_1):SPI_NIC_SCLK_R   I130 @BASEBOARD_FAB2_LIB.BASEBOARD_FAB2(SCH_1):PAGE139
     2 SPI_NIC_SCLK @BASEBOARD_FAB2_LIB.BASEBOARD_FAB2(SCH_1):SPI_NIC_SCLK   I130 @BASEBOARD_FAB2_LIB.BASEBOARD_FAB2(SCH_1):PAGE139

R9E9 RES_0402-33.2,1%,1/16W,CHIP,G2A
     1 SPI_NIC_MOSI_R @BASEBOARD_FAB2_LIB.BASEBOARD_FAB2(SCH_1):SPI_NIC_MOSI_R   I128 @BASEBOARD_FAB2_LIB.BASEBOARD_FAB2(SCH_1):PAGE139
     2 SPI_NIC_MOSI @BASEBOARD_FAB2_LIB.BASEBOARD_FAB2(SCH_1):SPI_NIC_MOSI   I128 @BASEBOARD_FAB2_LIB.BASEBOARD_FAB2(SCH_1):PAGE139

R9E10 RES_0402-200.0,1%,1/16W,CHIP,GA
     1 RST_PCIE_CPU_DEV1_R_N @BASEBOARD_FAB2_LIB.BASEBOARD_FAB2(SCH_1):RST_PCIE_CPU_DEV1_R_N   I145 @BASEBOARD_FAB2_LIB.BASEBOARD_FAB2(SCH_1):PAGE187
     2 RST_PCIE_CPU_DEV1_N @BASEBOARD_FAB2_LIB.BASEBOARD_FAB2(SCH_1):RST_PCIE_CPU_DEV1_N   I145 @BASEBOARD_FAB2_LIB.BASEBOARD_FAB2(SCH_1):PAGE187

R9E11 RES_0402-200.0,1%,1/16W,CHIP,GA
     1 RST_PCIE_CPU_DEV2_R_N @BASEBOARD_FAB2_LIB.BASEBOARD_FAB2(SCH_1):RST_PCIE_CPU_DEV2_R_N   I150 @BASEBOARD_FAB2_LIB.BASEBOARD_FAB2(SCH_1):PAGE187
     2 RST_PCIE_CPU_DEV2_N @BASEBOARD_FAB2_LIB.BASEBOARD_FAB2(SCH_1):RST_PCIE_CPU_DEV2_N   I150 @BASEBOARD_FAB2_LIB.BASEBOARD_FAB2(SCH_1):PAGE187

R9E12 RES_0402-200.0,1%,1/16W,CHIP,GA
     1 RST_PCIE_CPU_DEV3_R_N @BASEBOARD_FAB2_LIB.BASEBOARD_FAB2(SCH_1):RST_PCIE_CPU_DEV3_R_N   I153 @BASEBOARD_FAB2_LIB.BASEBOARD_FAB2(SCH_1):PAGE187
     2 RST_PCIE_CPU_DEV3_N @BASEBOARD_FAB2_LIB.BASEBOARD_FAB2(SCH_1):RST_PCIE_CPU_DEV3_N   I153 @BASEBOARD_FAB2_LIB.BASEBOARD_FAB2(SCH_1):PAGE187

R9E13 RES_0402-10.0K,1%,1/16W,CHIP,GA
     1 RMII_BMC_PCH_SPRNGVLLE_TXEN @BASEBOARD_FAB2_LIB.BASEBOARD_FAB2(SCH_1):RMII_BMC_PCH_SPRNGVLLE_TXEN   I212 @BASEBOARD_FAB2_LIB.BASEBOARD_FAB2(SCH_1):PAGE139
     2    GND @BASEBOARD_FAB2_LIB.BASEBOARD_FAB2(SCH_1):GND   I212 @BASEBOARD_FAB2_LIB.BASEBOARD_FAB2(SCH_1):PAGE139

R9E14 RES_0402-0.0,5%,1/16W,CHIP,G21A
     1 FM_TPM_PRES_RST_N @BASEBOARD_FAB2_LIB.BASEBOARD_FAB2(SCH_1):FM_TPM_PRES_RST_N   I379 @BASEBOARD_FAB2_LIB.BASEBOARD_FAB2(SCH_1):PAGE157
     2 FM_BMC_ENABLE_N @BASEBOARD_FAB2_LIB.BASEBOARD_FAB2(SCH_1):FM_BMC_ENABLE_N   I379 @BASEBOARD_FAB2_LIB.BASEBOARD_FAB2(SCH_1):PAGE157

R9E16 RES_0402-33.2,1%,1/16W,CHIP,G2A
     1 RMII_PCH_SPRNGVLLE_ARB_IN_R @BASEBOARD_FAB2_LIB.BASEBOARD_FAB2(SCH_1):RMII_PCH_SPRNGVLLE_ARB_IN_R   I235 @BASEBOARD_FAB2_LIB.BASEBOARD_FAB2(SCH_1):PAGE139
     2 RMII_PCH_SPRNGVLLE_ARB_IN @BASEBOARD_FAB2_LIB.BASEBOARD_FAB2(SCH_1):RMII_PCH_SPRNGVLLE_ARB_IN   I235 @BASEBOARD_FAB2_LIB.BASEBOARD_FAB2(SCH_1):PAGE139

R9E17 RES_0402-22.1,1.0%,1/16W,CHIP,A
     1 RMII_SPRNGVLLE_BMC_PCH_RXD0_R @BASEBOARD_FAB2_LIB.BASEBOARD_FAB2(SCH_1):RMII_SPRNGVLLE_BMC_PCH_RXD0_R   I229 @BASEBOARD_FAB2_LIB.BASEBOARD_FAB2(SCH_1):PAGE139
     2 RMII_SPRNGVLLE_BMC_PCH_RXD0 @BASEBOARD_FAB2_LIB.BASEBOARD_FAB2(SCH_1):RMII_SPRNGVLLE_BMC_PCH_RXD0   I229 @BASEBOARD_FAB2_LIB.BASEBOARD_FAB2(SCH_1):PAGE139

R9E18 RES_0402-0.0,5%,1/16W,CHIP,G21A
     1 XTAL_25MHZ_OUT_R @BASEBOARD_FAB2_LIB.BASEBOARD_FAB2(SCH_1):XTAL_25MHZ_OUT_R   I201 @BASEBOARD_FAB2_LIB.BASEBOARD_FAB2(SCH_1):PAGE139
     2 XTAL_25MHZ_OUT @BASEBOARD_FAB2_LIB.BASEBOARD_FAB2(SCH_1):XTAL_25MHZ_OUT   I201 @BASEBOARD_FAB2_LIB.BASEBOARD_FAB2(SCH_1):PAGE139

R9E19 RES_0402-22.1,1.0%,1/16W,CHIP,A
     1 RMII_SPRNGVLLE_BMC_PCH_RXD1_R @BASEBOARD_FAB2_LIB.BASEBOARD_FAB2(SCH_1):RMII_SPRNGVLLE_BMC_PCH_RXD1_R   I228 @BASEBOARD_FAB2_LIB.BASEBOARD_FAB2(SCH_1):PAGE139
     2 RMII_SPRNGVLLE_BMC_PCH_RXD1 @BASEBOARD_FAB2_LIB.BASEBOARD_FAB2(SCH_1):RMII_SPRNGVLLE_BMC_PCH_RXD1   I228 @BASEBOARD_FAB2_LIB.BASEBOARD_FAB2(SCH_1):PAGE139

R9E20 RES_0402-0.0,5%,1/16W,CHIP,G21A
     1 XTAL_25MHZ_IN @BASEBOARD_FAB2_LIB.BASEBOARD_FAB2(SCH_1):XTAL_25MHZ_IN   I110 @BASEBOARD_FAB2_LIB.BASEBOARD_FAB2(SCH_1):PAGE139
     2 XTAL_25MHZ_IN_R @BASEBOARD_FAB2_LIB.BASEBOARD_FAB2(SCH_1):XTAL_25MHZ_IN_R   I110 @BASEBOARD_FAB2_LIB.BASEBOARD_FAB2(SCH_1):PAGE139

R9E21 RES_0402-4.75K,1%,1/16W,CHIP,GA
     1 P3V3_STBY @BASEBOARD_FAB2_LIB.BASEBOARD_FAB2(SCH_1):P3V3_STBY   I111 @BASEBOARD_FAB2_LIB.BASEBOARD_FAB2(SCH_1):PAGE149
     2 FM_HEARTBEAT_LED @BASEBOARD_FAB2_LIB.BASEBOARD_FAB2(SCH_1):FM_HEARTBEAT_LED   I111 @BASEBOARD_FAB2_LIB.BASEBOARD_FAB2(SCH_1):PAGE149

R9E22 RES_0402-10.0K,1%,1/16W,CHIP,GA
     1 PU_JTAG_SPRV_TDO @BASEBOARD_FAB2_LIB.BASEBOARD_FAB2(SCH_1):PU_JTAG_SPRV_TDO   I181 @BASEBOARD_FAB2_LIB.BASEBOARD_FAB2(SCH_1):PAGE139
     2 P3V3_STBY @BASEBOARD_FAB2_LIB.BASEBOARD_FAB2(SCH_1):P3V3_STBY   I181 @BASEBOARD_FAB2_LIB.BASEBOARD_FAB2(SCH_1):PAGE139

R9E23 RES_0402-4.99K,1%,1/16W,CHIP,GA
     1 PD_SPRV_RSET @BASEBOARD_FAB2_LIB.BASEBOARD_FAB2(SCH_1):PD_SPRV_RSET   I174 @BASEBOARD_FAB2_LIB.BASEBOARD_FAB2(SCH_1):PAGE139
     2    GND @BASEBOARD_FAB2_LIB.BASEBOARD_FAB2(SCH_1):GND   I174 @BASEBOARD_FAB2_LIB.BASEBOARD_FAB2(SCH_1):PAGE139

R9E24 RES_0402-221,1.0%,1/16W,CHIP,GA
     1 FM_HEARTBEAT_LED_A @BASEBOARD_FAB2_LIB.BASEBOARD_FAB2(SCH_1):FM_HEARTBEAT_LED_A    I94 @BASEBOARD_FAB2_LIB.BASEBOARD_FAB2(SCH_1):PAGE149
     2 P3V3_STBY @BASEBOARD_FAB2_LIB.BASEBOARD_FAB2(SCH_1):P3V3_STBY    I94 @BASEBOARD_FAB2_LIB.BASEBOARD_FAB2(SCH_1):PAGE149

R9F1 RES_0402-22.1,1.0%,1/16W,CHIP,A
     1 RMII_BMC_PCH_SPRNGVLLE_CRSDV_R @BASEBOARD_FAB2_LIB.BASEBOARD_FAB2(SCH_1):RMII_BMC_PCH_SPRNGVLLE_CRSDV_R   I225 @BASEBOARD_FAB2_LIB.BASEBOARD_FAB2(SCH_1):PAGE139
     2 RMII_BMC_PCH_SPRNGVLLE_CRSDV @BASEBOARD_FAB2_LIB.BASEBOARD_FAB2(SCH_1):RMII_BMC_PCH_SPRNGVLLE_CRSDV   I225 @BASEBOARD_FAB2_LIB.BASEBOARD_FAB2(SCH_1):PAGE139

R9F3 RES_0402-4.75K,1%,1/16W,CHIP,GA
     1 P3V3_STBY @BASEBOARD_FAB2_LIB.BASEBOARD_FAB2(SCH_1):P3V3_STBY    I65 @BASEBOARD_FAB2_LIB.BASEBOARD_FAB2(SCH_1):PAGE170
     2 FM_FAST_PROCHOT_EN @BASEBOARD_FAB2_LIB.BASEBOARD_FAB2(SCH_1):FM_FAST_PROCHOT_EN    I65 @BASEBOARD_FAB2_LIB.BASEBOARD_FAB2(SCH_1):PAGE170

R9F5 RES_0402-3.32K,1%,1/16W,CHIP,GA
     1 P3V3_STBY @BASEBOARD_FAB2_LIB.BASEBOARD_FAB2(SCH_1):P3V3_STBY   I173 @BASEBOARD_FAB2_LIB.BASEBOARD_FAB2(SCH_1):PAGE139
     2 PU_SPRV_LAN_PWR_GOOD @BASEBOARD_FAB2_LIB.BASEBOARD_FAB2(SCH_1):PU_SPRV_LAN_PWR_GOOD   I173 @BASEBOARD_FAB2_LIB.BASEBOARD_FAB2(SCH_1):PAGE139

R9F6 4K42R2F-GP_SMD-RG-4K42R2F-GP,6A
     1 P1V15_AUX_BMC @BASEBOARD_FAB2_LIB.BASEBOARD_FAB2(SCH_1):P1V15_AUX_BMC    I45 @BASEBOARD_FAB2_LIB.BASEBOARD_FAB2(SCH_1):PAGE238
     2 VR_P1V26_BMC_STBY_FB @BASEBOARD_FAB2_LIB.BASEBOARD_FAB2(SCH_1):VR_P1V26_BMC_STBY_FB    I45 @BASEBOARD_FAB2_LIB.BASEBOARD_FAB2(SCH_1):PAGE238

R9F8 RES_0402-10.0K,1%,1/16W,CHIP,GA
     1    GND @BASEBOARD_FAB2_LIB.BASEBOARD_FAB2(SCH_1):GND    I14 @BASEBOARD_FAB2_LIB.BASEBOARD_FAB2(SCH_1):PAGE238
     2 VR_P1V26_BMC_STBY_FB @BASEBOARD_FAB2_LIB.BASEBOARD_FAB2(SCH_1):VR_P1V26_BMC_STBY_FB    I14 @BASEBOARD_FAB2_LIB.BASEBOARD_FAB2(SCH_1):PAGE238

R9F11 RES_0402-22.1,1.0%,1/16W,CHIP,A
     1 PWRGD_P1V26_BMC_STBY_R @BASEBOARD_FAB2_LIB.BASEBOARD_FAB2(SCH_1):PWRGD_P1V26_BMC_STBY_R    I41 @BASEBOARD_FAB2_LIB.BASEBOARD_FAB2(SCH_1):PAGE238
     2 PWRGD_P1V26_BMC_STBY @BASEBOARD_FAB2_LIB.BASEBOARD_FAB2(SCH_1):PWRGD_P1V26_BMC_STBY    I41 @BASEBOARD_FAB2_LIB.BASEBOARD_FAB2(SCH_1):PAGE238

R9F12 RES_0402-10.0K,1%,1/16W,CHIP,GA
     1 P3V3_STBY @BASEBOARD_FAB2_LIB.BASEBOARD_FAB2(SCH_1):P3V3_STBY     I6 @BASEBOARD_FAB2_LIB.BASEBOARD_FAB2(SCH_1):PAGE239
     2 PWRGD_P1V538_BMC_STBY_R @BASEBOARD_FAB2_LIB.BASEBOARD_FAB2(SCH_1):PWRGD_P1V538_BMC_STBY_R     I6 @BASEBOARD_FAB2_LIB.BASEBOARD_FAB2(SCH_1):PAGE239

R9F13 RES_0402-10.0K,1%,1/16W,CHIP,GA
     1 P3V3_STBY @BASEBOARD_FAB2_LIB.BASEBOARD_FAB2(SCH_1):P3V3_STBY    I21 @BASEBOARD_FAB2_LIB.BASEBOARD_FAB2(SCH_1):PAGE238
     2 PWRGD_P1V26_BMC_STBY_R @BASEBOARD_FAB2_LIB.BASEBOARD_FAB2(SCH_1):PWRGD_P1V26_BMC_STBY_R    I21 @BASEBOARD_FAB2_LIB.BASEBOARD_FAB2(SCH_1):PAGE238

R9F20 RES_0402-348,1%,1/16W,EMPTY,G2A
     1 PECI_BMC @BASEBOARD_FAB2_LIB.BASEBOARD_FAB2(SCH_1):PECI_BMC    I22 @BASEBOARD_FAB2_LIB.BASEBOARD_FAB2(SCH_1):PAGE145
     2    GND @BASEBOARD_FAB2_LIB.BASEBOARD_FAB2(SCH_1):GND    I22 @BASEBOARD_FAB2_LIB.BASEBOARD_FAB2(SCH_1):PAGE145

R9F22 RES_0402-20.0,1%,1/16W,CHIP,G2A
     1 SMB_LAN_STBY_LVC3_SCL_R @BASEBOARD_FAB2_LIB.BASEBOARD_FAB2(SCH_1):SMB_LAN_STBY_LVC3_SCL_R    I52 @BASEBOARD_FAB2_LIB.BASEBOARD_FAB2(SCH_1):PAGE160
     2 SMB_LAN_STBY_LVC3_SCL @BASEBOARD_FAB2_LIB.BASEBOARD_FAB2(SCH_1):SMB_LAN_STBY_LVC3_SCL    I52 @BASEBOARD_FAB2_LIB.BASEBOARD_FAB2(SCH_1):PAGE160

R9F23 RES_0402-20.0,1%,1/16W,CHIP,G2A
     1 SMB_LAN_STBY_LVC3_SDA_R @BASEBOARD_FAB2_LIB.BASEBOARD_FAB2(SCH_1):SMB_LAN_STBY_LVC3_SDA_R    I51 @BASEBOARD_FAB2_LIB.BASEBOARD_FAB2(SCH_1):PAGE160
     2 SMB_LAN_STBY_LVC3_SDA @BASEBOARD_FAB2_LIB.BASEBOARD_FAB2(SCH_1):SMB_LAN_STBY_LVC3_SDA    I51 @BASEBOARD_FAB2_LIB.BASEBOARD_FAB2(SCH_1):PAGE160

R9F24 RES_0402-0.0,5%,1/16W,EMPTY,G2A
     1 SPA_MID_DBG_RX @BASEBOARD_FAB2_LIB.BASEBOARD_FAB2(SCH_1):SPA_MID_DBG_RX   I100 @BASEBOARD_FAB2_LIB.BASEBOARD_FAB2(SCH_1):PAGE158
     2 SP2_BMC_CM_UART_RX @BASEBOARD_FAB2_LIB.BASEBOARD_FAB2(SCH_1):SP2_BMC_CM_UART_RX   I100 @BASEBOARD_FAB2_LIB.BASEBOARD_FAB2(SCH_1):PAGE158

R9F25 RES_0402-100.0,1%,1/16W,CHIP,GA
     1 SPA_MID_DBG_RX @BASEBOARD_FAB2_LIB.BASEBOARD_FAB2(SCH_1):SPA_MID_DBG_RX    I86 @BASEBOARD_FAB2_LIB.BASEBOARD_FAB2(SCH_1):PAGE158
     2 UART_MUX_IN_R @BASEBOARD_FAB2_LIB.BASEBOARD_FAB2(SCH_1):UART_MUX_IN_R    I86 @BASEBOARD_FAB2_LIB.BASEBOARD_FAB2(SCH_1):PAGE158

R9F26 RES_0402-0.0,5%,1/16W,EMPTY,G2A
     1 SP2_BMC_CM_UART_TX @BASEBOARD_FAB2_LIB.BASEBOARD_FAB2(SCH_1):SP2_BMC_CM_UART_TX    I99 @BASEBOARD_FAB2_LIB.BASEBOARD_FAB2(SCH_1):PAGE158
     2 SPA_MID_DBG_TX @BASEBOARD_FAB2_LIB.BASEBOARD_FAB2(SCH_1):SPA_MID_DBG_TX    I99 @BASEBOARD_FAB2_LIB.BASEBOARD_FAB2(SCH_1):PAGE158

R9F27 RES_0402-0.0,5%,1/16W,CHIP,G21A
     1 UART_MUX_OUT_R @BASEBOARD_FAB2_LIB.BASEBOARD_FAB2(SCH_1):UART_MUX_OUT_R    I91 @BASEBOARD_FAB2_LIB.BASEBOARD_FAB2(SCH_1):PAGE158
     2 SPA_MID_DBG_TX @BASEBOARD_FAB2_LIB.BASEBOARD_FAB2(SCH_1):SPA_MID_DBG_TX    I91 @BASEBOARD_FAB2_LIB.BASEBOARD_FAB2(SCH_1):PAGE158

R9F28 RES_0402-221,1.0%,1/16W,CHIP,GA
     1 P3V3_STBY @BASEBOARD_FAB2_LIB.BASEBOARD_FAB2(SCH_1):P3V3_STBY    I72 @BASEBOARD_FAB2_LIB.BASEBOARD_FAB2(SCH_1):PAGE177
     2 FM_RED_LED_ANODE @BASEBOARD_FAB2_LIB.BASEBOARD_FAB2(SCH_1):FM_RED_LED_ANODE    I72 @BASEBOARD_FAB2_LIB.BASEBOARD_FAB2(SCH_1):PAGE177

R9F29 RES_0402-4.75K,1%,1/16W,CHIP,GA
     1 P1V2_AUX_BMC @BASEBOARD_FAB2_LIB.BASEBOARD_FAB2(SCH_1):P1V2_AUX_BMC    I16 @BASEBOARD_FAB2_LIB.BASEBOARD_FAB2(SCH_1):PAGE149
     2 RST_BMC_DDR3_R_N @BASEBOARD_FAB2_LIB.BASEBOARD_FAB2(SCH_1):RST_BMC_DDR3_R_N    I16 @BASEBOARD_FAB2_LIB.BASEBOARD_FAB2(SCH_1):PAGE149

R9F30 RES_0402-4.75K,1%,1/16W,CHIP,GA
     1 P3V3_STBY @BASEBOARD_FAB2_LIB.BASEBOARD_FAB2(SCH_1):P3V3_STBY    I76 @BASEBOARD_FAB2_LIB.BASEBOARD_FAB2(SCH_1):PAGE177
     2 FM_BMC_FAULT_LED_N @BASEBOARD_FAB2_LIB.BASEBOARD_FAB2(SCH_1):FM_BMC_FAULT_LED_N    I76 @BASEBOARD_FAB2_LIB.BASEBOARD_FAB2(SCH_1):PAGE177

R9F31 5K1R2F-2-GP_SMD-RG-5K1R2F-2-GPA
     1 P1V2_AUX_BMC @BASEBOARD_FAB2_LIB.BASEBOARD_FAB2(SCH_1):P1V2_AUX_BMC    I98 @BASEBOARD_FAB2_LIB.BASEBOARD_FAB2(SCH_1):PAGE239
     2 VR_P1V538_BMC_STBY_FB @BASEBOARD_FAB2_LIB.BASEBOARD_FAB2(SCH_1):VR_P1V538_BMC_STBY_FB    I98 @BASEBOARD_FAB2_LIB.BASEBOARD_FAB2(SCH_1):PAGE239

R9F32 RES_0402-13K,1.0%,1/16W,CHIP,GA
     1    GND @BASEBOARD_FAB2_LIB.BASEBOARD_FAB2(SCH_1):GND    I15 @BASEBOARD_FAB2_LIB.BASEBOARD_FAB2(SCH_1):PAGE239
     2 VR_P1V538_BMC_STBY_FB @BASEBOARD_FAB2_LIB.BASEBOARD_FAB2(SCH_1):VR_P1V538_BMC_STBY_FB    I15 @BASEBOARD_FAB2_LIB.BASEBOARD_FAB2(SCH_1):PAGE239

R9F33 RES_0402-0.0,5%,1/16W,CHIP,G21A
     1 PECI_BMC @BASEBOARD_FAB2_LIB.BASEBOARD_FAB2(SCH_1):PECI_BMC    I20 @BASEBOARD_FAB2_LIB.BASEBOARD_FAB2(SCH_1):PAGE145
     2 PECI_BMC_R @BASEBOARD_FAB2_LIB.BASEBOARD_FAB2(SCH_1):PECI_BMC_R    I20 @BASEBOARD_FAB2_LIB.BASEBOARD_FAB2(SCH_1):PAGE145

R9F34 RES_0402-33.2,1%,1/16W,CHIP,G2A
     1 RST_BMC_DDR3_R_N @BASEBOARD_FAB2_LIB.BASEBOARD_FAB2(SCH_1):RST_BMC_DDR3_R_N    I14 @BASEBOARD_FAB2_LIB.BASEBOARD_FAB2(SCH_1):PAGE149
     2 BMC_M_RST_N @BASEBOARD_FAB2_LIB.BASEBOARD_FAB2(SCH_1):BMC_M_RST_N    I14 @BASEBOARD_FAB2_LIB.BASEBOARD_FAB2(SCH_1):PAGE149

R9F47 RES_0402-4.75K,1%,1/16W,CHIP,GA
     1 P3V3_STBY @BASEBOARD_FAB2_LIB.BASEBOARD_FAB2(SCH_1):P3V3_STBY     I4 @BASEBOARD_FAB2_LIB.BASEBOARD_FAB2(SCH_1):PAGE183
     2 PU_PI7C9X1172_I2C_SPI_N @BASEBOARD_FAB2_LIB.BASEBOARD_FAB2(SCH_1):PU_PI7C9X1172_I2C_SPI_N     I4 @BASEBOARD_FAB2_LIB.BASEBOARD_FAB2(SCH_1):PAGE183

R9F48 RES_0402-4.75K,1%,1/16W,EMPTY,A
     1 P3V3_STBY @BASEBOARD_FAB2_LIB.BASEBOARD_FAB2(SCH_1):P3V3_STBY    I13 @BASEBOARD_FAB2_LIB.BASEBOARD_FAB2(SCH_1):PAGE183
     2 FM_PI7C9X1172_A1 @BASEBOARD_FAB2_LIB.BASEBOARD_FAB2(SCH_1):FM_PI7C9X1172_A1    I13 @BASEBOARD_FAB2_LIB.BASEBOARD_FAB2(SCH_1):PAGE183

R9F49 RES_0402-4.75K,1%,1/16W,EMPTY,A
     1 P3V3_STBY @BASEBOARD_FAB2_LIB.BASEBOARD_FAB2(SCH_1):P3V3_STBY    I14 @BASEBOARD_FAB2_LIB.BASEBOARD_FAB2(SCH_1):PAGE183
     2 FM_PI7C9X1172_A0 @BASEBOARD_FAB2_LIB.BASEBOARD_FAB2(SCH_1):FM_PI7C9X1172_A0    I14 @BASEBOARD_FAB2_LIB.BASEBOARD_FAB2(SCH_1):PAGE183

R9F50 RES_0402-1.00K,1%,1/16W,CHIP,GA
     1 FM_PI7C9X1172_A1 @BASEBOARD_FAB2_LIB.BASEBOARD_FAB2(SCH_1):FM_PI7C9X1172_A1    I11 @BASEBOARD_FAB2_LIB.BASEBOARD_FAB2(SCH_1):PAGE183
     2    GND @BASEBOARD_FAB2_LIB.BASEBOARD_FAB2(SCH_1):GND    I11 @BASEBOARD_FAB2_LIB.BASEBOARD_FAB2(SCH_1):PAGE183

R9F51 RES_0402-1.00K,1%,1/16W,CHIP,GA
     1 FM_PI7C9X1172_A0 @BASEBOARD_FAB2_LIB.BASEBOARD_FAB2(SCH_1):FM_PI7C9X1172_A0    I12 @BASEBOARD_FAB2_LIB.BASEBOARD_FAB2(SCH_1):PAGE183
     2    GND @BASEBOARD_FAB2_LIB.BASEBOARD_FAB2(SCH_1):GND    I12 @BASEBOARD_FAB2_LIB.BASEBOARD_FAB2(SCH_1):PAGE183

R9F52 RES_0402-4.75K,1%,1/16W,CHIP,GA
     1 P3V3_STBY @BASEBOARD_FAB2_LIB.BASEBOARD_FAB2(SCH_1):P3V3_STBY    I82 @BASEBOARD_FAB2_LIB.BASEBOARD_FAB2(SCH_1):PAGE177
     2 FM_BMC_FAULT_LED @BASEBOARD_FAB2_LIB.BASEBOARD_FAB2(SCH_1):FM_BMC_FAULT_LED    I82 @BASEBOARD_FAB2_LIB.BASEBOARD_FAB2(SCH_1):PAGE177

R9F53 RES_0402-0.0,5%,1/16W,CHIP,G21A
     1 UART_BMC_RXD5 @BASEBOARD_FAB2_LIB.BASEBOARD_FAB2(SCH_1):UART_BMC_RXD5    I53 @BASEBOARD_FAB2_LIB.BASEBOARD_FAB2(SCH_1):PAGE183
     2 UART_BRIDGE_RXD5 @BASEBOARD_FAB2_LIB.BASEBOARD_FAB2(SCH_1):UART_BRIDGE_RXD5    I53 @BASEBOARD_FAB2_LIB.BASEBOARD_FAB2(SCH_1):PAGE183

R9F54 RES_0402-0.0,5%,1/16W,CHIP,G21A
     1 SP1_BMC_HOST_UART_RX @BASEBOARD_FAB2_LIB.BASEBOARD_FAB2(SCH_1):SP1_BMC_HOST_UART_RX    I52 @BASEBOARD_FAB2_LIB.BASEBOARD_FAB2(SCH_1):PAGE183
     2 SP1_HOST_BRIDGE_UART_RX @BASEBOARD_FAB2_LIB.BASEBOARD_FAB2(SCH_1):SP1_HOST_BRIDGE_UART_RX    I52 @BASEBOARD_FAB2_LIB.BASEBOARD_FAB2(SCH_1):PAGE183

R9F55 RES_0402-4.75K,1%,1/16W,CHIP,GA
     1 P3V3_STBY @BASEBOARD_FAB2_LIB.BASEBOARD_FAB2(SCH_1):P3V3_STBY    I30 @BASEBOARD_FAB2_LIB.BASEBOARD_FAB2(SCH_1):PAGE183
     2 FM_UART_ALERT_N @BASEBOARD_FAB2_LIB.BASEBOARD_FAB2(SCH_1):FM_UART_ALERT_N    I30 @BASEBOARD_FAB2_LIB.BASEBOARD_FAB2(SCH_1):PAGE183

R9F56 RES_0402-0.0,5%,1/16W,CHIP,G21A
     1 SP1_HOST_BRIDGE_UART_TX @BASEBOARD_FAB2_LIB.BASEBOARD_FAB2(SCH_1):SP1_HOST_BRIDGE_UART_TX    I49 @BASEBOARD_FAB2_LIB.BASEBOARD_FAB2(SCH_1):PAGE183
     2 SP1_BMC_HOST_UART_TX @BASEBOARD_FAB2_LIB.BASEBOARD_FAB2(SCH_1):SP1_BMC_HOST_UART_TX    I49 @BASEBOARD_FAB2_LIB.BASEBOARD_FAB2(SCH_1):PAGE183

R9F57 RES_0402-0.0,5%,1/16W,CHIP,G21A
     1 UART_BRIDGE_TXD5 @BASEBOARD_FAB2_LIB.BASEBOARD_FAB2(SCH_1):UART_BRIDGE_TXD5    I48 @BASEBOARD_FAB2_LIB.BASEBOARD_FAB2(SCH_1):PAGE183
     2 UART_BMC_TXD5 @BASEBOARD_FAB2_LIB.BASEBOARD_FAB2(SCH_1):UART_BMC_TXD5    I48 @BASEBOARD_FAB2_LIB.BASEBOARD_FAB2(SCH_1):PAGE183

R9F58 RES_0402-0.0,5%,1/16W,CHIP,G21A
     1 XTAL_24MHZ_PI7C9X1172_IN @BASEBOARD_FAB2_LIB.BASEBOARD_FAB2(SCH_1):XTAL_24MHZ_PI7C9X1172_IN    I24 @BASEBOARD_FAB2_LIB.BASEBOARD_FAB2(SCH_1):PAGE183
     2 XTAL_24MHZ_IN_R @BASEBOARD_FAB2_LIB.BASEBOARD_FAB2(SCH_1):XTAL_24MHZ_IN_R    I24 @BASEBOARD_FAB2_LIB.BASEBOARD_FAB2(SCH_1):PAGE183

R9F59 RES_0402-0.0,5%,1/16W,CHIP,G21A
     1 XTAL_24MHZ_PI7C9X1172_OUT @BASEBOARD_FAB2_LIB.BASEBOARD_FAB2(SCH_1):XTAL_24MHZ_PI7C9X1172_OUT    I25 @BASEBOARD_FAB2_LIB.BASEBOARD_FAB2(SCH_1):PAGE183
     2 XTAL_24MHZ_OUT_R @BASEBOARD_FAB2_LIB.BASEBOARD_FAB2(SCH_1):XTAL_24MHZ_OUT_R    I25 @BASEBOARD_FAB2_LIB.BASEBOARD_FAB2(SCH_1):PAGE183

R9F60 RES_0402-0.0,5%,1/16W,EMPTY,G2A
     1 CLK_25M_BMC @BASEBOARD_FAB2_LIB.BASEBOARD_FAB2(SCH_1):CLK_25M_BMC    I10 @BASEBOARD_FAB2_LIB.BASEBOARD_FAB2(SCH_1):PAGE145
     2 CLK_24M_25M_BMC_CLKIN @BASEBOARD_FAB2_LIB.BASEBOARD_FAB2(SCH_1):CLK_24M_25M_BMC_CLKIN    I10 @BASEBOARD_FAB2_LIB.BASEBOARD_FAB2(SCH_1):PAGE145

R9F61 RES_0402-10.0K,1%,1/16W,CHIP,GA
     1 P3V3_STBY @BASEBOARD_FAB2_LIB.BASEBOARD_FAB2(SCH_1):P3V3_STBY    I14 @BASEBOARD_FAB2_LIB.BASEBOARD_FAB2(SCH_1):PAGE145
     2 PU_24M_OSC_OE @BASEBOARD_FAB2_LIB.BASEBOARD_FAB2(SCH_1):PU_24M_OSC_OE    I14 @BASEBOARD_FAB2_LIB.BASEBOARD_FAB2(SCH_1):PAGE145

R9F62 RES_0402-0.0,5%,1/16W,CHIP,G21A
     1 CLK_24M_BMC_CLKIN_R @BASEBOARD_FAB2_LIB.BASEBOARD_FAB2(SCH_1):CLK_24M_BMC_CLKIN_R    I11 @BASEBOARD_FAB2_LIB.BASEBOARD_FAB2(SCH_1):PAGE145
     2 CLK_24M_25M_BMC_CLKIN @BASEBOARD_FAB2_LIB.BASEBOARD_FAB2(SCH_1):CLK_24M_25M_BMC_CLKIN    I11 @BASEBOARD_FAB2_LIB.BASEBOARD_FAB2(SCH_1):PAGE145

R9F63 RES_0402-0.0,5%,1/16W,EMPTY,G2A
     1 SPA_MID_DBG_RX @BASEBOARD_FAB2_LIB.BASEBOARD_FAB2(SCH_1):SPA_MID_DBG_RX   I282 @BASEBOARD_FAB2_LIB.BASEBOARD_FAB2(SCH_1):PAGE181
     2 SPA_MID_DBG_RX_R @BASEBOARD_FAB2_LIB.BASEBOARD_FAB2(SCH_1):SPA_MID_DBG_RX_R   I282 @BASEBOARD_FAB2_LIB.BASEBOARD_FAB2(SCH_1):PAGE181

R9F64 RES_0402-0.0,5%,1/16W,CHIP,G21A
     1 SP2_BMC_CM_UART_TX_R1 @BASEBOARD_FAB2_LIB.BASEBOARD_FAB2(SCH_1):SP2_BMC_CM_UART_TX_R1   I281 @BASEBOARD_FAB2_LIB.BASEBOARD_FAB2(SCH_1):PAGE181
     2 SPA_MID_DBG_RX_R @BASEBOARD_FAB2_LIB.BASEBOARD_FAB2(SCH_1):SPA_MID_DBG_RX_R   I281 @BASEBOARD_FAB2_LIB.BASEBOARD_FAB2(SCH_1):PAGE181

R9F65 RES_0402-0.0,5%,1/16W,CHIP,G21A
     1 SP2_BMC_CM_UART_TX_R1 @BASEBOARD_FAB2_LIB.BASEBOARD_FAB2(SCH_1):SP2_BMC_CM_UART_TX_R1   I148 @BASEBOARD_FAB2_LIB.BASEBOARD_FAB2(SCH_1):PAGE158
     2 SP2_BMC_CM_UART_TX_R @BASEBOARD_FAB2_LIB.BASEBOARD_FAB2(SCH_1):SP2_BMC_CM_UART_TX_R   I148 @BASEBOARD_FAB2_LIB.BASEBOARD_FAB2(SCH_1):PAGE158

R9F66 RES_0402-0.0,5%,1/16W,EMPTY,G2A
     1 SP2_BMC_CM_UART_TX @BASEBOARD_FAB2_LIB.BASEBOARD_FAB2(SCH_1):SP2_BMC_CM_UART_TX   I152 @BASEBOARD_FAB2_LIB.BASEBOARD_FAB2(SCH_1):PAGE158
     2 SP2_BMC_CM_UART_TX_R @BASEBOARD_FAB2_LIB.BASEBOARD_FAB2(SCH_1):SP2_BMC_CM_UART_TX_R   I152 @BASEBOARD_FAB2_LIB.BASEBOARD_FAB2(SCH_1):PAGE158

R9F67 RES_0402-0.0,5%,1/16W,CHIP,G21A
     1 SP2_BMC_CM_UART_RX_R1 @BASEBOARD_FAB2_LIB.BASEBOARD_FAB2(SCH_1):SP2_BMC_CM_UART_RX_R1   I279 @BASEBOARD_FAB2_LIB.BASEBOARD_FAB2(SCH_1):PAGE181
     2 SPA_MID_DBG_TX_R @BASEBOARD_FAB2_LIB.BASEBOARD_FAB2(SCH_1):SPA_MID_DBG_TX_R   I279 @BASEBOARD_FAB2_LIB.BASEBOARD_FAB2(SCH_1):PAGE181

R9F68 RES_0402-0.0,5%,1/16W,EMPTY,G2A
     1 SP2_BMC_CM_UART_RX_R @BASEBOARD_FAB2_LIB.BASEBOARD_FAB2(SCH_1):SP2_BMC_CM_UART_RX_R   I149 @BASEBOARD_FAB2_LIB.BASEBOARD_FAB2(SCH_1):PAGE158
     2 SP2_BMC_CM_UART_RX @BASEBOARD_FAB2_LIB.BASEBOARD_FAB2(SCH_1):SP2_BMC_CM_UART_RX   I149 @BASEBOARD_FAB2_LIB.BASEBOARD_FAB2(SCH_1):PAGE158

R9F69 RES_0402-0.0,5%,1/16W,CHIP,G21A
     1 SP2_BMC_CM_UART_RX_R @BASEBOARD_FAB2_LIB.BASEBOARD_FAB2(SCH_1):SP2_BMC_CM_UART_RX_R   I150 @BASEBOARD_FAB2_LIB.BASEBOARD_FAB2(SCH_1):PAGE158
     2 SP2_BMC_CM_UART_RX_R1 @BASEBOARD_FAB2_LIB.BASEBOARD_FAB2(SCH_1):SP2_BMC_CM_UART_RX_R1   I150 @BASEBOARD_FAB2_LIB.BASEBOARD_FAB2(SCH_1):PAGE158

R9F70 RES_0402-0.0,5%,1/16W,EMPTY,G2A
     1 SPA_MID_DBG_TX @BASEBOARD_FAB2_LIB.BASEBOARD_FAB2(SCH_1):SPA_MID_DBG_TX   I280 @BASEBOARD_FAB2_LIB.BASEBOARD_FAB2(SCH_1):PAGE181
     2 SPA_MID_DBG_TX_R @BASEBOARD_FAB2_LIB.BASEBOARD_FAB2(SCH_1):SPA_MID_DBG_TX_R   I280 @BASEBOARD_FAB2_LIB.BASEBOARD_FAB2(SCH_1):PAGE181

R9G1 RES_0402-150.0,1%,1/16W,CHIP,GA
     1 LED_LAN_1_N @BASEBOARD_FAB2_LIB.BASEBOARD_FAB2(SCH_1):LED_LAN_1_N    I54 @BASEBOARD_FAB2_LIB.BASEBOARD_FAB2(SCH_1):PAGE141
     2 LED_LAN_1_R_N @BASEBOARD_FAB2_LIB.BASEBOARD_FAB2(SCH_1):LED_LAN_1_R_N    I54 @BASEBOARD_FAB2_LIB.BASEBOARD_FAB2(SCH_1):PAGE141

R9G2 RES_0402-150.0,1%,1/16W,CHIP,GA
     1 LED_LAN_2_R_N @BASEBOARD_FAB2_LIB.BASEBOARD_FAB2(SCH_1):LED_LAN_2_R_N    I30 @BASEBOARD_FAB2_LIB.BASEBOARD_FAB2(SCH_1):PAGE141
     2 LED_LAN_2_N @BASEBOARD_FAB2_LIB.BASEBOARD_FAB2(SCH_1):LED_LAN_2_N    I30 @BASEBOARD_FAB2_LIB.BASEBOARD_FAB2(SCH_1):PAGE141

R9G3 RES_0402-150.0,1%,1/16W,CHIP,GA
     1 LED_LAN_0_R_N @BASEBOARD_FAB2_LIB.BASEBOARD_FAB2(SCH_1):LED_LAN_0_R_N    I28 @BASEBOARD_FAB2_LIB.BASEBOARD_FAB2(SCH_1):PAGE141
     2 LED_LAN_0_N @BASEBOARD_FAB2_LIB.BASEBOARD_FAB2(SCH_1):LED_LAN_0_N    I28 @BASEBOARD_FAB2_LIB.BASEBOARD_FAB2(SCH_1):PAGE141

R9G4 RES_0402-0.0,5%,1/16W,CHIP,G21A
     1 NIC_LED_ACT_ANODE_R @BASEBOARD_FAB2_LIB.BASEBOARD_FAB2(SCH_1):NIC_LED_ACT_ANODE_R    I56 @BASEBOARD_FAB2_LIB.BASEBOARD_FAB2(SCH_1):PAGE141
     2 P3V3_STBY @BASEBOARD_FAB2_LIB.BASEBOARD_FAB2(SCH_1):P3V3_STBY    I56 @BASEBOARD_FAB2_LIB.BASEBOARD_FAB2(SCH_1):PAGE141

R9G9 RES_0402-0.0,5%,1/16W,CHIP,G21A
     1 NIC_SER_P_MDI_3_DP @BASEBOARD_FAB2_LIB.BASEBOARD_FAB2(SCH_1):NIC_SER_P_MDI_3_DP    I75 @BASEBOARD_FAB2_LIB.BASEBOARD_FAB2(SCH_1):PAGE141
     2 NIC_MDI_SPRV_RJ45_3_R_DP @BASEBOARD_FAB2_LIB.BASEBOARD_FAB2(SCH_1):NIC_MDI_SPRV_RJ45_3_R_DP    I75 @BASEBOARD_FAB2_LIB.BASEBOARD_FAB2(SCH_1):PAGE141

R9G11 RES_0402-0.0,5%,1/16W,CHIP,G21A
     1 NIC_SER_N_MDI_3_DN @BASEBOARD_FAB2_LIB.BASEBOARD_FAB2(SCH_1):NIC_SER_N_MDI_3_DN    I76 @BASEBOARD_FAB2_LIB.BASEBOARD_FAB2(SCH_1):PAGE141
     2 NIC_MDI_SPRV_RJ45_3_R_DN @BASEBOARD_FAB2_LIB.BASEBOARD_FAB2(SCH_1):NIC_MDI_SPRV_RJ45_3_R_DN    I76 @BASEBOARD_FAB2_LIB.BASEBOARD_FAB2(SCH_1):PAGE141

R9G12 RES_0402-20.0,1%,1/16W,CHIP,G2A
     1 SMB_OCP_LAN_STBY_LVC3_SDA @BASEBOARD_FAB2_LIB.BASEBOARD_FAB2(SCH_1):SMB_OCP_LAN_STBY_LVC3_SDA   I224 @BASEBOARD_FAB2_LIB.BASEBOARD_FAB2(SCH_1):PAGE159
     2 SMB_SPRINGVILLE_STBY_LVC3_SDA @BASEBOARD_FAB2_LIB.BASEBOARD_FAB2(SCH_1):SMB_SPRINGVILLE_STBY_LVC3_SDA   I224 @BASEBOARD_FAB2_LIB.BASEBOARD_FAB2(SCH_1):PAGE159

R9G13 RES_0402-20.0,1%,1/16W,CHIP,G2A
     1 SMB_OCP_LAN_STBY_LVC3_SCL @BASEBOARD_FAB2_LIB.BASEBOARD_FAB2(SCH_1):SMB_OCP_LAN_STBY_LVC3_SCL   I227 @BASEBOARD_FAB2_LIB.BASEBOARD_FAB2(SCH_1):PAGE159
     2 SMB_SPRINGVILLE_STBY_LVC3_SCL @BASEBOARD_FAB2_LIB.BASEBOARD_FAB2(SCH_1):SMB_SPRINGVILLE_STBY_LVC3_SCL   I227 @BASEBOARD_FAB2_LIB.BASEBOARD_FAB2(SCH_1):PAGE159

R9G14 RES_0402-20.0,1%,1/16W,CHIP,G2A
     1 SMB_SENSOR_BMC_STBY_LVC3_SCL @BASEBOARD_FAB2_LIB.BASEBOARD_FAB2(SCH_1):SMB_SENSOR_BMC_STBY_LVC3_SCL    I77 @BASEBOARD_FAB2_LIB.BASEBOARD_FAB2(SCH_1):PAGE167
     2 SMB_SENSOR_STBY_LVC3_SCL @BASEBOARD_FAB2_LIB.BASEBOARD_FAB2(SCH_1):SMB_SENSOR_STBY_LVC3_SCL    I77 @BASEBOARD_FAB2_LIB.BASEBOARD_FAB2(SCH_1):PAGE167

R9G15 RES_0402-20.0,1%,1/16W,CHIP,G2A
     1 SMB_SENSOR_BMC_STBY_LVC3_SDA @BASEBOARD_FAB2_LIB.BASEBOARD_FAB2(SCH_1):SMB_SENSOR_BMC_STBY_LVC3_SDA    I58 @BASEBOARD_FAB2_LIB.BASEBOARD_FAB2(SCH_1):PAGE167
     2 SMB_SENSOR_STBY_LVC3_SDA @BASEBOARD_FAB2_LIB.BASEBOARD_FAB2(SCH_1):SMB_SENSOR_STBY_LVC3_SDA    I58 @BASEBOARD_FAB2_LIB.BASEBOARD_FAB2(SCH_1):PAGE167

R9G17 RES_0402-0.0,5%,1/16W,CHIP,G21A
     1 NIC_SET_N_MDI_2_DN @BASEBOARD_FAB2_LIB.BASEBOARD_FAB2(SCH_1):NIC_SET_N_MDI_2_DN    I78 @BASEBOARD_FAB2_LIB.BASEBOARD_FAB2(SCH_1):PAGE141
     2 NIC_MDI_SPRV_RJ45_2_R_DN @BASEBOARD_FAB2_LIB.BASEBOARD_FAB2(SCH_1):NIC_MDI_SPRV_RJ45_2_R_DN    I78 @BASEBOARD_FAB2_LIB.BASEBOARD_FAB2(SCH_1):PAGE141

R9G18 RES_0402-0.0,5%,1/16W,CHIP,G21A
     1 NIC_SET_P_MDI_2_DP @BASEBOARD_FAB2_LIB.BASEBOARD_FAB2(SCH_1):NIC_SET_P_MDI_2_DP    I77 @BASEBOARD_FAB2_LIB.BASEBOARD_FAB2(SCH_1):PAGE141
     2 NIC_MDI_SPRV_RJ45_2_R_DP @BASEBOARD_FAB2_LIB.BASEBOARD_FAB2(SCH_1):NIC_MDI_SPRV_RJ45_2_R_DP    I77 @BASEBOARD_FAB2_LIB.BASEBOARD_FAB2(SCH_1):PAGE141

R9G19 RES_0402-0.0,5%,1/16W,CHIP,G21A
     1 NIC_MDI_SPRV_RJ45_1_DP @BASEBOARD_FAB2_LIB.BASEBOARD_FAB2(SCH_1):NIC_MDI_SPRV_RJ45_1_DP    I79 @BASEBOARD_FAB2_LIB.BASEBOARD_FAB2(SCH_1):PAGE141
     2 NIC_MDI_SPRV_RJ45_1_R_DP @BASEBOARD_FAB2_LIB.BASEBOARD_FAB2(SCH_1):NIC_MDI_SPRV_RJ45_1_R_DP    I79 @BASEBOARD_FAB2_LIB.BASEBOARD_FAB2(SCH_1):PAGE141

R9G20 RES_0402-0.0,5%,1/16W,CHIP,G21A
     1 NIC_MDI_SPRV_RJ45_1_DN @BASEBOARD_FAB2_LIB.BASEBOARD_FAB2(SCH_1):NIC_MDI_SPRV_RJ45_1_DN    I80 @BASEBOARD_FAB2_LIB.BASEBOARD_FAB2(SCH_1):PAGE141
     2 NIC_MDI_SPRV_RJ45_1_R_DN @BASEBOARD_FAB2_LIB.BASEBOARD_FAB2(SCH_1):NIC_MDI_SPRV_RJ45_1_R_DN    I80 @BASEBOARD_FAB2_LIB.BASEBOARD_FAB2(SCH_1):PAGE141

R9G21 RES_0402-4.75K,1%,1/16W,CHIP,GA
     1 P3V3_STBY @BASEBOARD_FAB2_LIB.BASEBOARD_FAB2(SCH_1):P3V3_STBY    I69 @BASEBOARD_FAB2_LIB.BASEBOARD_FAB2(SCH_1):PAGE165
     2 IRQ_VM_INT_R_N @BASEBOARD_FAB2_LIB.BASEBOARD_FAB2(SCH_1):IRQ_VM_INT_R_N    I69 @BASEBOARD_FAB2_LIB.BASEBOARD_FAB2(SCH_1):PAGE165

R9G22 RES_0402-0.0,5%,1/16W,CHIP,G21A
     1 NIC_MDI_SPRV_RJ45_0_DN @BASEBOARD_FAB2_LIB.BASEBOARD_FAB2(SCH_1):NIC_MDI_SPRV_RJ45_0_DN    I82 @BASEBOARD_FAB2_LIB.BASEBOARD_FAB2(SCH_1):PAGE141
     2 NIC_MDI_SPRV_RJ45_0_R_DN @BASEBOARD_FAB2_LIB.BASEBOARD_FAB2(SCH_1):NIC_MDI_SPRV_RJ45_0_R_DN    I82 @BASEBOARD_FAB2_LIB.BASEBOARD_FAB2(SCH_1):PAGE141

R9G23 RES_0402-4.75K,1%,1/16W,EMPTY,A
     1 P3V3_STBY @BASEBOARD_FAB2_LIB.BASEBOARD_FAB2(SCH_1):P3V3_STBY    I57 @BASEBOARD_FAB2_LIB.BASEBOARD_FAB2(SCH_1):PAGE165
     2 FM_ADC128_A0 @BASEBOARD_FAB2_LIB.BASEBOARD_FAB2(SCH_1):FM_ADC128_A0    I57 @BASEBOARD_FAB2_LIB.BASEBOARD_FAB2(SCH_1):PAGE165

R9G24 RES_0402-0.0,5%,1/16W,CHIP,G21A
     1 NIC_MDI_SPRV_RJ45_0_DP @BASEBOARD_FAB2_LIB.BASEBOARD_FAB2(SCH_1):NIC_MDI_SPRV_RJ45_0_DP    I81 @BASEBOARD_FAB2_LIB.BASEBOARD_FAB2(SCH_1):PAGE141
     2 NIC_MDI_SPRV_RJ45_0_R_DP @BASEBOARD_FAB2_LIB.BASEBOARD_FAB2(SCH_1):NIC_MDI_SPRV_RJ45_0_R_DP    I81 @BASEBOARD_FAB2_LIB.BASEBOARD_FAB2(SCH_1):PAGE141

R9G25 RES_0402-4.75K,1%,1/16W,EMPTY,A
     1 P3V3_STBY @BASEBOARD_FAB2_LIB.BASEBOARD_FAB2(SCH_1):P3V3_STBY    I58 @BASEBOARD_FAB2_LIB.BASEBOARD_FAB2(SCH_1):PAGE165
     2 FM_ADC128_A1 @BASEBOARD_FAB2_LIB.BASEBOARD_FAB2(SCH_1):FM_ADC128_A1    I58 @BASEBOARD_FAB2_LIB.BASEBOARD_FAB2(SCH_1):PAGE165

R9G26 RES_0402-100.0K,1%,1/16W,CHIP,A
     1 A_P3V_BAT_SCALED @BASEBOARD_FAB2_LIB.BASEBOARD_FAB2(SCH_1):A_P3V_BAT_SCALED   I106 @BASEBOARD_FAB2_LIB.BASEBOARD_FAB2(SCH_1):PAGE169
     2    GND @BASEBOARD_FAB2_LIB.BASEBOARD_FAB2(SCH_1):GND   I106 @BASEBOARD_FAB2_LIB.BASEBOARD_FAB2(SCH_1):PAGE169

R9G27 RES_0402-0.0,5%,1/16W,EMPTY,G2A
     1 H_CPU0_MEMDEF_MEMHOT_G_PCH_N @BASEBOARD_FAB2_LIB.BASEBOARD_FAB2(SCH_1):H_CPU0_MEMDEF_MEMHOT_G_PCH_N    I47 @BASEBOARD_FAB2_LIB.BASEBOARD_FAB2(SCH_1):PAGE152
     2 H_CPU0_MEMDEF_MEMHOT_LVT3_K_N @BASEBOARD_FAB2_LIB.BASEBOARD_FAB2(SCH_1):H_CPU0_MEMDEF_MEMHOT_LVT3_K_N    I47 @BASEBOARD_FAB2_LIB.BASEBOARD_FAB2(SCH_1):PAGE152

R9G28 RES_0402-0.0,5%,1/16W,CHIP,G21A
     1 H_CPU1_KLM_MEMHOT_LVT3_R_N @BASEBOARD_FAB2_LIB.BASEBOARD_FAB2(SCH_1):H_CPU1_KLM_MEMHOT_LVT3_R_N    I71 @BASEBOARD_FAB2_LIB.BASEBOARD_FAB2(SCH_1):PAGE152
     2 H_CPU1_MEMKLM_MEMHOT_LVT3_K_N @BASEBOARD_FAB2_LIB.BASEBOARD_FAB2(SCH_1):H_CPU1_MEMKLM_MEMHOT_LVT3_K_N    I71 @BASEBOARD_FAB2_LIB.BASEBOARD_FAB2(SCH_1):PAGE152

R9G29 RES_0402-0.0,5%,1/16W,CHIP,G21A
     1 H_CPU0_MEMDEF_MEMHOT_LVT3_N @BASEBOARD_FAB2_LIB.BASEBOARD_FAB2(SCH_1):H_CPU0_MEMDEF_MEMHOT_LVT3_N    I92 @BASEBOARD_FAB2_LIB.BASEBOARD_FAB2(SCH_1):PAGE152
     2 H_CPU0_MEMDEF_MEMHOT_LVT3_BMC_N @BASEBOARD_FAB2_LIB.BASEBOARD_FAB2(SCH_1):H_CPU0_MEMDEF_MEMHOT_LVT3_BMC_N    I92 @BASEBOARD_FAB2_LIB.BASEBOARD_FAB2(SCH_1):PAGE152

R9G30 RES_0402-0.0,5%,1/16W,EMPTY,G2A
     1 H_CPU0_MEMDEF_MEMHOT_LVT3_N @BASEBOARD_FAB2_LIB.BASEBOARD_FAB2(SCH_1):H_CPU0_MEMDEF_MEMHOT_LVT3_N    I98 @BASEBOARD_FAB2_LIB.BASEBOARD_FAB2(SCH_1):PAGE152
     2 H_CPU0_MEMDEF_MEMHOT_PCH_N @BASEBOARD_FAB2_LIB.BASEBOARD_FAB2(SCH_1):H_CPU0_MEMDEF_MEMHOT_PCH_N    I98 @BASEBOARD_FAB2_LIB.BASEBOARD_FAB2(SCH_1):PAGE152

R9G31 RES_0402-33.2,1%,1/16W,CHIP,G2A
     1 H_CPU0_MEMDEF_MEMHOT_LVT3_K_N @BASEBOARD_FAB2_LIB.BASEBOARD_FAB2(SCH_1):H_CPU0_MEMDEF_MEMHOT_LVT3_K_N    I14 @BASEBOARD_FAB2_LIB.BASEBOARD_FAB2(SCH_1):PAGE152
     2 H_CPU0_MEMDEF_MEMHOT_LVT3_N @BASEBOARD_FAB2_LIB.BASEBOARD_FAB2(SCH_1):H_CPU0_MEMDEF_MEMHOT_LVT3_N    I14 @BASEBOARD_FAB2_LIB.BASEBOARD_FAB2(SCH_1):PAGE152

R9G32 RES_0402-0.0,5%,1/16W,CHIP,G21A
     1 H_CPU1_GHJ_MEMHOT_LVT3_R_N @BASEBOARD_FAB2_LIB.BASEBOARD_FAB2(SCH_1):H_CPU1_GHJ_MEMHOT_LVT3_R_N    I72 @BASEBOARD_FAB2_LIB.BASEBOARD_FAB2(SCH_1):PAGE152
     2 H_CPU1_MEMGHJ_MEMHOT_LVT3_K_N @BASEBOARD_FAB2_LIB.BASEBOARD_FAB2(SCH_1):H_CPU1_MEMGHJ_MEMHOT_LVT3_K_N    I72 @BASEBOARD_FAB2_LIB.BASEBOARD_FAB2(SCH_1):PAGE152

R9G33 RES_0402-0.0,5%,1/16W,CHIP,G21A
     1 H_CPU0_DEF_MEMHOT_LVT3_R_N @BASEBOARD_FAB2_LIB.BASEBOARD_FAB2(SCH_1):H_CPU0_DEF_MEMHOT_LVT3_R_N    I73 @BASEBOARD_FAB2_LIB.BASEBOARD_FAB2(SCH_1):PAGE152
     2 H_CPU0_MEMDEF_MEMHOT_LVT3_K_N @BASEBOARD_FAB2_LIB.BASEBOARD_FAB2(SCH_1):H_CPU0_MEMDEF_MEMHOT_LVT3_K_N    I73 @BASEBOARD_FAB2_LIB.BASEBOARD_FAB2(SCH_1):PAGE152

R9G34 RES_0402-0.0,5%,1/16W,CHIP,G21A
     1 H_CPU0_MEMABC_MEMHOT_G_N @BASEBOARD_FAB2_LIB.BASEBOARD_FAB2(SCH_1):H_CPU0_MEMABC_MEMHOT_G_N    I45 @BASEBOARD_FAB2_LIB.BASEBOARD_FAB2(SCH_1):PAGE152
     2 H_CPU0_MEMABC_MEMHOT_G_R_N @BASEBOARD_FAB2_LIB.BASEBOARD_FAB2(SCH_1):H_CPU0_MEMABC_MEMHOT_G_R_N    I45 @BASEBOARD_FAB2_LIB.BASEBOARD_FAB2(SCH_1):PAGE152

R9G35 RES_0402-2.7K,1%,1/16W,CHIP,G2A
     1 P3V3_STBY @BASEBOARD_FAB2_LIB.BASEBOARD_FAB2(SCH_1):P3V3_STBY   I164 @BASEBOARD_FAB2_LIB.BASEBOARD_FAB2(SCH_1):PAGE169
     2 FM_BATTERY_SENSE_EN_N @BASEBOARD_FAB2_LIB.BASEBOARD_FAB2(SCH_1):FM_BATTERY_SENSE_EN_N   I164 @BASEBOARD_FAB2_LIB.BASEBOARD_FAB2(SCH_1):PAGE169

R9L1 RES_0402-1.00K,1%,1/16W,CHIP,GA
     1 M_M_VREF @BASEBOARD_FAB2_LIB.BASEBOARD_FAB2(SCH_1):M_M_VREF    I40 @BASEBOARD_FAB2_LIB.BASEBOARD_FAB2(SCH_1):PAGE100
     2    GND @BASEBOARD_FAB2_LIB.BASEBOARD_FAB2(SCH_1):GND    I40 @BASEBOARD_FAB2_LIB.BASEBOARD_FAB2(SCH_1):PAGE100

R9L2 RES_0402-1.00K,1%,1/16W,CHIP,GA
     1 PVDDQ_KLM @BASEBOARD_FAB2_LIB.BASEBOARD_FAB2(SCH_1):PVDDQ_KLM    I38 @BASEBOARD_FAB2_LIB.BASEBOARD_FAB2(SCH_1):PAGE100
     2 M_M_VREF @BASEBOARD_FAB2_LIB.BASEBOARD_FAB2(SCH_1):M_M_VREF    I38 @BASEBOARD_FAB2_LIB.BASEBOARD_FAB2(SCH_1):PAGE100

R9L3 RES_0402-2,1.0%,1/16W,CHIP,G21A
     1 M_M_CPU_VREF @BASEBOARD_FAB2_LIB.BASEBOARD_FAB2(SCH_1):M_M_CPU_VREF    I45 @BASEBOARD_FAB2_LIB.BASEBOARD_FAB2(SCH_1):PAGE100
     2 M_M_VREF @BASEBOARD_FAB2_LIB.BASEBOARD_FAB2(SCH_1):M_M_VREF    I45 @BASEBOARD_FAB2_LIB.BASEBOARD_FAB2(SCH_1):PAGE100

R9L4 RES_0402-1.0,1%,1/16W,CHIP,G21A
     1 VR_PVDDQ_KLM_PH2_VCIN @BASEBOARD_FAB2_LIB.BASEBOARD_FAB2(SCH_1):VR_PVDDQ_KLM_PH2_VCIN    I76 @BASEBOARD_FAB2_LIB.BASEBOARD_FAB2(SCH_1):PAGE227
     2 P5V_STBY @BASEBOARD_FAB2_LIB.BASEBOARD_FAB2(SCH_1):P5V_STBY    I76 @BASEBOARD_FAB2_LIB.BASEBOARD_FAB2(SCH_1):PAGE227

R9L6 RES_0402-1.00K,1%,1/16W,CHIP,GA
     1 M_L_VREF @BASEBOARD_FAB2_LIB.BASEBOARD_FAB2(SCH_1):M_L_VREF    I24 @BASEBOARD_FAB2_LIB.BASEBOARD_FAB2(SCH_1):PAGE100
     2    GND @BASEBOARD_FAB2_LIB.BASEBOARD_FAB2(SCH_1):GND    I24 @BASEBOARD_FAB2_LIB.BASEBOARD_FAB2(SCH_1):PAGE100

R9L7 RES_0402-1.00K,1%,1/16W,CHIP,GA
     1 PVDDQ_KLM @BASEBOARD_FAB2_LIB.BASEBOARD_FAB2(SCH_1):PVDDQ_KLM    I22 @BASEBOARD_FAB2_LIB.BASEBOARD_FAB2(SCH_1):PAGE100
     2 M_L_VREF @BASEBOARD_FAB2_LIB.BASEBOARD_FAB2(SCH_1):M_L_VREF    I22 @BASEBOARD_FAB2_LIB.BASEBOARD_FAB2(SCH_1):PAGE100

R9L8 RES_0402-2,1.0%,1/16W,CHIP,G21A
     1 M_L_CPU_VREF @BASEBOARD_FAB2_LIB.BASEBOARD_FAB2(SCH_1):M_L_CPU_VREF    I29 @BASEBOARD_FAB2_LIB.BASEBOARD_FAB2(SCH_1):PAGE100
     2 M_L_VREF @BASEBOARD_FAB2_LIB.BASEBOARD_FAB2(SCH_1):M_L_VREF    I29 @BASEBOARD_FAB2_LIB.BASEBOARD_FAB2(SCH_1):PAGE100

R9L9 RES_0402-1.0,1%,1/16W,CHIP,G21A
     1 VR_PVDDQ_KLM_PH1_VCIN @BASEBOARD_FAB2_LIB.BASEBOARD_FAB2(SCH_1):VR_PVDDQ_KLM_PH1_VCIN    I52 @BASEBOARD_FAB2_LIB.BASEBOARD_FAB2(SCH_1):PAGE227
     2 P5V_STBY @BASEBOARD_FAB2_LIB.BASEBOARD_FAB2(SCH_1):P5V_STBY    I52 @BASEBOARD_FAB2_LIB.BASEBOARD_FAB2(SCH_1):PAGE227

R9L11 RES_0402-1.00K,1%,1/16W,CHIP,GA
     1 M_K_VREF @BASEBOARD_FAB2_LIB.BASEBOARD_FAB2(SCH_1):M_K_VREF     I4 @BASEBOARD_FAB2_LIB.BASEBOARD_FAB2(SCH_1):PAGE100
     2    GND @BASEBOARD_FAB2_LIB.BASEBOARD_FAB2(SCH_1):GND     I4 @BASEBOARD_FAB2_LIB.BASEBOARD_FAB2(SCH_1):PAGE100

R9M1 RES_0402-1.00K,1%,1/16W,CHIP,GA
     1 PVDDQ_KLM @BASEBOARD_FAB2_LIB.BASEBOARD_FAB2(SCH_1):PVDDQ_KLM    I11 @BASEBOARD_FAB2_LIB.BASEBOARD_FAB2(SCH_1):PAGE100
     2 M_K_VREF @BASEBOARD_FAB2_LIB.BASEBOARD_FAB2(SCH_1):M_K_VREF    I11 @BASEBOARD_FAB2_LIB.BASEBOARD_FAB2(SCH_1):PAGE100

R9M2 RES_0402-2,1.0%,1/16W,CHIP,G21A
     1 M_K_CPU_VREF @BASEBOARD_FAB2_LIB.BASEBOARD_FAB2(SCH_1):M_K_CPU_VREF    I13 @BASEBOARD_FAB2_LIB.BASEBOARD_FAB2(SCH_1):PAGE100
     2 M_K_VREF @BASEBOARD_FAB2_LIB.BASEBOARD_FAB2(SCH_1):M_K_VREF    I13 @BASEBOARD_FAB2_LIB.BASEBOARD_FAB2(SCH_1):PAGE100

R9M3 RES_0402-0.0,5%,1/16W,CHIP,G21A
     1 P3V3_STBY @BASEBOARD_FAB2_LIB.BASEBOARD_FAB2(SCH_1):P3V3_STBY    I30 @BASEBOARD_FAB2_LIB.BASEBOARD_FAB2(SCH_1):PAGE226
     2 VR_PVDDQ_KLM_VDD @BASEBOARD_FAB2_LIB.BASEBOARD_FAB2(SCH_1):VR_PVDDQ_KLM_VDD    I30 @BASEBOARD_FAB2_LIB.BASEBOARD_FAB2(SCH_1):PAGE226

R9M4 RES_1206-0.002,1%,1W,CHIP,G521A
     1 P12V_NVDIMM_KLM @BASEBOARD_FAB2_LIB.BASEBOARD_FAB2(SCH_1):P12V_NVDIMM_KLM   I142 @BASEBOARD_FAB2_LIB.BASEBOARD_FAB2(SCH_1):PAGE197
     2 P12V_STBY @BASEBOARD_FAB2_LIB.BASEBOARD_FAB2(SCH_1):P12V_STBY   I142 @BASEBOARD_FAB2_LIB.BASEBOARD_FAB2(SCH_1):PAGE197

R9M5 RES_0402-100.0K,1%,1/16W,EMPTYA
     1 P3V3_STBY @BASEBOARD_FAB2_LIB.BASEBOARD_FAB2(SCH_1):P3V3_STBY    I85 @BASEBOARD_FAB2_LIB.BASEBOARD_FAB2(SCH_1):PAGE226
     2 VR_PVDDQ_KLM_VREN @BASEBOARD_FAB2_LIB.BASEBOARD_FAB2(SCH_1):VR_PVDDQ_KLM_VREN    I85 @BASEBOARD_FAB2_LIB.BASEBOARD_FAB2(SCH_1):PAGE226

R9M6 RES_0402-49.9,1%,1/16W,CHIP,G2A
     1 PVCCIO_CPU1 @BASEBOARD_FAB2_LIB.BASEBOARD_FAB2(SCH_1):PVCCIO_CPU1    I50 @BASEBOARD_FAB2_LIB.BASEBOARD_FAB2(SCH_1):PAGE226
     2 SVID_CLK1_CPU1_R @BASEBOARD_FAB2_LIB.BASEBOARD_FAB2(SCH_1):SVID_CLK1_CPU1_R    I50 @BASEBOARD_FAB2_LIB.BASEBOARD_FAB2(SCH_1):PAGE226

R9M7 RES_0402-100.0,1%,1/16W,EMPTY,A
     1 PVCCIO_CPU1 @BASEBOARD_FAB2_LIB.BASEBOARD_FAB2(SCH_1):PVCCIO_CPU1     I8 @BASEBOARD_FAB2_LIB.BASEBOARD_FAB2(SCH_1):PAGE226
     2 SVID_DIO1_CPU1_R @BASEBOARD_FAB2_LIB.BASEBOARD_FAB2(SCH_1):SVID_DIO1_CPU1_R     I8 @BASEBOARD_FAB2_LIB.BASEBOARD_FAB2(SCH_1):PAGE226

R9M8 RES_0402-100.0K,1%,1/16W,CHIP,B
     1 VR_FET_SW_P12V_STBY_PVDDQ_KLM @BASEBOARD_FAB2_LIB.BASEBOARD_FAB2(SCH_1):VR_FET_SW_P12V_STBY_PVDDQ_KLM    I57 @BASEBOARD_FAB2_LIB.BASEBOARD_FAB2(SCH_1):PAGE226
     2 VR_PVDDQ_KLM_VINSEN @BASEBOARD_FAB2_LIB.BASEBOARD_FAB2(SCH_1):VR_PVDDQ_KLM_VINSEN    I57 @BASEBOARD_FAB2_LIB.BASEBOARD_FAB2(SCH_1):PAGE226

R9M9 RES_0402-0.0,5%,1/16W,CHIP,G21A
     1 FM_PVDDQ_KLM_EN @BASEBOARD_FAB2_LIB.BASEBOARD_FAB2(SCH_1):FM_PVDDQ_KLM_EN    I84 @BASEBOARD_FAB2_LIB.BASEBOARD_FAB2(SCH_1):PAGE226
     2 VR_PVDDQ_KLM_VREN @BASEBOARD_FAB2_LIB.BASEBOARD_FAB2(SCH_1):VR_PVDDQ_KLM_VREN    I84 @BASEBOARD_FAB2_LIB.BASEBOARD_FAB2(SCH_1):PAGE226

R9M10 RES_0402-0.0,5%,1/16W,CHIP,G21A
     1 VR_PVDDQ_KLM_VD12 @BASEBOARD_FAB2_LIB.BASEBOARD_FAB2(SCH_1):VR_PVDDQ_KLM_VD12    I88 @BASEBOARD_FAB2_LIB.BASEBOARD_FAB2(SCH_1):PAGE226
     2 VR_PVDDQ_KLM_AIREF2 @BASEBOARD_FAB2_LIB.BASEBOARD_FAB2(SCH_1):VR_PVDDQ_KLM_AIREF2    I88 @BASEBOARD_FAB2_LIB.BASEBOARD_FAB2(SCH_1):PAGE226

R9M11 RES_0402-0.0,5%,1/16W,CHIP,G21A
     1 VR_PVDDQ_KLM_VD12 @BASEBOARD_FAB2_LIB.BASEBOARD_FAB2(SCH_1):VR_PVDDQ_KLM_VD12    I87 @BASEBOARD_FAB2_LIB.BASEBOARD_FAB2(SCH_1):PAGE226
     2 VR_PVDDQ_KLM_AIREF1 @BASEBOARD_FAB2_LIB.BASEBOARD_FAB2(SCH_1):VR_PVDDQ_KLM_AIREF1    I87 @BASEBOARD_FAB2_LIB.BASEBOARD_FAB2(SCH_1):PAGE226

R9M12 RES_0402-20.0,1%,1/16W,CHIP,G2A
     1 SMB_PEHPCPU1_STBY_LVC3_R_SDA @BASEBOARD_FAB2_LIB.BASEBOARD_FAB2(SCH_1):SMB_PEHPCPU1_STBY_LVC3_R_SDA    I24 @BASEBOARD_FAB2_LIB.BASEBOARD_FAB2(SCH_1):PAGE163
     2 SMB_SLOTX24_BMC_STBY_LVC3_SDA @BASEBOARD_FAB2_LIB.BASEBOARD_FAB2(SCH_1):SMB_SLOTX24_BMC_STBY_LVC3_SDA    I24 @BASEBOARD_FAB2_LIB.BASEBOARD_FAB2(SCH_1):PAGE163

R9M13 RES_0402-20.0,1%,1/16W,CHIP,G2A
     1 SMB_PEHPCPU1_STBY_LVC3_R_SDA @BASEBOARD_FAB2_LIB.BASEBOARD_FAB2(SCH_1):SMB_PEHPCPU1_STBY_LVC3_R_SDA    I21 @BASEBOARD_FAB2_LIB.BASEBOARD_FAB2(SCH_1):PAGE163
     2 SMB_PEHPCPU1_STBY_LVC3_SDA @BASEBOARD_FAB2_LIB.BASEBOARD_FAB2(SCH_1):SMB_PEHPCPU1_STBY_LVC3_SDA    I21 @BASEBOARD_FAB2_LIB.BASEBOARD_FAB2(SCH_1):PAGE163

R9M14 RES_0402-20.0,1%,1/16W,CHIP,G2A
     1 SMB_PEHPCPU1_STBY_LVC3_R_SCL @BASEBOARD_FAB2_LIB.BASEBOARD_FAB2(SCH_1):SMB_PEHPCPU1_STBY_LVC3_R_SCL    I20 @BASEBOARD_FAB2_LIB.BASEBOARD_FAB2(SCH_1):PAGE163
     2 SMB_PEHPCPU1_STBY_LVC3_SCL @BASEBOARD_FAB2_LIB.BASEBOARD_FAB2(SCH_1):SMB_PEHPCPU1_STBY_LVC3_SCL    I20 @BASEBOARD_FAB2_LIB.BASEBOARD_FAB2(SCH_1):PAGE163

R9M15 RES_0402-20.0,1%,1/16W,CHIP,G2A
     1 SMB_PEHPCPU1_STBY_LVC3_R_SCL @BASEBOARD_FAB2_LIB.BASEBOARD_FAB2(SCH_1):SMB_PEHPCPU1_STBY_LVC3_R_SCL    I25 @BASEBOARD_FAB2_LIB.BASEBOARD_FAB2(SCH_1):PAGE163
     2 SMB_SLOTX24_BMC_STBY_LVC3_SCL @BASEBOARD_FAB2_LIB.BASEBOARD_FAB2(SCH_1):SMB_SLOTX24_BMC_STBY_LVC3_SCL    I25 @BASEBOARD_FAB2_LIB.BASEBOARD_FAB2(SCH_1):PAGE163

R9M16 RES_0402-2.0K,1%,1/16W,CHIP,G2A
     1 P3V3_STBY @BASEBOARD_FAB2_LIB.BASEBOARD_FAB2(SCH_1):P3V3_STBY    I16 @BASEBOARD_FAB2_LIB.BASEBOARD_FAB2(SCH_1):PAGE163
     2 SMB_PEHPCPU1_STBY_LVC3_R_SDA @BASEBOARD_FAB2_LIB.BASEBOARD_FAB2(SCH_1):SMB_PEHPCPU1_STBY_LVC3_R_SDA    I16 @BASEBOARD_FAB2_LIB.BASEBOARD_FAB2(SCH_1):PAGE163

R9M17 RES_0402-2.0K,1%,1/16W,CHIP,G2A
     1 P3V3_STBY @BASEBOARD_FAB2_LIB.BASEBOARD_FAB2(SCH_1):P3V3_STBY    I15 @BASEBOARD_FAB2_LIB.BASEBOARD_FAB2(SCH_1):PAGE163
     2 SMB_PEHPCPU1_STBY_LVC3_R_SCL @BASEBOARD_FAB2_LIB.BASEBOARD_FAB2(SCH_1):SMB_PEHPCPU1_STBY_LVC3_R_SCL    I15 @BASEBOARD_FAB2_LIB.BASEBOARD_FAB2(SCH_1):PAGE163

R9M18 RES_0402-240,1.0%,1/16W,CHIP,GA
     1 PVCCIO_CPU1 @BASEBOARD_FAB2_LIB.BASEBOARD_FAB2(SCH_1):PVCCIO_CPU1     I6 @BASEBOARD_FAB2_LIB.BASEBOARD_FAB2(SCH_1):PAGE163
     2 SMB_CPU1_PE_HP_GTL_R_SDA @BASEBOARD_FAB2_LIB.BASEBOARD_FAB2(SCH_1):SMB_CPU1_PE_HP_GTL_R_SDA     I6 @BASEBOARD_FAB2_LIB.BASEBOARD_FAB2(SCH_1):PAGE163

R9M19 RES_0402-240,1.0%,1/16W,CHIP,GA
     1 PVCCIO_CPU1 @BASEBOARD_FAB2_LIB.BASEBOARD_FAB2(SCH_1):PVCCIO_CPU1     I7 @BASEBOARD_FAB2_LIB.BASEBOARD_FAB2(SCH_1):PAGE163
     2 SMB_CPU1_PE_HP_GTL_R_SCL @BASEBOARD_FAB2_LIB.BASEBOARD_FAB2(SCH_1):SMB_CPU1_PE_HP_GTL_R_SCL     I7 @BASEBOARD_FAB2_LIB.BASEBOARD_FAB2(SCH_1):PAGE163

R9M20 RES_0402-0.0,5%,1/16W,CHIP,G21A
     1 SMB_LAN_STBY_LVC3_SCL @BASEBOARD_FAB2_LIB.BASEBOARD_FAB2(SCH_1):SMB_LAN_STBY_LVC3_SCL   I323 @BASEBOARD_FAB2_LIB.BASEBOARD_FAB2(SCH_1):PAGE156
     2 SMB_PIROM_CPU1_SCL @BASEBOARD_FAB2_LIB.BASEBOARD_FAB2(SCH_1):SMB_PIROM_CPU1_SCL   I323 @BASEBOARD_FAB2_LIB.BASEBOARD_FAB2(SCH_1):PAGE156

R9M21 RES_0402-0.0,5%,1/16W,CHIP,G21A
     1 SMB_LAN_STBY_LVC3_SDA @BASEBOARD_FAB2_LIB.BASEBOARD_FAB2(SCH_1):SMB_LAN_STBY_LVC3_SDA   I321 @BASEBOARD_FAB2_LIB.BASEBOARD_FAB2(SCH_1):PAGE156
     2 SMB_PIROM_CPU1_SDA @BASEBOARD_FAB2_LIB.BASEBOARD_FAB2(SCH_1):SMB_PIROM_CPU1_SDA   I321 @BASEBOARD_FAB2_LIB.BASEBOARD_FAB2(SCH_1):PAGE156

R9N1 RES_0402-49.9,1%,1/16W,CHIP,G2A
     1 PVCCIO_CPU1 @BASEBOARD_FAB2_LIB.BASEBOARD_FAB2(SCH_1):PVCCIO_CPU1     I4 @BASEBOARD_FAB2_LIB.BASEBOARD_FAB2(SCH_1):PAGE55
     2 SVID_ALERT1_CPU1_R_N @BASEBOARD_FAB2_LIB.BASEBOARD_FAB2(SCH_1):SVID_ALERT1_CPU1_R_N     I4 @BASEBOARD_FAB2_LIB.BASEBOARD_FAB2(SCH_1):PAGE55

R9N2 RES_0402-100.0,1%,1/16W,CHIP,GA
     1 PVCCIO_CPU1 @BASEBOARD_FAB2_LIB.BASEBOARD_FAB2(SCH_1):PVCCIO_CPU1     I7 @BASEBOARD_FAB2_LIB.BASEBOARD_FAB2(SCH_1):PAGE55
     2 SVID_DIO1_CPU1_R @BASEBOARD_FAB2_LIB.BASEBOARD_FAB2(SCH_1):SVID_DIO1_CPU1_R     I7 @BASEBOARD_FAB2_LIB.BASEBOARD_FAB2(SCH_1):PAGE55

R9N3 RES_0402-1.0,1%,1/16W,CHIP,G21A
     1 VR_PVSA_CPU1_VCIN @BASEBOARD_FAB2_LIB.BASEBOARD_FAB2(SCH_1):VR_PVSA_CPU1_VCIN    I20 @BASEBOARD_FAB2_LIB.BASEBOARD_FAB2(SCH_1):PAGE210
     2 P5V_STBY @BASEBOARD_FAB2_LIB.BASEBOARD_FAB2(SCH_1):P5V_STBY    I20 @BASEBOARD_FAB2_LIB.BASEBOARD_FAB2(SCH_1):PAGE210

R9N4 RES_0402-51.1,1.0%,1/16W,CHIP,A
     1 PVSA_CPU1 @BASEBOARD_FAB2_LIB.BASEBOARD_FAB2(SCH_1):PVSA_CPU1    I45 @BASEBOARD_FAB2_LIB.BASEBOARD_FAB2(SCH_1):PAGE210
     2    GND @BASEBOARD_FAB2_LIB.BASEBOARD_FAB2(SCH_1):GND    I45 @BASEBOARD_FAB2_LIB.BASEBOARD_FAB2(SCH_1):PAGE210

R9N5 RES_0402-0.0,5%,1/16W,CHIP,G21A
     1 VR_PVCCIN_CPU1_VD12 @BASEBOARD_FAB2_LIB.BASEBOARD_FAB2(SCH_1):VR_PVCCIN_CPU1_VD12   I128 @BASEBOARD_FAB2_LIB.BASEBOARD_FAB2(SCH_1):PAGE206
     2 VR_PVSA_CPU1_BIREF1 @BASEBOARD_FAB2_LIB.BASEBOARD_FAB2(SCH_1):VR_PVSA_CPU1_BIREF1   I128 @BASEBOARD_FAB2_LIB.BASEBOARD_FAB2(SCH_1):PAGE206

R9N7 RES_0402-3.16K,1%,1/16W,CHIP,GA
     1 VR_PVCCIN_CPU1_XADDR2 @BASEBOARD_FAB2_LIB.BASEBOARD_FAB2(SCH_1):VR_PVCCIN_CPU1_XADDR2   I111 @BASEBOARD_FAB2_LIB.BASEBOARD_FAB2(SCH_1):PAGE206
     2    GND @BASEBOARD_FAB2_LIB.BASEBOARD_FAB2(SCH_1):GND   I111 @BASEBOARD_FAB2_LIB.BASEBOARD_FAB2(SCH_1):PAGE206

R9N8 RES_0402-4.02K,1%,1/16W,CHIP,GA
     1 VR_PVCCIN_CPU1_XADDR1 @BASEBOARD_FAB2_LIB.BASEBOARD_FAB2(SCH_1):VR_PVCCIN_CPU1_XADDR1   I112 @BASEBOARD_FAB2_LIB.BASEBOARD_FAB2(SCH_1):PAGE206
     2    GND @BASEBOARD_FAB2_LIB.BASEBOARD_FAB2(SCH_1):GND   I112 @BASEBOARD_FAB2_LIB.BASEBOARD_FAB2(SCH_1):PAGE206

R9N9 RES_0402-0.0,5%,1/16W,CHIP,G21A
     1 VR_PVCCIN_CPU1_VD12 @BASEBOARD_FAB2_LIB.BASEBOARD_FAB2(SCH_1):VR_PVCCIN_CPU1_VD12   I126 @BASEBOARD_FAB2_LIB.BASEBOARD_FAB2(SCH_1):PAGE206
     2 VR_PVCCIN_CPU1_AIREF5 @BASEBOARD_FAB2_LIB.BASEBOARD_FAB2(SCH_1):VR_PVCCIN_CPU1_AIREF5   I126 @BASEBOARD_FAB2_LIB.BASEBOARD_FAB2(SCH_1):PAGE206

R9N10 RES_0402-0.0,5%,1/16W,CHIP,G21A
     1 VR_PVCCIN_CPU1_VD12 @BASEBOARD_FAB2_LIB.BASEBOARD_FAB2(SCH_1):VR_PVCCIN_CPU1_VD12   I125 @BASEBOARD_FAB2_LIB.BASEBOARD_FAB2(SCH_1):PAGE206
     2 VR_PVCCIN_CPU1_AIREF4 @BASEBOARD_FAB2_LIB.BASEBOARD_FAB2(SCH_1):VR_PVCCIN_CPU1_AIREF4   I125 @BASEBOARD_FAB2_LIB.BASEBOARD_FAB2(SCH_1):PAGE206

R9N12 RES_0402-0.0,5%,1/16W,CHIP,G21A
     1 VR_PVCCIN_CPU1_VD12 @BASEBOARD_FAB2_LIB.BASEBOARD_FAB2(SCH_1):VR_PVCCIN_CPU1_VD12   I124 @BASEBOARD_FAB2_LIB.BASEBOARD_FAB2(SCH_1):PAGE206
     2 VR_PVCCIN_CPU1_AIREF3 @BASEBOARD_FAB2_LIB.BASEBOARD_FAB2(SCH_1):VR_PVCCIN_CPU1_AIREF3   I124 @BASEBOARD_FAB2_LIB.BASEBOARD_FAB2(SCH_1):PAGE206

R9N14 RES_0402-1.00K,1%,1/16W,CHIP,GA
     1 PVCCIO_CPU1 @BASEBOARD_FAB2_LIB.BASEBOARD_FAB2(SCH_1):PVCCIO_CPU1   I120 @BASEBOARD_FAB2_LIB.BASEBOARD_FAB2(SCH_1):PAGE206
     2 VR_PVCCIN_CPU1_VREN @BASEBOARD_FAB2_LIB.BASEBOARD_FAB2(SCH_1):VR_PVCCIN_CPU1_VREN   I120 @BASEBOARD_FAB2_LIB.BASEBOARD_FAB2(SCH_1):PAGE206

R9N15 RES_0402-0.0,5%,1/16W,CHIP,G21A
     1 VR_PVCCIN_CPU1_VD12 @BASEBOARD_FAB2_LIB.BASEBOARD_FAB2(SCH_1):VR_PVCCIN_CPU1_VD12   I122 @BASEBOARD_FAB2_LIB.BASEBOARD_FAB2(SCH_1):PAGE206
     2 VR_PVCCIN_CPU1_AIREF1 @BASEBOARD_FAB2_LIB.BASEBOARD_FAB2(SCH_1):VR_PVCCIN_CPU1_AIREF1   I122 @BASEBOARD_FAB2_LIB.BASEBOARD_FAB2(SCH_1):PAGE206

R9N16 RES_0402-0.0,5%,1/16W,CHIP,G21A
     1 FM_PVCCIN_PVCCSA_CPU1_EN_LVC1 @BASEBOARD_FAB2_LIB.BASEBOARD_FAB2(SCH_1):FM_PVCCIN_PVCCSA_CPU1_EN_LVC1   I119 @BASEBOARD_FAB2_LIB.BASEBOARD_FAB2(SCH_1):PAGE206
     2 VR_PVCCIN_CPU1_VREN @BASEBOARD_FAB2_LIB.BASEBOARD_FAB2(SCH_1):VR_PVCCIN_CPU1_VREN   I119 @BASEBOARD_FAB2_LIB.BASEBOARD_FAB2(SCH_1):PAGE206

R9N17 RES_0402-0.0,5%,1/16W,CHIP,G21A
     1 VR_PVCCIN_CPU1_VD12 @BASEBOARD_FAB2_LIB.BASEBOARD_FAB2(SCH_1):VR_PVCCIN_CPU1_VD12   I123 @BASEBOARD_FAB2_LIB.BASEBOARD_FAB2(SCH_1):PAGE206
     2 VR_PVCCIN_CPU1_AIREF2 @BASEBOARD_FAB2_LIB.BASEBOARD_FAB2(SCH_1):VR_PVCCIN_CPU1_AIREF2   I123 @BASEBOARD_FAB2_LIB.BASEBOARD_FAB2(SCH_1):PAGE206

R9P1 RES_0402-100.0,1%,1/16W,CHIP,GA
     1 PVCCIO_CPU1 @BASEBOARD_FAB2_LIB.BASEBOARD_FAB2(SCH_1):PVCCIO_CPU1     I4 @BASEBOARD_FAB2_LIB.BASEBOARD_FAB2(SCH_1):PAGE206
     2 SVID_DIO0_CPU1_R @BASEBOARD_FAB2_LIB.BASEBOARD_FAB2(SCH_1):SVID_DIO0_CPU1_R     I4 @BASEBOARD_FAB2_LIB.BASEBOARD_FAB2(SCH_1):PAGE206

R9P2 RES_0402-49.9,1%,1/16W,CHIP,G2A
     1 PVCCIO_CPU1 @BASEBOARD_FAB2_LIB.BASEBOARD_FAB2(SCH_1):PVCCIO_CPU1    I53 @BASEBOARD_FAB2_LIB.BASEBOARD_FAB2(SCH_1):PAGE206
     2 SVID_CLK0_CPU1_R @BASEBOARD_FAB2_LIB.BASEBOARD_FAB2(SCH_1):SVID_CLK0_CPU1_R    I53 @BASEBOARD_FAB2_LIB.BASEBOARD_FAB2(SCH_1):PAGE206

R9P3 RES_0402-33.2,1%,1/16W,CHIP,G2A
     1 IRQ_PVCCIN_CPU1_VRHOT_LVC3_R_N @BASEBOARD_FAB2_LIB.BASEBOARD_FAB2(SCH_1):IRQ_PVCCIN_CPU1_VRHOT_LVC3_R_N   I117 @BASEBOARD_FAB2_LIB.BASEBOARD_FAB2(SCH_1):PAGE206
     2 IRQ_PVCCIN_CPU1_VRHOT_LVC3_N @BASEBOARD_FAB2_LIB.BASEBOARD_FAB2(SCH_1):IRQ_PVCCIN_CPU1_VRHOT_LVC3_N   I117 @BASEBOARD_FAB2_LIB.BASEBOARD_FAB2(SCH_1):PAGE206

R9P4 RES_0402-2.7K,1%,1/16W,CHIP,G2A
     1 P3V3_STBY @BASEBOARD_FAB2_LIB.BASEBOARD_FAB2(SCH_1):P3V3_STBY   I210 @BASEBOARD_FAB2_LIB.BASEBOARD_FAB2(SCH_1):PAGE200
     2 IRQ_UV_DETECT_N @BASEBOARD_FAB2_LIB.BASEBOARD_FAB2(SCH_1):IRQ_UV_DETECT_N   I210 @BASEBOARD_FAB2_LIB.BASEBOARD_FAB2(SCH_1):PAGE200

R9P5 RES_0402-10.0K,1%,1/16W,CHIP,GA
     1 P3V3_STBY @BASEBOARD_FAB2_LIB.BASEBOARD_FAB2(SCH_1):P3V3_STBY   I215 @BASEBOARD_FAB2_LIB.BASEBOARD_FAB2(SCH_1):PAGE200
     2 FM_DISABLE_FAN_N @BASEBOARD_FAB2_LIB.BASEBOARD_FAB2(SCH_1):FM_DISABLE_FAN_N   I215 @BASEBOARD_FAB2_LIB.BASEBOARD_FAB2(SCH_1):PAGE200

R9P6 RES_0402-10.0K,1%,1/16W,CHIP,GA
     1 P3V3_STBY @BASEBOARD_FAB2_LIB.BASEBOARD_FAB2(SCH_1):P3V3_STBY   I149 @BASEBOARD_FAB2_LIB.BASEBOARD_FAB2(SCH_1):PAGE200
     2 FM_UV_ADR_TRIGGER_N @BASEBOARD_FAB2_LIB.BASEBOARD_FAB2(SCH_1):FM_UV_ADR_TRIGGER_N   I149 @BASEBOARD_FAB2_LIB.BASEBOARD_FAB2(SCH_1):PAGE200

R9P7 RES_0402-249K,1.0%,1/16W,CHIP,A
     1 P12V_STBY @BASEBOARD_FAB2_LIB.BASEBOARD_FAB2(SCH_1):P12V_STBY   I145 @BASEBOARD_FAB2_LIB.BASEBOARD_FAB2(SCH_1):PAGE200
     2 A_P12V_STBY_ADR_TRIGGER @BASEBOARD_FAB2_LIB.BASEBOARD_FAB2(SCH_1):A_P12V_STBY_ADR_TRIGGER   I145 @BASEBOARD_FAB2_LIB.BASEBOARD_FAB2(SCH_1):PAGE200

R9P8 RES_0402-1.0,1%,1/16W,CHIP,G21A
     1 VR_PVCCIN_CPU1_PH4_VCIN @BASEBOARD_FAB2_LIB.BASEBOARD_FAB2(SCH_1):VR_PVCCIN_CPU1_PH4_VCIN    I49 @BASEBOARD_FAB2_LIB.BASEBOARD_FAB2(SCH_1):PAGE208
     2 P5V_STBY @BASEBOARD_FAB2_LIB.BASEBOARD_FAB2(SCH_1):P5V_STBY    I49 @BASEBOARD_FAB2_LIB.BASEBOARD_FAB2(SCH_1):PAGE208

R9P9 RES_0402-10.0K,1%,1/16W,CHIP,GA
     1 A_P12V_STBY_ADR_TRIGGER @BASEBOARD_FAB2_LIB.BASEBOARD_FAB2(SCH_1):A_P12V_STBY_ADR_TRIGGER   I146 @BASEBOARD_FAB2_LIB.BASEBOARD_FAB2(SCH_1):PAGE200
     2 AGND_HSC @BASEBOARD_FAB2_LIB.BASEBOARD_FAB2(SCH_1):AGND_HSC   I146 @BASEBOARD_FAB2_LIB.BASEBOARD_FAB2(SCH_1):PAGE200

R9P10 RES_0402-10.0K,1%,1/16W,CHIP,GA
     1 P3V3_STBY @BASEBOARD_FAB2_LIB.BASEBOARD_FAB2(SCH_1):P3V3_STBY   I192 @BASEBOARD_FAB2_LIB.BASEBOARD_FAB2(SCH_1):PAGE200
     2 A_P12V_STBY_FPH_GATE @BASEBOARD_FAB2_LIB.BASEBOARD_FAB2(SCH_1):A_P12V_STBY_FPH_GATE   I192 @BASEBOARD_FAB2_LIB.BASEBOARD_FAB2(SCH_1):PAGE200

R9P11 RES_0402-10.0K,1%,1/16W,CHIP,GA
     1 A_P12V_STBY_FP_TRIGGER @BASEBOARD_FAB2_LIB.BASEBOARD_FAB2(SCH_1):A_P12V_STBY_FP_TRIGGER   I108 @BASEBOARD_FAB2_LIB.BASEBOARD_FAB2(SCH_1):PAGE200
     2 AGND_HSC @BASEBOARD_FAB2_LIB.BASEBOARD_FAB2(SCH_1):AGND_HSC   I108 @BASEBOARD_FAB2_LIB.BASEBOARD_FAB2(SCH_1):PAGE200

R9P12 RES_0402-4.99K,1%,1/16W,CHIP,GA
     1 A_HSC_INAP @BASEBOARD_FAB2_LIB.BASEBOARD_FAB2(SCH_1):A_HSC_INAP   I218 @BASEBOARD_FAB2_LIB.BASEBOARD_FAB2(SCH_1):PAGE200
     2 AGND_HSC @BASEBOARD_FAB2_LIB.BASEBOARD_FAB2(SCH_1):AGND_HSC   I218 @BASEBOARD_FAB2_LIB.BASEBOARD_FAB2(SCH_1):PAGE200

R9P13 RES_0402-274K,1.0%,1/16W,CHIP,A
     1 P12V_STBY @BASEBOARD_FAB2_LIB.BASEBOARD_FAB2(SCH_1):P12V_STBY   I107 @BASEBOARD_FAB2_LIB.BASEBOARD_FAB2(SCH_1):PAGE200
     2 A_P12V_STBY_FP_TRIGGER @BASEBOARD_FAB2_LIB.BASEBOARD_FAB2(SCH_1):A_P12V_STBY_FP_TRIGGER   I107 @BASEBOARD_FAB2_LIB.BASEBOARD_FAB2(SCH_1):PAGE200

R9P15 RES_0402-0.0,5%,1/16W,EMPTY,G2A
     1 A_HSC_LOW_DRAIN @BASEBOARD_FAB2_LIB.BASEBOARD_FAB2(SCH_1):A_HSC_LOW_DRAIN   I198 @BASEBOARD_FAB2_LIB.BASEBOARD_FAB2(SCH_1):PAGE200
     2 IRQ_OC_DETECT_N @BASEBOARD_FAB2_LIB.BASEBOARD_FAB2(SCH_1):IRQ_OC_DETECT_N   I198 @BASEBOARD_FAB2_LIB.BASEBOARD_FAB2(SCH_1):PAGE200

R9P16 RES_0402-0.0,5%,1/16W,CHIP,G21A
     1 FM_P12V_HSC_ADR2 @BASEBOARD_FAB2_LIB.BASEBOARD_FAB2(SCH_1):FM_P12V_HSC_ADR2    I36 @BASEBOARD_FAB2_LIB.BASEBOARD_FAB2(SCH_1):PAGE199
     2 AGND_HSC @BASEBOARD_FAB2_LIB.BASEBOARD_FAB2(SCH_1):AGND_HSC    I36 @BASEBOARD_FAB2_LIB.BASEBOARD_FAB2(SCH_1):PAGE199

R9P17 RES_0402-150.0K,1%,1/16W,CHIP,A
     1 FM_P12V_HSC_ADR1 @BASEBOARD_FAB2_LIB.BASEBOARD_FAB2(SCH_1):FM_P12V_HSC_ADR1    I33 @BASEBOARD_FAB2_LIB.BASEBOARD_FAB2(SCH_1):PAGE199
     2 AGND_HSC @BASEBOARD_FAB2_LIB.BASEBOARD_FAB2(SCH_1):AGND_HSC    I33 @BASEBOARD_FAB2_LIB.BASEBOARD_FAB2(SCH_1):PAGE199

R9P18 RES_0402-15.0K,1%,1/16W,CHIP,GA
     1 P12V_STBY @BASEBOARD_FAB2_LIB.BASEBOARD_FAB2(SCH_1):P12V_STBY    I41 @BASEBOARD_FAB2_LIB.BASEBOARD_FAB2(SCH_1):PAGE199
     2 PWRGD_P12V_R @BASEBOARD_FAB2_LIB.BASEBOARD_FAB2(SCH_1):PWRGD_P12V_R    I41 @BASEBOARD_FAB2_LIB.BASEBOARD_FAB2(SCH_1):PAGE199

R9P19 RES_0402-10.0K,1%,1/16W,EMPTY,A
     1 A_HSC_TIMER_R @BASEBOARD_FAB2_LIB.BASEBOARD_FAB2(SCH_1):A_HSC_TIMER_R    I70 @BASEBOARD_FAB2_LIB.BASEBOARD_FAB2(SCH_1):PAGE200
     2 AGND_HSC @BASEBOARD_FAB2_LIB.BASEBOARD_FAB2(SCH_1):AGND_HSC    I70 @BASEBOARD_FAB2_LIB.BASEBOARD_FAB2(SCH_1):PAGE200

R9P20 RES_0402-2.7K,1%,1/16W,CHIP,G2A
     1 P3V3_STBY @BASEBOARD_FAB2_LIB.BASEBOARD_FAB2(SCH_1):P3V3_STBY    I86 @BASEBOARD_FAB2_LIB.BASEBOARD_FAB2(SCH_1):PAGE200
     2 FM_HSC_TIMER_EXP_N @BASEBOARD_FAB2_LIB.BASEBOARD_FAB2(SCH_1):FM_HSC_TIMER_EXP_N    I86 @BASEBOARD_FAB2_LIB.BASEBOARD_FAB2(SCH_1):PAGE200

R9P21 RES_0402-0.0,5%,1/16W,CHIP,G21A
     1 A_HSC_TIMER @BASEBOARD_FAB2_LIB.BASEBOARD_FAB2(SCH_1):A_HSC_TIMER    I71 @BASEBOARD_FAB2_LIB.BASEBOARD_FAB2(SCH_1):PAGE200
     2 A_HSC_TIMER_R @BASEBOARD_FAB2_LIB.BASEBOARD_FAB2(SCH_1):A_HSC_TIMER_R    I71 @BASEBOARD_FAB2_LIB.BASEBOARD_FAB2(SCH_1):PAGE200

R9P22 RES_0402-1.0,1%,1/16W,CHIP,G21A
     1 VR_PVCCIN_CPU1_PH3_VCIN @BASEBOARD_FAB2_LIB.BASEBOARD_FAB2(SCH_1):VR_PVCCIN_CPU1_PH3_VCIN    I36 @BASEBOARD_FAB2_LIB.BASEBOARD_FAB2(SCH_1):PAGE208
     2 P5V_STBY @BASEBOARD_FAB2_LIB.BASEBOARD_FAB2(SCH_1):P5V_STBY    I36 @BASEBOARD_FAB2_LIB.BASEBOARD_FAB2(SCH_1):PAGE208

R9P23 RES_0402-100.0K,1%,1/16W,CHIP,A
     1 P12V_STBY @BASEBOARD_FAB2_LIB.BASEBOARD_FAB2(SCH_1):P12V_STBY    I54 @BASEBOARD_FAB2_LIB.BASEBOARD_FAB2(SCH_1):PAGE199
     2 A_HSC_PWGIN @BASEBOARD_FAB2_LIB.BASEBOARD_FAB2(SCH_1):A_HSC_PWGIN    I54 @BASEBOARD_FAB2_LIB.BASEBOARD_FAB2(SCH_1):PAGE199

R9P24 RES_0402-12.1K,1%,1/16W,CHIP,GA
     1 A_HSC_PWGIN @BASEBOARD_FAB2_LIB.BASEBOARD_FAB2(SCH_1):A_HSC_PWGIN    I55 @BASEBOARD_FAB2_LIB.BASEBOARD_FAB2(SCH_1):PAGE199
     2 AGND_HSC @BASEBOARD_FAB2_LIB.BASEBOARD_FAB2(SCH_1):AGND_HSC    I55 @BASEBOARD_FAB2_LIB.BASEBOARD_FAB2(SCH_1):PAGE199

R9P26 RES_0402-10.0,1%,1/16W,CHIP,G2A
     1 P12V_HSC_SENN1 @BASEBOARD_FAB2_LIB.BASEBOARD_FAB2(SCH_1):P12V_HSC_SENN1    I51 @BASEBOARD_FAB2_LIB.BASEBOARD_FAB2(SCH_1):PAGE200
     2 A_HSC_HSN @BASEBOARD_FAB2_LIB.BASEBOARD_FAB2(SCH_1):A_HSC_HSN    I51 @BASEBOARD_FAB2_LIB.BASEBOARD_FAB2(SCH_1):PAGE200

R9P27 RES_0402-10.0,1%,1/16W,CHIP,G2A
     1 P12V_HSC_SENP1 @BASEBOARD_FAB2_LIB.BASEBOARD_FAB2(SCH_1):P12V_HSC_SENP1    I47 @BASEBOARD_FAB2_LIB.BASEBOARD_FAB2(SCH_1):PAGE200
     2 A_HSC_HSP @BASEBOARD_FAB2_LIB.BASEBOARD_FAB2(SCH_1):A_HSC_HSP    I47 @BASEBOARD_FAB2_LIB.BASEBOARD_FAB2(SCH_1):PAGE200

R9P28 RES_0402-100.0K,1%,1/16W,CHIP,A
     1 P12V_PSU @BASEBOARD_FAB2_LIB.BASEBOARD_FAB2(SCH_1):P12V_PSU     I6 @BASEBOARD_FAB2_LIB.BASEBOARD_FAB2(SCH_1):PAGE199
     2 A_HSC_OV @BASEBOARD_FAB2_LIB.BASEBOARD_FAB2(SCH_1):A_HSC_OV     I6 @BASEBOARD_FAB2_LIB.BASEBOARD_FAB2(SCH_1):PAGE199

R9P29 RES_0402-100.0K,1%,1/16W,CHIP,A
     1 P12V_PSU @BASEBOARD_FAB2_LIB.BASEBOARD_FAB2(SCH_1):P12V_PSU    I12 @BASEBOARD_FAB2_LIB.BASEBOARD_FAB2(SCH_1):PAGE199
     2 A_HSC_UV @BASEBOARD_FAB2_LIB.BASEBOARD_FAB2(SCH_1):A_HSC_UV    I12 @BASEBOARD_FAB2_LIB.BASEBOARD_FAB2(SCH_1):PAGE199

R9P30 RES_0603-10.0,1%,1/10W,CHIP,G2A
     1 P12V_PSU @BASEBOARD_FAB2_LIB.BASEBOARD_FAB2(SCH_1):P12V_PSU     I2 @BASEBOARD_FAB2_LIB.BASEBOARD_FAB2(SCH_1):PAGE199
     2 P12V_HSC_VCC @BASEBOARD_FAB2_LIB.BASEBOARD_FAB2(SCH_1):P12V_HSC_VCC     I2 @BASEBOARD_FAB2_LIB.BASEBOARD_FAB2(SCH_1):PAGE199

R9P32 RES_0402-1.0,1%,1/16W,CHIP,G21A
     1 VR_PVCCIN_CPU1_PH5_VCIN @BASEBOARD_FAB2_LIB.BASEBOARD_FAB2(SCH_1):VR_PVCCIN_CPU1_PH5_VCIN    I24 @BASEBOARD_FAB2_LIB.BASEBOARD_FAB2(SCH_1):PAGE209
     2 P5V_STBY @BASEBOARD_FAB2_LIB.BASEBOARD_FAB2(SCH_1):P5V_STBY    I24 @BASEBOARD_FAB2_LIB.BASEBOARD_FAB2(SCH_1):PAGE209

R9P33 RES_0402-100.0K,1%,1/16W,CHIP,A
     1 P12V_STBY @BASEBOARD_FAB2_LIB.BASEBOARD_FAB2(SCH_1):P12V_STBY   I222 @BASEBOARD_FAB2_LIB.BASEBOARD_FAB2(SCH_1):PAGE200
     2 A_HSC_INAP @BASEBOARD_FAB2_LIB.BASEBOARD_FAB2(SCH_1):A_HSC_INAP   I222 @BASEBOARD_FAB2_LIB.BASEBOARD_FAB2(SCH_1):PAGE200

R9R1 RES_PWR_6PAD-0.001,1%,3W,CHIP,A
     1 P12V_PSU @BASEBOARD_FAB2_LIB.BASEBOARD_FAB2(SCH_1):P12V_PSU    I49 @BASEBOARD_FAB2_LIB.BASEBOARD_FAB2(SCH_1):PAGE200
     2 P12V_MB0_SW @BASEBOARD_FAB2_LIB.BASEBOARD_FAB2(SCH_1):P12V_MB0_SW    I49 @BASEBOARD_FAB2_LIB.BASEBOARD_FAB2(SCH_1):PAGE200
     3 P12V_HSC_SENP1 @BASEBOARD_FAB2_LIB.BASEBOARD_FAB2(SCH_1):P12V_HSC_SENP1    I49 @BASEBOARD_FAB2_LIB.BASEBOARD_FAB2(SCH_1):PAGE200
     4 P12V_HSC_SENN1 @BASEBOARD_FAB2_LIB.BASEBOARD_FAB2(SCH_1):P12V_HSC_SENN1    I49 @BASEBOARD_FAB2_LIB.BASEBOARD_FAB2(SCH_1):PAGE200
     5 P12V_PSU @BASEBOARD_FAB2_LIB.BASEBOARD_FAB2(SCH_1):P12V_PSU    I49 @BASEBOARD_FAB2_LIB.BASEBOARD_FAB2(SCH_1):PAGE200
     6 P12V_MB0_SW @BASEBOARD_FAB2_LIB.BASEBOARD_FAB2(SCH_1):P12V_MB0_SW    I49 @BASEBOARD_FAB2_LIB.BASEBOARD_FAB2(SCH_1):PAGE200

R9R2 RES_0402-1.0,1%,1/16W,CHIP,G21A
     1 VR_PVCCIN_CPU1_PH1_VCIN @BASEBOARD_FAB2_LIB.BASEBOARD_FAB2(SCH_1):VR_PVCCIN_CPU1_PH1_VCIN    I26 @BASEBOARD_FAB2_LIB.BASEBOARD_FAB2(SCH_1):PAGE207
     2 P5V_STBY @BASEBOARD_FAB2_LIB.BASEBOARD_FAB2(SCH_1):P5V_STBY    I26 @BASEBOARD_FAB2_LIB.BASEBOARD_FAB2(SCH_1):PAGE207

R9R4 RES_0402-10.0,1%,1/16W,CHIP,G2A
     1 A_HSC_GATE @BASEBOARD_FAB2_LIB.BASEBOARD_FAB2(SCH_1):A_HSC_GATE    I58 @BASEBOARD_FAB2_LIB.BASEBOARD_FAB2(SCH_1):PAGE200
     2 A_HSC_GATE2_R @BASEBOARD_FAB2_LIB.BASEBOARD_FAB2(SCH_1):A_HSC_GATE2_R    I58 @BASEBOARD_FAB2_LIB.BASEBOARD_FAB2(SCH_1):PAGE200

R9R5 RES_0402-49.9,1%,1/16W,CHIP,G2A
     1 ISENSE_TMP421_2_E @BASEBOARD_FAB2_LIB.BASEBOARD_FAB2(SCH_1):ISENSE_TMP421_2_E    I25 @BASEBOARD_FAB2_LIB.BASEBOARD_FAB2(SCH_1):PAGE167
     2 ISENSE_TMP421_2_DXP @BASEBOARD_FAB2_LIB.BASEBOARD_FAB2(SCH_1):ISENSE_TMP421_2_DXP    I25 @BASEBOARD_FAB2_LIB.BASEBOARD_FAB2(SCH_1):PAGE167

R9R6 RES_0402-49.9,1%,1/16W,CHIP,G2A
     1 ISENSE_TMP421_2_BC @BASEBOARD_FAB2_LIB.BASEBOARD_FAB2(SCH_1):ISENSE_TMP421_2_BC    I26 @BASEBOARD_FAB2_LIB.BASEBOARD_FAB2(SCH_1):PAGE167
     2 ISENSE_TMP421_2_DXN @BASEBOARD_FAB2_LIB.BASEBOARD_FAB2(SCH_1):ISENSE_TMP421_2_DXN    I26 @BASEBOARD_FAB2_LIB.BASEBOARD_FAB2(SCH_1):PAGE167

R9R7 RES_0402-20.0,1%,1/16W,CHIP,G2A
     1 SMB_SENSOR_TMP421_2_SCL @BASEBOARD_FAB2_LIB.BASEBOARD_FAB2(SCH_1):SMB_SENSOR_TMP421_2_SCL    I75 @BASEBOARD_FAB2_LIB.BASEBOARD_FAB2(SCH_1):PAGE167
     2 SMB_SENSOR_STBY_LVC3_SCL @BASEBOARD_FAB2_LIB.BASEBOARD_FAB2(SCH_1):SMB_SENSOR_STBY_LVC3_SCL    I75 @BASEBOARD_FAB2_LIB.BASEBOARD_FAB2(SCH_1):PAGE167

R9R8 RES_0402-20.0,1%,1/16W,CHIP,G2A
     1 SMB_SENSOR_TMP421_2_SDA @BASEBOARD_FAB2_LIB.BASEBOARD_FAB2(SCH_1):SMB_SENSOR_TMP421_2_SDA    I76 @BASEBOARD_FAB2_LIB.BASEBOARD_FAB2(SCH_1):PAGE167
     2 SMB_SENSOR_STBY_LVC3_SDA @BASEBOARD_FAB2_LIB.BASEBOARD_FAB2(SCH_1):SMB_SENSOR_STBY_LVC3_SDA    I76 @BASEBOARD_FAB2_LIB.BASEBOARD_FAB2(SCH_1):PAGE167

R9R9 RES_0402-0.0,5%,1/16W,CHIP,G21A
     1 FAN_TACH3 @BASEBOARD_FAB2_LIB.BASEBOARD_FAB2(SCH_1):FAN_TACH3   I254 @BASEBOARD_FAB2_LIB.BASEBOARD_FAB2(SCH_1):PAGE181
     2 FAN_TACH3_R @BASEBOARD_FAB2_LIB.BASEBOARD_FAB2(SCH_1):FAN_TACH3_R   I254 @BASEBOARD_FAB2_LIB.BASEBOARD_FAB2(SCH_1):PAGE181

R9R10 RES_0402-0.0,5%,1/16W,CHIP,G21A
     1 FAN_TACH1 @BASEBOARD_FAB2_LIB.BASEBOARD_FAB2(SCH_1):FAN_TACH1   I256 @BASEBOARD_FAB2_LIB.BASEBOARD_FAB2(SCH_1):PAGE181
     2 FAN_TACH1_R @BASEBOARD_FAB2_LIB.BASEBOARD_FAB2(SCH_1):FAN_TACH1_R   I256 @BASEBOARD_FAB2_LIB.BASEBOARD_FAB2(SCH_1):PAGE181

R9R11 RES_0402-1.0,1%,1/16W,CHIP,G21A
     1 VR_PVCCIN_CPU1_PH2_VCIN @BASEBOARD_FAB2_LIB.BASEBOARD_FAB2(SCH_1):VR_PVCCIN_CPU1_PH2_VCIN    I39 @BASEBOARD_FAB2_LIB.BASEBOARD_FAB2(SCH_1):PAGE207
     2 P5V_STBY @BASEBOARD_FAB2_LIB.BASEBOARD_FAB2(SCH_1):P5V_STBY    I39 @BASEBOARD_FAB2_LIB.BASEBOARD_FAB2(SCH_1):PAGE207

R9R12 RES_0402-0.0,5%,1/16W,CHIP,G21A
     1 FAN_TACH2 @BASEBOARD_FAB2_LIB.BASEBOARD_FAB2(SCH_1):FAN_TACH2   I255 @BASEBOARD_FAB2_LIB.BASEBOARD_FAB2(SCH_1):PAGE181
     2 FAN_TACH2_R @BASEBOARD_FAB2_LIB.BASEBOARD_FAB2(SCH_1):FAN_TACH2_R   I255 @BASEBOARD_FAB2_LIB.BASEBOARD_FAB2(SCH_1):PAGE181

R9T1 RES_0402-0.0,5%,1/16W,CHIP,G21A
     1 FAN_PWM_OUT_SYS0_R @BASEBOARD_FAB2_LIB.BASEBOARD_FAB2(SCH_1):FAN_PWM_OUT_SYS0_R   I261 @BASEBOARD_FAB2_LIB.BASEBOARD_FAB2(SCH_1):PAGE181
     2 FAN_PWM_OUT_SYS0_R1 @BASEBOARD_FAB2_LIB.BASEBOARD_FAB2(SCH_1):FAN_PWM_OUT_SYS0_R1   I261 @BASEBOARD_FAB2_LIB.BASEBOARD_FAB2(SCH_1):PAGE181

R9T3 RES_0402-6.19K,1%,1/16W,CHIP,GA
     1 FM_P12V_HOTSWAP0_EN @BASEBOARD_FAB2_LIB.BASEBOARD_FAB2(SCH_1):FM_P12V_HOTSWAP0_EN   I185 @BASEBOARD_FAB2_LIB.BASEBOARD_FAB2(SCH_1):PAGE181
     2    GND @BASEBOARD_FAB2_LIB.BASEBOARD_FAB2(SCH_1):GND   I185 @BASEBOARD_FAB2_LIB.BASEBOARD_FAB2(SCH_1):PAGE181

R9T4 RES_0402-0.0,5%,1/16W,CHIP,G21A
     1 VR_PVDDQ_GHJ_AIINSEN_R @BASEBOARD_FAB2_LIB.BASEBOARD_FAB2(SCH_1):VR_PVDDQ_GHJ_AIINSEN_R   I126 @BASEBOARD_FAB2_LIB.BASEBOARD_FAB2(SCH_1):PAGE197
     2 VR_PVDDQ_GHJ_AIINSEN @BASEBOARD_FAB2_LIB.BASEBOARD_FAB2(SCH_1):VR_PVDDQ_GHJ_AIINSEN   I126 @BASEBOARD_FAB2_LIB.BASEBOARD_FAB2(SCH_1):PAGE197

R9T5 RES_0402-4.75K,1%,1/16W,CHIP,GA
     1 P3V3_STBY @BASEBOARD_FAB2_LIB.BASEBOARD_FAB2(SCH_1):P3V3_STBY   I135 @BASEBOARD_FAB2_LIB.BASEBOARD_FAB2(SCH_1):PAGE161
     2 FAN_TACH1 @BASEBOARD_FAB2_LIB.BASEBOARD_FAB2(SCH_1):FAN_TACH1   I135 @BASEBOARD_FAB2_LIB.BASEBOARD_FAB2(SCH_1):PAGE161

R9T6 RES_0402-15.0K,1%,1/16W,CHIP,GA
     1 P12V_PSU @BASEBOARD_FAB2_LIB.BASEBOARD_FAB2(SCH_1):P12V_PSU   I183 @BASEBOARD_FAB2_LIB.BASEBOARD_FAB2(SCH_1):PAGE181
     2 FM_P12V_HOTSWAP0_EN @BASEBOARD_FAB2_LIB.BASEBOARD_FAB2(SCH_1):FM_P12V_HOTSWAP0_EN   I183 @BASEBOARD_FAB2_LIB.BASEBOARD_FAB2(SCH_1):PAGE181

R9T7 RES_0402-100.0,1%,1/16W,CHIP,GA
     1 FAN_TACH1 @BASEBOARD_FAB2_LIB.BASEBOARD_FAB2(SCH_1):FAN_TACH1   I134 @BASEBOARD_FAB2_LIB.BASEBOARD_FAB2(SCH_1):PAGE161
     2 FAN_TACH1_CPU1_D2 @BASEBOARD_FAB2_LIB.BASEBOARD_FAB2(SCH_1):FAN_TACH1_CPU1_D2   I134 @BASEBOARD_FAB2_LIB.BASEBOARD_FAB2(SCH_1):PAGE161

R9T8 RES_0402-0.0,5%,1/16W,CHIP,G21A
     1    GND @BASEBOARD_FAB2_LIB.BASEBOARD_FAB2(SCH_1):GND   I278 @BASEBOARD_FAB2_LIB.BASEBOARD_FAB2(SCH_1):PAGE181
     2 FM_MATED_IN_N @BASEBOARD_FAB2_LIB.BASEBOARD_FAB2(SCH_1):FM_MATED_IN_N   I278 @BASEBOARD_FAB2_LIB.BASEBOARD_FAB2(SCH_1):PAGE181

R9T9 RES_0402-4.75K,1%,1/16W,CHIP,GA
     1 P12V_PSU @BASEBOARD_FAB2_LIB.BASEBOARD_FAB2(SCH_1):P12V_PSU   I177 @BASEBOARD_FAB2_LIB.BASEBOARD_FAB2(SCH_1):PAGE181
     2 FM_MATED_IN_N @BASEBOARD_FAB2_LIB.BASEBOARD_FAB2(SCH_1):FM_MATED_IN_N   I177 @BASEBOARD_FAB2_LIB.BASEBOARD_FAB2(SCH_1):PAGE181

R9U1 RES_0402-1.0,1%,1/16W,CHIP,G21A
     1 VR_PVDDQ_GHJ_PH1_VCIN @BASEBOARD_FAB2_LIB.BASEBOARD_FAB2(SCH_1):VR_PVDDQ_GHJ_PH1_VCIN    I52 @BASEBOARD_FAB2_LIB.BASEBOARD_FAB2(SCH_1):PAGE224
     2 P5V_STBY @BASEBOARD_FAB2_LIB.BASEBOARD_FAB2(SCH_1):P5V_STBY    I52 @BASEBOARD_FAB2_LIB.BASEBOARD_FAB2(SCH_1):PAGE224

R9U3 RES_0402-100.0,1%,1/16W,CHIP,GA
     1 PVCCIO_CPU1 @BASEBOARD_FAB2_LIB.BASEBOARD_FAB2(SCH_1):PVCCIO_CPU1     I8 @BASEBOARD_FAB2_LIB.BASEBOARD_FAB2(SCH_1):PAGE223
     2 SVID_DIO1_CPU1_R @BASEBOARD_FAB2_LIB.BASEBOARD_FAB2(SCH_1):SVID_DIO1_CPU1_R     I8 @BASEBOARD_FAB2_LIB.BASEBOARD_FAB2(SCH_1):PAGE223

R9U4 RES_0402-49.9,1%,1/16W,EMPTY,GA
     1 PVCCIO_CPU1 @BASEBOARD_FAB2_LIB.BASEBOARD_FAB2(SCH_1):PVCCIO_CPU1    I50 @BASEBOARD_FAB2_LIB.BASEBOARD_FAB2(SCH_1):PAGE223
     2 SVID_CLK1_CPU1_R @BASEBOARD_FAB2_LIB.BASEBOARD_FAB2(SCH_1):SVID_CLK1_CPU1_R    I50 @BASEBOARD_FAB2_LIB.BASEBOARD_FAB2(SCH_1):PAGE223

R9U7 RES_0402-0.0,5%,1/16W,CHIP,G21A
     1 FM_PVDDQ_GHJ_EN @BASEBOARD_FAB2_LIB.BASEBOARD_FAB2(SCH_1):FM_PVDDQ_GHJ_EN    I84 @BASEBOARD_FAB2_LIB.BASEBOARD_FAB2(SCH_1):PAGE223
     2 VR_PVDDQ_GHJ_VREN @BASEBOARD_FAB2_LIB.BASEBOARD_FAB2(SCH_1):VR_PVDDQ_GHJ_VREN    I84 @BASEBOARD_FAB2_LIB.BASEBOARD_FAB2(SCH_1):PAGE223

R9U8 RES_0402-100.0K,1%,1/16W,EMPTYA
     1 P3V3_STBY @BASEBOARD_FAB2_LIB.BASEBOARD_FAB2(SCH_1):P3V3_STBY    I85 @BASEBOARD_FAB2_LIB.BASEBOARD_FAB2(SCH_1):PAGE223
     2 VR_PVDDQ_GHJ_VREN @BASEBOARD_FAB2_LIB.BASEBOARD_FAB2(SCH_1):VR_PVDDQ_GHJ_VREN    I85 @BASEBOARD_FAB2_LIB.BASEBOARD_FAB2(SCH_1):PAGE223

R9U10 RES_0402-0.0,5%,1/16W,CHIP,G21A
     1 P3V3_STBY @BASEBOARD_FAB2_LIB.BASEBOARD_FAB2(SCH_1):P3V3_STBY    I30 @BASEBOARD_FAB2_LIB.BASEBOARD_FAB2(SCH_1):PAGE223
     2 VR_PVDDQ_GHJ_VDD @BASEBOARD_FAB2_LIB.BASEBOARD_FAB2(SCH_1):VR_PVDDQ_GHJ_VDD    I30 @BASEBOARD_FAB2_LIB.BASEBOARD_FAB2(SCH_1):PAGE223

R9U11 RES_0402-100.0K,1%,1/16W,CHIP,B
     1 VR_FET_SW_P12V_STBY_PVDDQ_GHJ @BASEBOARD_FAB2_LIB.BASEBOARD_FAB2(SCH_1):VR_FET_SW_P12V_STBY_PVDDQ_GHJ    I57 @BASEBOARD_FAB2_LIB.BASEBOARD_FAB2(SCH_1):PAGE223
     2 VR_PVDDQ_GHJ_VINSEN @BASEBOARD_FAB2_LIB.BASEBOARD_FAB2(SCH_1):VR_PVDDQ_GHJ_VINSEN    I57 @BASEBOARD_FAB2_LIB.BASEBOARD_FAB2(SCH_1):PAGE223

R9U12 RES_0402-1.0,1%,1/16W,CHIP,G21A
     1 VR_PVDDQ_GHJ_PH2_VCIN @BASEBOARD_FAB2_LIB.BASEBOARD_FAB2(SCH_1):VR_PVDDQ_GHJ_PH2_VCIN    I76 @BASEBOARD_FAB2_LIB.BASEBOARD_FAB2(SCH_1):PAGE224
     2 P5V_STBY @BASEBOARD_FAB2_LIB.BASEBOARD_FAB2(SCH_1):P5V_STBY    I76 @BASEBOARD_FAB2_LIB.BASEBOARD_FAB2(SCH_1):PAGE224

R9W12 RES_0402-10.0K,1%,1/16W,CHIP,GA
     1 P3V3_STBY @BASEBOARD_FAB2_LIB.BASEBOARD_FAB2(SCH_1):P3V3_STBY    I79 @BASEBOARD_FAB2_LIB.BASEBOARD_FAB2(SCH_1):PAGE239
     2 UNNAMED_239_CAP_I84_A @BASEBOARD_FAB2_LIB.BASEBOARD_FAB2(SCH_1):UNNAMED_239_CAP_I84_A    I79 @BASEBOARD_FAB2_LIB.BASEBOARD_FAB2(SCH_1):PAGE239

R9W31 21K5R2F-GP_RCL_GP-21K5R2F-GP,6A
     1 P2V5_AUX_BMC @BASEBOARD_FAB2_LIB.BASEBOARD_FAB2(SCH_1):P2V5_AUX_BMC    I99 @BASEBOARD_FAB2_LIB.BASEBOARD_FAB2(SCH_1):PAGE239
     2 UNNAMED_239_21K5R2F-GP_I99_2 @BASEBOARD_FAB2_LIB.BASEBOARD_FAB2(SCH_1):UNNAMED_239_21K5R2F-GP_I99_2    I99 @BASEBOARD_FAB2_LIB.BASEBOARD_FAB2(SCH_1):PAGE239

R9W32 RES_0402-13K,1.0%,1/16W,CHIP,GA
     1    GND @BASEBOARD_FAB2_LIB.BASEBOARD_FAB2(SCH_1):GND    I87 @BASEBOARD_FAB2_LIB.BASEBOARD_FAB2(SCH_1):PAGE239
     2 UNNAMED_239_21K5R2F-GP_I99_2 @BASEBOARD_FAB2_LIB.BASEBOARD_FAB2(SCH_1):UNNAMED_239_21K5R2F-GP_I99_2    I87 @BASEBOARD_FAB2_LIB.BASEBOARD_FAB2(SCH_1):PAGE239

R25W1 120R2F-GP_RCL_GP-120R2F-GP,64.A
     1    GND @BASEBOARD_FAB2_LIB.BASEBOARD_FAB2(SCH_1):GND   I160 @BASEBOARD_FAB2_LIB.BASEBOARD_FAB2(SCH_1):PAGE149
     2 BMC_M_CKE @BASEBOARD_FAB2_LIB.BASEBOARD_FAB2(SCH_1):BMC_M_CKE   I160 @BASEBOARD_FAB2_LIB.BASEBOARD_FAB2(SCH_1):PAGE149

R25W2 120R2F-GP_RCL_GP-120R2F-GP,64.A
     1    GND @BASEBOARD_FAB2_LIB.BASEBOARD_FAB2(SCH_1):GND   I161 @BASEBOARD_FAB2_LIB.BASEBOARD_FAB2(SCH_1):PAGE149
     2 BMC_M_ODT @BASEBOARD_FAB2_LIB.BASEBOARD_FAB2(SCH_1):BMC_M_ODT   I161 @BASEBOARD_FAB2_LIB.BASEBOARD_FAB2(SCH_1):PAGE149

R25W3 120R2F-GP_RCL_GP-120R2F-GP,64.A
     1    GND @BASEBOARD_FAB2_LIB.BASEBOARD_FAB2(SCH_1):GND   I163 @BASEBOARD_FAB2_LIB.BASEBOARD_FAB2(SCH_1):PAGE149
     2 BMC_M_RST_N @BASEBOARD_FAB2_LIB.BASEBOARD_FAB2(SCH_1):BMC_M_RST_N   I163 @BASEBOARD_FAB2_LIB.BASEBOARD_FAB2(SCH_1):PAGE149

R25W4 120R2F-GP_RCL_GP-120R2F-GP,64.A
     1    GND @BASEBOARD_FAB2_LIB.BASEBOARD_FAB2(SCH_1):GND   I162 @BASEBOARD_FAB2_LIB.BASEBOARD_FAB2(SCH_1):PAGE149
     2 BMC_M_MALERT_N @BASEBOARD_FAB2_LIB.BASEBOARD_FAB2(SCH_1):BMC_M_MALERT_N   I162 @BASEBOARD_FAB2_LIB.BASEBOARD_FAB2(SCH_1):PAGE149

R25W5 120R2F-GP_RCL_GP-120R2F-GP,64.A
     1    GND @BASEBOARD_FAB2_LIB.BASEBOARD_FAB2(SCH_1):GND   I164 @BASEBOARD_FAB2_LIB.BASEBOARD_FAB2(SCH_1):PAGE149
     2 BMC_M_CS_N @BASEBOARD_FAB2_LIB.BASEBOARD_FAB2(SCH_1):BMC_M_CS_N   I164 @BASEBOARD_FAB2_LIB.BASEBOARD_FAB2(SCH_1):PAGE149

R25W6 120R2F-GP_RCL_GP-120R2F-GP,64.A
     1    GND @BASEBOARD_FAB2_LIB.BASEBOARD_FAB2(SCH_1):GND   I165 @BASEBOARD_FAB2_LIB.BASEBOARD_FAB2(SCH_1):PAGE149
     2 BMC_M_RAS_N @BASEBOARD_FAB2_LIB.BASEBOARD_FAB2(SCH_1):BMC_M_RAS_N   I165 @BASEBOARD_FAB2_LIB.BASEBOARD_FAB2(SCH_1):PAGE149

R25W7 120R2F-GP_RCL_GP-120R2F-GP,64.A
     1    GND @BASEBOARD_FAB2_LIB.BASEBOARD_FAB2(SCH_1):GND   I166 @BASEBOARD_FAB2_LIB.BASEBOARD_FAB2(SCH_1):PAGE149
     2 BMC_M_CAS_N @BASEBOARD_FAB2_LIB.BASEBOARD_FAB2(SCH_1):BMC_M_CAS_N   I166 @BASEBOARD_FAB2_LIB.BASEBOARD_FAB2(SCH_1):PAGE149

R25W8 120R2F-GP_RCL_GP-120R2F-GP,64.A
     1    GND @BASEBOARD_FAB2_LIB.BASEBOARD_FAB2(SCH_1):GND   I167 @BASEBOARD_FAB2_LIB.BASEBOARD_FAB2(SCH_1):PAGE149
     2 BMC_M_WE_N @BASEBOARD_FAB2_LIB.BASEBOARD_FAB2(SCH_1):BMC_M_WE_N   I167 @BASEBOARD_FAB2_LIB.BASEBOARD_FAB2(SCH_1):PAGE149

R25W9 120R2F-GP_RCL_GP-120R2F-GP,64.A
     1    GND @BASEBOARD_FAB2_LIB.BASEBOARD_FAB2(SCH_1):GND   I168 @BASEBOARD_FAB2_LIB.BASEBOARD_FAB2(SCH_1):PAGE149
     2 BMC_M_BA0 @BASEBOARD_FAB2_LIB.BASEBOARD_FAB2(SCH_1):BMC_M_BA0   I168 @BASEBOARD_FAB2_LIB.BASEBOARD_FAB2(SCH_1):PAGE149

R25W10 120R2F-GP_RCL_GP-120R2F-GP,64.A
     1    GND @BASEBOARD_FAB2_LIB.BASEBOARD_FAB2(SCH_1):GND   I169 @BASEBOARD_FAB2_LIB.BASEBOARD_FAB2(SCH_1):PAGE149
     2 BMC_M_BA1 @BASEBOARD_FAB2_LIB.BASEBOARD_FAB2(SCH_1):BMC_M_BA1   I169 @BASEBOARD_FAB2_LIB.BASEBOARD_FAB2(SCH_1):PAGE149

R25W11 120R2F-GP_RCL_GP-120R2F-GP,64.A
     1    GND @BASEBOARD_FAB2_LIB.BASEBOARD_FAB2(SCH_1):GND   I171 @BASEBOARD_FAB2_LIB.BASEBOARD_FAB2(SCH_1):PAGE149
     2 BMC_M_BG0 @BASEBOARD_FAB2_LIB.BASEBOARD_FAB2(SCH_1):BMC_M_BG0   I171 @BASEBOARD_FAB2_LIB.BASEBOARD_FAB2(SCH_1):PAGE149

R25W12 120R2F-GP_RCL_GP-120R2F-GP,64.A
     1    GND @BASEBOARD_FAB2_LIB.BASEBOARD_FAB2(SCH_1):GND   I170 @BASEBOARD_FAB2_LIB.BASEBOARD_FAB2(SCH_1):PAGE149
     2 BMC_M_A0 @BASEBOARD_FAB2_LIB.BASEBOARD_FAB2(SCH_1):BMC_M_A0   I170 @BASEBOARD_FAB2_LIB.BASEBOARD_FAB2(SCH_1):PAGE149

R25W13 120R2F-GP_RCL_GP-120R2F-GP,64.A
     1    GND @BASEBOARD_FAB2_LIB.BASEBOARD_FAB2(SCH_1):GND   I172 @BASEBOARD_FAB2_LIB.BASEBOARD_FAB2(SCH_1):PAGE149
     2 BMC_M_A1 @BASEBOARD_FAB2_LIB.BASEBOARD_FAB2(SCH_1):BMC_M_A1   I172 @BASEBOARD_FAB2_LIB.BASEBOARD_FAB2(SCH_1):PAGE149

R25W14 120R2F-GP_RCL_GP-120R2F-GP,64.A
     1    GND @BASEBOARD_FAB2_LIB.BASEBOARD_FAB2(SCH_1):GND   I175 @BASEBOARD_FAB2_LIB.BASEBOARD_FAB2(SCH_1):PAGE149
     2 BMC_M_A2 @BASEBOARD_FAB2_LIB.BASEBOARD_FAB2(SCH_1):BMC_M_A2   I175 @BASEBOARD_FAB2_LIB.BASEBOARD_FAB2(SCH_1):PAGE149

R25W15 120R2F-GP_RCL_GP-120R2F-GP,64.A
     1    GND @BASEBOARD_FAB2_LIB.BASEBOARD_FAB2(SCH_1):GND   I174 @BASEBOARD_FAB2_LIB.BASEBOARD_FAB2(SCH_1):PAGE149
     2 BMC_M_A3 @BASEBOARD_FAB2_LIB.BASEBOARD_FAB2(SCH_1):BMC_M_A3   I174 @BASEBOARD_FAB2_LIB.BASEBOARD_FAB2(SCH_1):PAGE149

R25W16 120R2F-GP_RCL_GP-120R2F-GP,64.A
     1    GND @BASEBOARD_FAB2_LIB.BASEBOARD_FAB2(SCH_1):GND   I173 @BASEBOARD_FAB2_LIB.BASEBOARD_FAB2(SCH_1):PAGE149
     2 BMC_M_A4 @BASEBOARD_FAB2_LIB.BASEBOARD_FAB2(SCH_1):BMC_M_A4   I173 @BASEBOARD_FAB2_LIB.BASEBOARD_FAB2(SCH_1):PAGE149

R25W17 120R2F-GP_RCL_GP-120R2F-GP,64.A
     1    GND @BASEBOARD_FAB2_LIB.BASEBOARD_FAB2(SCH_1):GND   I181 @BASEBOARD_FAB2_LIB.BASEBOARD_FAB2(SCH_1):PAGE149
     2 BMC_M_A5 @BASEBOARD_FAB2_LIB.BASEBOARD_FAB2(SCH_1):BMC_M_A5   I181 @BASEBOARD_FAB2_LIB.BASEBOARD_FAB2(SCH_1):PAGE149

R25W18 120R2F-GP_RCL_GP-120R2F-GP,64.A
     1    GND @BASEBOARD_FAB2_LIB.BASEBOARD_FAB2(SCH_1):GND   I182 @BASEBOARD_FAB2_LIB.BASEBOARD_FAB2(SCH_1):PAGE149
     2 BMC_M_A6 @BASEBOARD_FAB2_LIB.BASEBOARD_FAB2(SCH_1):BMC_M_A6   I182 @BASEBOARD_FAB2_LIB.BASEBOARD_FAB2(SCH_1):PAGE149

R25W19 120R2F-GP_RCL_GP-120R2F-GP,64.A
     1    GND @BASEBOARD_FAB2_LIB.BASEBOARD_FAB2(SCH_1):GND   I183 @BASEBOARD_FAB2_LIB.BASEBOARD_FAB2(SCH_1):PAGE149
     2 BMC_M_A7 @BASEBOARD_FAB2_LIB.BASEBOARD_FAB2(SCH_1):BMC_M_A7   I183 @BASEBOARD_FAB2_LIB.BASEBOARD_FAB2(SCH_1):PAGE149

R25W20 120R2F-GP_RCL_GP-120R2F-GP,64.A
     1    GND @BASEBOARD_FAB2_LIB.BASEBOARD_FAB2(SCH_1):GND   I184 @BASEBOARD_FAB2_LIB.BASEBOARD_FAB2(SCH_1):PAGE149
     2 BMC_M_A8 @BASEBOARD_FAB2_LIB.BASEBOARD_FAB2(SCH_1):BMC_M_A8   I184 @BASEBOARD_FAB2_LIB.BASEBOARD_FAB2(SCH_1):PAGE149

R25W21 120R2F-GP_RCL_GP-120R2F-GP,64.A
     1    GND @BASEBOARD_FAB2_LIB.BASEBOARD_FAB2(SCH_1):GND   I185 @BASEBOARD_FAB2_LIB.BASEBOARD_FAB2(SCH_1):PAGE149
     2 BMC_M_A9 @BASEBOARD_FAB2_LIB.BASEBOARD_FAB2(SCH_1):BMC_M_A9   I185 @BASEBOARD_FAB2_LIB.BASEBOARD_FAB2(SCH_1):PAGE149

R25W22 120R2F-GP_RCL_GP-120R2F-GP,64.A
     1    GND @BASEBOARD_FAB2_LIB.BASEBOARD_FAB2(SCH_1):GND   I176 @BASEBOARD_FAB2_LIB.BASEBOARD_FAB2(SCH_1):PAGE149
     2 BMC_M_A10 @BASEBOARD_FAB2_LIB.BASEBOARD_FAB2(SCH_1):BMC_M_A10   I176 @BASEBOARD_FAB2_LIB.BASEBOARD_FAB2(SCH_1):PAGE149

R25W23 120R2F-GP_RCL_GP-120R2F-GP,64.A
     1    GND @BASEBOARD_FAB2_LIB.BASEBOARD_FAB2(SCH_1):GND   I177 @BASEBOARD_FAB2_LIB.BASEBOARD_FAB2(SCH_1):PAGE149
     2 BMC_M_A11 @BASEBOARD_FAB2_LIB.BASEBOARD_FAB2(SCH_1):BMC_M_A11   I177 @BASEBOARD_FAB2_LIB.BASEBOARD_FAB2(SCH_1):PAGE149

R25W24 120R2F-GP_RCL_GP-120R2F-GP,64.A
     1    GND @BASEBOARD_FAB2_LIB.BASEBOARD_FAB2(SCH_1):GND   I178 @BASEBOARD_FAB2_LIB.BASEBOARD_FAB2(SCH_1):PAGE149
     2 BMC_M_A12 @BASEBOARD_FAB2_LIB.BASEBOARD_FAB2(SCH_1):BMC_M_A12   I178 @BASEBOARD_FAB2_LIB.BASEBOARD_FAB2(SCH_1):PAGE149

R25W25 120R2F-GP_RCL_GP-120R2F-GP,64.A
     1    GND @BASEBOARD_FAB2_LIB.BASEBOARD_FAB2(SCH_1):GND   I179 @BASEBOARD_FAB2_LIB.BASEBOARD_FAB2(SCH_1):PAGE149
     2 BMC_M_A13 @BASEBOARD_FAB2_LIB.BASEBOARD_FAB2(SCH_1):BMC_M_A13   I179 @BASEBOARD_FAB2_LIB.BASEBOARD_FAB2(SCH_1):PAGE149

R25W26 120R2F-GP_RCL_GP-120R2F-GP,64.A
     1    GND @BASEBOARD_FAB2_LIB.BASEBOARD_FAB2(SCH_1):GND   I180 @BASEBOARD_FAB2_LIB.BASEBOARD_FAB2(SCH_1):PAGE149
     2 BMC_M_MACT_N @BASEBOARD_FAB2_LIB.BASEBOARD_FAB2(SCH_1):BMC_M_MACT_N   I180 @BASEBOARD_FAB2_LIB.BASEBOARD_FAB2(SCH_1):PAGE149

R25W27 120R2F-GP_RCL_GP-120R2F-GP,64.A
     1 BMC_M_CKE @BASEBOARD_FAB2_LIB.BASEBOARD_FAB2(SCH_1):BMC_M_CKE   I186 @BASEBOARD_FAB2_LIB.BASEBOARD_FAB2(SCH_1):PAGE149
     2 P1V2_AUX_BMC @BASEBOARD_FAB2_LIB.BASEBOARD_FAB2(SCH_1):P1V2_AUX_BMC   I186 @BASEBOARD_FAB2_LIB.BASEBOARD_FAB2(SCH_1):PAGE149

R25W28 120R2F-GP_RCL_GP-120R2F-GP,64.A
     1 BMC_M_ODT @BASEBOARD_FAB2_LIB.BASEBOARD_FAB2(SCH_1):BMC_M_ODT   I187 @BASEBOARD_FAB2_LIB.BASEBOARD_FAB2(SCH_1):PAGE149
     2 P1V2_AUX_BMC @BASEBOARD_FAB2_LIB.BASEBOARD_FAB2(SCH_1):P1V2_AUX_BMC   I187 @BASEBOARD_FAB2_LIB.BASEBOARD_FAB2(SCH_1):PAGE149

R25W29 120R2F-GP_RCL_GP-120R2F-GP,64.A
     1 BMC_M_RST_N @BASEBOARD_FAB2_LIB.BASEBOARD_FAB2(SCH_1):BMC_M_RST_N   I189 @BASEBOARD_FAB2_LIB.BASEBOARD_FAB2(SCH_1):PAGE149
     2 P1V2_AUX_BMC @BASEBOARD_FAB2_LIB.BASEBOARD_FAB2(SCH_1):P1V2_AUX_BMC   I189 @BASEBOARD_FAB2_LIB.BASEBOARD_FAB2(SCH_1):PAGE149

R25W30 120R2F-GP_RCL_GP-120R2F-GP,64.A
     1 BMC_M_MALERT_N @BASEBOARD_FAB2_LIB.BASEBOARD_FAB2(SCH_1):BMC_M_MALERT_N   I188 @BASEBOARD_FAB2_LIB.BASEBOARD_FAB2(SCH_1):PAGE149
     2 P1V2_AUX_BMC @BASEBOARD_FAB2_LIB.BASEBOARD_FAB2(SCH_1):P1V2_AUX_BMC   I188 @BASEBOARD_FAB2_LIB.BASEBOARD_FAB2(SCH_1):PAGE149

R25W31 120R2F-GP_RCL_GP-120R2F-GP,64.A
     1 BMC_M_CS_N @BASEBOARD_FAB2_LIB.BASEBOARD_FAB2(SCH_1):BMC_M_CS_N   I190 @BASEBOARD_FAB2_LIB.BASEBOARD_FAB2(SCH_1):PAGE149
     2 P1V2_AUX_BMC @BASEBOARD_FAB2_LIB.BASEBOARD_FAB2(SCH_1):P1V2_AUX_BMC   I190 @BASEBOARD_FAB2_LIB.BASEBOARD_FAB2(SCH_1):PAGE149

R25W32 120R2F-GP_RCL_GP-120R2F-GP,64.A
     1 BMC_M_RAS_N @BASEBOARD_FAB2_LIB.BASEBOARD_FAB2(SCH_1):BMC_M_RAS_N   I191 @BASEBOARD_FAB2_LIB.BASEBOARD_FAB2(SCH_1):PAGE149
     2 P1V2_AUX_BMC @BASEBOARD_FAB2_LIB.BASEBOARD_FAB2(SCH_1):P1V2_AUX_BMC   I191 @BASEBOARD_FAB2_LIB.BASEBOARD_FAB2(SCH_1):PAGE149

R25W33 120R2F-GP_RCL_GP-120R2F-GP,64.A
     1 BMC_M_CAS_N @BASEBOARD_FAB2_LIB.BASEBOARD_FAB2(SCH_1):BMC_M_CAS_N   I192 @BASEBOARD_FAB2_LIB.BASEBOARD_FAB2(SCH_1):PAGE149
     2 P1V2_AUX_BMC @BASEBOARD_FAB2_LIB.BASEBOARD_FAB2(SCH_1):P1V2_AUX_BMC   I192 @BASEBOARD_FAB2_LIB.BASEBOARD_FAB2(SCH_1):PAGE149

R25W34 120R2F-GP_RCL_GP-120R2F-GP,64.A
     1 BMC_M_WE_N @BASEBOARD_FAB2_LIB.BASEBOARD_FAB2(SCH_1):BMC_M_WE_N   I193 @BASEBOARD_FAB2_LIB.BASEBOARD_FAB2(SCH_1):PAGE149
     2 P1V2_AUX_BMC @BASEBOARD_FAB2_LIB.BASEBOARD_FAB2(SCH_1):P1V2_AUX_BMC   I193 @BASEBOARD_FAB2_LIB.BASEBOARD_FAB2(SCH_1):PAGE149

R25W35 120R2F-GP_RCL_GP-120R2F-GP,64.A
     1 BMC_M_BA0 @BASEBOARD_FAB2_LIB.BASEBOARD_FAB2(SCH_1):BMC_M_BA0   I194 @BASEBOARD_FAB2_LIB.BASEBOARD_FAB2(SCH_1):PAGE149
     2 P1V2_AUX_BMC @BASEBOARD_FAB2_LIB.BASEBOARD_FAB2(SCH_1):P1V2_AUX_BMC   I194 @BASEBOARD_FAB2_LIB.BASEBOARD_FAB2(SCH_1):PAGE149

R25W36 120R2F-GP_RCL_GP-120R2F-GP,64.A
     1 BMC_M_BA1 @BASEBOARD_FAB2_LIB.BASEBOARD_FAB2(SCH_1):BMC_M_BA1   I195 @BASEBOARD_FAB2_LIB.BASEBOARD_FAB2(SCH_1):PAGE149
     2 P1V2_AUX_BMC @BASEBOARD_FAB2_LIB.BASEBOARD_FAB2(SCH_1):P1V2_AUX_BMC   I195 @BASEBOARD_FAB2_LIB.BASEBOARD_FAB2(SCH_1):PAGE149

R25W37 120R2F-GP_RCL_GP-120R2F-GP,64.A
     1 BMC_M_BG0 @BASEBOARD_FAB2_LIB.BASEBOARD_FAB2(SCH_1):BMC_M_BG0   I196 @BASEBOARD_FAB2_LIB.BASEBOARD_FAB2(SCH_1):PAGE149
     2 P1V2_AUX_BMC @BASEBOARD_FAB2_LIB.BASEBOARD_FAB2(SCH_1):P1V2_AUX_BMC   I196 @BASEBOARD_FAB2_LIB.BASEBOARD_FAB2(SCH_1):PAGE149

R25W38 120R2F-GP_RCL_GP-120R2F-GP,64.A
     1 BMC_M_A0 @BASEBOARD_FAB2_LIB.BASEBOARD_FAB2(SCH_1):BMC_M_A0   I197 @BASEBOARD_FAB2_LIB.BASEBOARD_FAB2(SCH_1):PAGE149
     2 P1V2_AUX_BMC @BASEBOARD_FAB2_LIB.BASEBOARD_FAB2(SCH_1):P1V2_AUX_BMC   I197 @BASEBOARD_FAB2_LIB.BASEBOARD_FAB2(SCH_1):PAGE149

R25W39 120R2F-GP_RCL_GP-120R2F-GP,64.A
     1 BMC_M_A1 @BASEBOARD_FAB2_LIB.BASEBOARD_FAB2(SCH_1):BMC_M_A1   I198 @BASEBOARD_FAB2_LIB.BASEBOARD_FAB2(SCH_1):PAGE149
     2 P1V2_AUX_BMC @BASEBOARD_FAB2_LIB.BASEBOARD_FAB2(SCH_1):P1V2_AUX_BMC   I198 @BASEBOARD_FAB2_LIB.BASEBOARD_FAB2(SCH_1):PAGE149

R25W40 120R2F-GP_RCL_GP-120R2F-GP,64.A
     1 BMC_M_A2 @BASEBOARD_FAB2_LIB.BASEBOARD_FAB2(SCH_1):BMC_M_A2   I200 @BASEBOARD_FAB2_LIB.BASEBOARD_FAB2(SCH_1):PAGE149
     2 P1V2_AUX_BMC @BASEBOARD_FAB2_LIB.BASEBOARD_FAB2(SCH_1):P1V2_AUX_BMC   I200 @BASEBOARD_FAB2_LIB.BASEBOARD_FAB2(SCH_1):PAGE149

R25W41 120R2F-GP_RCL_GP-120R2F-GP,64.A
     1 BMC_M_A3 @BASEBOARD_FAB2_LIB.BASEBOARD_FAB2(SCH_1):BMC_M_A3   I199 @BASEBOARD_FAB2_LIB.BASEBOARD_FAB2(SCH_1):PAGE149
     2 P1V2_AUX_BMC @BASEBOARD_FAB2_LIB.BASEBOARD_FAB2(SCH_1):P1V2_AUX_BMC   I199 @BASEBOARD_FAB2_LIB.BASEBOARD_FAB2(SCH_1):PAGE149

R25W42 120R2F-GP_RCL_GP-120R2F-GP,64.A
     1 BMC_M_A4 @BASEBOARD_FAB2_LIB.BASEBOARD_FAB2(SCH_1):BMC_M_A4   I201 @BASEBOARD_FAB2_LIB.BASEBOARD_FAB2(SCH_1):PAGE149
     2 P1V2_AUX_BMC @BASEBOARD_FAB2_LIB.BASEBOARD_FAB2(SCH_1):P1V2_AUX_BMC   I201 @BASEBOARD_FAB2_LIB.BASEBOARD_FAB2(SCH_1):PAGE149

R25W43 120R2F-GP_RCL_GP-120R2F-GP,64.A
     1 BMC_M_A5 @BASEBOARD_FAB2_LIB.BASEBOARD_FAB2(SCH_1):BMC_M_A5   I202 @BASEBOARD_FAB2_LIB.BASEBOARD_FAB2(SCH_1):PAGE149
     2 P1V2_AUX_BMC @BASEBOARD_FAB2_LIB.BASEBOARD_FAB2(SCH_1):P1V2_AUX_BMC   I202 @BASEBOARD_FAB2_LIB.BASEBOARD_FAB2(SCH_1):PAGE149

R25W44 120R2F-GP_RCL_GP-120R2F-GP,64.A
     1 BMC_M_A6 @BASEBOARD_FAB2_LIB.BASEBOARD_FAB2(SCH_1):BMC_M_A6   I203 @BASEBOARD_FAB2_LIB.BASEBOARD_FAB2(SCH_1):PAGE149
     2 P1V2_AUX_BMC @BASEBOARD_FAB2_LIB.BASEBOARD_FAB2(SCH_1):P1V2_AUX_BMC   I203 @BASEBOARD_FAB2_LIB.BASEBOARD_FAB2(SCH_1):PAGE149

R25W45 120R2F-GP_RCL_GP-120R2F-GP,64.A
     1 BMC_M_A7 @BASEBOARD_FAB2_LIB.BASEBOARD_FAB2(SCH_1):BMC_M_A7   I204 @BASEBOARD_FAB2_LIB.BASEBOARD_FAB2(SCH_1):PAGE149
     2 P1V2_AUX_BMC @BASEBOARD_FAB2_LIB.BASEBOARD_FAB2(SCH_1):P1V2_AUX_BMC   I204 @BASEBOARD_FAB2_LIB.BASEBOARD_FAB2(SCH_1):PAGE149

R25W46 120R2F-GP_RCL_GP-120R2F-GP,64.A
     1 BMC_M_A8 @BASEBOARD_FAB2_LIB.BASEBOARD_FAB2(SCH_1):BMC_M_A8   I205 @BASEBOARD_FAB2_LIB.BASEBOARD_FAB2(SCH_1):PAGE149
     2 P1V2_AUX_BMC @BASEBOARD_FAB2_LIB.BASEBOARD_FAB2(SCH_1):P1V2_AUX_BMC   I205 @BASEBOARD_FAB2_LIB.BASEBOARD_FAB2(SCH_1):PAGE149

R25W47 120R2F-GP_RCL_GP-120R2F-GP,64.A
     1 BMC_M_A9 @BASEBOARD_FAB2_LIB.BASEBOARD_FAB2(SCH_1):BMC_M_A9   I206 @BASEBOARD_FAB2_LIB.BASEBOARD_FAB2(SCH_1):PAGE149
     2 P1V2_AUX_BMC @BASEBOARD_FAB2_LIB.BASEBOARD_FAB2(SCH_1):P1V2_AUX_BMC   I206 @BASEBOARD_FAB2_LIB.BASEBOARD_FAB2(SCH_1):PAGE149

R25W48 120R2F-GP_RCL_GP-120R2F-GP,64.A
     1 BMC_M_A10 @BASEBOARD_FAB2_LIB.BASEBOARD_FAB2(SCH_1):BMC_M_A10   I207 @BASEBOARD_FAB2_LIB.BASEBOARD_FAB2(SCH_1):PAGE149
     2 P1V2_AUX_BMC @BASEBOARD_FAB2_LIB.BASEBOARD_FAB2(SCH_1):P1V2_AUX_BMC   I207 @BASEBOARD_FAB2_LIB.BASEBOARD_FAB2(SCH_1):PAGE149

R25W49 120R2F-GP_RCL_GP-120R2F-GP,64.A
     1 BMC_M_A11 @BASEBOARD_FAB2_LIB.BASEBOARD_FAB2(SCH_1):BMC_M_A11   I208 @BASEBOARD_FAB2_LIB.BASEBOARD_FAB2(SCH_1):PAGE149
     2 P1V2_AUX_BMC @BASEBOARD_FAB2_LIB.BASEBOARD_FAB2(SCH_1):P1V2_AUX_BMC   I208 @BASEBOARD_FAB2_LIB.BASEBOARD_FAB2(SCH_1):PAGE149

R25W50 120R2F-GP_RCL_GP-120R2F-GP,64.A
     1 BMC_M_A12 @BASEBOARD_FAB2_LIB.BASEBOARD_FAB2(SCH_1):BMC_M_A12   I209 @BASEBOARD_FAB2_LIB.BASEBOARD_FAB2(SCH_1):PAGE149
     2 P1V2_AUX_BMC @BASEBOARD_FAB2_LIB.BASEBOARD_FAB2(SCH_1):P1V2_AUX_BMC   I209 @BASEBOARD_FAB2_LIB.BASEBOARD_FAB2(SCH_1):PAGE149

R25W51 120R2F-GP_RCL_GP-120R2F-GP,64.A
     1 BMC_M_A13 @BASEBOARD_FAB2_LIB.BASEBOARD_FAB2(SCH_1):BMC_M_A13   I210 @BASEBOARD_FAB2_LIB.BASEBOARD_FAB2(SCH_1):PAGE149
     2 P1V2_AUX_BMC @BASEBOARD_FAB2_LIB.BASEBOARD_FAB2(SCH_1):P1V2_AUX_BMC   I210 @BASEBOARD_FAB2_LIB.BASEBOARD_FAB2(SCH_1):PAGE149

R25W52 120R2F-GP_RCL_GP-120R2F-GP,64.A
     1 BMC_M_MACT_N @BASEBOARD_FAB2_LIB.BASEBOARD_FAB2(SCH_1):BMC_M_MACT_N   I211 @BASEBOARD_FAB2_LIB.BASEBOARD_FAB2(SCH_1):PAGE149
     2 P1V2_AUX_BMC @BASEBOARD_FAB2_LIB.BASEBOARD_FAB2(SCH_1):P1V2_AUX_BMC   I211 @BASEBOARD_FAB2_LIB.BASEBOARD_FAB2(SCH_1):PAGE149

R25W57 RES_0402-2.7K,1%,1/16W,CHIP,G2A
     1    GND @BASEBOARD_FAB2_LIB.BASEBOARD_FAB2(SCH_1):GND    I40 @BASEBOARD_FAB2_LIB.BASEBOARD_FAB2(SCH_1):PAGE147
     2 PD_ADCREXT @BASEBOARD_FAB2_LIB.BASEBOARD_FAB2(SCH_1):PD_ADCREXT    I40 @BASEBOARD_FAB2_LIB.BASEBOARD_FAB2(SCH_1):PAGE147

R25W58 RES_0402-2.7K,1%,1/16W,CHIP,G2A
     1 A_DACRSET @BASEBOARD_FAB2_LIB.BASEBOARD_FAB2(SCH_1):A_DACRSET    I73 @BASEBOARD_FAB2_LIB.BASEBOARD_FAB2(SCH_1):PAGE144
     2    GND @BASEBOARD_FAB2_LIB.BASEBOARD_FAB2(SCH_1):GND    I73 @BASEBOARD_FAB2_LIB.BASEBOARD_FAB2(SCH_1):PAGE144

R25W59 RES_0402-0.0,5%,1/16W,CHIP,G21A
     1 P3V3_STBY @BASEBOARD_FAB2_LIB.BASEBOARD_FAB2(SCH_1):P3V3_STBY    I16 @BASEBOARD_FAB2_LIB.BASEBOARD_FAB2(SCH_1):PAGE148
     2 VCCBAT_TW12 @BASEBOARD_FAB2_LIB.BASEBOARD_FAB2(SCH_1):VCCBAT_TW12    I16 @BASEBOARD_FAB2_LIB.BASEBOARD_FAB2(SCH_1):PAGE148

R25W60 RES_0402-100.0K,1%,1/16W,CHIP,A
     1 CLK_100M_BMC_PE_R_DN @BASEBOARD_FAB2_LIB.BASEBOARD_FAB2(SCH_1):CLK_100M_BMC_PE_R_DN    I34 @BASEBOARD_FAB2_LIB.BASEBOARD_FAB2(SCH_1):PAGE145
     2    GND @BASEBOARD_FAB2_LIB.BASEBOARD_FAB2(SCH_1):GND    I34 @BASEBOARD_FAB2_LIB.BASEBOARD_FAB2(SCH_1):PAGE145

R25W61 RES_0402-100.0K,1%,1/16W,CHIP,A
     1 CLK_100M_BMC_PE_R_DP @BASEBOARD_FAB2_LIB.BASEBOARD_FAB2(SCH_1):CLK_100M_BMC_PE_R_DP    I30 @BASEBOARD_FAB2_LIB.BASEBOARD_FAB2(SCH_1):PAGE145
     2    GND @BASEBOARD_FAB2_LIB.BASEBOARD_FAB2(SCH_1):GND    I30 @BASEBOARD_FAB2_LIB.BASEBOARD_FAB2(SCH_1):PAGE145

R25W62 RES_0402-100.0K,1%,1/16W,CHIP,A
     1 RST_PLTRST_BUF_N @BASEBOARD_FAB2_LIB.BASEBOARD_FAB2(SCH_1):RST_PLTRST_BUF_N    I31 @BASEBOARD_FAB2_LIB.BASEBOARD_FAB2(SCH_1):PAGE145
     2    GND @BASEBOARD_FAB2_LIB.BASEBOARD_FAB2(SCH_1):GND    I31 @BASEBOARD_FAB2_LIB.BASEBOARD_FAB2(SCH_1):PAGE145

R25W63 RES_0402-100.0K,1%,1/16W,CHIP,A
     1 FM_PE_BMC_WAKE_N @BASEBOARD_FAB2_LIB.BASEBOARD_FAB2(SCH_1):FM_PE_BMC_WAKE_N    I65 @BASEBOARD_FAB2_LIB.BASEBOARD_FAB2(SCH_1):PAGE146
     2    GND @BASEBOARD_FAB2_LIB.BASEBOARD_FAB2(SCH_1):GND    I65 @BASEBOARD_FAB2_LIB.BASEBOARD_FAB2(SCH_1):PAGE146

R25W64 RES_0402-100.0K,1%,1/16W,CHIP,A
     1 P2E_SSB_BMC_TX_C_DP @BASEBOARD_FAB2_LIB.BASEBOARD_FAB2(SCH_1):P2E_SSB_BMC_TX_C_DP    I36 @BASEBOARD_FAB2_LIB.BASEBOARD_FAB2(SCH_1):PAGE145
     2    GND @BASEBOARD_FAB2_LIB.BASEBOARD_FAB2(SCH_1):GND    I36 @BASEBOARD_FAB2_LIB.BASEBOARD_FAB2(SCH_1):PAGE145

R25W65 RES_0402-100.0K,1%,1/16W,CHIP,A
     1 P2E_SSB_BMC_TX_C_DN @BASEBOARD_FAB2_LIB.BASEBOARD_FAB2(SCH_1):P2E_SSB_BMC_TX_C_DN    I38 @BASEBOARD_FAB2_LIB.BASEBOARD_FAB2(SCH_1):PAGE145
     2    GND @BASEBOARD_FAB2_LIB.BASEBOARD_FAB2(SCH_1):GND    I38 @BASEBOARD_FAB2_LIB.BASEBOARD_FAB2(SCH_1):PAGE145

R25W66 RES_0402-100.0K,1%,1/16W,CHIP,A
     1 CLK_24M_BMC_LPC_R1 @BASEBOARD_FAB2_LIB.BASEBOARD_FAB2(SCH_1):CLK_24M_BMC_LPC_R1    I76 @BASEBOARD_FAB2_LIB.BASEBOARD_FAB2(SCH_1):PAGE146
     2    GND @BASEBOARD_FAB2_LIB.BASEBOARD_FAB2(SCH_1):GND    I76 @BASEBOARD_FAB2_LIB.BASEBOARD_FAB2(SCH_1):PAGE146

R25W67 RES_0402-10.0K,1%,1/16W,EMPTY,A
     1 PD_PEREXT @BASEBOARD_FAB2_LIB.BASEBOARD_FAB2(SCH_1):PD_PEREXT    I46 @BASEBOARD_FAB2_LIB.BASEBOARD_FAB2(SCH_1):PAGE145
     2    GND @BASEBOARD_FAB2_LIB.BASEBOARD_FAB2(SCH_1):GND    I46 @BASEBOARD_FAB2_LIB.BASEBOARD_FAB2(SCH_1):PAGE145

R25W68 RES_0402-33.2,1%,1/16W,CHIP,G2A
     1 LPC_LAD3_IO3 @BASEBOARD_FAB2_LIB.BASEBOARD_FAB2(SCH_1):LPC_LAD3_IO3    I84 @BASEBOARD_FAB2_LIB.BASEBOARD_FAB2(SCH_1):PAGE146
     2 LPC_LAD3_IO3_R @BASEBOARD_FAB2_LIB.BASEBOARD_FAB2(SCH_1):LPC_LAD3_IO3_R    I84 @BASEBOARD_FAB2_LIB.BASEBOARD_FAB2(SCH_1):PAGE146

R25W69 RES_0402-33.2,1%,1/16W,CHIP,G2A
     1 LPC_LAD1_IO1 @BASEBOARD_FAB2_LIB.BASEBOARD_FAB2(SCH_1):LPC_LAD1_IO1    I85 @BASEBOARD_FAB2_LIB.BASEBOARD_FAB2(SCH_1):PAGE146
     2 LPC_LAD1_IO1_R @BASEBOARD_FAB2_LIB.BASEBOARD_FAB2(SCH_1):LPC_LAD1_IO1_R    I85 @BASEBOARD_FAB2_LIB.BASEBOARD_FAB2(SCH_1):PAGE146

R25W70 RES_0402-33.2,1%,1/16W,CHIP,G2A
     1 FM_CPU0_FIVR_FAULT_LVT3_R_N @BASEBOARD_FAB2_LIB.BASEBOARD_FAB2(SCH_1):FM_CPU0_FIVR_FAULT_LVT3_R_N    I64 @BASEBOARD_FAB2_LIB.BASEBOARD_FAB2(SCH_1):PAGE146
     2 FM_CPU0_FIVR_FAULT_LVT3_N @BASEBOARD_FAB2_LIB.BASEBOARD_FAB2(SCH_1):FM_CPU0_FIVR_FAULT_LVT3_N    I64 @BASEBOARD_FAB2_LIB.BASEBOARD_FAB2(SCH_1):PAGE146

R25W71 RES_0402-33.2,1%,1/16W,CHIP,G2A
     1 CLK_24M_BMC_LPC @BASEBOARD_FAB2_LIB.BASEBOARD_FAB2(SCH_1):CLK_24M_BMC_LPC    I72 @BASEBOARD_FAB2_LIB.BASEBOARD_FAB2(SCH_1):PAGE146
     2 CLK_24M_BMC_LPC_R1 @BASEBOARD_FAB2_LIB.BASEBOARD_FAB2(SCH_1):CLK_24M_BMC_LPC_R1    I72 @BASEBOARD_FAB2_LIB.BASEBOARD_FAB2(SCH_1):PAGE146

R25W72 RES_0402-33.2,1%,1/16W,CHIP,G2A
     1 LPC_LFRAME_N_CS0_N @BASEBOARD_FAB2_LIB.BASEBOARD_FAB2(SCH_1):LPC_LFRAME_N_CS0_N    I71 @BASEBOARD_FAB2_LIB.BASEBOARD_FAB2(SCH_1):PAGE146
     2 LPC_LFRAME_N_CS0_R_N @BASEBOARD_FAB2_LIB.BASEBOARD_FAB2(SCH_1):LPC_LFRAME_N_CS0_R_N    I71 @BASEBOARD_FAB2_LIB.BASEBOARD_FAB2(SCH_1):PAGE146

R25W73 RES_0402-33.2,1%,1/16W,CHIP,G2A
     1 IRQ_LPC_SERIRQ_N @BASEBOARD_FAB2_LIB.BASEBOARD_FAB2(SCH_1):IRQ_LPC_SERIRQ_N    I73 @BASEBOARD_FAB2_LIB.BASEBOARD_FAB2(SCH_1):PAGE146
     2 IRQ_LPC_SERIRQ_R @BASEBOARD_FAB2_LIB.BASEBOARD_FAB2(SCH_1):IRQ_LPC_SERIRQ_R    I73 @BASEBOARD_FAB2_LIB.BASEBOARD_FAB2(SCH_1):PAGE146

R25W74 RES_0402-0.0,5%,1/16W,CHIP,G21A
     1 RST_PLTRST_BUF_N @BASEBOARD_FAB2_LIB.BASEBOARD_FAB2(SCH_1):RST_PLTRST_BUF_N    I70 @BASEBOARD_FAB2_LIB.BASEBOARD_FAB2(SCH_1):PAGE146
     2 RST_BMC_LVC3_N @BASEBOARD_FAB2_LIB.BASEBOARD_FAB2(SCH_1):RST_BMC_LVC3_N    I70 @BASEBOARD_FAB2_LIB.BASEBOARD_FAB2(SCH_1):PAGE146

R25W75 RES_0402-33.2,1%,1/16W,CHIP,G2A
     1 FM_CPU1_FIVR_FAULT_LVT3_N @BASEBOARD_FAB2_LIB.BASEBOARD_FAB2(SCH_1):FM_CPU1_FIVR_FAULT_LVT3_N    I23 @BASEBOARD_FAB2_LIB.BASEBOARD_FAB2(SCH_1):PAGE148
     2 FM_CPU1_FIVR_FAULT_LVT3_R_N @BASEBOARD_FAB2_LIB.BASEBOARD_FAB2(SCH_1):FM_CPU1_FIVR_FAULT_LVT3_R_N    I23 @BASEBOARD_FAB2_LIB.BASEBOARD_FAB2(SCH_1):PAGE148

R25W78 RES_0402-22.1,1.0%,1/16W,CHIP,A
     1 SPI_BMC_BT_CS_N @BASEBOARD_FAB2_LIB.BASEBOARD_FAB2(SCH_1):SPI_BMC_BT_CS_N    I69 @BASEBOARD_FAB2_LIB.BASEBOARD_FAB2(SCH_1):PAGE146
     2 SPI_BMC_BT_CS_R_N @BASEBOARD_FAB2_LIB.BASEBOARD_FAB2(SCH_1):SPI_BMC_BT_CS_R_N    I69 @BASEBOARD_FAB2_LIB.BASEBOARD_FAB2(SCH_1):PAGE146

R25W79 RES_0402-10.0K,1%,1/16W,CHIP,GA
     1 P3V3_STBY @BASEBOARD_FAB2_LIB.BASEBOARD_FAB2(SCH_1):P3V3_STBY    I42 @BASEBOARD_FAB2_LIB.BASEBOARD_FAB2(SCH_1):PAGE147
     2 RMII_SPRNGVLLE_BMC_PCH_RXD0 @BASEBOARD_FAB2_LIB.BASEBOARD_FAB2(SCH_1):RMII_SPRNGVLLE_BMC_PCH_RXD0    I42 @BASEBOARD_FAB2_LIB.BASEBOARD_FAB2(SCH_1):PAGE147

R25W80 RES_0402-10.0K,1%,1/16W,CHIP,GA
     1 P3V3_STBY @BASEBOARD_FAB2_LIB.BASEBOARD_FAB2(SCH_1):P3V3_STBY    I43 @BASEBOARD_FAB2_LIB.BASEBOARD_FAB2(SCH_1):PAGE147
     2 RMII_SPRNGVLLE_BMC_PCH_RXD1 @BASEBOARD_FAB2_LIB.BASEBOARD_FAB2(SCH_1):RMII_SPRNGVLLE_BMC_PCH_RXD1    I43 @BASEBOARD_FAB2_LIB.BASEBOARD_FAB2(SCH_1):PAGE147

R25W81 RES_0402-33.2,1%,1/16W,CHIP,G2A
     1 SPI_BMC_BT_CLK @BASEBOARD_FAB2_LIB.BASEBOARD_FAB2(SCH_1):SPI_BMC_BT_CLK    I67 @BASEBOARD_FAB2_LIB.BASEBOARD_FAB2(SCH_1):PAGE146
     2 SPI_BMC_BT_CLK_R @BASEBOARD_FAB2_LIB.BASEBOARD_FAB2(SCH_1):SPI_BMC_BT_CLK_R    I67 @BASEBOARD_FAB2_LIB.BASEBOARD_FAB2(SCH_1):PAGE146

R25W82 RES_0402-33.2,1%,1/16W,CHIP,G2A
     1 SPI_BMC_BT_DO @BASEBOARD_FAB2_LIB.BASEBOARD_FAB2(SCH_1):SPI_BMC_BT_DO    I68 @BASEBOARD_FAB2_LIB.BASEBOARD_FAB2(SCH_1):PAGE146
     2 SPI_BMC_BT_DO_R @BASEBOARD_FAB2_LIB.BASEBOARD_FAB2(SCH_1):SPI_BMC_BT_DO_R    I68 @BASEBOARD_FAB2_LIB.BASEBOARD_FAB2(SCH_1):PAGE146

R25W83 RES_0402-0.0,5%,1/16W,CHIP,G21A
     1 FM_BMC_NMI_N @BASEBOARD_FAB2_LIB.BASEBOARD_FAB2(SCH_1):FM_BMC_NMI_N    I26 @BASEBOARD_FAB2_LIB.BASEBOARD_FAB2(SCH_1):PAGE146
     2 FM_BMC_NMI_N_R @BASEBOARD_FAB2_LIB.BASEBOARD_FAB2(SCH_1):FM_BMC_NMI_N_R    I26 @BASEBOARD_FAB2_LIB.BASEBOARD_FAB2(SCH_1):PAGE146

R25W84 RES_0402-0.0,5%,1/16W,CHIP,G21A
     1 IRQ_SML0_ALERT_N @BASEBOARD_FAB2_LIB.BASEBOARD_FAB2(SCH_1):IRQ_SML0_ALERT_N    I27 @BASEBOARD_FAB2_LIB.BASEBOARD_FAB2(SCH_1):PAGE146
     2 FM_BMC_NMI_N_R @BASEBOARD_FAB2_LIB.BASEBOARD_FAB2(SCH_1):FM_BMC_NMI_N_R    I27 @BASEBOARD_FAB2_LIB.BASEBOARD_FAB2(SCH_1):PAGE146

R25W85 RES_0402-22.1,1.0%,1/16W,CHIP,A
     1 RMII_BMC_OCP_TXEN_R @BASEBOARD_FAB2_LIB.BASEBOARD_FAB2(SCH_1):RMII_BMC_OCP_TXEN_R    I23 @BASEBOARD_FAB2_LIB.BASEBOARD_FAB2(SCH_1):PAGE147
     2 RMII_BMC_OCP_TXEN @BASEBOARD_FAB2_LIB.BASEBOARD_FAB2(SCH_1):RMII_BMC_OCP_TXEN    I23 @BASEBOARD_FAB2_LIB.BASEBOARD_FAB2(SCH_1):PAGE147

R25W86 RES_0402-22.1,1.0%,1/16W,CHIP,A
     1 RMII_BMC_OCP_TXD0_R @BASEBOARD_FAB2_LIB.BASEBOARD_FAB2(SCH_1):RMII_BMC_OCP_TXD0_R    I24 @BASEBOARD_FAB2_LIB.BASEBOARD_FAB2(SCH_1):PAGE147
     2 RMII_BMC_OCP_TXD0 @BASEBOARD_FAB2_LIB.BASEBOARD_FAB2(SCH_1):RMII_BMC_OCP_TXD0    I24 @BASEBOARD_FAB2_LIB.BASEBOARD_FAB2(SCH_1):PAGE147

R25W87 RES_0402-22.1,1.0%,1/16W,CHIP,A
     1 RMII_BMC_OCP_TXD1_R @BASEBOARD_FAB2_LIB.BASEBOARD_FAB2(SCH_1):RMII_BMC_OCP_TXD1_R    I25 @BASEBOARD_FAB2_LIB.BASEBOARD_FAB2(SCH_1):PAGE147
     2 RMII_BMC_OCP_TXD1 @BASEBOARD_FAB2_LIB.BASEBOARD_FAB2(SCH_1):RMII_BMC_OCP_TXD1    I25 @BASEBOARD_FAB2_LIB.BASEBOARD_FAB2(SCH_1):PAGE147

R25W88 RES_0402-22.1,1.0%,1/16W,CHIP,A
     1 RMII_BMC_SPRNGVLLE_TXEN_R @BASEBOARD_FAB2_LIB.BASEBOARD_FAB2(SCH_1):RMII_BMC_SPRNGVLLE_TXEN_R     I8 @BASEBOARD_FAB2_LIB.BASEBOARD_FAB2(SCH_1):PAGE147
     2 RMII_BMC_PCH_SPRNGVLLE_TXEN @BASEBOARD_FAB2_LIB.BASEBOARD_FAB2(SCH_1):RMII_BMC_PCH_SPRNGVLLE_TXEN     I8 @BASEBOARD_FAB2_LIB.BASEBOARD_FAB2(SCH_1):PAGE147

R25W89 RES_0402-22.1,1.0%,1/16W,CHIP,A
     1 RMII_BMC_PCH_SPRNGVLLE_TXD0_R @BASEBOARD_FAB2_LIB.BASEBOARD_FAB2(SCH_1):RMII_BMC_PCH_SPRNGVLLE_TXD0_R    I22 @BASEBOARD_FAB2_LIB.BASEBOARD_FAB2(SCH_1):PAGE147
     2 RMII_BMC_PCH_SPRNGVLLE_TXD0 @BASEBOARD_FAB2_LIB.BASEBOARD_FAB2(SCH_1):RMII_BMC_PCH_SPRNGVLLE_TXD0    I22 @BASEBOARD_FAB2_LIB.BASEBOARD_FAB2(SCH_1):PAGE147

R25W90 RES_0402-22.1,1.0%,1/16W,CHIP,A
     1 RMII_BMC_PCH_SPRNGVLLE_TXD1_R @BASEBOARD_FAB2_LIB.BASEBOARD_FAB2(SCH_1):RMII_BMC_PCH_SPRNGVLLE_TXD1_R    I21 @BASEBOARD_FAB2_LIB.BASEBOARD_FAB2(SCH_1):PAGE147
     2 RMII_BMC_PCH_SPRNGVLLE_TXD1 @BASEBOARD_FAB2_LIB.BASEBOARD_FAB2(SCH_1):RMII_BMC_PCH_SPRNGVLLE_TXD1    I21 @BASEBOARD_FAB2_LIB.BASEBOARD_FAB2(SCH_1):PAGE147

R25W91 RES_0402-10.0K,1%,1/16W,CHIP,GA
     1 P3V3_STBY @BASEBOARD_FAB2_LIB.BASEBOARD_FAB2(SCH_1):P3V3_STBY     I4 @BASEBOARD_FAB2_LIB.BASEBOARD_FAB2(SCH_1):PAGE147
     2 RMII_BMC_PCH_SPRNGVLLE_TXD0 @BASEBOARD_FAB2_LIB.BASEBOARD_FAB2(SCH_1):RMII_BMC_PCH_SPRNGVLLE_TXD0     I4 @BASEBOARD_FAB2_LIB.BASEBOARD_FAB2(SCH_1):PAGE147

R25W92 RES_0402-10.0K,1%,1/16W,CHIP,GA
     1 P3V3_STBY @BASEBOARD_FAB2_LIB.BASEBOARD_FAB2(SCH_1):P3V3_STBY     I3 @BASEBOARD_FAB2_LIB.BASEBOARD_FAB2(SCH_1):PAGE147
     2 RMII_BMC_PCH_SPRNGVLLE_TXD1 @BASEBOARD_FAB2_LIB.BASEBOARD_FAB2(SCH_1):RMII_BMC_PCH_SPRNGVLLE_TXD1     I3 @BASEBOARD_FAB2_LIB.BASEBOARD_FAB2(SCH_1):PAGE147

R25W93 0R3J-0-U-GP_RCL_GP-0R3J-0-U-GPA
     1 P3V3_STBY @BASEBOARD_FAB2_LIB.BASEBOARD_FAB2(SCH_1):P3V3_STBY    I57 @BASEBOARD_FAB2_LIB.BASEBOARD_FAB2(SCH_1):PAGE150
     2 VCC_DACAV3V3 @BASEBOARD_FAB2_LIB.BASEBOARD_FAB2(SCH_1):VCC_DACAV3V3    I57 @BASEBOARD_FAB2_LIB.BASEBOARD_FAB2(SCH_1):PAGE150

R25W94 RES_0402-4.75K,1%,1/16W,CHIP,GA
     1 P3V3_STBY @BASEBOARD_FAB2_LIB.BASEBOARD_FAB2(SCH_1):P3V3_STBY     I9 @BASEBOARD_FAB2_LIB.BASEBOARD_FAB2(SCH_1):PAGE151
     2 SPI_BMC_BT_CS_N @BASEBOARD_FAB2_LIB.BASEBOARD_FAB2(SCH_1):SPI_BMC_BT_CS_N     I9 @BASEBOARD_FAB2_LIB.BASEBOARD_FAB2(SCH_1):PAGE151

R25W95 RES_0402-4.75K,1%,1/16W,CHIP,GA
     1 P3V3_STBY @BASEBOARD_FAB2_LIB.BASEBOARD_FAB2(SCH_1):P3V3_STBY     I2 @BASEBOARD_FAB2_LIB.BASEBOARD_FAB2(SCH_1):PAGE151
     2 SPI_BMC_BT_CLK @BASEBOARD_FAB2_LIB.BASEBOARD_FAB2(SCH_1):SPI_BMC_BT_CLK     I2 @BASEBOARD_FAB2_LIB.BASEBOARD_FAB2(SCH_1):PAGE151

R25W96 RES_0402-4.75K,1%,1/16W,CHIP,GA
     1 P3V3_STBY @BASEBOARD_FAB2_LIB.BASEBOARD_FAB2(SCH_1):P3V3_STBY    I10 @BASEBOARD_FAB2_LIB.BASEBOARD_FAB2(SCH_1):PAGE151
     2 SPI_BMC_BT_DO @BASEBOARD_FAB2_LIB.BASEBOARD_FAB2(SCH_1):SPI_BMC_BT_DO    I10 @BASEBOARD_FAB2_LIB.BASEBOARD_FAB2(SCH_1):PAGE151

R25W97 RES_0402-4.75K,1%,1/16W,EMPTY,A
     1 P3V3_STBY @BASEBOARD_FAB2_LIB.BASEBOARD_FAB2(SCH_1):P3V3_STBY    I11 @BASEBOARD_FAB2_LIB.BASEBOARD_FAB2(SCH_1):PAGE151
     2 SPI_BMC_BT_DI @BASEBOARD_FAB2_LIB.BASEBOARD_FAB2(SCH_1):SPI_BMC_BT_DI    I11 @BASEBOARD_FAB2_LIB.BASEBOARD_FAB2(SCH_1):PAGE151

R25W98 RES_0402-4.75K,1%,1/16W,CHIP,GA
     1 P3V3_STBY @BASEBOARD_FAB2_LIB.BASEBOARD_FAB2(SCH_1):P3V3_STBY    I12 @BASEBOARD_FAB2_LIB.BASEBOARD_FAB2(SCH_1):PAGE151
     2 H_CPU0_MEMDEF_MEMHOT_LVT3_BMC_N @BASEBOARD_FAB2_LIB.BASEBOARD_FAB2(SCH_1):H_CPU0_MEMDEF_MEMHOT_LVT3_BMC_N    I12 @BASEBOARD_FAB2_LIB.BASEBOARD_FAB2(SCH_1):PAGE151

R25W99 RES_0402-4.75K,1%,1/16W,EMPTY,A
     1 P3V3_STBY @BASEBOARD_FAB2_LIB.BASEBOARD_FAB2(SCH_1):P3V3_STBY    I14 @BASEBOARD_FAB2_LIB.BASEBOARD_FAB2(SCH_1):PAGE151
     2 FP_PWR_ID_LED_N @BASEBOARD_FAB2_LIB.BASEBOARD_FAB2(SCH_1):FP_PWR_ID_LED_N    I14 @BASEBOARD_FAB2_LIB.BASEBOARD_FAB2(SCH_1):PAGE151

R25W100 RES_0402-4.75K,1%,1/16W,CHIP,GA
     1 P3V3_STBY @BASEBOARD_FAB2_LIB.BASEBOARD_FAB2(SCH_1):P3V3_STBY    I13 @BASEBOARD_FAB2_LIB.BASEBOARD_FAB2(SCH_1):PAGE151
     2 GPIOS7 @BASEBOARD_FAB2_LIB.BASEBOARD_FAB2(SCH_1):GPIOS7    I13 @BASEBOARD_FAB2_LIB.BASEBOARD_FAB2(SCH_1):PAGE151

R25W101 RES_0402-4.75K,1%,1/16W,EMPTY,A
     1 P3V3_STBY @BASEBOARD_FAB2_LIB.BASEBOARD_FAB2(SCH_1):P3V3_STBY    I27 @BASEBOARD_FAB2_LIB.BASEBOARD_FAB2(SCH_1):PAGE151
     2 HSC_SMBUS_SWITCH_EN @BASEBOARD_FAB2_LIB.BASEBOARD_FAB2(SCH_1):HSC_SMBUS_SWITCH_EN    I27 @BASEBOARD_FAB2_LIB.BASEBOARD_FAB2(SCH_1):PAGE151

R25W102 RES_0402-4.75K,1%,1/16W,CHIP,GA
     1 P3V3_STBY @BASEBOARD_FAB2_LIB.BASEBOARD_FAB2(SCH_1):P3V3_STBY    I28 @BASEBOARD_FAB2_LIB.BASEBOARD_FAB2(SCH_1):PAGE151
     2 FM_CPU0_THERMTRIP_LATCH_LVT3_N @BASEBOARD_FAB2_LIB.BASEBOARD_FAB2(SCH_1):FM_CPU0_THERMTRIP_LATCH_LVT3_N    I28 @BASEBOARD_FAB2_LIB.BASEBOARD_FAB2(SCH_1):PAGE151

R25W103 RES_0402-4.75K,1%,1/16W,EMPTY,A
     1 P3V3_STBY @BASEBOARD_FAB2_LIB.BASEBOARD_FAB2(SCH_1):P3V3_STBY    I29 @BASEBOARD_FAB2_LIB.BASEBOARD_FAB2(SCH_1):PAGE151
     2 H_CPU0_MEMABC_MEMHOT_LVT3_BMC_N @BASEBOARD_FAB2_LIB.BASEBOARD_FAB2(SCH_1):H_CPU0_MEMABC_MEMHOT_LVT3_BMC_N    I29 @BASEBOARD_FAB2_LIB.BASEBOARD_FAB2(SCH_1):PAGE151

R25W104 RES_0402-4.75K,1%,1/16W,EMPTY,A
     1 P3V3_STBY @BASEBOARD_FAB2_LIB.BASEBOARD_FAB2(SCH_1):P3V3_STBY    I30 @BASEBOARD_FAB2_LIB.BASEBOARD_FAB2(SCH_1):PAGE151
     2 FM_CPU1_PROC_ID0 @BASEBOARD_FAB2_LIB.BASEBOARD_FAB2(SCH_1):FM_CPU1_PROC_ID0    I30 @BASEBOARD_FAB2_LIB.BASEBOARD_FAB2(SCH_1):PAGE151

R25W105 RES_0402-4.75K,1%,1/16W,EMPTY,A
     1 P3V3_STBY @BASEBOARD_FAB2_LIB.BASEBOARD_FAB2(SCH_1):P3V3_STBY    I31 @BASEBOARD_FAB2_LIB.BASEBOARD_FAB2(SCH_1):PAGE151
     2 JTAG_BMC_TRST_N @BASEBOARD_FAB2_LIB.BASEBOARD_FAB2(SCH_1):JTAG_BMC_TRST_N    I31 @BASEBOARD_FAB2_LIB.BASEBOARD_FAB2(SCH_1):PAGE151

R25W106 RES_0402-4.75K,1%,1/16W,EMPTY,A
     1 P3V3_STBY @BASEBOARD_FAB2_LIB.BASEBOARD_FAB2(SCH_1):P3V3_STBY    I32 @BASEBOARD_FAB2_LIB.BASEBOARD_FAB2(SCH_1):PAGE151
     2 RMII_BMC_OCP_TXEN @BASEBOARD_FAB2_LIB.BASEBOARD_FAB2(SCH_1):RMII_BMC_OCP_TXEN    I32 @BASEBOARD_FAB2_LIB.BASEBOARD_FAB2(SCH_1):PAGE151

R25W107 RES_0402-4.75K,1%,1/16W,EMPTY,A
     1 P3V3_STBY @BASEBOARD_FAB2_LIB.BASEBOARD_FAB2(SCH_1):P3V3_STBY    I33 @BASEBOARD_FAB2_LIB.BASEBOARD_FAB2(SCH_1):PAGE151
     2 RMII_BMC_OCP_TXD0_R @BASEBOARD_FAB2_LIB.BASEBOARD_FAB2(SCH_1):RMII_BMC_OCP_TXD0_R    I33 @BASEBOARD_FAB2_LIB.BASEBOARD_FAB2(SCH_1):PAGE151

R25W108 RES_0402-4.75K,1%,1/16W,CHIP,GA
     1 P3V3_STBY @BASEBOARD_FAB2_LIB.BASEBOARD_FAB2(SCH_1):P3V3_STBY    I34 @BASEBOARD_FAB2_LIB.BASEBOARD_FAB2(SCH_1):PAGE151
     2 RMII_BMC_OCP_TXD1_R @BASEBOARD_FAB2_LIB.BASEBOARD_FAB2(SCH_1):RMII_BMC_OCP_TXD1_R    I34 @BASEBOARD_FAB2_LIB.BASEBOARD_FAB2(SCH_1):PAGE151

R25W109 RES_0402-4.75K,1%,1/16W,EMPTY,A
     1 P3V3_STBY @BASEBOARD_FAB2_LIB.BASEBOARD_FAB2(SCH_1):P3V3_STBY    I35 @BASEBOARD_FAB2_LIB.BASEBOARD_FAB2(SCH_1):PAGE151
     2 TP_RGMII2TXD3_GPIOT5 @BASEBOARD_FAB2_LIB.BASEBOARD_FAB2(SCH_1):TP_RGMII2TXD3_GPIOT5    I35 @BASEBOARD_FAB2_LIB.BASEBOARD_FAB2(SCH_1):PAGE151

R25W110 RES_0402-4.75K,1%,1/16W,CHIP,GA
     1 P3V3_STBY @BASEBOARD_FAB2_LIB.BASEBOARD_FAB2(SCH_1):P3V3_STBY    I36 @BASEBOARD_FAB2_LIB.BASEBOARD_FAB2(SCH_1):PAGE151
     2 TP_RGMII2TXD2_GPIOT4 @BASEBOARD_FAB2_LIB.BASEBOARD_FAB2(SCH_1):TP_RGMII2TXD2_GPIOT4    I36 @BASEBOARD_FAB2_LIB.BASEBOARD_FAB2(SCH_1):PAGE151

R25W111 RES_0402-4.75K,1%,1/16W,EMPTY,A
     1 P3V3_STBY @BASEBOARD_FAB2_LIB.BASEBOARD_FAB2(SCH_1):P3V3_STBY    I43 @BASEBOARD_FAB2_LIB.BASEBOARD_FAB2(SCH_1):PAGE151
     2 RMII_BMC_PCH_SPRNGVLLE_TXEN @BASEBOARD_FAB2_LIB.BASEBOARD_FAB2(SCH_1):RMII_BMC_PCH_SPRNGVLLE_TXEN    I43 @BASEBOARD_FAB2_LIB.BASEBOARD_FAB2(SCH_1):PAGE151

R25W112 RES_0402-4.75K,1%,1/16W,EMPTY,A
     1 P3V3_STBY @BASEBOARD_FAB2_LIB.BASEBOARD_FAB2(SCH_1):P3V3_STBY    I44 @BASEBOARD_FAB2_LIB.BASEBOARD_FAB2(SCH_1):PAGE151
     2 RMII_BMC_PCH_SPRNGVLLE_TXD0_R @BASEBOARD_FAB2_LIB.BASEBOARD_FAB2(SCH_1):RMII_BMC_PCH_SPRNGVLLE_TXD0_R    I44 @BASEBOARD_FAB2_LIB.BASEBOARD_FAB2(SCH_1):PAGE151

R25W113 RES_0402-4.75K,1%,1/16W,EMPTY,A
     1 P3V3_STBY @BASEBOARD_FAB2_LIB.BASEBOARD_FAB2(SCH_1):P3V3_STBY    I45 @BASEBOARD_FAB2_LIB.BASEBOARD_FAB2(SCH_1):PAGE151
     2 RMII_BMC_PCH_SPRNGVLLE_TXD1_R @BASEBOARD_FAB2_LIB.BASEBOARD_FAB2(SCH_1):RMII_BMC_PCH_SPRNGVLLE_TXD1_R    I45 @BASEBOARD_FAB2_LIB.BASEBOARD_FAB2(SCH_1):PAGE151

R25W114 RES_0402-4.75K,1%,1/16W,EMPTY,A
     1 P3V3_STBY @BASEBOARD_FAB2_LIB.BASEBOARD_FAB2(SCH_1):P3V3_STBY    I46 @BASEBOARD_FAB2_LIB.BASEBOARD_FAB2(SCH_1):PAGE151
     2 TP_RGMII1TXD2_GPIOT4 @BASEBOARD_FAB2_LIB.BASEBOARD_FAB2(SCH_1):TP_RGMII1TXD2_GPIOT4    I46 @BASEBOARD_FAB2_LIB.BASEBOARD_FAB2(SCH_1):PAGE151

R25W115 RES_0402-4.75K,1%,1/16W,CHIP,GA
     1 P3V3_STBY @BASEBOARD_FAB2_LIB.BASEBOARD_FAB2(SCH_1):P3V3_STBY    I47 @BASEBOARD_FAB2_LIB.BASEBOARD_FAB2(SCH_1):PAGE151
     2 TP_RGMII1TXD3_GPIOT5 @BASEBOARD_FAB2_LIB.BASEBOARD_FAB2(SCH_1):TP_RGMII1TXD3_GPIOT5    I47 @BASEBOARD_FAB2_LIB.BASEBOARD_FAB2(SCH_1):PAGE151

R25W116 RES_0402-3.32K,1%,1/16W,CHIP,GA
     1    GND @BASEBOARD_FAB2_LIB.BASEBOARD_FAB2(SCH_1):GND    I48 @BASEBOARD_FAB2_LIB.BASEBOARD_FAB2(SCH_1):PAGE151
     2 UART_BMC_TXD5 @BASEBOARD_FAB2_LIB.BASEBOARD_FAB2(SCH_1):UART_BMC_TXD5    I48 @BASEBOARD_FAB2_LIB.BASEBOARD_FAB2(SCH_1):PAGE151

R25W117 RES_0402-240,1.0%,1/16W,CHIP,GA
     1 BMC_ZQ @BASEBOARD_FAB2_LIB.BASEBOARD_FAB2(SCH_1):BMC_ZQ    I55 @BASEBOARD_FAB2_LIB.BASEBOARD_FAB2(SCH_1):PAGE149
     2    GND @BASEBOARD_FAB2_LIB.BASEBOARD_FAB2(SCH_1):GND    I55 @BASEBOARD_FAB2_LIB.BASEBOARD_FAB2(SCH_1):PAGE149

R25W118 RES_0402-4.75K,1%,1/16W,EMPTY,A
     1 BMC_M_PAR @BASEBOARD_FAB2_LIB.BASEBOARD_FAB2(SCH_1):BMC_M_PAR   I122 @BASEBOARD_FAB2_LIB.BASEBOARD_FAB2(SCH_1):PAGE149
     2    GND @BASEBOARD_FAB2_LIB.BASEBOARD_FAB2(SCH_1):GND   I122 @BASEBOARD_FAB2_LIB.BASEBOARD_FAB2(SCH_1):PAGE149

R25W119 RES_0402-4.75K,1%,1/16W,CHIP,GA
     1 P1V2_AUX_BMC @BASEBOARD_FAB2_LIB.BASEBOARD_FAB2(SCH_1):P1V2_AUX_BMC   I120 @BASEBOARD_FAB2_LIB.BASEBOARD_FAB2(SCH_1):PAGE149
     2 BMC_M_PAR @BASEBOARD_FAB2_LIB.BASEBOARD_FAB2(SCH_1):BMC_M_PAR   I120 @BASEBOARD_FAB2_LIB.BASEBOARD_FAB2(SCH_1):PAGE149

R25W120 0R3J-0-U-GP_RCL_GP-0R3J-0-U-GPA
     1 P3V3_STBY @BASEBOARD_FAB2_LIB.BASEBOARD_FAB2(SCH_1):P3V3_STBY     I7 @BASEBOARD_FAB2_LIB.BASEBOARD_FAB2(SCH_1):PAGE150
     2 P3V3_USB2A_ALG @BASEBOARD_FAB2_LIB.BASEBOARD_FAB2(SCH_1):P3V3_USB2A_ALG     I7 @BASEBOARD_FAB2_LIB.BASEBOARD_FAB2(SCH_1):PAGE150

R760 RES_0402-0.0,5%,1/16W,CHIP,G21A
     1 P3E_CPU0_PE1_PCH_RXN<15> @BASEBOARD_FAB2_LIB.BASEBOARD_FAB2(SCH_1):P3E_CPU0_PE1_PCH_RXN(15)    I64 @BASEBOARD_FAB2_LIB.BASEBOARD_FAB2(SCH_1):PAGE244
     2 P3E_CPU0_PE1_PCH_CON_RXN<15> @BASEBOARD_FAB2_LIB.BASEBOARD_FAB2(SCH_1):P3E_CPU0_PE1_PCH_CON_RXN(15)    I64 @BASEBOARD_FAB2_LIB.BASEBOARD_FAB2(SCH_1):PAGE244

R767 RES_0402-0.0,5%,1/16W,CHIP,G21A
     1 P3E_CPU0_PE1_PCH_RXP<15> @BASEBOARD_FAB2_LIB.BASEBOARD_FAB2(SCH_1):P3E_CPU0_PE1_PCH_RXP(15)    I39 @BASEBOARD_FAB2_LIB.BASEBOARD_FAB2(SCH_1):PAGE244
     2 P3E_CPU0_PE1_PCH_CON_RXP<15> @BASEBOARD_FAB2_LIB.BASEBOARD_FAB2(SCH_1):P3E_CPU0_PE1_PCH_CON_RXP(15)    I39 @BASEBOARD_FAB2_LIB.BASEBOARD_FAB2(SCH_1):PAGE244

R768 RES_0402-0.0,5%,1/16W,CHIP,G21A
     1 P3E_CPU0_PE1_PCH_RXN<14> @BASEBOARD_FAB2_LIB.BASEBOARD_FAB2(SCH_1):P3E_CPU0_PE1_PCH_RXN(14)    I66 @BASEBOARD_FAB2_LIB.BASEBOARD_FAB2(SCH_1):PAGE244
     2 P3E_CPU0_PE1_PCH_CON_RXN<14> @BASEBOARD_FAB2_LIB.BASEBOARD_FAB2(SCH_1):P3E_CPU0_PE1_PCH_CON_RXN(14)    I66 @BASEBOARD_FAB2_LIB.BASEBOARD_FAB2(SCH_1):PAGE244

R769 RES_0402-0.0,5%,1/16W,CHIP,G21A
     1 P3E_CPU0_PE1_PCH_RXP<14> @BASEBOARD_FAB2_LIB.BASEBOARD_FAB2(SCH_1):P3E_CPU0_PE1_PCH_RXP(14)    I58 @BASEBOARD_FAB2_LIB.BASEBOARD_FAB2(SCH_1):PAGE244
     2 P3E_CPU0_PE1_PCH_CON_RXP<14> @BASEBOARD_FAB2_LIB.BASEBOARD_FAB2(SCH_1):P3E_CPU0_PE1_PCH_CON_RXP(14)    I58 @BASEBOARD_FAB2_LIB.BASEBOARD_FAB2(SCH_1):PAGE244

R771 RES_0402-0.0,5%,1/16W,CHIP,G21A
     1 P3E_CPU0_PE1_PCH_RXN<13> @BASEBOARD_FAB2_LIB.BASEBOARD_FAB2(SCH_1):P3E_CPU0_PE1_PCH_RXN(13)    I65 @BASEBOARD_FAB2_LIB.BASEBOARD_FAB2(SCH_1):PAGE244
     2 P3E_CPU0_PE1_PCH_CON_RXN<13> @BASEBOARD_FAB2_LIB.BASEBOARD_FAB2(SCH_1):P3E_CPU0_PE1_PCH_CON_RXN(13)    I65 @BASEBOARD_FAB2_LIB.BASEBOARD_FAB2(SCH_1):PAGE244

R774 RES_0402-0.0,5%,1/16W,CHIP,G21A
     1 P3E_CPU0_PE1_PCH_RXP<13> @BASEBOARD_FAB2_LIB.BASEBOARD_FAB2(SCH_1):P3E_CPU0_PE1_PCH_RXP(13)    I72 @BASEBOARD_FAB2_LIB.BASEBOARD_FAB2(SCH_1):PAGE244
     2 P3E_CPU0_PE1_PCH_CON_RXP<13> @BASEBOARD_FAB2_LIB.BASEBOARD_FAB2(SCH_1):P3E_CPU0_PE1_PCH_CON_RXP(13)    I72 @BASEBOARD_FAB2_LIB.BASEBOARD_FAB2(SCH_1):PAGE244

R775 RES_0402-0.0,5%,1/16W,CHIP,G21A
     1 P3E_CPU0_PE1_PCH_RXN<12> @BASEBOARD_FAB2_LIB.BASEBOARD_FAB2(SCH_1):P3E_CPU0_PE1_PCH_RXN(12)    I93 @BASEBOARD_FAB2_LIB.BASEBOARD_FAB2(SCH_1):PAGE244
     2 P3E_CPU0_PE1_PCH_CON_RXN<12> @BASEBOARD_FAB2_LIB.BASEBOARD_FAB2(SCH_1):P3E_CPU0_PE1_PCH_CON_RXN(12)    I93 @BASEBOARD_FAB2_LIB.BASEBOARD_FAB2(SCH_1):PAGE244

R777 RES_0402-0.0,5%,1/16W,CHIP,G21A
     1 P3E_CPU0_PE1_PCH_RXP<12> @BASEBOARD_FAB2_LIB.BASEBOARD_FAB2(SCH_1):P3E_CPU0_PE1_PCH_RXP(12)    I80 @BASEBOARD_FAB2_LIB.BASEBOARD_FAB2(SCH_1):PAGE244
     2 P3E_CPU0_PE1_PCH_CON_RXP<12> @BASEBOARD_FAB2_LIB.BASEBOARD_FAB2(SCH_1):P3E_CPU0_PE1_PCH_CON_RXP(12)    I80 @BASEBOARD_FAB2_LIB.BASEBOARD_FAB2(SCH_1):PAGE244

R778 RES_0402-0.0,5%,1/16W,CHIP,G21A
     1 P3E_CPU0_PE1_PCH_RXN<11> @BASEBOARD_FAB2_LIB.BASEBOARD_FAB2(SCH_1):P3E_CPU0_PE1_PCH_RXN(11)    I94 @BASEBOARD_FAB2_LIB.BASEBOARD_FAB2(SCH_1):PAGE244
     2 P3E_CPU0_PE1_PCH_CON_RXN<11> @BASEBOARD_FAB2_LIB.BASEBOARD_FAB2(SCH_1):P3E_CPU0_PE1_PCH_CON_RXN(11)    I94 @BASEBOARD_FAB2_LIB.BASEBOARD_FAB2(SCH_1):PAGE244

R779 RES_0402-0.0,5%,1/16W,CHIP,G21A
     1 P3E_CPU0_PE1_PCH_RXP<11> @BASEBOARD_FAB2_LIB.BASEBOARD_FAB2(SCH_1):P3E_CPU0_PE1_PCH_RXP(11)    I74 @BASEBOARD_FAB2_LIB.BASEBOARD_FAB2(SCH_1):PAGE244
     2 P3E_CPU0_PE1_PCH_CON_RXP<11> @BASEBOARD_FAB2_LIB.BASEBOARD_FAB2(SCH_1):P3E_CPU0_PE1_PCH_CON_RXP(11)    I74 @BASEBOARD_FAB2_LIB.BASEBOARD_FAB2(SCH_1):PAGE244

R780 RES_0402-0.0,5%,1/16W,CHIP,G21A
     1 P3E_CPU0_PE1_PCH_RXN<10> @BASEBOARD_FAB2_LIB.BASEBOARD_FAB2(SCH_1):P3E_CPU0_PE1_PCH_RXN(10)    I97 @BASEBOARD_FAB2_LIB.BASEBOARD_FAB2(SCH_1):PAGE244
     2 P3E_CPU0_PE1_PCH_CON_RXN<10> @BASEBOARD_FAB2_LIB.BASEBOARD_FAB2(SCH_1):P3E_CPU0_PE1_PCH_CON_RXN(10)    I97 @BASEBOARD_FAB2_LIB.BASEBOARD_FAB2(SCH_1):PAGE244

R781 RES_0402-0.0,5%,1/16W,CHIP,G21A
     1 P3E_CPU0_PE1_PCH_RXP<10> @BASEBOARD_FAB2_LIB.BASEBOARD_FAB2(SCH_1):P3E_CPU0_PE1_PCH_RXP(10)    I86 @BASEBOARD_FAB2_LIB.BASEBOARD_FAB2(SCH_1):PAGE244
     2 P3E_CPU0_PE1_PCH_CON_RXP<10> @BASEBOARD_FAB2_LIB.BASEBOARD_FAB2(SCH_1):P3E_CPU0_PE1_PCH_CON_RXP(10)    I86 @BASEBOARD_FAB2_LIB.BASEBOARD_FAB2(SCH_1):PAGE244

R782 RES_0402-0.0,5%,1/16W,CHIP,G21A
     1 P3E_CPU0_PE1_PCH_RXN<9> @BASEBOARD_FAB2_LIB.BASEBOARD_FAB2(SCH_1):P3E_CPU0_PE1_PCH_RXN(9)    I98 @BASEBOARD_FAB2_LIB.BASEBOARD_FAB2(SCH_1):PAGE244
     2 P3E_CPU0_PE1_PCH_CON_RXN<9> @BASEBOARD_FAB2_LIB.BASEBOARD_FAB2(SCH_1):P3E_CPU0_PE1_PCH_CON_RXN(9)    I98 @BASEBOARD_FAB2_LIB.BASEBOARD_FAB2(SCH_1):PAGE244

R783 RES_0402-0.0,5%,1/16W,CHIP,G21A
     1 P3E_CPU0_PE1_PCH_RXP<9> @BASEBOARD_FAB2_LIB.BASEBOARD_FAB2(SCH_1):P3E_CPU0_PE1_PCH_RXP(9)    I77 @BASEBOARD_FAB2_LIB.BASEBOARD_FAB2(SCH_1):PAGE244
     2 P3E_CPU0_PE1_PCH_CON_RXP<9> @BASEBOARD_FAB2_LIB.BASEBOARD_FAB2(SCH_1):P3E_CPU0_PE1_PCH_CON_RXP(9)    I77 @BASEBOARD_FAB2_LIB.BASEBOARD_FAB2(SCH_1):PAGE244

R784 RES_0402-0.0,5%,1/16W,CHIP,G21A
     1 P3E_CPU0_PE1_PCH_RXN<8> @BASEBOARD_FAB2_LIB.BASEBOARD_FAB2(SCH_1):P3E_CPU0_PE1_PCH_RXN(8)    I99 @BASEBOARD_FAB2_LIB.BASEBOARD_FAB2(SCH_1):PAGE244
     2 P3E_CPU0_PE1_PCH_CON_RXN<8> @BASEBOARD_FAB2_LIB.BASEBOARD_FAB2(SCH_1):P3E_CPU0_PE1_PCH_CON_RXN(8)    I99 @BASEBOARD_FAB2_LIB.BASEBOARD_FAB2(SCH_1):PAGE244

R785 RES_0402-0.0,5%,1/16W,CHIP,G21A
     1 P3E_CPU0_PE1_PCH_RXP<8> @BASEBOARD_FAB2_LIB.BASEBOARD_FAB2(SCH_1):P3E_CPU0_PE1_PCH_RXP(8)   I103 @BASEBOARD_FAB2_LIB.BASEBOARD_FAB2(SCH_1):PAGE244
     2 P3E_CPU0_PE1_PCH_CON_RXP<8> @BASEBOARD_FAB2_LIB.BASEBOARD_FAB2(SCH_1):P3E_CPU0_PE1_PCH_CON_RXP(8)   I103 @BASEBOARD_FAB2_LIB.BASEBOARD_FAB2(SCH_1):PAGE244

RM1E1 CONN3_G98259001_PIP-CONN,G9825A
     1    GND @BASEBOARD_FAB2_LIB.BASEBOARD_FAB2(SCH_1):GND    I26 @BASEBOARD_FAB2_LIB.BASEBOARD_FAB2(SCH_1):PAGE195
     2    GND @BASEBOARD_FAB2_LIB.BASEBOARD_FAB2(SCH_1):GND    I26 @BASEBOARD_FAB2_LIB.BASEBOARD_FAB2(SCH_1):PAGE195
     3    GND @BASEBOARD_FAB2_LIB.BASEBOARD_FAB2(SCH_1):GND    I26 @BASEBOARD_FAB2_LIB.BASEBOARD_FAB2(SCH_1):PAGE195

RM1G1 CAPTIVE_SCREW_TH-HDW,H57868-001

RM8D1 STANDOFF_TH1-SO,H72821-001
     1    GND @BASEBOARD_FAB2_LIB.BASEBOARD_FAB2(SCH_1):GND   I104 @BASEBOARD_FAB2_LIB.BASEBOARD_FAB2(SCH_1):PAGE184

RN8F1 RES_0402-4.75K,1%,1/16W,CHIP,GA
     1 P3V3_STBY @BASEBOARD_FAB2_LIB.BASEBOARD_FAB2(SCH_1):P3V3_STBY     I5 @BASEBOARD_FAB2_LIB.BASEBOARD_FAB2(SCH_1):PAGE246
     2 SPI_BMC_BT_CS1_N @BASEBOARD_FAB2_LIB.BASEBOARD_FAB2(SCH_1):SPI_BMC_BT_CS1_N     I5 @BASEBOARD_FAB2_LIB.BASEBOARD_FAB2(SCH_1):PAGE246

RN8F2 RES_0402-4.75K,1%,1/16W,CHIP,GA
     1 P3V3_STBY @BASEBOARD_FAB2_LIB.BASEBOARD_FAB2(SCH_1):P3V3_STBY    I10 @BASEBOARD_FAB2_LIB.BASEBOARD_FAB2(SCH_1):PAGE246
     2 PU_TPM_SPI_BMC_WP_N @BASEBOARD_FAB2_LIB.BASEBOARD_FAB2(SCH_1):PU_TPM_SPI_BMC_WP_N    I10 @BASEBOARD_FAB2_LIB.BASEBOARD_FAB2(SCH_1):PAGE246

RN8F3 RES_0402-4.75K,1%,1/16W,CHIP,GA
     1 P3V3_STBY @BASEBOARD_FAB2_LIB.BASEBOARD_FAB2(SCH_1):P3V3_STBY    I11 @BASEBOARD_FAB2_LIB.BASEBOARD_FAB2(SCH_1):PAGE246
     2 PU_TPM_SPI_BMC_HOLD_N @BASEBOARD_FAB2_LIB.BASEBOARD_FAB2(SCH_1):PU_TPM_SPI_BMC_HOLD_N    I11 @BASEBOARD_FAB2_LIB.BASEBOARD_FAB2(SCH_1):PAGE246

RN8F4 RES_0402-4.75K,1%,1/16W,EMPTY,A
     1 P3V3_STBY @BASEBOARD_FAB2_LIB.BASEBOARD_FAB2(SCH_1):P3V3_STBY    I12 @BASEBOARD_FAB2_LIB.BASEBOARD_FAB2(SCH_1):PAGE246
     2 PU_TPM_SPI_FLASH_RESET_2_N @BASEBOARD_FAB2_LIB.BASEBOARD_FAB2(SCH_1):PU_TPM_SPI_FLASH_RESET_2_N    I12 @BASEBOARD_FAB2_LIB.BASEBOARD_FAB2(SCH_1):PAGE246

RN8F5 RES_0402-33.2,1%,1/16W,CHIP,G2A
     1 SPI_BMC_BT_DI @BASEBOARD_FAB2_LIB.BASEBOARD_FAB2(SCH_1):SPI_BMC_BT_DI     I9 @BASEBOARD_FAB2_LIB.BASEBOARD_FAB2(SCH_1):PAGE246
     2 SPI_TPM_BMC_DI_R_ @BASEBOARD_FAB2_LIB.BASEBOARD_FAB2(SCH_1):SPI_TPM_BMC_DI_R_     I9 @BASEBOARD_FAB2_LIB.BASEBOARD_FAB2(SCH_1):PAGE246

RN8F6 RES_0402-1.00K,1%,1/16W,EMPTY,A
     1 PU_TPM_SPI_BMC_WP_N @BASEBOARD_FAB2_LIB.BASEBOARD_FAB2(SCH_1):PU_TPM_SPI_BMC_WP_N     I8 @BASEBOARD_FAB2_LIB.BASEBOARD_FAB2(SCH_1):PAGE246
     2    GND @BASEBOARD_FAB2_LIB.BASEBOARD_FAB2(SCH_1):GND     I8 @BASEBOARD_FAB2_LIB.BASEBOARD_FAB2(SCH_1):PAGE246

 RT1 RES_0402-0.0,5%,1/16W,CHIP,G21A
     1 VR_PVCCIN_CPU0_PH1_BOOT @BASEBOARD_FAB2_LIB.BASEBOARD_FAB2(SCH_1):VR_PVCCIN_CPU0_PH1_BOOT    I88 @BASEBOARD_FAB2_LIB.BASEBOARD_FAB2(SCH_1):PAGE202
     2 VR_PVCCIN_CPU0_PH1_BOOT_R @BASEBOARD_FAB2_LIB.BASEBOARD_FAB2(SCH_1):VR_PVCCIN_CPU0_PH1_BOOT_R    I88 @BASEBOARD_FAB2_LIB.BASEBOARD_FAB2(SCH_1):PAGE202

 RT2 3D01R5F-GP_SMD-RG5-3D01R5F-GP,A
     1    GND @BASEBOARD_FAB2_LIB.BASEBOARD_FAB2(SCH_1):GND    I75 @BASEBOARD_FAB2_LIB.BASEBOARD_FAB2(SCH_1):PAGE202
     2 UNNAMED_202_3D01R5F-GP_I75_2 @BASEBOARD_FAB2_LIB.BASEBOARD_FAB2(SCH_1):UNNAMED_202_3D01R5F-GP_I75_2    I75 @BASEBOARD_FAB2_LIB.BASEBOARD_FAB2(SCH_1):PAGE202

 RT3 RES_0402-0.0,5%,1/16W,CHIP,G21A
     1 VR_PVCCIN_CPU0_PH2_BOOT @BASEBOARD_FAB2_LIB.BASEBOARD_FAB2(SCH_1):VR_PVCCIN_CPU0_PH2_BOOT    I89 @BASEBOARD_FAB2_LIB.BASEBOARD_FAB2(SCH_1):PAGE202
     2 VR_PVCCIN_CPU0_PH2_BOOT_R @BASEBOARD_FAB2_LIB.BASEBOARD_FAB2(SCH_1):VR_PVCCIN_CPU0_PH2_BOOT_R    I89 @BASEBOARD_FAB2_LIB.BASEBOARD_FAB2(SCH_1):PAGE202

 RT4 3D01R5F-GP_SMD-RG5-3D01R5F-GP,A
     1    GND @BASEBOARD_FAB2_LIB.BASEBOARD_FAB2(SCH_1):GND    I83 @BASEBOARD_FAB2_LIB.BASEBOARD_FAB2(SCH_1):PAGE202
     2 UNNAMED_202_3D01R5F-GP_I83_2 @BASEBOARD_FAB2_LIB.BASEBOARD_FAB2(SCH_1):UNNAMED_202_3D01R5F-GP_I83_2    I83 @BASEBOARD_FAB2_LIB.BASEBOARD_FAB2(SCH_1):PAGE202

 RT5 RES_0402-0.0,5%,1/16W,CHIP,G21A
     1 VR_PVDDQ_KLM_PH1_BOOT @BASEBOARD_FAB2_LIB.BASEBOARD_FAB2(SCH_1):VR_PVDDQ_KLM_PH1_BOOT   I126 @BASEBOARD_FAB2_LIB.BASEBOARD_FAB2(SCH_1):PAGE227
     2 VR_PVDDQ_KLM_PH1_BOOT_R @BASEBOARD_FAB2_LIB.BASEBOARD_FAB2(SCH_1):VR_PVDDQ_KLM_PH1_BOOT_R   I126 @BASEBOARD_FAB2_LIB.BASEBOARD_FAB2(SCH_1):PAGE227

 RT6 3D01R5F-GP_SMD-RG5-3D01R5F-GP,A
     1 UNNAMED_227_3D01R5F-GP_I125_1 @BASEBOARD_FAB2_LIB.BASEBOARD_FAB2(SCH_1):UNNAMED_227_3D01R5F-GP_I125_1   I125 @BASEBOARD_FAB2_LIB.BASEBOARD_FAB2(SCH_1):PAGE227
     2    GND @BASEBOARD_FAB2_LIB.BASEBOARD_FAB2(SCH_1):GND   I125 @BASEBOARD_FAB2_LIB.BASEBOARD_FAB2(SCH_1):PAGE227

 RT7 3D01R5F-GP_SMD-RG5-3D01R5F-GP,A
     1 UNNAMED_227_3D01R5F-GP_I124_1 @BASEBOARD_FAB2_LIB.BASEBOARD_FAB2(SCH_1):UNNAMED_227_3D01R5F-GP_I124_1   I124 @BASEBOARD_FAB2_LIB.BASEBOARD_FAB2(SCH_1):PAGE227
     2    GND @BASEBOARD_FAB2_LIB.BASEBOARD_FAB2(SCH_1):GND   I124 @BASEBOARD_FAB2_LIB.BASEBOARD_FAB2(SCH_1):PAGE227

 RT8 RES_0402-0.0,5%,1/16W,CHIP,G21A
     1 VR_PVDDQ_KLM_PH2_BOOT @BASEBOARD_FAB2_LIB.BASEBOARD_FAB2(SCH_1):VR_PVDDQ_KLM_PH2_BOOT   I127 @BASEBOARD_FAB2_LIB.BASEBOARD_FAB2(SCH_1):PAGE227
     2 VR_PVDDQ_KLM_PH2_BOOT_R @BASEBOARD_FAB2_LIB.BASEBOARD_FAB2(SCH_1):VR_PVDDQ_KLM_PH2_BOOT_R   I127 @BASEBOARD_FAB2_LIB.BASEBOARD_FAB2(SCH_1):PAGE227

RT8P1 RES_0603-100.0K,1%,1/10W,CHIP,A
     1 PVCCIN_CPU1 @BASEBOARD_FAB2_LIB.BASEBOARD_FAB2(SCH_1):PVCCIN_CPU1    I49 @BASEBOARD_FAB2_LIB.BASEBOARD_FAB2(SCH_1):PAGE71
     2 VSENSE_VCCINR2PMAX_CPU1 @BASEBOARD_FAB2_LIB.BASEBOARD_FAB2(SCH_1):VSENSE_VCCINR2PMAX_CPU1    I49 @BASEBOARD_FAB2_LIB.BASEBOARD_FAB2(SCH_1):PAGE71

 RT9 RES_0402-0.0,5%,1/16W,CHIP,G21A
     1 VR_PVCCIN_CPU1_PH5_BOOT @BASEBOARD_FAB2_LIB.BASEBOARD_FAB2(SCH_1):VR_PVCCIN_CPU1_PH5_BOOT    I69 @BASEBOARD_FAB2_LIB.BASEBOARD_FAB2(SCH_1):PAGE209
     2 VR_PVCCIN_CPU1_PH5_BOOT_R @BASEBOARD_FAB2_LIB.BASEBOARD_FAB2(SCH_1):VR_PVCCIN_CPU1_PH5_BOOT_R    I69 @BASEBOARD_FAB2_LIB.BASEBOARD_FAB2(SCH_1):PAGE209

RT10 3D01R5F-GP_SMD-RG5-3D01R5F-GP,A
     1    GND @BASEBOARD_FAB2_LIB.BASEBOARD_FAB2(SCH_1):GND    I66 @BASEBOARD_FAB2_LIB.BASEBOARD_FAB2(SCH_1):PAGE209
     2 UNNAMED_209_3D01R5F-GP_I66_2 @BASEBOARD_FAB2_LIB.BASEBOARD_FAB2(SCH_1):UNNAMED_209_3D01R5F-GP_I66_2    I66 @BASEBOARD_FAB2_LIB.BASEBOARD_FAB2(SCH_1):PAGE209

RT11 RES_0402-0.0,5%,1/16W,CHIP,G21A
     1 VR_PVCCIN_CPU1_PH3_BOOT @BASEBOARD_FAB2_LIB.BASEBOARD_FAB2(SCH_1):VR_PVCCIN_CPU1_PH3_BOOT    I96 @BASEBOARD_FAB2_LIB.BASEBOARD_FAB2(SCH_1):PAGE208
     2 VR_PVCCIN_CPU1_PH3_BOOT_R @BASEBOARD_FAB2_LIB.BASEBOARD_FAB2(SCH_1):VR_PVCCIN_CPU1_PH3_BOOT_R    I96 @BASEBOARD_FAB2_LIB.BASEBOARD_FAB2(SCH_1):PAGE208

RT12 3D01R5F-GP_SMD-RG5-3D01R5F-GP,A
     1    GND @BASEBOARD_FAB2_LIB.BASEBOARD_FAB2(SCH_1):GND    I86 @BASEBOARD_FAB2_LIB.BASEBOARD_FAB2(SCH_1):PAGE208
     2 UNNAMED_208_3D01R5F-GP_I86_2 @BASEBOARD_FAB2_LIB.BASEBOARD_FAB2(SCH_1):UNNAMED_208_3D01R5F-GP_I86_2    I86 @BASEBOARD_FAB2_LIB.BASEBOARD_FAB2(SCH_1):PAGE208

RT13 3D01R5F-GP_SMD-RG5-3D01R5F-GP,A
     1    GND @BASEBOARD_FAB2_LIB.BASEBOARD_FAB2(SCH_1):GND    I94 @BASEBOARD_FAB2_LIB.BASEBOARD_FAB2(SCH_1):PAGE208
     2 UNNAMED_208_3D01R5F-GP_I94_2 @BASEBOARD_FAB2_LIB.BASEBOARD_FAB2(SCH_1):UNNAMED_208_3D01R5F-GP_I94_2    I94 @BASEBOARD_FAB2_LIB.BASEBOARD_FAB2(SCH_1):PAGE208

RT14 RES_0402-0.0,5%,1/16W,CHIP,G21A
     1 VR_PVCCIN_CPU1_PH4_BOOT @BASEBOARD_FAB2_LIB.BASEBOARD_FAB2(SCH_1):VR_PVCCIN_CPU1_PH4_BOOT    I97 @BASEBOARD_FAB2_LIB.BASEBOARD_FAB2(SCH_1):PAGE208
     2 VR_PVCCIN_CPU1_PH4_BOOT_R @BASEBOARD_FAB2_LIB.BASEBOARD_FAB2(SCH_1):VR_PVCCIN_CPU1_PH4_BOOT_R    I97 @BASEBOARD_FAB2_LIB.BASEBOARD_FAB2(SCH_1):PAGE208

RT15 RES_0402-0.0,5%,1/16W,CHIP,G21A
     1 VR_PVCCIN_CPU1_PH1_BOOT @BASEBOARD_FAB2_LIB.BASEBOARD_FAB2(SCH_1):VR_PVCCIN_CPU1_PH1_BOOT    I87 @BASEBOARD_FAB2_LIB.BASEBOARD_FAB2(SCH_1):PAGE207
     2 VR_PVCCIN_CPU1_PH1_BOOT_R @BASEBOARD_FAB2_LIB.BASEBOARD_FAB2(SCH_1):VR_PVCCIN_CPU1_PH1_BOOT_R    I87 @BASEBOARD_FAB2_LIB.BASEBOARD_FAB2(SCH_1):PAGE207

RT16 3D01R5F-GP_SMD-RG5-3D01R5F-GP,A
     1    GND @BASEBOARD_FAB2_LIB.BASEBOARD_FAB2(SCH_1):GND    I76 @BASEBOARD_FAB2_LIB.BASEBOARD_FAB2(SCH_1):PAGE207
     2 UNNAMED_207_3D01R5F-GP_I76_2 @BASEBOARD_FAB2_LIB.BASEBOARD_FAB2(SCH_1):UNNAMED_207_3D01R5F-GP_I76_2    I76 @BASEBOARD_FAB2_LIB.BASEBOARD_FAB2(SCH_1):PAGE207

RT17 RES_0402-0.0,5%,1/16W,CHIP,G21A
     1 VR_PVCCIN_CPU1_PH2_BOOT @BASEBOARD_FAB2_LIB.BASEBOARD_FAB2(SCH_1):VR_PVCCIN_CPU1_PH2_BOOT    I88 @BASEBOARD_FAB2_LIB.BASEBOARD_FAB2(SCH_1):PAGE207
     2 VR_PVCCIN_CPU1_PH2_BOOT_R @BASEBOARD_FAB2_LIB.BASEBOARD_FAB2(SCH_1):VR_PVCCIN_CPU1_PH2_BOOT_R    I88 @BASEBOARD_FAB2_LIB.BASEBOARD_FAB2(SCH_1):PAGE207

RT18 3D01R5F-GP_SMD-RG5-3D01R5F-GP,A
     1    GND @BASEBOARD_FAB2_LIB.BASEBOARD_FAB2(SCH_1):GND    I85 @BASEBOARD_FAB2_LIB.BASEBOARD_FAB2(SCH_1):PAGE207
     2 UNNAMED_207_3D01R5F-GP_I85_2 @BASEBOARD_FAB2_LIB.BASEBOARD_FAB2(SCH_1):UNNAMED_207_3D01R5F-GP_I85_2    I85 @BASEBOARD_FAB2_LIB.BASEBOARD_FAB2(SCH_1):PAGE207

RT19 RES_0402-0.0,5%,1/16W,CHIP,G21A
     1 VR_PVDDQ_GHJ_PH1_BOOT @BASEBOARD_FAB2_LIB.BASEBOARD_FAB2(SCH_1):VR_PVDDQ_GHJ_PH1_BOOT   I132 @BASEBOARD_FAB2_LIB.BASEBOARD_FAB2(SCH_1):PAGE224
     2 VR_PVDDQ_GHJ_PH1_BOOT_R @BASEBOARD_FAB2_LIB.BASEBOARD_FAB2(SCH_1):VR_PVDDQ_GHJ_PH1_BOOT_R   I132 @BASEBOARD_FAB2_LIB.BASEBOARD_FAB2(SCH_1):PAGE224

RT20 3D01R5F-GP_SMD-RG5-3D01R5F-GP,A
     1    GND @BASEBOARD_FAB2_LIB.BASEBOARD_FAB2(SCH_1):GND   I119 @BASEBOARD_FAB2_LIB.BASEBOARD_FAB2(SCH_1):PAGE224
     2 UNNAMED_224_3D01R5F-GP_I119_2 @BASEBOARD_FAB2_LIB.BASEBOARD_FAB2(SCH_1):UNNAMED_224_3D01R5F-GP_I119_2   I119 @BASEBOARD_FAB2_LIB.BASEBOARD_FAB2(SCH_1):PAGE224

RT21 RES_0402-0.0,5%,1/16W,CHIP,G21A
     1 VR_PVDDQ_GHJ_PH2_BOOT @BASEBOARD_FAB2_LIB.BASEBOARD_FAB2(SCH_1):VR_PVDDQ_GHJ_PH2_BOOT   I133 @BASEBOARD_FAB2_LIB.BASEBOARD_FAB2(SCH_1):PAGE224
     2 VR_PVDDQ_GHJ_PH2_BOOT_R @BASEBOARD_FAB2_LIB.BASEBOARD_FAB2(SCH_1):VR_PVDDQ_GHJ_PH2_BOOT_R   I133 @BASEBOARD_FAB2_LIB.BASEBOARD_FAB2(SCH_1):PAGE224

RT22 3D01R5F-GP_SMD-RG5-3D01R5F-GP,A
     1    GND @BASEBOARD_FAB2_LIB.BASEBOARD_FAB2(SCH_1):GND   I129 @BASEBOARD_FAB2_LIB.BASEBOARD_FAB2(SCH_1):PAGE224
     2 UNNAMED_224_3D01R5F-GP_I129_2 @BASEBOARD_FAB2_LIB.BASEBOARD_FAB2(SCH_1):UNNAMED_224_3D01R5F-GP_I129_2   I129 @BASEBOARD_FAB2_LIB.BASEBOARD_FAB2(SCH_1):PAGE224

RT23 RES_0402-0.0,5%,1/16W,CHIP,G21A
     1 VR_PVCCIN_CPU0_PH5_BOOT @BASEBOARD_FAB2_LIB.BASEBOARD_FAB2(SCH_1):VR_PVCCIN_CPU0_PH5_BOOT    I93 @BASEBOARD_FAB2_LIB.BASEBOARD_FAB2(SCH_1):PAGE204
     2 VR_PVCCIN_CPU0_PH5_BOOT_R @BASEBOARD_FAB2_LIB.BASEBOARD_FAB2(SCH_1):VR_PVCCIN_CPU0_PH5_BOOT_R    I93 @BASEBOARD_FAB2_LIB.BASEBOARD_FAB2(SCH_1):PAGE204

RT24 3D01R5F-GP_SMD-RG5-3D01R5F-GP,A
     1    GND @BASEBOARD_FAB2_LIB.BASEBOARD_FAB2(SCH_1):GND    I91 @BASEBOARD_FAB2_LIB.BASEBOARD_FAB2(SCH_1):PAGE204
     2 UNNAMED_204_3D01R5F-GP_I91_2 @BASEBOARD_FAB2_LIB.BASEBOARD_FAB2(SCH_1):UNNAMED_204_3D01R5F-GP_I91_2    I91 @BASEBOARD_FAB2_LIB.BASEBOARD_FAB2(SCH_1):PAGE204

RT25 RES_0402-0.0,5%,1/16W,CHIP,G21A
     1 VR_PVCCIN_CPU0_PH3_BOOT @BASEBOARD_FAB2_LIB.BASEBOARD_FAB2(SCH_1):VR_PVCCIN_CPU0_PH3_BOOT   I110 @BASEBOARD_FAB2_LIB.BASEBOARD_FAB2(SCH_1):PAGE203
     2 VR_PVCCIN_CPU0_PH3_BOOT_R @BASEBOARD_FAB2_LIB.BASEBOARD_FAB2(SCH_1):VR_PVCCIN_CPU0_PH3_BOOT_R   I110 @BASEBOARD_FAB2_LIB.BASEBOARD_FAB2(SCH_1):PAGE203

RT26 3D01R5F-GP_SMD-RG5-3D01R5F-GP,A
     1    GND @BASEBOARD_FAB2_LIB.BASEBOARD_FAB2(SCH_1):GND   I102 @BASEBOARD_FAB2_LIB.BASEBOARD_FAB2(SCH_1):PAGE203
     2 UNNAMED_203_3D01R5F-GP_I102_2 @BASEBOARD_FAB2_LIB.BASEBOARD_FAB2(SCH_1):UNNAMED_203_3D01R5F-GP_I102_2   I102 @BASEBOARD_FAB2_LIB.BASEBOARD_FAB2(SCH_1):PAGE203

RT27 3D01R5F-GP_SMD-RG5-3D01R5F-GP,A
     1    GND @BASEBOARD_FAB2_LIB.BASEBOARD_FAB2(SCH_1):GND   I105 @BASEBOARD_FAB2_LIB.BASEBOARD_FAB2(SCH_1):PAGE203
     2 UNNAMED_203_3D01R5F-GP_I105_2 @BASEBOARD_FAB2_LIB.BASEBOARD_FAB2(SCH_1):UNNAMED_203_3D01R5F-GP_I105_2   I105 @BASEBOARD_FAB2_LIB.BASEBOARD_FAB2(SCH_1):PAGE203

RT28 RES_0402-0.0,5%,1/16W,CHIP,G21A
     1 VR_PVCCIN_CPU0_PH4_BOOT @BASEBOARD_FAB2_LIB.BASEBOARD_FAB2(SCH_1):VR_PVCCIN_CPU0_PH4_BOOT   I111 @BASEBOARD_FAB2_LIB.BASEBOARD_FAB2(SCH_1):PAGE203
     2 VR_PVCCIN_CPU0_PH4_BOOT_R @BASEBOARD_FAB2_LIB.BASEBOARD_FAB2(SCH_1):VR_PVCCIN_CPU0_PH4_BOOT_R   I111 @BASEBOARD_FAB2_LIB.BASEBOARD_FAB2(SCH_1):PAGE203

RT29 3D01R5F-GP_SMD-RG5-3D01R5F-GP,A
     1    GND @BASEBOARD_FAB2_LIB.BASEBOARD_FAB2(SCH_1):GND   I126 @BASEBOARD_FAB2_LIB.BASEBOARD_FAB2(SCH_1):PAGE219
     2 UNNAMED_219_3D01R5F-GP_I126_2 @BASEBOARD_FAB2_LIB.BASEBOARD_FAB2(SCH_1):UNNAMED_219_3D01R5F-GP_I126_2   I126 @BASEBOARD_FAB2_LIB.BASEBOARD_FAB2(SCH_1):PAGE219

RT30 RES_0402-0.0,5%,1/16W,CHIP,G21A
     1 VR_PVDDQ_DEF_PH1_BOOT @BASEBOARD_FAB2_LIB.BASEBOARD_FAB2(SCH_1):VR_PVDDQ_DEF_PH1_BOOT   I129 @BASEBOARD_FAB2_LIB.BASEBOARD_FAB2(SCH_1):PAGE219
     2 VR_PVDDQ_DEF_PH1_BOOT_R @BASEBOARD_FAB2_LIB.BASEBOARD_FAB2(SCH_1):VR_PVDDQ_DEF_PH1_BOOT_R   I129 @BASEBOARD_FAB2_LIB.BASEBOARD_FAB2(SCH_1):PAGE219

RT31 RES_0402-0.0,5%,1/16W,CHIP,G21A
     1 VR_PVDDQ_DEF_PH2_BOOT @BASEBOARD_FAB2_LIB.BASEBOARD_FAB2(SCH_1):VR_PVDDQ_DEF_PH2_BOOT   I130 @BASEBOARD_FAB2_LIB.BASEBOARD_FAB2(SCH_1):PAGE219
     2 VR_PVDDQ_DEF_PH2_BOOT_R @BASEBOARD_FAB2_LIB.BASEBOARD_FAB2(SCH_1):VR_PVDDQ_DEF_PH2_BOOT_R   I130 @BASEBOARD_FAB2_LIB.BASEBOARD_FAB2(SCH_1):PAGE219

RT32 3D01R5F-GP_SMD-RG5-3D01R5F-GP,A
     1    GND @BASEBOARD_FAB2_LIB.BASEBOARD_FAB2(SCH_1):GND   I123 @BASEBOARD_FAB2_LIB.BASEBOARD_FAB2(SCH_1):PAGE219
     2 UNNAMED_219_3D01R5F-GP_I123_2 @BASEBOARD_FAB2_LIB.BASEBOARD_FAB2(SCH_1):UNNAMED_219_3D01R5F-GP_I123_2   I123 @BASEBOARD_FAB2_LIB.BASEBOARD_FAB2(SCH_1):PAGE219

RT33 RES_0402-0.0,5%,1/16W,CHIP,G21A
     1 VR_PVDDQ_ABC_PH1_BOOT @BASEBOARD_FAB2_LIB.BASEBOARD_FAB2(SCH_1):VR_PVDDQ_ABC_PH1_BOOT   I126 @BASEBOARD_FAB2_LIB.BASEBOARD_FAB2(SCH_1):PAGE216
     2 VR_PVDDQ_ABC_PH1_BOOT_R @BASEBOARD_FAB2_LIB.BASEBOARD_FAB2(SCH_1):VR_PVDDQ_ABC_PH1_BOOT_R   I126 @BASEBOARD_FAB2_LIB.BASEBOARD_FAB2(SCH_1):PAGE216

RT34 3D01R5F-GP_SMD-RG5-3D01R5F-GP,A
     1    GND @BASEBOARD_FAB2_LIB.BASEBOARD_FAB2(SCH_1):GND   I114 @BASEBOARD_FAB2_LIB.BASEBOARD_FAB2(SCH_1):PAGE216
     2 UNNAMED_216_3D01R5F-GP_I114_2 @BASEBOARD_FAB2_LIB.BASEBOARD_FAB2(SCH_1):UNNAMED_216_3D01R5F-GP_I114_2   I114 @BASEBOARD_FAB2_LIB.BASEBOARD_FAB2(SCH_1):PAGE216

RT35 3D01R5F-GP_SMD-RG5-3D01R5F-GP,A
     1    GND @BASEBOARD_FAB2_LIB.BASEBOARD_FAB2(SCH_1):GND   I123 @BASEBOARD_FAB2_LIB.BASEBOARD_FAB2(SCH_1):PAGE216
     2 UNNAMED_216_3D01R5F-GP_I123_2 @BASEBOARD_FAB2_LIB.BASEBOARD_FAB2(SCH_1):UNNAMED_216_3D01R5F-GP_I123_2   I123 @BASEBOARD_FAB2_LIB.BASEBOARD_FAB2(SCH_1):PAGE216

RT36 RES_0402-0.0,5%,1/16W,CHIP,G21A
     1 VR_PVDDQ_ABC_PH2_BOOT @BASEBOARD_FAB2_LIB.BASEBOARD_FAB2(SCH_1):VR_PVDDQ_ABC_PH2_BOOT   I127 @BASEBOARD_FAB2_LIB.BASEBOARD_FAB2(SCH_1):PAGE216
     2 VR_PVDDQ_ABC_PH2_BOOT_R @BASEBOARD_FAB2_LIB.BASEBOARD_FAB2(SCH_1):VR_PVDDQ_ABC_PH2_BOOT_R   I127 @BASEBOARD_FAB2_LIB.BASEBOARD_FAB2(SCH_1):PAGE216

RT37 RES_0402-0.0,5%,1/16W,CHIP,G21A
     1 VR_PVSA_CPU1_BOOT @BASEBOARD_FAB2_LIB.BASEBOARD_FAB2(SCH_1):VR_PVSA_CPU1_BOOT    I62 @BASEBOARD_FAB2_LIB.BASEBOARD_FAB2(SCH_1):PAGE210
     2 VR_PVSA_CPU1_BOOT_R @BASEBOARD_FAB2_LIB.BASEBOARD_FAB2(SCH_1):VR_PVSA_CPU1_BOOT_R    I62 @BASEBOARD_FAB2_LIB.BASEBOARD_FAB2(SCH_1):PAGE210

RT38 3D01R5F-GP_SMD-RG5-3D01R5F-GP,A
     1    GND @BASEBOARD_FAB2_LIB.BASEBOARD_FAB2(SCH_1):GND    I59 @BASEBOARD_FAB2_LIB.BASEBOARD_FAB2(SCH_1):PAGE210
     2 UNNAMED_210_3D01R5F-GP_I59_2 @BASEBOARD_FAB2_LIB.BASEBOARD_FAB2(SCH_1):UNNAMED_210_3D01R5F-GP_I59_2    I59 @BASEBOARD_FAB2_LIB.BASEBOARD_FAB2(SCH_1):PAGE210

RT39 3D01R5F-GP_SMD-RG5-3D01R5F-GP,A
     1    GND @BASEBOARD_FAB2_LIB.BASEBOARD_FAB2(SCH_1):GND    I68 @BASEBOARD_FAB2_LIB.BASEBOARD_FAB2(SCH_1):PAGE205
     2 UNNAMED_205_3D01R5F-GP_I68_2 @BASEBOARD_FAB2_LIB.BASEBOARD_FAB2(SCH_1):UNNAMED_205_3D01R5F-GP_I68_2    I68 @BASEBOARD_FAB2_LIB.BASEBOARD_FAB2(SCH_1):PAGE205

RT40 RES_0402-0.0,5%,1/16W,CHIP,G21A
     1 VR_PVSA_CPU0_BOOT @BASEBOARD_FAB2_LIB.BASEBOARD_FAB2(SCH_1):VR_PVSA_CPU0_BOOT    I72 @BASEBOARD_FAB2_LIB.BASEBOARD_FAB2(SCH_1):PAGE205
     2 VR_PVSA_CPU0_BOOT_R @BASEBOARD_FAB2_LIB.BASEBOARD_FAB2(SCH_1):VR_PVSA_CPU0_BOOT_R    I72 @BASEBOARD_FAB2_LIB.BASEBOARD_FAB2(SCH_1):PAGE205

RT41 RES_0402-0.0,5%,1/16W,CHIP,G21A
     1 VR_PVCCIO_CPU1_PH1_BOOT @BASEBOARD_FAB2_LIB.BASEBOARD_FAB2(SCH_1):VR_PVCCIO_CPU1_PH1_BOOT   I139 @BASEBOARD_FAB2_LIB.BASEBOARD_FAB2(SCH_1):PAGE214
     2 VR_PVCCIO_CPU1_PH1_BOOT_R @BASEBOARD_FAB2_LIB.BASEBOARD_FAB2(SCH_1):VR_PVCCIO_CPU1_PH1_BOOT_R   I139 @BASEBOARD_FAB2_LIB.BASEBOARD_FAB2(SCH_1):PAGE214

RT42 3D01R5F-GP_SMD-RG5-3D01R5F-GP,A
     1    GND @BASEBOARD_FAB2_LIB.BASEBOARD_FAB2(SCH_1):GND   I132 @BASEBOARD_FAB2_LIB.BASEBOARD_FAB2(SCH_1):PAGE214
     2 UNNAMED_214_3D01R5F-GP_I132_2 @BASEBOARD_FAB2_LIB.BASEBOARD_FAB2(SCH_1):UNNAMED_214_3D01R5F-GP_I132_2   I132 @BASEBOARD_FAB2_LIB.BASEBOARD_FAB2(SCH_1):PAGE214

RT43 3D01R5F-GP_SMD-RG5-3D01R5F-GP,A
     1    GND @BASEBOARD_FAB2_LIB.BASEBOARD_FAB2(SCH_1):GND   I132 @BASEBOARD_FAB2_LIB.BASEBOARD_FAB2(SCH_1):PAGE236
     2 UNNAMED_236_3D01R5F-GP_I132_2 @BASEBOARD_FAB2_LIB.BASEBOARD_FAB2(SCH_1):UNNAMED_236_3D01R5F-GP_I132_2   I132 @BASEBOARD_FAB2_LIB.BASEBOARD_FAB2(SCH_1):PAGE236

RT44 RES_0402-0.0,5%,1/16W,CHIP,G21A
     1 VR_PVNN_PCH_PH1_BOOT @BASEBOARD_FAB2_LIB.BASEBOARD_FAB2(SCH_1):VR_PVNN_PCH_PH1_BOOT   I141 @BASEBOARD_FAB2_LIB.BASEBOARD_FAB2(SCH_1):PAGE236
     2 VR_PVNN_PCH_PH1_BOOT_R @BASEBOARD_FAB2_LIB.BASEBOARD_FAB2(SCH_1):VR_PVNN_PCH_PH1_BOOT_R   I141 @BASEBOARD_FAB2_LIB.BASEBOARD_FAB2(SCH_1):PAGE236

RT45 3D01R5F-GP_SMD-RG5-3D01R5F-GP,A
     1    GND @BASEBOARD_FAB2_LIB.BASEBOARD_FAB2(SCH_1):GND   I137 @BASEBOARD_FAB2_LIB.BASEBOARD_FAB2(SCH_1):PAGE236
     2 UNNAMED_236_3D01R5F-GP_I137_2 @BASEBOARD_FAB2_LIB.BASEBOARD_FAB2(SCH_1):UNNAMED_236_3D01R5F-GP_I137_2   I137 @BASEBOARD_FAB2_LIB.BASEBOARD_FAB2(SCH_1):PAGE236

RT46 RES_0402-0.0,5%,1/16W,CHIP,G21A
     1 VR_P1V05_PCH_STBY_PH1_BOOT @BASEBOARD_FAB2_LIB.BASEBOARD_FAB2(SCH_1):VR_P1V05_PCH_STBY_PH1_BOOT   I142 @BASEBOARD_FAB2_LIB.BASEBOARD_FAB2(SCH_1):PAGE236
     2 VR_P1V05_PCH_STBY_PH1_BOOT_R @BASEBOARD_FAB2_LIB.BASEBOARD_FAB2(SCH_1):VR_P1V05_PCH_STBY_PH1_BOOT_R   I142 @BASEBOARD_FAB2_LIB.BASEBOARD_FAB2(SCH_1):PAGE236

RT47 RES_0402-0.0,5%,1/16W,CHIP,G21A
     1 VR_PVCCIO_CPU0_PH1_BOOT @BASEBOARD_FAB2_LIB.BASEBOARD_FAB2(SCH_1):VR_PVCCIO_CPU0_PH1_BOOT   I114 @BASEBOARD_FAB2_LIB.BASEBOARD_FAB2(SCH_1):PAGE212
     2 VR_PVCCIO_CPU0_PH1_BOOT_R @BASEBOARD_FAB2_LIB.BASEBOARD_FAB2(SCH_1):VR_PVCCIO_CPU0_PH1_BOOT_R   I114 @BASEBOARD_FAB2_LIB.BASEBOARD_FAB2(SCH_1):PAGE212

RT48 3D01R5F-GP_SMD-RG5-3D01R5F-GP,A
     1    GND @BASEBOARD_FAB2_LIB.BASEBOARD_FAB2(SCH_1):GND   I112 @BASEBOARD_FAB2_LIB.BASEBOARD_FAB2(SCH_1):PAGE212
     2 UNNAMED_212_3D01R5F-GP_I112_2 @BASEBOARD_FAB2_LIB.BASEBOARD_FAB2(SCH_1):UNNAMED_212_3D01R5F-GP_I112_2   I112 @BASEBOARD_FAB2_LIB.BASEBOARD_FAB2(SCH_1):PAGE212

S8E1 SWITCH_D90553001_SMLF-IC,D9055A
     1    GND @BASEBOARD_FAB2_LIB.BASEBOARD_FAB2(SCH_1):GND   I351 @BASEBOARD_FAB2_LIB.BASEBOARD_FAB2(SCH_1):PAGE157
     2 FP_NMI_BTN_OUT_R_N @BASEBOARD_FAB2_LIB.BASEBOARD_FAB2(SCH_1):FP_NMI_BTN_OUT_R_N   I351 @BASEBOARD_FAB2_LIB.BASEBOARD_FAB2(SCH_1):PAGE157

S9A1 SWITCH_D37771002_SM-IC,D37771-A
     4    GND @BASEBOARD_FAB2_LIB.BASEBOARD_FAB2(SCH_1):GND    I78 @BASEBOARD_FAB2_LIB.BASEBOARD_FAB2(SCH_1):PAGE175
     3    GND @BASEBOARD_FAB2_LIB.BASEBOARD_FAB2(SCH_1):GND    I78 @BASEBOARD_FAB2_LIB.BASEBOARD_FAB2(SCH_1):PAGE175
     1 FM_DEBUG_RST_BTN_N @BASEBOARD_FAB2_LIB.BASEBOARD_FAB2(SCH_1):FM_DEBUG_RST_BTN_N    I78 @BASEBOARD_FAB2_LIB.BASEBOARD_FAB2(SCH_1):PAGE175
     2 FM_DEBUG_RST_BTN_N @BASEBOARD_FAB2_LIB.BASEBOARD_FAB2(SCH_1):FM_DEBUG_RST_BTN_N    I78 @BASEBOARD_FAB2_LIB.BASEBOARD_FAB2(SCH_1):PAGE175

S9A2 SW_H67881001_SM-IC,H67881-001
     1 FP_PWR_BTN_R_N @BASEBOARD_FAB2_LIB.BASEBOARD_FAB2(SCH_1):FP_PWR_BTN_R_N    I84 @BASEBOARD_FAB2_LIB.BASEBOARD_FAB2(SCH_1):PAGE175
     2 FP_PWR_BTN_R_N @BASEBOARD_FAB2_LIB.BASEBOARD_FAB2(SCH_1):FP_PWR_BTN_R_N    I84 @BASEBOARD_FAB2_LIB.BASEBOARD_FAB2(SCH_1):PAGE175
     3    GND @BASEBOARD_FAB2_LIB.BASEBOARD_FAB2(SCH_1):GND    I84 @BASEBOARD_FAB2_LIB.BASEBOARD_FAB2(SCH_1):PAGE175
     4    GND @BASEBOARD_FAB2_LIB.BASEBOARD_FAB2(SCH_1):GND    I84 @BASEBOARD_FAB2_LIB.BASEBOARD_FAB2(SCH_1):PAGE175

SH3D1 SHUNT_SH0201-EMPTY,N_A
     1 VSENSE_PVCCIO_CPU1_SKT_VRTN @BASEBOARD_FAB2_LIB.BASEBOARD_FAB2(SCH_1):VSENSE_PVCCIO_CPU1_SKT_VRTN   I130 @BASEBOARD_FAB2_LIB.BASEBOARD_FAB2(SCH_1):PAGE214
     2 VSENSE_PVCCIO_CPU1_AVSN @BASEBOARD_FAB2_LIB.BASEBOARD_FAB2(SCH_1):VSENSE_PVCCIO_CPU1_AVSN   I130 @BASEBOARD_FAB2_LIB.BASEBOARD_FAB2(SCH_1):PAGE214

SH3D2 SHUNT_SH0201-EMPTY,N_A
     1 VSENSE_PVCCIO_CPU1_SKT_VSEN @BASEBOARD_FAB2_LIB.BASEBOARD_FAB2(SCH_1):VSENSE_PVCCIO_CPU1_SKT_VSEN   I129 @BASEBOARD_FAB2_LIB.BASEBOARD_FAB2(SCH_1):PAGE214
     2 VSENSE_PVCCIO_CPU1_AVSP @BASEBOARD_FAB2_LIB.BASEBOARD_FAB2(SCH_1):VSENSE_PVCCIO_CPU1_AVSP   I129 @BASEBOARD_FAB2_LIB.BASEBOARD_FAB2(SCH_1):PAGE214

SH3P1 SHUNT_SH0201-EMPTY,N_A
     1 VSENSE_PVCCIO_CPU0_SKT_VSEN @BASEBOARD_FAB2_LIB.BASEBOARD_FAB2(SCH_1):VSENSE_PVCCIO_CPU0_SKT_VSEN   I104 @BASEBOARD_FAB2_LIB.BASEBOARD_FAB2(SCH_1):PAGE212
     2 VSENSE_PVCCIO_CPU0_AVSP @BASEBOARD_FAB2_LIB.BASEBOARD_FAB2(SCH_1):VSENSE_PVCCIO_CPU0_AVSP   I104 @BASEBOARD_FAB2_LIB.BASEBOARD_FAB2(SCH_1):PAGE212

SH3P2 SHUNT_SH0201-EMPTY,N_A
     1 VSENSE_PVCCIO_CPU0_SKT_VRTN @BASEBOARD_FAB2_LIB.BASEBOARD_FAB2(SCH_1):VSENSE_PVCCIO_CPU0_SKT_VRTN   I105 @BASEBOARD_FAB2_LIB.BASEBOARD_FAB2(SCH_1):PAGE212
     2 VSENSE_PVCCIO_CPU0_AVSN @BASEBOARD_FAB2_LIB.BASEBOARD_FAB2(SCH_1):VSENSE_PVCCIO_CPU0_AVSN   I105 @BASEBOARD_FAB2_LIB.BASEBOARD_FAB2(SCH_1):PAGE212

SH4L1 SHUNT_SH0201-EMPTY,N_A
     1 VSENSE_PVDDQ_DEF_N @BASEBOARD_FAB2_LIB.BASEBOARD_FAB2(SCH_1):VSENSE_PVDDQ_DEF_N   I240 @BASEBOARD_FAB2_LIB.BASEBOARD_FAB2(SCH_1):PAGE220
     2    GND @BASEBOARD_FAB2_LIB.BASEBOARD_FAB2(SCH_1):GND   I240 @BASEBOARD_FAB2_LIB.BASEBOARD_FAB2(SCH_1):PAGE220

SH4L2 SHUNT_SH0201-EMPTY,N_A
     1 VSENSE_PVDDQ_DEF_P @BASEBOARD_FAB2_LIB.BASEBOARD_FAB2(SCH_1):VSENSE_PVDDQ_DEF_P   I239 @BASEBOARD_FAB2_LIB.BASEBOARD_FAB2(SCH_1):PAGE220
     2 PVDDQ_DEF @BASEBOARD_FAB2_LIB.BASEBOARD_FAB2(SCH_1):PVDDQ_DEF   I239 @BASEBOARD_FAB2_LIB.BASEBOARD_FAB2(SCH_1):PAGE220

SH4U1 SHUNT_SH0201-EMPTY,N_A
     1 VSENSE_PVDDQ_ABC_N @BASEBOARD_FAB2_LIB.BASEBOARD_FAB2(SCH_1):VSENSE_PVDDQ_ABC_N   I259 @BASEBOARD_FAB2_LIB.BASEBOARD_FAB2(SCH_1):PAGE217
     2    GND @BASEBOARD_FAB2_LIB.BASEBOARD_FAB2(SCH_1):GND   I259 @BASEBOARD_FAB2_LIB.BASEBOARD_FAB2(SCH_1):PAGE217

SH4U2 SHUNT_SH0201-EMPTY,N_A
     1 VSENSE_PVDDQ_ABC_P @BASEBOARD_FAB2_LIB.BASEBOARD_FAB2(SCH_1):VSENSE_PVDDQ_ABC_P   I260 @BASEBOARD_FAB2_LIB.BASEBOARD_FAB2(SCH_1):PAGE217
     2 PVDDQ_ABC @BASEBOARD_FAB2_LIB.BASEBOARD_FAB2(SCH_1):PVDDQ_ABC   I260 @BASEBOARD_FAB2_LIB.BASEBOARD_FAB2(SCH_1):PAGE217

SH5L1 SHUNT_SH0201-EMPTY,N_A
     1 VR_PVTT_DEF_SNS @BASEBOARD_FAB2_LIB.BASEBOARD_FAB2(SCH_1):VR_PVTT_DEF_SNS    I53 @BASEBOARD_FAB2_LIB.BASEBOARD_FAB2(SCH_1):PAGE222
     2 PVTT_DEF @BASEBOARD_FAB2_LIB.BASEBOARD_FAB2(SCH_1):PVTT_DEF    I53 @BASEBOARD_FAB2_LIB.BASEBOARD_FAB2(SCH_1):PAGE222

SH5U1 SHUNT_SH0201-EMPTY,N_A
     1 VR_PVTT_ABC_SNS @BASEBOARD_FAB2_LIB.BASEBOARD_FAB2(SCH_1):VR_PVTT_ABC_SNS    I56 @BASEBOARD_FAB2_LIB.BASEBOARD_FAB2(SCH_1):PAGE221
     2 PVTT_ABC @BASEBOARD_FAB2_LIB.BASEBOARD_FAB2(SCH_1):PVTT_ABC    I56 @BASEBOARD_FAB2_LIB.BASEBOARD_FAB2(SCH_1):PAGE221

SH7L1 SHUNT_SH0201-EMPTY,N_A
     1 VSENSE_PVDDQ_KLM_N @BASEBOARD_FAB2_LIB.BASEBOARD_FAB2(SCH_1):VSENSE_PVDDQ_KLM_N   I246 @BASEBOARD_FAB2_LIB.BASEBOARD_FAB2(SCH_1):PAGE228
     2    GND @BASEBOARD_FAB2_LIB.BASEBOARD_FAB2(SCH_1):GND   I246 @BASEBOARD_FAB2_LIB.BASEBOARD_FAB2(SCH_1):PAGE228

SH7L2 SHUNT_SH0201-EMPTY,N_A
     1 VSENSE_PVDDQ_KLM_P @BASEBOARD_FAB2_LIB.BASEBOARD_FAB2(SCH_1):VSENSE_PVDDQ_KLM_P   I245 @BASEBOARD_FAB2_LIB.BASEBOARD_FAB2(SCH_1):PAGE228
     2 PVDDQ_KLM @BASEBOARD_FAB2_LIB.BASEBOARD_FAB2(SCH_1):PVDDQ_KLM   I245 @BASEBOARD_FAB2_LIB.BASEBOARD_FAB2(SCH_1):PAGE228

SH7U1 SHUNT_SH0201-EMPTY,N_A
     1 VSENSE_PVDDQ_GHJ_P @BASEBOARD_FAB2_LIB.BASEBOARD_FAB2(SCH_1):VSENSE_PVDDQ_GHJ_P   I243 @BASEBOARD_FAB2_LIB.BASEBOARD_FAB2(SCH_1):PAGE225
     2 PVDDQ_GHJ @BASEBOARD_FAB2_LIB.BASEBOARD_FAB2(SCH_1):PVDDQ_GHJ   I243 @BASEBOARD_FAB2_LIB.BASEBOARD_FAB2(SCH_1):PAGE225

SH7U2 SHUNT_SH0201-EMPTY,N_A
     1 VSENSE_PVDDQ_GHJ_N @BASEBOARD_FAB2_LIB.BASEBOARD_FAB2(SCH_1):VSENSE_PVDDQ_GHJ_N   I244 @BASEBOARD_FAB2_LIB.BASEBOARD_FAB2(SCH_1):PAGE225
     2    GND @BASEBOARD_FAB2_LIB.BASEBOARD_FAB2(SCH_1):GND   I244 @BASEBOARD_FAB2_LIB.BASEBOARD_FAB2(SCH_1):PAGE225

SH8L1 SHUNT_SH0201-EMPTY,N_A
     1 VR_PVTT_KLM_SNS @BASEBOARD_FAB2_LIB.BASEBOARD_FAB2(SCH_1):VR_PVTT_KLM_SNS    I53 @BASEBOARD_FAB2_LIB.BASEBOARD_FAB2(SCH_1):PAGE230
     2 PVTT_KLM @BASEBOARD_FAB2_LIB.BASEBOARD_FAB2(SCH_1):PVTT_KLM    I53 @BASEBOARD_FAB2_LIB.BASEBOARD_FAB2(SCH_1):PAGE230

SH8U1 SHUNT_SH0201-EMPTY,N_A
     1 VR_PVTT_GHJ_SNS @BASEBOARD_FAB2_LIB.BASEBOARD_FAB2(SCH_1):VR_PVTT_GHJ_SNS    I53 @BASEBOARD_FAB2_LIB.BASEBOARD_FAB2(SCH_1):PAGE229
     2 PVTT_GHJ @BASEBOARD_FAB2_LIB.BASEBOARD_FAB2(SCH_1):PVTT_GHJ    I53 @BASEBOARD_FAB2_LIB.BASEBOARD_FAB2(SCH_1):PAGE229

TC1A1 RCC_DFX1940_ID4-EMPTY,N_A
     1    GND @BASEBOARD_FAB2_LIB.BASEBOARD_FAB2(SCH_1):GND     I7 @BASEBOARD_FAB2_LIB.BASEBOARD_FAB2(SCH_1):PAGE110
     2 RCC_DFX_1940_1 @BASEBOARD_FAB2_LIB.BASEBOARD_FAB2(SCH_1):RCC_DFX_1940_1     I7 @BASEBOARD_FAB2_LIB.BASEBOARD_FAB2(SCH_1):PAGE110
     3 RCC_DFX_1940_1 @BASEBOARD_FAB2_LIB.BASEBOARD_FAB2(SCH_1):RCC_DFX_1940_1     I7 @BASEBOARD_FAB2_LIB.BASEBOARD_FAB2(SCH_1):PAGE110

TC1G1 RCC_DFX1940_ID4-EMPTY,N_A
     1    GND @BASEBOARD_FAB2_LIB.BASEBOARD_FAB2(SCH_1):GND     I3 @BASEBOARD_FAB2_LIB.BASEBOARD_FAB2(SCH_1):PAGE110
     2 RCC_DFX_1940_4 @BASEBOARD_FAB2_LIB.BASEBOARD_FAB2(SCH_1):RCC_DFX_1940_4     I3 @BASEBOARD_FAB2_LIB.BASEBOARD_FAB2(SCH_1):PAGE110
     3 RCC_DFX_1940_4 @BASEBOARD_FAB2_LIB.BASEBOARD_FAB2(SCH_1):RCC_DFX_1940_4     I3 @BASEBOARD_FAB2_LIB.BASEBOARD_FAB2(SCH_1):PAGE110

TC9A1 RCC_DFX1940_ID4-EMPTY,N_A
     1    GND @BASEBOARD_FAB2_LIB.BASEBOARD_FAB2(SCH_1):GND     I9 @BASEBOARD_FAB2_LIB.BASEBOARD_FAB2(SCH_1):PAGE110
     2 RCC_DFX_1940_2 @BASEBOARD_FAB2_LIB.BASEBOARD_FAB2(SCH_1):RCC_DFX_1940_2     I9 @BASEBOARD_FAB2_LIB.BASEBOARD_FAB2(SCH_1):PAGE110
     3 RCC_DFX_1940_2 @BASEBOARD_FAB2_LIB.BASEBOARD_FAB2(SCH_1):RCC_DFX_1940_2     I9 @BASEBOARD_FAB2_LIB.BASEBOARD_FAB2(SCH_1):PAGE110

TC9F1 RCC_DFX1940_ID4-EMPTY,N_A
     1    GND @BASEBOARD_FAB2_LIB.BASEBOARD_FAB2(SCH_1):GND     I1 @BASEBOARD_FAB2_LIB.BASEBOARD_FAB2(SCH_1):PAGE110
     2 RCC_DFX_1940_3 @BASEBOARD_FAB2_LIB.BASEBOARD_FAB2(SCH_1):RCC_DFX_1940_3     I1 @BASEBOARD_FAB2_LIB.BASEBOARD_FAB2(SCH_1):PAGE110
     3 RCC_DFX_1940_3 @BASEBOARD_FAB2_LIB.BASEBOARD_FAB2(SCH_1):RCC_DFX_1940_3     I1 @BASEBOARD_FAB2_LIB.BASEBOARD_FAB2(SCH_1):PAGE110

TH1A1 MTG_KEYHOLE_TH-EMPTY,NA
     1    GND @BASEBOARD_FAB2_LIB.BASEBOARD_FAB2(SCH_1):GND    I56 @BASEBOARD_FAB2_LIB.BASEBOARD_FAB2(SCH_1):PAGE195

TH4A1 MTG_KEYHOLE_TH-EMPTY,NA
     1    GND @BASEBOARD_FAB2_LIB.BASEBOARD_FAB2(SCH_1):GND    I62 @BASEBOARD_FAB2_LIB.BASEBOARD_FAB2(SCH_1):PAGE195

TH4G1 MTG_KEYHOLE_TH-EMPTY,NA
     1    GND @BASEBOARD_FAB2_LIB.BASEBOARD_FAB2(SCH_1):GND    I49 @BASEBOARD_FAB2_LIB.BASEBOARD_FAB2(SCH_1):PAGE195

TH7A1 MTG_KEYHOLE_TH-EMPTY,NA
     1    GND @BASEBOARD_FAB2_LIB.BASEBOARD_FAB2(SCH_1):GND    I65 @BASEBOARD_FAB2_LIB.BASEBOARD_FAB2(SCH_1):PAGE195

TH7G1 MTG_KEYHOLE_TH-EMPTY,NA
     1    GND @BASEBOARD_FAB2_LIB.BASEBOARD_FAB2(SCH_1):GND    I67 @BASEBOARD_FAB2_LIB.BASEBOARD_FAB2(SCH_1):PAGE195

TH9A1 MTG_KEYHOLE_TH-EMPTY,NA
     1    GND @BASEBOARD_FAB2_LIB.BASEBOARD_FAB2(SCH_1):GND    I54 @BASEBOARD_FAB2_LIB.BASEBOARD_FAB2(SCH_1):PAGE195

TH9G1 MTG_KEYHOLE_TH-EMPTY,NA
     1    GND @BASEBOARD_FAB2_LIB.BASEBOARD_FAB2(SCH_1):GND    I52 @BASEBOARD_FAB2_LIB.BASEBOARD_FAB2(SCH_1):PAGE195

U1B1 MAX9634_SOT-IC,H35789-001
     1    GND @BASEBOARD_FAB2_LIB.BASEBOARD_FAB2(SCH_1):GND   I144 @BASEBOARD_FAB2_LIB.BASEBOARD_FAB2(SCH_1):PAGE197
     2    GND @BASEBOARD_FAB2_LIB.BASEBOARD_FAB2(SCH_1):GND   I144 @BASEBOARD_FAB2_LIB.BASEBOARD_FAB2(SCH_1):PAGE197
     3 VR_PVDDQ_KLM_AIINSEN_R @BASEBOARD_FAB2_LIB.BASEBOARD_FAB2(SCH_1):VR_PVDDQ_KLM_AIINSEN_R   I144 @BASEBOARD_FAB2_LIB.BASEBOARD_FAB2(SCH_1):PAGE197
     4 P12V_NVDIMM_KLM @BASEBOARD_FAB2_LIB.BASEBOARD_FAB2(SCH_1):P12V_NVDIMM_KLM   I144 @BASEBOARD_FAB2_LIB.BASEBOARD_FAB2(SCH_1):PAGE197
     5 P12V_STBY @BASEBOARD_FAB2_LIB.BASEBOARD_FAB2(SCH_1):P12V_STBY   I144 @BASEBOARD_FAB2_LIB.BASEBOARD_FAB2(SCH_1):PAGE197

U1B2 PCA9517_SM-IC,G77073-001-GND=GA
     5 TP_SMB_PEHPCPU1_EN @BASEBOARD_FAB2_LIB.BASEBOARD_FAB2(SCH_1):TP_SMB_PEHPCPU1_EN     I1 @BASEBOARD_FAB2_LIB.BASEBOARD_FAB2(SCH_1):PAGE163
     2 SMB_CPU1_PE_HP_GTL_R_SCL @BASEBOARD_FAB2_LIB.BASEBOARD_FAB2(SCH_1):SMB_CPU1_PE_HP_GTL_R_SCL     I1 @BASEBOARD_FAB2_LIB.BASEBOARD_FAB2(SCH_1):PAGE163
     7 SMB_PEHPCPU1_STBY_LVC3_R_SCL @BASEBOARD_FAB2_LIB.BASEBOARD_FAB2(SCH_1):SMB_PEHPCPU1_STBY_LVC3_R_SCL     I1 @BASEBOARD_FAB2_LIB.BASEBOARD_FAB2(SCH_1):PAGE163
     3 SMB_CPU1_PE_HP_GTL_R_SDA @BASEBOARD_FAB2_LIB.BASEBOARD_FAB2(SCH_1):SMB_CPU1_PE_HP_GTL_R_SDA     I1 @BASEBOARD_FAB2_LIB.BASEBOARD_FAB2(SCH_1):PAGE163
     6 SMB_PEHPCPU1_STBY_LVC3_R_SDA @BASEBOARD_FAB2_LIB.BASEBOARD_FAB2(SCH_1):SMB_PEHPCPU1_STBY_LVC3_R_SDA     I1 @BASEBOARD_FAB2_LIB.BASEBOARD_FAB2(SCH_1):PAGE163
     1 PVCCIO_CPU1 @BASEBOARD_FAB2_LIB.BASEBOARD_FAB2(SCH_1):PVCCIO_CPU1     I1 @BASEBOARD_FAB2_LIB.BASEBOARD_FAB2(SCH_1):PAGE163
     8 P3V3_STBY @BASEBOARD_FAB2_LIB.BASEBOARD_FAB2(SCH_1):P3V3_STBY     I1 @BASEBOARD_FAB2_LIB.BASEBOARD_FAB2(SCH_1):PAGE163

U1B3 ADM4073_SM-EMPTY,G12194-001
     2    GND @BASEBOARD_FAB2_LIB.BASEBOARD_FAB2(SCH_1):GND    I52 @BASEBOARD_FAB2_LIB.BASEBOARD_FAB2(SCH_1):PAGE209
     1    GND @BASEBOARD_FAB2_LIB.BASEBOARD_FAB2(SCH_1):GND    I52 @BASEBOARD_FAB2_LIB.BASEBOARD_FAB2(SCH_1):PAGE209
     6 PVCCIN_PVSA_CPU1_IINSEN @BASEBOARD_FAB2_LIB.BASEBOARD_FAB2(SCH_1):PVCCIN_PVSA_CPU1_IINSEN    I52 @BASEBOARD_FAB2_LIB.BASEBOARD_FAB2(SCH_1):PAGE209
     5 VR_FET_SW_P12V_STBY_PVCCIN_CPU1 @BASEBOARD_FAB2_LIB.BASEBOARD_FAB2(SCH_1):VR_FET_SW_P12V_STBY_PVCCIN_CPU1    I52 @BASEBOARD_FAB2_LIB.BASEBOARD_FAB2(SCH_1):PAGE209
     4 VR_FET_SW_P12V_PVCCIN_CPU1_R @BASEBOARD_FAB2_LIB.BASEBOARD_FAB2(SCH_1):VR_FET_SW_P12V_PVCCIN_CPU1_R    I52 @BASEBOARD_FAB2_LIB.BASEBOARD_FAB2(SCH_1):PAGE209
     3 VR_FET_SW_P12V_PVCCIN_CPU1_R @BASEBOARD_FAB2_LIB.BASEBOARD_FAB2(SCH_1):VR_FET_SW_P12V_PVCCIN_CPU1_R    I52 @BASEBOARD_FAB2_LIB.BASEBOARD_FAB2(SCH_1):PAGE209

U1D1 TTL1G126_A_SOT-74HC1G126,IC,A7B
     1 FM_OC_DETECT_EN @BASEBOARD_FAB2_LIB.BASEBOARD_FAB2(SCH_1):FM_OC_DETECT_EN   I103 @BASEBOARD_FAB2_LIB.BASEBOARD_FAB2(SCH_1):PAGE200
     2 IRQ_OC_DETECT_N @BASEBOARD_FAB2_LIB.BASEBOARD_FAB2(SCH_1):IRQ_OC_DETECT_N   I103 @BASEBOARD_FAB2_LIB.BASEBOARD_FAB2(SCH_1):PAGE200
     4 FM_OC_DETECT_N @BASEBOARD_FAB2_LIB.BASEBOARD_FAB2(SCH_1):FM_OC_DETECT_N   I103 @BASEBOARD_FAB2_LIB.BASEBOARD_FAB2(SCH_1):PAGE200

U1D2 TPS3700_SM-IC,H69492-001
     5    GND @BASEBOARD_FAB2_LIB.BASEBOARD_FAB2(SCH_1):GND   I170 @BASEBOARD_FAB2_LIB.BASEBOARD_FAB2(SCH_1):PAGE200
     4 A_HSC_LOW @BASEBOARD_FAB2_LIB.BASEBOARD_FAB2(SCH_1):A_HSC_LOW   I170 @BASEBOARD_FAB2_LIB.BASEBOARD_FAB2(SCH_1):PAGE200
     3 A_HSC_HIGH @BASEBOARD_FAB2_LIB.BASEBOARD_FAB2(SCH_1):A_HSC_HIGH   I170 @BASEBOARD_FAB2_LIB.BASEBOARD_FAB2(SCH_1):PAGE200
     6 A_HSC_LOW_GATE @BASEBOARD_FAB2_LIB.BASEBOARD_FAB2(SCH_1):A_HSC_LOW_GATE   I170 @BASEBOARD_FAB2_LIB.BASEBOARD_FAB2(SCH_1):PAGE200
     1 IRQ_OC_DETECT_N @BASEBOARD_FAB2_LIB.BASEBOARD_FAB2(SCH_1):IRQ_OC_DETECT_N   I170 @BASEBOARD_FAB2_LIB.BASEBOARD_FAB2(SCH_1):PAGE200
     2 P12V_STBY @BASEBOARD_FAB2_LIB.BASEBOARD_FAB2(SCH_1):P12V_STBY   I170 @BASEBOARD_FAB2_LIB.BASEBOARD_FAB2(SCH_1):PAGE200

U1E1 TMP421_TSSOP-IC,G62962-001
     3 PD_TMP421_2_A1 @BASEBOARD_FAB2_LIB.BASEBOARD_FAB2(SCH_1):PD_TMP421_2_A1    I30 @BASEBOARD_FAB2_LIB.BASEBOARD_FAB2(SCH_1):PAGE167
     4 PU_TMP421_2_A0 @BASEBOARD_FAB2_LIB.BASEBOARD_FAB2(SCH_1):PU_TMP421_2_A0    I30 @BASEBOARD_FAB2_LIB.BASEBOARD_FAB2(SCH_1):PAGE167
     2 ISENSE_TMP421_2_DXN @BASEBOARD_FAB2_LIB.BASEBOARD_FAB2(SCH_1):ISENSE_TMP421_2_DXN    I30 @BASEBOARD_FAB2_LIB.BASEBOARD_FAB2(SCH_1):PAGE167
     1 ISENSE_TMP421_2_DXP @BASEBOARD_FAB2_LIB.BASEBOARD_FAB2(SCH_1):ISENSE_TMP421_2_DXP    I30 @BASEBOARD_FAB2_LIB.BASEBOARD_FAB2(SCH_1):PAGE167
     5    GND @BASEBOARD_FAB2_LIB.BASEBOARD_FAB2(SCH_1):GND    I30 @BASEBOARD_FAB2_LIB.BASEBOARD_FAB2(SCH_1):PAGE167
     7 SMB_SENSOR_TMP421_2_SCL @BASEBOARD_FAB2_LIB.BASEBOARD_FAB2(SCH_1):SMB_SENSOR_TMP421_2_SCL    I30 @BASEBOARD_FAB2_LIB.BASEBOARD_FAB2(SCH_1):PAGE167
     6 SMB_SENSOR_TMP421_2_SDA @BASEBOARD_FAB2_LIB.BASEBOARD_FAB2(SCH_1):SMB_SENSOR_TMP421_2_SDA    I30 @BASEBOARD_FAB2_LIB.BASEBOARD_FAB2(SCH_1):PAGE167
     8 P3V3_STBY @BASEBOARD_FAB2_LIB.BASEBOARD_FAB2(SCH_1):P3V3_STBY    I30 @BASEBOARD_FAB2_LIB.BASEBOARD_FAB2(SCH_1):PAGE167

U1E2 TTL1G08_SOTLF-NC7SZ08,IC,D1032B
     4 FM_ENABLE_FAN_POWER @BASEBOARD_FAB2_LIB.BASEBOARD_FAB2(SCH_1):FM_ENABLE_FAN_POWER   I121 @BASEBOARD_FAB2_LIB.BASEBOARD_FAB2(SCH_1):PAGE161
     1 FM_CTNR_PS_ON @BASEBOARD_FAB2_LIB.BASEBOARD_FAB2(SCH_1):FM_CTNR_PS_ON   I121 @BASEBOARD_FAB2_LIB.BASEBOARD_FAB2(SCH_1):PAGE161
     2 FM_DISABLE_FAN_N @BASEBOARD_FAB2_LIB.BASEBOARD_FAB2(SCH_1):FM_DISABLE_FAN_N   I121 @BASEBOARD_FAB2_LIB.BASEBOARD_FAB2(SCH_1):PAGE161

U1F1 MAX9634_SOT-IC,H35789-001
     1    GND @BASEBOARD_FAB2_LIB.BASEBOARD_FAB2(SCH_1):GND   I133 @BASEBOARD_FAB2_LIB.BASEBOARD_FAB2(SCH_1):PAGE197
     2    GND @BASEBOARD_FAB2_LIB.BASEBOARD_FAB2(SCH_1):GND   I133 @BASEBOARD_FAB2_LIB.BASEBOARD_FAB2(SCH_1):PAGE197
     3 VR_PVDDQ_GHJ_AIINSEN_R @BASEBOARD_FAB2_LIB.BASEBOARD_FAB2(SCH_1):VR_PVDDQ_GHJ_AIINSEN_R   I133 @BASEBOARD_FAB2_LIB.BASEBOARD_FAB2(SCH_1):PAGE197
     4 P12V_NVDIMM_GHJ @BASEBOARD_FAB2_LIB.BASEBOARD_FAB2(SCH_1):P12V_NVDIMM_GHJ   I133 @BASEBOARD_FAB2_LIB.BASEBOARD_FAB2(SCH_1):PAGE197
     5 P12V_STBY @BASEBOARD_FAB2_LIB.BASEBOARD_FAB2(SCH_1):P12V_STBY   I133 @BASEBOARD_FAB2_LIB.BASEBOARD_FAB2(SCH_1):PAGE197

U1L1 TTL3126_QFNLF-74CBTLV3126,IC,DB
     1 PWRGD_PVCCIN_CPU0 @BASEBOARD_FAB2_LIB.BASEBOARD_FAB2(SCH_1):PWRGD_PVCCIN_CPU0   I108 @BASEBOARD_FAB2_LIB.BASEBOARD_FAB2(SCH_1):PAGE112
     2 XDP_TRST_N @BASEBOARD_FAB2_LIB.BASEBOARD_FAB2(SCH_1):XDP_TRST_N   I108 @BASEBOARD_FAB2_LIB.BASEBOARD_FAB2(SCH_1):PAGE112
     3 XDP_CPU_TRST_N @BASEBOARD_FAB2_LIB.BASEBOARD_FAB2(SCH_1):XDP_CPU_TRST_N   I108 @BASEBOARD_FAB2_LIB.BASEBOARD_FAB2(SCH_1):PAGE112
     4 PWRGD_PVCCIN_CPU0 @BASEBOARD_FAB2_LIB.BASEBOARD_FAB2(SCH_1):PWRGD_PVCCIN_CPU0   I108 @BASEBOARD_FAB2_LIB.BASEBOARD_FAB2(SCH_1):PAGE112
     5 XDP_TMS @BASEBOARD_FAB2_LIB.BASEBOARD_FAB2(SCH_1):XDP_TMS   I108 @BASEBOARD_FAB2_LIB.BASEBOARD_FAB2(SCH_1):PAGE112
     6 XDP_CPU_TMS @BASEBOARD_FAB2_LIB.BASEBOARD_FAB2(SCH_1):XDP_CPU_TMS   I108 @BASEBOARD_FAB2_LIB.BASEBOARD_FAB2(SCH_1):PAGE112
    10 PWRGD_PVCCIN_CPU0 @BASEBOARD_FAB2_LIB.BASEBOARD_FAB2(SCH_1):PWRGD_PVCCIN_CPU0   I108 @BASEBOARD_FAB2_LIB.BASEBOARD_FAB2(SCH_1):PAGE112
     9 XDP_TDO @BASEBOARD_FAB2_LIB.BASEBOARD_FAB2(SCH_1):XDP_TDO   I108 @BASEBOARD_FAB2_LIB.BASEBOARD_FAB2(SCH_1):PAGE112
     8 XDP_CPU_TDO @BASEBOARD_FAB2_LIB.BASEBOARD_FAB2(SCH_1):XDP_CPU_TDO   I108 @BASEBOARD_FAB2_LIB.BASEBOARD_FAB2(SCH_1):PAGE112
    13 PWRGD_PVCCIN_CPU0 @BASEBOARD_FAB2_LIB.BASEBOARD_FAB2(SCH_1):PWRGD_PVCCIN_CPU0   I108 @BASEBOARD_FAB2_LIB.BASEBOARD_FAB2(SCH_1):PAGE112
    12 XDP_TDI @BASEBOARD_FAB2_LIB.BASEBOARD_FAB2(SCH_1):XDP_TDI   I108 @BASEBOARD_FAB2_LIB.BASEBOARD_FAB2(SCH_1):PAGE112
    11 XDP_CPU_TDI @BASEBOARD_FAB2_LIB.BASEBOARD_FAB2(SCH_1):XDP_CPU_TDI   I108 @BASEBOARD_FAB2_LIB.BASEBOARD_FAB2(SCH_1):PAGE112

U1L2 TTL1G86_SOTLF-74AHCT1G86,IC,D3B
     1 PWRGD_P3V3_R @BASEBOARD_FAB2_LIB.BASEBOARD_FAB2(SCH_1):PWRGD_P3V3_R    I57 @BASEBOARD_FAB2_LIB.BASEBOARD_FAB2(SCH_1):PAGE175
     2 FP_PWR_ID_LED_N @BASEBOARD_FAB2_LIB.BASEBOARD_FAB2(SCH_1):FP_PWR_ID_LED_N    I57 @BASEBOARD_FAB2_LIB.BASEBOARD_FAB2(SCH_1):PAGE175
     4 FP_ID_LED_P5V_STBY_N @BASEBOARD_FAB2_LIB.BASEBOARD_FAB2(SCH_1):FP_ID_LED_P5V_STBY_N    I57 @BASEBOARD_FAB2_LIB.BASEBOARD_FAB2(SCH_1):PAGE175

U1L3 ADM809_SMLF-IC,D23047-001-GND=A
     3   P3V3 @BASEBOARD_FAB2_LIB.BASEBOARD_FAB2(SCH_1):P3V3    I80 @BASEBOARD_FAB2_LIB.BASEBOARD_FAB2(SCH_1):PAGE196
     2 PWRGD_P3V3_R1 @BASEBOARD_FAB2_LIB.BASEBOARD_FAB2(SCH_1):PWRGD_P3V3_R1    I80 @BASEBOARD_FAB2_LIB.BASEBOARD_FAB2(SCH_1):PAGE196

U1L4 TTL1G07_A_SOP-74LVC1G07,IC,C88B
     2 XDP_RST_CO_N @BASEBOARD_FAB2_LIB.BASEBOARD_FAB2(SCH_1):XDP_RST_CO_N    I85 @BASEBOARD_FAB2_LIB.BASEBOARD_FAB2(SCH_1):PAGE111
     4 FM_DEBUG_RST_BTN_R1_N @BASEBOARD_FAB2_LIB.BASEBOARD_FAB2(SCH_1):FM_DEBUG_RST_BTN_R1_N    I85 @BASEBOARD_FAB2_LIB.BASEBOARD_FAB2(SCH_1):PAGE111

U1L5 TTL3126_QFNLF-74CBTLV3126,IC,DB
     1 PWRGD_PVCCIN_CPU0 @BASEBOARD_FAB2_LIB.BASEBOARD_FAB2(SCH_1):PWRGD_PVCCIN_CPU0   I109 @BASEBOARD_FAB2_LIB.BASEBOARD_FAB2(SCH_1):PAGE112
     2 XDP_OBSFN_B1_MBP7_N @BASEBOARD_FAB2_LIB.BASEBOARD_FAB2(SCH_1):XDP_OBSFN_B1_MBP7_N   I109 @BASEBOARD_FAB2_LIB.BASEBOARD_FAB2(SCH_1):PAGE112
     3 XDP_CPU_OBSFN_B1_MBP7_N @BASEBOARD_FAB2_LIB.BASEBOARD_FAB2(SCH_1):XDP_CPU_OBSFN_B1_MBP7_N   I109 @BASEBOARD_FAB2_LIB.BASEBOARD_FAB2(SCH_1):PAGE112
     4 PWRGD_PVCCIN_CPU0 @BASEBOARD_FAB2_LIB.BASEBOARD_FAB2(SCH_1):PWRGD_PVCCIN_CPU0   I109 @BASEBOARD_FAB2_LIB.BASEBOARD_FAB2(SCH_1):PAGE112
     5 XDP_OBSFN_B0_MBP6_N @BASEBOARD_FAB2_LIB.BASEBOARD_FAB2(SCH_1):XDP_OBSFN_B0_MBP6_N   I109 @BASEBOARD_FAB2_LIB.BASEBOARD_FAB2(SCH_1):PAGE112
     6 XDP_CPU_OBSFN_B0_MBP6_N @BASEBOARD_FAB2_LIB.BASEBOARD_FAB2(SCH_1):XDP_CPU_OBSFN_B0_MBP6_N   I109 @BASEBOARD_FAB2_LIB.BASEBOARD_FAB2(SCH_1):PAGE112
    10 PWRGD_PVCCIN_CPU0 @BASEBOARD_FAB2_LIB.BASEBOARD_FAB2(SCH_1):PWRGD_PVCCIN_CPU0   I109 @BASEBOARD_FAB2_LIB.BASEBOARD_FAB2(SCH_1):PAGE112
     9 XDP_PRDY_N @BASEBOARD_FAB2_LIB.BASEBOARD_FAB2(SCH_1):XDP_PRDY_N   I109 @BASEBOARD_FAB2_LIB.BASEBOARD_FAB2(SCH_1):PAGE112
     8 XDP_CPU_PRDY_N @BASEBOARD_FAB2_LIB.BASEBOARD_FAB2(SCH_1):XDP_CPU_PRDY_N   I109 @BASEBOARD_FAB2_LIB.BASEBOARD_FAB2(SCH_1):PAGE112
    13 PWRGD_PVCCIN_CPU0 @BASEBOARD_FAB2_LIB.BASEBOARD_FAB2(SCH_1):PWRGD_PVCCIN_CPU0   I109 @BASEBOARD_FAB2_LIB.BASEBOARD_FAB2(SCH_1):PAGE112
    12 XDP_PREQ_N @BASEBOARD_FAB2_LIB.BASEBOARD_FAB2(SCH_1):XDP_PREQ_N   I109 @BASEBOARD_FAB2_LIB.BASEBOARD_FAB2(SCH_1):PAGE112
    11 XDP_CPU_PREQ_N @BASEBOARD_FAB2_LIB.BASEBOARD_FAB2(SCH_1):XDP_CPU_PREQ_N   I109 @BASEBOARD_FAB2_LIB.BASEBOARD_FAB2(SCH_1):PAGE112

U1M1 TTL1G08_SOTLF-NC7SZ08,IC,D1032C
     4 FP_LED_HDD_ACTIVITY_AND_N @BASEBOARD_FAB2_LIB.BASEBOARD_FAB2(SCH_1):FP_LED_HDD_ACTIVITY_AND_N    I70 @BASEBOARD_FAB2_LIB.BASEBOARD_FAB2(SCH_1):PAGE177
     1 LED_SATA_ACT_R_N @BASEBOARD_FAB2_LIB.BASEBOARD_FAB2(SCH_1):LED_SATA_ACT_R_N    I70 @BASEBOARD_FAB2_LIB.BASEBOARD_FAB2(SCH_1):PAGE177
     2 LED_SAS_ACT_R_N @BASEBOARD_FAB2_LIB.BASEBOARD_FAB2(SCH_1):LED_SAS_ACT_R_N    I70 @BASEBOARD_FAB2_LIB.BASEBOARD_FAB2(SCH_1):PAGE177

U1M2 NC7SB3157_SMLF-IC,C99406-001
     6 FM_CPU1_CD_PRES @BASEBOARD_FAB2_LIB.BASEBOARD_FAB2(SCH_1):FM_CPU1_CD_PRES   I107 @BASEBOARD_FAB2_LIB.BASEBOARD_FAB2(SCH_1):PAGE113
     3 JTAG_MCP_CPU1_TDO @BASEBOARD_FAB2_LIB.BASEBOARD_FAB2(SCH_1):JTAG_MCP_CPU1_TDO   I107 @BASEBOARD_FAB2_LIB.BASEBOARD_FAB2(SCH_1):PAGE113
     1 JTAG_MCP_CPU0_TDO @BASEBOARD_FAB2_LIB.BASEBOARD_FAB2(SCH_1):JTAG_MCP_CPU0_TDO   I107 @BASEBOARD_FAB2_LIB.BASEBOARD_FAB2(SCH_1):PAGE113
     4 JTAG_MCP_MUX_TDO @BASEBOARD_FAB2_LIB.BASEBOARD_FAB2(SCH_1):JTAG_MCP_MUX_TDO   I107 @BASEBOARD_FAB2_LIB.BASEBOARD_FAB2(SCH_1):PAGE113
     5 P3V3_STBY @BASEBOARD_FAB2_LIB.BASEBOARD_FAB2(SCH_1):P3V3_STBY   I107 @BASEBOARD_FAB2_LIB.BASEBOARD_FAB2(SCH_1):PAGE113
     2    GND @BASEBOARD_FAB2_LIB.BASEBOARD_FAB2(SCH_1):GND   I107 @BASEBOARD_FAB2_LIB.BASEBOARD_FAB2(SCH_1):PAGE113

U1M3 TPS2061_SM-IC,H66405-001
     4 FM_USB_P0_EN_BOOT_BIOS_STRAP_N @BASEBOARD_FAB2_LIB.BASEBOARD_FAB2(SCH_1):FM_USB_P0_EN_BOOT_BIOS_STRAP_N   I100 @BASEBOARD_FAB2_LIB.BASEBOARD_FAB2(SCH_1):PAGE176
     2    GND @BASEBOARD_FAB2_LIB.BASEBOARD_FAB2(SCH_1):GND   I100 @BASEBOARD_FAB2_LIB.BASEBOARD_FAB2(SCH_1):PAGE176
     5    P5V @BASEBOARD_FAB2_LIB.BASEBOARD_FAB2(SCH_1):P5V   I100 @BASEBOARD_FAB2_LIB.BASEBOARD_FAB2(SCH_1):PAGE176
     3 FM_OC0_USB_N @BASEBOARD_FAB2_LIB.BASEBOARD_FAB2(SCH_1):FM_OC0_USB_N   I100 @BASEBOARD_FAB2_LIB.BASEBOARD_FAB2(SCH_1):PAGE176
     1 P5V_USB @BASEBOARD_FAB2_LIB.BASEBOARD_FAB2(SCH_1):P5V_USB   I100 @BASEBOARD_FAB2_LIB.BASEBOARD_FAB2(SCH_1):PAGE176

U1M4 74CBTLV1G125_SMLF-IC,C88177-00A
     4 XDP_CPU1_TDI @BASEBOARD_FAB2_LIB.BASEBOARD_FAB2(SCH_1):XDP_CPU1_TDI   I127 @BASEBOARD_FAB2_LIB.BASEBOARD_FAB2(SCH_1):PAGE112
     1 FM_CPU1_SKTOCC_LVT3_N @BASEBOARD_FAB2_LIB.BASEBOARD_FAB2(SCH_1):FM_CPU1_SKTOCC_LVT3_N   I127 @BASEBOARD_FAB2_LIB.BASEBOARD_FAB2(SCH_1):PAGE112
     2 XDP_CPU0_TDO @BASEBOARD_FAB2_LIB.BASEBOARD_FAB2(SCH_1):XDP_CPU0_TDO   I127 @BASEBOARD_FAB2_LIB.BASEBOARD_FAB2(SCH_1):PAGE112

U1M5 74CBTLV1G125_SMLF-IC,C88177-00A
     4 JTAG_MCP_TMS_R1 @BASEBOARD_FAB2_LIB.BASEBOARD_FAB2(SCH_1):JTAG_MCP_TMS_R1   I196 @BASEBOARD_FAB2_LIB.BASEBOARD_FAB2(SCH_1):PAGE113
     1 FM_CPU0_OR_CPU1_MCP_PRES @BASEBOARD_FAB2_LIB.BASEBOARD_FAB2(SCH_1):FM_CPU0_OR_CPU1_MCP_PRES   I196 @BASEBOARD_FAB2_LIB.BASEBOARD_FAB2(SCH_1):PAGE113
     2 P1V8_MCP_CPU0 @BASEBOARD_FAB2_LIB.BASEBOARD_FAB2(SCH_1):P1V8_MCP_CPU0   I196 @BASEBOARD_FAB2_LIB.BASEBOARD_FAB2(SCH_1):PAGE113

U1M6 74CBTLV1G125_SMLF-IC,C88177-00A
     4 JTAG_MCP_CPU1_TDI @BASEBOARD_FAB2_LIB.BASEBOARD_FAB2(SCH_1):JTAG_MCP_CPU1_TDI   I127 @BASEBOARD_FAB2_LIB.BASEBOARD_FAB2(SCH_1):PAGE113
     1 FM_CPU0_AND_CPU1_MCP_PRES @BASEBOARD_FAB2_LIB.BASEBOARD_FAB2(SCH_1):FM_CPU0_AND_CPU1_MCP_PRES   I127 @BASEBOARD_FAB2_LIB.BASEBOARD_FAB2(SCH_1):PAGE113
     2 JTAG_MCP_CPU0_TDO @BASEBOARD_FAB2_LIB.BASEBOARD_FAB2(SCH_1):JTAG_MCP_CPU0_TDO   I127 @BASEBOARD_FAB2_LIB.BASEBOARD_FAB2(SCH_1):PAGE113

U1M7 NC7SB3157_SMLF-IC,C99406-001
     6 FM_CPU1_SKTOCC_LVT3_N @BASEBOARD_FAB2_LIB.BASEBOARD_FAB2(SCH_1):FM_CPU1_SKTOCC_LVT3_N    I40 @BASEBOARD_FAB2_LIB.BASEBOARD_FAB2(SCH_1):PAGE112
     3 XDP_CPU1_TDO @BASEBOARD_FAB2_LIB.BASEBOARD_FAB2(SCH_1):XDP_CPU1_TDO    I40 @BASEBOARD_FAB2_LIB.BASEBOARD_FAB2(SCH_1):PAGE112
     1 XDP_CPU0_TDO @BASEBOARD_FAB2_LIB.BASEBOARD_FAB2(SCH_1):XDP_CPU0_TDO    I40 @BASEBOARD_FAB2_LIB.BASEBOARD_FAB2(SCH_1):PAGE112
     4 XDP_CPU_TDO @BASEBOARD_FAB2_LIB.BASEBOARD_FAB2(SCH_1):XDP_CPU_TDO    I40 @BASEBOARD_FAB2_LIB.BASEBOARD_FAB2(SCH_1):PAGE112
     5 P3V3_STBY @BASEBOARD_FAB2_LIB.BASEBOARD_FAB2(SCH_1):P3V3_STBY    I40 @BASEBOARD_FAB2_LIB.BASEBOARD_FAB2(SCH_1):PAGE112
     2    GND @BASEBOARD_FAB2_LIB.BASEBOARD_FAB2(SCH_1):GND    I40 @BASEBOARD_FAB2_LIB.BASEBOARD_FAB2(SCH_1):PAGE112

U1R1 TTL1G07_A_SOP-74LVC1G07,IC,C88B
     2 FM_FAST_PROCHOT_THROTTLE_DLY_BU @BASEBOARD_FAB2_LIB.BASEBOARD_FAB2(SCH_1):FM_FAST_PROCHOT_THROTTLE_DLY_BUF_N    I46 @BASEBOARD_FAB2_LIB.BASEBOARD_FAB2(SCH_1):PAGE170
     4 FM_THROTTLE_R1_N @BASEBOARD_FAB2_LIB.BASEBOARD_FAB2(SCH_1):FM_THROTTLE_R1_N    I46 @BASEBOARD_FAB2_LIB.BASEBOARD_FAB2(SCH_1):PAGE170

U1R2 TTL1G126_A_SOT-74HC1G126,IC,A7B
     1 FM_FAST_PROCHOT_EN @BASEBOARD_FAB2_LIB.BASEBOARD_FAB2(SCH_1):FM_FAST_PROCHOT_EN    I20 @BASEBOARD_FAB2_LIB.BASEBOARD_FAB2(SCH_1):PAGE170
     2 FM_FAST_PROCHOT_THROTTLE_DLY_N @BASEBOARD_FAB2_LIB.BASEBOARD_FAB2(SCH_1):FM_FAST_PROCHOT_THROTTLE_DLY_N    I20 @BASEBOARD_FAB2_LIB.BASEBOARD_FAB2(SCH_1):PAGE170
     4 FM_FAST_PROCHOT_THROTTLE_DLY_BU @BASEBOARD_FAB2_LIB.BASEBOARD_FAB2(SCH_1):FM_FAST_PROCHOT_THROTTLE_DLY_BUF_N    I20 @BASEBOARD_FAB2_LIB.BASEBOARD_FAB2(SCH_1):PAGE170

U2D1 SKX_EXT_B_BGA1-IC,TBD
  AU24 CLK_100M_CPU1_BCLK0_DN @BASEBOARD_FAB2_LIB.BASEBOARD_FAB2(SCH_1):CLK_100M_CPU1_BCLK0_DN   I172 @BASEBOARD_FAB2_LIB.BASEBOARD_FAB2(SCH_1):PAGE55
  AW24 CLK_100M_CPU1_BCLK0_DP @BASEBOARD_FAB2_LIB.BASEBOARD_FAB2(SCH_1):CLK_100M_CPU1_BCLK0_DP   I172 @BASEBOARD_FAB2_LIB.BASEBOARD_FAB2(SCH_1):PAGE55
  CR26 CLK_100M_CPU1_BCLK1_DN @BASEBOARD_FAB2_LIB.BASEBOARD_FAB2(SCH_1):CLK_100M_CPU1_BCLK1_DN   I172 @BASEBOARD_FAB2_LIB.BASEBOARD_FAB2(SCH_1):PAGE55
  CP27 CLK_100M_CPU1_BCLK1_DP @BASEBOARD_FAB2_LIB.BASEBOARD_FAB2(SCH_1):CLK_100M_CPU1_BCLK1_DP   I172 @BASEBOARD_FAB2_LIB.BASEBOARD_FAB2(SCH_1):PAGE55
  CT25 CLK_100M_CPU1_BCLK2_DN @BASEBOARD_FAB2_LIB.BASEBOARD_FAB2(SCH_1):CLK_100M_CPU1_BCLK2_DN   I172 @BASEBOARD_FAB2_LIB.BASEBOARD_FAB2(SCH_1):PAGE55
  CU26 CLK_100M_CPU1_BCLK2_DP @BASEBOARD_FAB2_LIB.BASEBOARD_FAB2(SCH_1):CLK_100M_CPU1_BCLK2_DP   I172 @BASEBOARD_FAB2_LIB.BASEBOARD_FAB2(SCH_1):PAGE55
  BA20 PD_CPU1_BIST_ENABLE @BASEBOARD_FAB2_LIB.BASEBOARD_FAB2(SCH_1):PD_CPU1_BIST_ENABLE   I172 @BASEBOARD_FAB2_LIB.BASEBOARD_FAB2(SCH_1):PAGE55
  BD23 H_CPU1_BMCINIT @BASEBOARD_FAB2_LIB.BASEBOARD_FAB2(SCH_1):H_CPU1_BMCINIT   I172 @BASEBOARD_FAB2_LIB.BASEBOARD_FAB2(SCH_1):PAGE55
  AC12 XDP_CPU_OBSFN_B1_MBP7_N @BASEBOARD_FAB2_LIB.BASEBOARD_FAB2(SCH_1):XDP_CPU_OBSFN_B1_MBP7_N   I172 @BASEBOARD_FAB2_LIB.BASEBOARD_FAB2(SCH_1):PAGE55
  AE12 XDP_CPU_OBSFN_B0_MBP6_N @BASEBOARD_FAB2_LIB.BASEBOARD_FAB2(SCH_1):XDP_CPU_OBSFN_B0_MBP6_N   I172 @BASEBOARD_FAB2_LIB.BASEBOARD_FAB2(SCH_1):PAGE55
   Y11 TP_XDP_CPU1_OBSDATA_B3_MBP5_N @BASEBOARD_FAB2_LIB.BASEBOARD_FAB2(SCH_1):TP_XDP_CPU1_OBSDATA_B3_MBP5_N   I172 @BASEBOARD_FAB2_LIB.BASEBOARD_FAB2(SCH_1):PAGE55
  AA12 TP_XDP_CPU1_OBSDATA_B2_MBP4_N @BASEBOARD_FAB2_LIB.BASEBOARD_FAB2(SCH_1):TP_XDP_CPU1_OBSDATA_B2_MBP4_N   I172 @BASEBOARD_FAB2_LIB.BASEBOARD_FAB2(SCH_1):PAGE55
  AF11 TP_XDP_CPU1_OBSDATA_B1_MBP3_N @BASEBOARD_FAB2_LIB.BASEBOARD_FAB2(SCH_1):TP_XDP_CPU1_OBSDATA_B1_MBP3_N   I172 @BASEBOARD_FAB2_LIB.BASEBOARD_FAB2(SCH_1):PAGE55
  AG10 TP_XDP_CPU1_OBSDATA_B0_MBP2_N @BASEBOARD_FAB2_LIB.BASEBOARD_FAB2(SCH_1):TP_XDP_CPU1_OBSDATA_B0_MBP2_N   I172 @BASEBOARD_FAB2_LIB.BASEBOARD_FAB2(SCH_1):PAGE55
  AH11 XDP_CPU_MBP1_N @BASEBOARD_FAB2_LIB.BASEBOARD_FAB2(SCH_1):XDP_CPU_MBP1_N   I172 @BASEBOARD_FAB2_LIB.BASEBOARD_FAB2(SCH_1):PAGE55
  AJ10 XDP_CPU_MBP0_N @BASEBOARD_FAB2_LIB.BASEBOARD_FAB2(SCH_1):XDP_CPU_MBP0_N   I172 @BASEBOARD_FAB2_LIB.BASEBOARD_FAB2(SCH_1):PAGE55
  AL14 H_CPU1_CATERR_G_N @BASEBOARD_FAB2_LIB.BASEBOARD_FAB2(SCH_1):H_CPU1_CATERR_G_N   I172 @BASEBOARD_FAB2_LIB.BASEBOARD_FAB2(SCH_1):PAGE55
  AN30 PWRGD_CPU1_DRAMPWROK_GHJ_G @BASEBOARD_FAB2_LIB.BASEBOARD_FAB2(SCH_1):PWRGD_CPU1_DRAMPWROK_GHJ_G   I172 @BASEBOARD_FAB2_LIB.BASEBOARD_FAB2(SCH_1):PAGE55
  AC42 A_CPU1_GHJ_RCOMP2 @BASEBOARD_FAB2_LIB.BASEBOARD_FAB2(SCH_1):A_CPU1_GHJ_RCOMP2   I172 @BASEBOARD_FAB2_LIB.BASEBOARD_FAB2(SCH_1):PAGE55
  AB43 A_CPU1_GHJ_RCOMP1 @BASEBOARD_FAB2_LIB.BASEBOARD_FAB2(SCH_1):A_CPU1_GHJ_RCOMP1   I172 @BASEBOARD_FAB2_LIB.BASEBOARD_FAB2(SCH_1):PAGE55
   Y43 A_CPU1_GHJ_RCOMP0 @BASEBOARD_FAB2_LIB.BASEBOARD_FAB2(SCH_1):A_CPU1_GHJ_RCOMP0   I172 @BASEBOARD_FAB2_LIB.BASEBOARD_FAB2(SCH_1):PAGE55
   U64 M_GHJ_RST_N @BASEBOARD_FAB2_LIB.BASEBOARD_FAB2(SCH_1):M_GHJ_RST_N   I172 @BASEBOARD_FAB2_LIB.BASEBOARD_FAB2(SCH_1):PAGE55
  AJ18 SMB_DDR_GHJ_SCL_G_R @BASEBOARD_FAB2_LIB.BASEBOARD_FAB2(SCH_1):SMB_DDR_GHJ_SCL_G_R   I172 @BASEBOARD_FAB2_LIB.BASEBOARD_FAB2(SCH_1):PAGE55
  AF17 SMB_DDR_GHJ_SDA_G_R @BASEBOARD_FAB2_LIB.BASEBOARD_FAB2(SCH_1):SMB_DDR_GHJ_SDA_G_R   I172 @BASEBOARD_FAB2_LIB.BASEBOARD_FAB2(SCH_1):PAGE55
  AJ64 M_G_CPU_VREF @BASEBOARD_FAB2_LIB.BASEBOARD_FAB2(SCH_1):M_G_CPU_VREF   I172 @BASEBOARD_FAB2_LIB.BASEBOARD_FAB2(SCH_1):PAGE55
  AK63 M_H_CPU_VREF @BASEBOARD_FAB2_LIB.BASEBOARD_FAB2(SCH_1):M_H_CPU_VREF   I172 @BASEBOARD_FAB2_LIB.BASEBOARD_FAB2(SCH_1):PAGE55
  AH63 M_J_CPU_VREF @BASEBOARD_FAB2_LIB.BASEBOARD_FAB2(SCH_1):M_J_CPU_VREF   I172 @BASEBOARD_FAB2_LIB.BASEBOARD_FAB2(SCH_1):PAGE55
  CR28 PWRGD_CPU1_DRAMPWROK_KLM_G @BASEBOARD_FAB2_LIB.BASEBOARD_FAB2(SCH_1):PWRGD_CPU1_DRAMPWROK_KLM_G   I172 @BASEBOARD_FAB2_LIB.BASEBOARD_FAB2(SCH_1):PAGE55
  DD49 A_CPU1_KLM_RCOMP2 @BASEBOARD_FAB2_LIB.BASEBOARD_FAB2(SCH_1):A_CPU1_KLM_RCOMP2   I172 @BASEBOARD_FAB2_LIB.BASEBOARD_FAB2(SCH_1):PAGE55
  DD47 A_CPU1_KLM_RCOMP1 @BASEBOARD_FAB2_LIB.BASEBOARD_FAB2(SCH_1):A_CPU1_KLM_RCOMP1   I172 @BASEBOARD_FAB2_LIB.BASEBOARD_FAB2(SCH_1):PAGE55
  DC48 A_CPU1_KLM_RCOMP0 @BASEBOARD_FAB2_LIB.BASEBOARD_FAB2(SCH_1):A_CPU1_KLM_RCOMP0   I172 @BASEBOARD_FAB2_LIB.BASEBOARD_FAB2(SCH_1):PAGE55
  DV63 M_KLM_RST_N @BASEBOARD_FAB2_LIB.BASEBOARD_FAB2(SCH_1):M_KLM_RST_N   I172 @BASEBOARD_FAB2_LIB.BASEBOARD_FAB2(SCH_1):PAGE55
  AE18 SMB_DDR_KLM_SCL_G_R @BASEBOARD_FAB2_LIB.BASEBOARD_FAB2(SCH_1):SMB_DDR_KLM_SCL_G_R   I172 @BASEBOARD_FAB2_LIB.BASEBOARD_FAB2(SCH_1):PAGE55
  AD17 SMB_DDR_KLM_SDA_G_R @BASEBOARD_FAB2_LIB.BASEBOARD_FAB2(SCH_1):SMB_DDR_KLM_SDA_G_R   I172 @BASEBOARD_FAB2_LIB.BASEBOARD_FAB2(SCH_1):PAGE55
  CP61 M_K_CPU_VREF @BASEBOARD_FAB2_LIB.BASEBOARD_FAB2(SCH_1):M_K_CPU_VREF   I172 @BASEBOARD_FAB2_LIB.BASEBOARD_FAB2(SCH_1):PAGE55
  CT61 M_L_CPU_VREF @BASEBOARD_FAB2_LIB.BASEBOARD_FAB2(SCH_1):M_L_CPU_VREF   I172 @BASEBOARD_FAB2_LIB.BASEBOARD_FAB2(SCH_1):PAGE55
  CV61 M_M_CPU_VREF @BASEBOARD_FAB2_LIB.BASEBOARD_FAB2(SCH_1):M_M_CPU_VREF   I172 @BASEBOARD_FAB2_LIB.BASEBOARD_FAB2(SCH_1):PAGE55
  AJ14 PU_CPU1_EAR_N @BASEBOARD_FAB2_LIB.BASEBOARD_FAB2(SCH_1):PU_CPU1_EAR_N   I172 @BASEBOARD_FAB2_LIB.BASEBOARD_FAB2(SCH_1):PAGE55
  AL12 H_CPU1_ERR2_G_N @BASEBOARD_FAB2_LIB.BASEBOARD_FAB2(SCH_1):H_CPU1_ERR2_G_N   I172 @BASEBOARD_FAB2_LIB.BASEBOARD_FAB2(SCH_1):PAGE55
  AK11 H_CPU1_ERR1_G_N @BASEBOARD_FAB2_LIB.BASEBOARD_FAB2(SCH_1):H_CPU1_ERR1_G_N   I172 @BASEBOARD_FAB2_LIB.BASEBOARD_FAB2(SCH_1):PAGE55
  AJ12 H_CPU1_ERR0_G_N @BASEBOARD_FAB2_LIB.BASEBOARD_FAB2(SCH_1):H_CPU1_ERR0_G_N   I172 @BASEBOARD_FAB2_LIB.BASEBOARD_FAB2(SCH_1):PAGE55
  AV17 PU_CPU1_FRMAGENT @BASEBOARD_FAB2_LIB.BASEBOARD_FAB2(SCH_1):PU_CPU1_FRMAGENT   I172 @BASEBOARD_FAB2_LIB.BASEBOARD_FAB2(SCH_1):PAGE55
  AE20 PU_CPU1_LEGACY_SKT @BASEBOARD_FAB2_LIB.BASEBOARD_FAB2(SCH_1):PU_CPU1_LEGACY_SKT   I172 @BASEBOARD_FAB2_LIB.BASEBOARD_FAB2(SCH_1):PAGE55
  CT31 A_CPU1_MCP01_RBIAS @BASEBOARD_FAB2_LIB.BASEBOARD_FAB2(SCH_1):A_CPU1_MCP01_RBIAS   I172 @BASEBOARD_FAB2_LIB.BASEBOARD_FAB2(SCH_1):PAGE55
  CU32 A_CPU1_MCP01_RBIAS @BASEBOARD_FAB2_LIB.BASEBOARD_FAB2(SCH_1):A_CPU1_MCP01_RBIAS   I172 @BASEBOARD_FAB2_LIB.BASEBOARD_FAB2(SCH_1):PAGE55
  AH13 H_CPU1_MEMGHJ_MEMHOT_G_N @BASEBOARD_FAB2_LIB.BASEBOARD_FAB2(SCH_1):H_CPU1_MEMGHJ_MEMHOT_G_N   I172 @BASEBOARD_FAB2_LIB.BASEBOARD_FAB2(SCH_1):PAGE55
  AF13 H_CPU1_MEMKLM_MEMHOT_G_N @BASEBOARD_FAB2_LIB.BASEBOARD_FAB2(SCH_1):H_CPU1_MEMKLM_MEMHOT_G_N   I172 @BASEBOARD_FAB2_LIB.BASEBOARD_FAB2(SCH_1):PAGE55
  AN20 H_CPU1_MSMI_G_N @BASEBOARD_FAB2_LIB.BASEBOARD_FAB2(SCH_1):H_CPU1_MSMI_G_N   I172 @BASEBOARD_FAB2_LIB.BASEBOARD_FAB2(SCH_1):PAGE55
  AP11 TP_CPU1_NMI @BASEBOARD_FAB2_LIB.BASEBOARD_FAB2(SCH_1):TP_CPU1_NMI   I172 @BASEBOARD_FAB2_LIB.BASEBOARD_FAB2(SCH_1):PAGE55
  CL30 A_CPU1_PE012_RBIAS @BASEBOARD_FAB2_LIB.BASEBOARD_FAB2(SCH_1):A_CPU1_PE012_RBIAS   I172 @BASEBOARD_FAB2_LIB.BASEBOARD_FAB2(SCH_1):PAGE55
  CN30 A_CPU1_PE012_RBIAS @BASEBOARD_FAB2_LIB.BASEBOARD_FAB2(SCH_1):A_CPU1_PE012_RBIAS   I172 @BASEBOARD_FAB2_LIB.BASEBOARD_FAB2(SCH_1):PAGE55
  CR30 A_CPU1_PE3_RBIAS @BASEBOARD_FAB2_LIB.BASEBOARD_FAB2(SCH_1):A_CPU1_PE3_RBIAS   I172 @BASEBOARD_FAB2_LIB.BASEBOARD_FAB2(SCH_1):PAGE55
  CP29 A_CPU1_PE3_RBIAS @BASEBOARD_FAB2_LIB.BASEBOARD_FAB2(SCH_1):A_CPU1_PE3_RBIAS   I172 @BASEBOARD_FAB2_LIB.BASEBOARD_FAB2(SCH_1):PAGE55
  AU12 PECI_CPU_G @BASEBOARD_FAB2_LIB.BASEBOARD_FAB2(SCH_1):PECI_CPU_G   I172 @BASEBOARD_FAB2_LIB.BASEBOARD_FAB2(SCH_1):PAGE55
  AM19 SMB_CPU1_PE_HP_GTL_SCL @BASEBOARD_FAB2_LIB.BASEBOARD_FAB2(SCH_1):SMB_CPU1_PE_HP_GTL_SCL   I172 @BASEBOARD_FAB2_LIB.BASEBOARD_FAB2(SCH_1):PAGE55
  AL18 SMB_CPU1_PE_HP_GTL_SDA @BASEBOARD_FAB2_LIB.BASEBOARD_FAB2(SCH_1):SMB_CPU1_PE_HP_GTL_SDA   I172 @BASEBOARD_FAB2_LIB.BASEBOARD_FAB2(SCH_1):PAGE55
  CW56 PD_PIROM_CPU1_ADDR2 @BASEBOARD_FAB2_LIB.BASEBOARD_FAB2(SCH_1):PD_PIROM_CPU1_ADDR2   I172 @BASEBOARD_FAB2_LIB.BASEBOARD_FAB2(SCH_1):PAGE55
  CV57 PD_PIROM_CPU1_ADDR1 @BASEBOARD_FAB2_LIB.BASEBOARD_FAB2(SCH_1):PD_PIROM_CPU1_ADDR1   I172 @BASEBOARD_FAB2_LIB.BASEBOARD_FAB2(SCH_1):PAGE55
  CU58 PU_PIROM_CPU1_ADDR0 @BASEBOARD_FAB2_LIB.BASEBOARD_FAB2(SCH_1):PU_PIROM_CPU1_ADDR0   I172 @BASEBOARD_FAB2_LIB.BASEBOARD_FAB2(SCH_1):PAGE55
  DA72 FM_CPU1_PKGID2 @BASEBOARD_FAB2_LIB.BASEBOARD_FAB2(SCH_1):FM_CPU1_PKGID2   I172 @BASEBOARD_FAB2_LIB.BASEBOARD_FAB2(SCH_1):PAGE55
  CW72 FM_CPU1_PKGID1 @BASEBOARD_FAB2_LIB.BASEBOARD_FAB2(SCH_1):FM_CPU1_PKGID1   I172 @BASEBOARD_FAB2_LIB.BASEBOARD_FAB2(SCH_1):PAGE55
  DC72 FM_CPU1_PKGID0 @BASEBOARD_FAB2_LIB.BASEBOARD_FAB2(SCH_1):FM_CPU1_PKGID0   I172 @BASEBOARD_FAB2_LIB.BASEBOARD_FAB2(SCH_1):PAGE55
  AR14 H_PM_SYNC_GTL_R2 @BASEBOARD_FAB2_LIB.BASEBOARD_FAB2(SCH_1):H_PM_SYNC_GTL_R2   I172 @BASEBOARD_FAB2_LIB.BASEBOARD_FAB2(SCH_1):PAGE55
  AT19 H_PMSYNC_CLK_24M_CPU1 @BASEBOARD_FAB2_LIB.BASEBOARD_FAB2(SCH_1):H_PMSYNC_CLK_24M_CPU1   I172 @BASEBOARD_FAB2_LIB.BASEBOARD_FAB2(SCH_1):PAGE55
  AF15 H_CPU1_FAST_WAKE_N @BASEBOARD_FAB2_LIB.BASEBOARD_FAB2(SCH_1):H_CPU1_FAST_WAKE_N   I172 @BASEBOARD_FAB2_LIB.BASEBOARD_FAB2(SCH_1):PAGE55
  AG16 XDP_CPU_PRDY_N @BASEBOARD_FAB2_LIB.BASEBOARD_FAB2(SCH_1):XDP_CPU_PRDY_N   I172 @BASEBOARD_FAB2_LIB.BASEBOARD_FAB2(SCH_1):PAGE55
  AR12 XDP_CPU_PREQ_N @BASEBOARD_FAB2_LIB.BASEBOARD_FAB2(SCH_1):XDP_CPU_PREQ_N   I172 @BASEBOARD_FAB2_LIB.BASEBOARD_FAB2(SCH_1):PAGE55
  AB17 TP_CPU1_PROC_DIS_G_N @BASEBOARD_FAB2_LIB.BASEBOARD_FAB2(SCH_1):TP_CPU1_PROC_DIS_G_N   I172 @BASEBOARD_FAB2_LIB.BASEBOARD_FAB2(SCH_1):PAGE55
  AC16 H_CPU1_PROCHOT_G_N @BASEBOARD_FAB2_LIB.BASEBOARD_FAB2(SCH_1):H_CPU1_PROCHOT_G_N   I172 @BASEBOARD_FAB2_LIB.BASEBOARD_FAB2(SCH_1):PAGE55
  DB71 FM_CPU1_PROC_ID1 @BASEBOARD_FAB2_LIB.BASEBOARD_FAB2(SCH_1):FM_CPU1_PROC_ID1   I172 @BASEBOARD_FAB2_LIB.BASEBOARD_FAB2(SCH_1):PAGE55
  CY71 FM_CPU1_PROC_ID0 @BASEBOARD_FAB2_LIB.BASEBOARD_FAB2(SCH_1):FM_CPU1_PROC_ID0   I172 @BASEBOARD_FAB2_LIB.BASEBOARD_FAB2(SCH_1):PAGE55
  BC24 PWRGD_CPU1_G @BASEBOARD_FAB2_LIB.BASEBOARD_FAB2(SCH_1):PWRGD_CPU1_G   I172 @BASEBOARD_FAB2_LIB.BASEBOARD_FAB2(SCH_1):PAGE55
  AP21 RST_CPU1_G_N @BASEBOARD_FAB2_LIB.BASEBOARD_FAB2(SCH_1):RST_CPU1_G_N   I172 @BASEBOARD_FAB2_LIB.BASEBOARD_FAB2(SCH_1):PAGE55
  AR18 PU_CPU1_SAFE_MODE_BOOT @BASEBOARD_FAB2_LIB.BASEBOARD_FAB2(SCH_1):PU_CPU1_SAFE_MODE_BOOT   I172 @BASEBOARD_FAB2_LIB.BASEBOARD_FAB2(SCH_1):PAGE55
  AB13 FM_CPU1_SKTOCC_LVT3_N @BASEBOARD_FAB2_LIB.BASEBOARD_FAB2(SCH_1):FM_CPU1_SKTOCC_LVT3_N   I172 @BASEBOARD_FAB2_LIB.BASEBOARD_FAB2(SCH_1):PAGE55
  CT59 SMB_PIROM_CPU1_SCL @BASEBOARD_FAB2_LIB.BASEBOARD_FAB2(SCH_1):SMB_PIROM_CPU1_SCL   I172 @BASEBOARD_FAB2_LIB.BASEBOARD_FAB2(SCH_1):PAGE55
  CW58 SMB_PIROM_CPU1_SDA @BASEBOARD_FAB2_LIB.BASEBOARD_FAB2(SCH_1):SMB_PIROM_CPU1_SDA   I172 @BASEBOARD_FAB2_LIB.BASEBOARD_FAB2(SCH_1):PAGE55
  CV59 FM_CPU1_SM_WP @BASEBOARD_FAB2_LIB.BASEBOARD_FAB2(SCH_1):FM_CPU1_SM_WP   I172 @BASEBOARD_FAB2_LIB.BASEBOARD_FAB2(SCH_1):PAGE55
  AU20 TP_CPU1_SOCKET_ID_2 @BASEBOARD_FAB2_LIB.BASEBOARD_FAB2(SCH_1):TP_CPU1_SOCKET_ID_2   I172 @BASEBOARD_FAB2_LIB.BASEBOARD_FAB2(SCH_1):PAGE55
  AU16 PU_CPU1_SOCKET_ID_1 @BASEBOARD_FAB2_LIB.BASEBOARD_FAB2(SCH_1):PU_CPU1_SOCKET_ID_1   I172 @BASEBOARD_FAB2_LIB.BASEBOARD_FAB2(SCH_1):PAGE55
  AU22 PU_CPU1_SOCKET_ID_0 @BASEBOARD_FAB2_LIB.BASEBOARD_FAB2(SCH_1):PU_CPU1_SOCKET_ID_0   I172 @BASEBOARD_FAB2_LIB.BASEBOARD_FAB2(SCH_1):PAGE55
  DL44 SVID_ALERT1_CPU1_N @BASEBOARD_FAB2_LIB.BASEBOARD_FAB2(SCH_1):SVID_ALERT1_CPU1_N   I172 @BASEBOARD_FAB2_LIB.BASEBOARD_FAB2(SCH_1):PAGE55
  DE44 SVID_ALERT0_CPU1_N @BASEBOARD_FAB2_LIB.BASEBOARD_FAB2(SCH_1):SVID_ALERT0_CPU1_N   I172 @BASEBOARD_FAB2_LIB.BASEBOARD_FAB2(SCH_1):PAGE55
  DG44 SVID_CLK1_CPU1 @BASEBOARD_FAB2_LIB.BASEBOARD_FAB2(SCH_1):SVID_CLK1_CPU1   I172 @BASEBOARD_FAB2_LIB.BASEBOARD_FAB2(SCH_1):PAGE55
  DC44 SVID_CLK0_CPU1 @BASEBOARD_FAB2_LIB.BASEBOARD_FAB2(SCH_1):SVID_CLK0_CPU1   I172 @BASEBOARD_FAB2_LIB.BASEBOARD_FAB2(SCH_1):PAGE55
  DJ44 SVID_DIO1_CPU1 @BASEBOARD_FAB2_LIB.BASEBOARD_FAB2(SCH_1):SVID_DIO1_CPU1   I172 @BASEBOARD_FAB2_LIB.BASEBOARD_FAB2(SCH_1):PAGE55
  DB45 SVID_DIO0_CPU1 @BASEBOARD_FAB2_LIB.BASEBOARD_FAB2(SCH_1):SVID_DIO0_CPU1   I172 @BASEBOARD_FAB2_LIB.BASEBOARD_FAB2(SCH_1):PAGE55
  AA14 XDP_CPU_TCK0 @BASEBOARD_FAB2_LIB.BASEBOARD_FAB2(SCH_1):XDP_CPU_TCK0   I172 @BASEBOARD_FAB2_LIB.BASEBOARD_FAB2(SCH_1):PAGE55
  AC14 XDP_CPU1_TDI @BASEBOARD_FAB2_LIB.BASEBOARD_FAB2(SCH_1):XDP_CPU1_TDI   I172 @BASEBOARD_FAB2_LIB.BASEBOARD_FAB2(SCH_1):PAGE55
  AE14 XDP_CPU1_TDO @BASEBOARD_FAB2_LIB.BASEBOARD_FAB2(SCH_1):XDP_CPU1_TDO   I172 @BASEBOARD_FAB2_LIB.BASEBOARD_FAB2(SCH_1):PAGE55
  AY19 PD_CPU1_TEST12 @BASEBOARD_FAB2_LIB.BASEBOARD_FAB2(SCH_1):PD_CPU1_TEST12   I172 @BASEBOARD_FAB2_LIB.BASEBOARD_FAB2(SCH_1):PAGE55
  DB51 PD_CPU1_TEST13 @BASEBOARD_FAB2_LIB.BASEBOARD_FAB2(SCH_1):PD_CPU1_TEST13   I172 @BASEBOARD_FAB2_LIB.BASEBOARD_FAB2(SCH_1):PAGE55
  DC50 PD_CPU1_TEST14 @BASEBOARD_FAB2_LIB.BASEBOARD_FAB2(SCH_1):PD_CPU1_TEST14   I172 @BASEBOARD_FAB2_LIB.BASEBOARD_FAB2(SCH_1):PAGE55
  AW14 PD_CPU1_KSFC_DIS @BASEBOARD_FAB2_LIB.BASEBOARD_FAB2(SCH_1):PD_CPU1_KSFC_DIS   I172 @BASEBOARD_FAB2_LIB.BASEBOARD_FAB2(SCH_1):PAGE55
  AB15 H_CPU1_THERMTRIP_G_N @BASEBOARD_FAB2_LIB.BASEBOARD_FAB2(SCH_1):H_CPU1_THERMTRIP_G_N   I172 @BASEBOARD_FAB2_LIB.BASEBOARD_FAB2(SCH_1):PAGE55
   W14 XDP_CPU_TMS @BASEBOARD_FAB2_LIB.BASEBOARD_FAB2(SCH_1):XDP_CPU_TMS   I172 @BASEBOARD_FAB2_LIB.BASEBOARD_FAB2(SCH_1):PAGE55
   Y13 XDP_CPU_TRST_N @BASEBOARD_FAB2_LIB.BASEBOARD_FAB2(SCH_1):XDP_CPU_TRST_N   I172 @BASEBOARD_FAB2_LIB.BASEBOARD_FAB2(SCH_1):PAGE55
  AM11 PU_CPU1_TSC_SYNC @BASEBOARD_FAB2_LIB.BASEBOARD_FAB2(SCH_1):PU_CPU1_TSC_SYNC   I172 @BASEBOARD_FAB2_LIB.BASEBOARD_FAB2(SCH_1):PAGE55
  AW18 PU_CPU1_TXT_AGENT @BASEBOARD_FAB2_LIB.BASEBOARD_FAB2(SCH_1):PU_CPU1_TXT_AGENT   I172 @BASEBOARD_FAB2_LIB.BASEBOARD_FAB2(SCH_1):PAGE55
  AV15 PD_CPU1_TXT_PLTEN @BASEBOARD_FAB2_LIB.BASEBOARD_FAB2(SCH_1):PD_CPU1_TXT_PLTEN   I172 @BASEBOARD_FAB2_LIB.BASEBOARD_FAB2(SCH_1):PAGE55
  AP29 A_CPU1_UPI01_RBIAS @BASEBOARD_FAB2_LIB.BASEBOARD_FAB2(SCH_1):A_CPU1_UPI01_RBIAS   I172 @BASEBOARD_FAB2_LIB.BASEBOARD_FAB2(SCH_1):PAGE55
  AT29 A_CPU1_UPI01_RBIAS @BASEBOARD_FAB2_LIB.BASEBOARD_FAB2(SCH_1):A_CPU1_UPI01_RBIAS   I172 @BASEBOARD_FAB2_LIB.BASEBOARD_FAB2(SCH_1):PAGE55
  CK29 A_CPU1_UPI2_RBIAS @BASEBOARD_FAB2_LIB.BASEBOARD_FAB2(SCH_1):A_CPU1_UPI2_RBIAS   I172 @BASEBOARD_FAB2_LIB.BASEBOARD_FAB2(SCH_1):PAGE55
  CL28 A_CPU1_UPI2_RBIAS @BASEBOARD_FAB2_LIB.BASEBOARD_FAB2(SCH_1):A_CPU1_UPI2_RBIAS   I172 @BASEBOARD_FAB2_LIB.BASEBOARD_FAB2(SCH_1):PAGE55
  AV21 XDP_PRESENT_N @BASEBOARD_FAB2_LIB.BASEBOARD_FAB2(SCH_1):XDP_PRESENT_N   I169 @BASEBOARD_FAB2_LIB.BASEBOARD_FAB2(SCH_1):PAGE56
  AW12 PD_CPU1_DMIMODE_OVERRIDE @BASEBOARD_FAB2_LIB.BASEBOARD_FAB2(SCH_1):PD_CPU1_DMIMODE_OVERRIDE   I169 @BASEBOARD_FAB2_LIB.BASEBOARD_FAB2(SCH_1):PAGE56
  AU14 H_CPU1_FIVR_FAULT_G @BASEBOARD_FAB2_LIB.BASEBOARD_FAB2(SCH_1):H_CPU1_FIVR_FAULT_G   I169 @BASEBOARD_FAB2_LIB.BASEBOARD_FAB2(SCH_1):PAGE56
  AP17 XDP_CPU_PWR_DEBUG_N @BASEBOARD_FAB2_LIB.BASEBOARD_FAB2(SCH_1):XDP_CPU_PWR_DEBUG_N   I169 @BASEBOARD_FAB2_LIB.BASEBOARD_FAB2(SCH_1):PAGE56
    A4 TP_CPU1_RSVD_304 @BASEBOARD_FAB2_LIB.BASEBOARD_FAB2(SCH_1):TP_CPU1_RSVD_304   I169 @BASEBOARD_FAB2_LIB.BASEBOARD_FAB2(SCH_1):PAGE56
    A6 TP_CPU1_RSVD_303 @BASEBOARD_FAB2_LIB.BASEBOARD_FAB2(SCH_1):TP_CPU1_RSVD_303   I169 @BASEBOARD_FAB2_LIB.BASEBOARD_FAB2(SCH_1):PAGE56
   A14 P1V8_MCP_CPU1 @BASEBOARD_FAB2_LIB.BASEBOARD_FAB2(SCH_1):P1V8_MCP_CPU1   I169 @BASEBOARD_FAB2_LIB.BASEBOARD_FAB2(SCH_1):PAGE56
   A16 P1V8_MCP_CPU1 @BASEBOARD_FAB2_LIB.BASEBOARD_FAB2(SCH_1):P1V8_MCP_CPU1   I169 @BASEBOARD_FAB2_LIB.BASEBOARD_FAB2(SCH_1):PAGE56
   A24 TP_CPU1_RSVD_300 @BASEBOARD_FAB2_LIB.BASEBOARD_FAB2(SCH_1):TP_CPU1_RSVD_300   I169 @BASEBOARD_FAB2_LIB.BASEBOARD_FAB2(SCH_1):PAGE56
    B3 TP_CPU1_RSVD_299 @BASEBOARD_FAB2_LIB.BASEBOARD_FAB2(SCH_1):TP_CPU1_RSVD_299   I169 @BASEBOARD_FAB2_LIB.BASEBOARD_FAB2(SCH_1):PAGE56
    B7 TP_CPU1_RSVD_298 @BASEBOARD_FAB2_LIB.BASEBOARD_FAB2(SCH_1):TP_CPU1_RSVD_298   I169 @BASEBOARD_FAB2_LIB.BASEBOARD_FAB2(SCH_1):PAGE56
   B13 P1V8_MCP_CPU1 @BASEBOARD_FAB2_LIB.BASEBOARD_FAB2(SCH_1):P1V8_MCP_CPU1   I169 @BASEBOARD_FAB2_LIB.BASEBOARD_FAB2(SCH_1):PAGE56
   B15 P1V8_MCP_CPU1 @BASEBOARD_FAB2_LIB.BASEBOARD_FAB2(SCH_1):P1V8_MCP_CPU1   I169 @BASEBOARD_FAB2_LIB.BASEBOARD_FAB2(SCH_1):PAGE56
   B17 P1V8_MCP_CPU1 @BASEBOARD_FAB2_LIB.BASEBOARD_FAB2(SCH_1):P1V8_MCP_CPU1   I169 @BASEBOARD_FAB2_LIB.BASEBOARD_FAB2(SCH_1):PAGE56
   B77 TP_CPU1_RSVD_293 @BASEBOARD_FAB2_LIB.BASEBOARD_FAB2(SCH_1):TP_CPU1_RSVD_293   I169 @BASEBOARD_FAB2_LIB.BASEBOARD_FAB2(SCH_1):PAGE56
   B81 TP_CPU1_RSVD_292 @BASEBOARD_FAB2_LIB.BASEBOARD_FAB2(SCH_1):TP_CPU1_RSVD_292   I169 @BASEBOARD_FAB2_LIB.BASEBOARD_FAB2(SCH_1):PAGE56
    C6 TP_CPU1_RSVD_291 @BASEBOARD_FAB2_LIB.BASEBOARD_FAB2(SCH_1):TP_CPU1_RSVD_291   I169 @BASEBOARD_FAB2_LIB.BASEBOARD_FAB2(SCH_1):PAGE56
   C18 TP_CPU1_RSVD_290 @BASEBOARD_FAB2_LIB.BASEBOARD_FAB2(SCH_1):TP_CPU1_RSVD_290   I169 @BASEBOARD_FAB2_LIB.BASEBOARD_FAB2(SCH_1):PAGE56
   C24 TP_CPU1_RSVD_289 @BASEBOARD_FAB2_LIB.BASEBOARD_FAB2(SCH_1):TP_CPU1_RSVD_289   I169 @BASEBOARD_FAB2_LIB.BASEBOARD_FAB2(SCH_1):PAGE56
   C82 TP_CPU1_RSVD_288 @BASEBOARD_FAB2_LIB.BASEBOARD_FAB2(SCH_1):TP_CPU1_RSVD_288   I169 @BASEBOARD_FAB2_LIB.BASEBOARD_FAB2(SCH_1):PAGE56
    D5 TP_CPU1_RSVD_287 @BASEBOARD_FAB2_LIB.BASEBOARD_FAB2(SCH_1):TP_CPU1_RSVD_287   I169 @BASEBOARD_FAB2_LIB.BASEBOARD_FAB2(SCH_1):PAGE56
   D17 TP_CPU1_RSVD_286 @BASEBOARD_FAB2_LIB.BASEBOARD_FAB2(SCH_1):TP_CPU1_RSVD_286   I169 @BASEBOARD_FAB2_LIB.BASEBOARD_FAB2(SCH_1):PAGE56
   D65 TP_CPU1_RSVD_285 @BASEBOARD_FAB2_LIB.BASEBOARD_FAB2(SCH_1):TP_CPU1_RSVD_285   I169 @BASEBOARD_FAB2_LIB.BASEBOARD_FAB2(SCH_1):PAGE56
   D83 TP_CPU1_RSVD_284 @BASEBOARD_FAB2_LIB.BASEBOARD_FAB2(SCH_1):TP_CPU1_RSVD_284   I169 @BASEBOARD_FAB2_LIB.BASEBOARD_FAB2(SCH_1):PAGE56
    E2 TP_CPU1_RSVD_283 @BASEBOARD_FAB2_LIB.BASEBOARD_FAB2(SCH_1):TP_CPU1_RSVD_283   I169 @BASEBOARD_FAB2_LIB.BASEBOARD_FAB2(SCH_1):PAGE56
    E4 TP_CPU1_RSVD_282 @BASEBOARD_FAB2_LIB.BASEBOARD_FAB2(SCH_1):TP_CPU1_RSVD_282   I169 @BASEBOARD_FAB2_LIB.BASEBOARD_FAB2(SCH_1):PAGE56
   E24 TP_CPU1_RSVD_281 @BASEBOARD_FAB2_LIB.BASEBOARD_FAB2(SCH_1):TP_CPU1_RSVD_281   I169 @BASEBOARD_FAB2_LIB.BASEBOARD_FAB2(SCH_1):PAGE56
   E84 TP_CPU1_RSVD_280 @BASEBOARD_FAB2_LIB.BASEBOARD_FAB2(SCH_1):TP_CPU1_RSVD_280   I169 @BASEBOARD_FAB2_LIB.BASEBOARD_FAB2(SCH_1):PAGE56
    F3 TP_CPU1_RSVD_279 @BASEBOARD_FAB2_LIB.BASEBOARD_FAB2(SCH_1):TP_CPU1_RSVD_279   I169 @BASEBOARD_FAB2_LIB.BASEBOARD_FAB2(SCH_1):PAGE56
   F23 TP_CPU1_RSVD_278 @BASEBOARD_FAB2_LIB.BASEBOARD_FAB2(SCH_1):TP_CPU1_RSVD_278   I169 @BASEBOARD_FAB2_LIB.BASEBOARD_FAB2(SCH_1):PAGE56
   F65 TP_CPU1_RSVD_277 @BASEBOARD_FAB2_LIB.BASEBOARD_FAB2(SCH_1):TP_CPU1_RSVD_277   I169 @BASEBOARD_FAB2_LIB.BASEBOARD_FAB2(SCH_1):PAGE56
   F83 TP_CPU1_RSVD_276 @BASEBOARD_FAB2_LIB.BASEBOARD_FAB2(SCH_1):TP_CPU1_RSVD_276   I169 @BASEBOARD_FAB2_LIB.BASEBOARD_FAB2(SCH_1):PAGE56
    G2 TP_CPU1_RSVD_275 @BASEBOARD_FAB2_LIB.BASEBOARD_FAB2(SCH_1):TP_CPU1_RSVD_275   I169 @BASEBOARD_FAB2_LIB.BASEBOARD_FAB2(SCH_1):PAGE56
   G64 TP_CPU1_RSVD_274 @BASEBOARD_FAB2_LIB.BASEBOARD_FAB2(SCH_1):TP_CPU1_RSVD_274   I169 @BASEBOARD_FAB2_LIB.BASEBOARD_FAB2(SCH_1):PAGE56
   G84 TP_CPU1_RSVD_273 @BASEBOARD_FAB2_LIB.BASEBOARD_FAB2(SCH_1):TP_CPU1_RSVD_273   I169 @BASEBOARD_FAB2_LIB.BASEBOARD_FAB2(SCH_1):PAGE56
    H1 TP_CPU1_RSVD_272 @BASEBOARD_FAB2_LIB.BASEBOARD_FAB2(SCH_1):TP_CPU1_RSVD_272   I169 @BASEBOARD_FAB2_LIB.BASEBOARD_FAB2(SCH_1):PAGE56
   H83 TP_CPU1_RSVD_271 @BASEBOARD_FAB2_LIB.BASEBOARD_FAB2(SCH_1):TP_CPU1_RSVD_271   I169 @BASEBOARD_FAB2_LIB.BASEBOARD_FAB2(SCH_1):PAGE56
   H85 TP_CPU1_RSVD_270 @BASEBOARD_FAB2_LIB.BASEBOARD_FAB2(SCH_1):TP_CPU1_RSVD_270   I169 @BASEBOARD_FAB2_LIB.BASEBOARD_FAB2(SCH_1):PAGE56
   J46 TP_CPU1_RSVD_269 @BASEBOARD_FAB2_LIB.BASEBOARD_FAB2(SCH_1):TP_CPU1_RSVD_269   I169 @BASEBOARD_FAB2_LIB.BASEBOARD_FAB2(SCH_1):PAGE56
   J62 TP_CPU1_RSVD_268 @BASEBOARD_FAB2_LIB.BASEBOARD_FAB2(SCH_1):TP_CPU1_RSVD_268   I169 @BASEBOARD_FAB2_LIB.BASEBOARD_FAB2(SCH_1):PAGE56
   K61 TP_CPU1_RSVD_267 @BASEBOARD_FAB2_LIB.BASEBOARD_FAB2(SCH_1):TP_CPU1_RSVD_267   I169 @BASEBOARD_FAB2_LIB.BASEBOARD_FAB2(SCH_1):PAGE56
   M63 TP_CPU1_RSVD_266 @BASEBOARD_FAB2_LIB.BASEBOARD_FAB2(SCH_1):TP_CPU1_RSVD_266   I169 @BASEBOARD_FAB2_LIB.BASEBOARD_FAB2(SCH_1):PAGE56
   P65 TP_CPU1_RSVD_265 @BASEBOARD_FAB2_LIB.BASEBOARD_FAB2(SCH_1):TP_CPU1_RSVD_265   I169 @BASEBOARD_FAB2_LIB.BASEBOARD_FAB2(SCH_1):PAGE56
   R62 TP_CPU1_RSVD_264 @BASEBOARD_FAB2_LIB.BASEBOARD_FAB2(SCH_1):TP_CPU1_RSVD_264   I169 @BASEBOARD_FAB2_LIB.BASEBOARD_FAB2(SCH_1):PAGE56
   R66 TP_CPU1_RSVD_263 @BASEBOARD_FAB2_LIB.BASEBOARD_FAB2(SCH_1):TP_CPU1_RSVD_263   I169 @BASEBOARD_FAB2_LIB.BASEBOARD_FAB2(SCH_1):PAGE56
   T67 TP_CPU1_RSVD_262 @BASEBOARD_FAB2_LIB.BASEBOARD_FAB2(SCH_1):TP_CPU1_RSVD_262   I169 @BASEBOARD_FAB2_LIB.BASEBOARD_FAB2(SCH_1):PAGE56
   U66 TP_CPU1_RSVD_261 @BASEBOARD_FAB2_LIB.BASEBOARD_FAB2(SCH_1):TP_CPU1_RSVD_261   I169 @BASEBOARD_FAB2_LIB.BASEBOARD_FAB2(SCH_1):PAGE56
   V65 TP_CPU1_RSVD_260 @BASEBOARD_FAB2_LIB.BASEBOARD_FAB2(SCH_1):TP_CPU1_RSVD_260   I169 @BASEBOARD_FAB2_LIB.BASEBOARD_FAB2(SCH_1):PAGE56
   V67 TP_CPU1_RSVD_259 @BASEBOARD_FAB2_LIB.BASEBOARD_FAB2(SCH_1):TP_CPU1_RSVD_259   I169 @BASEBOARD_FAB2_LIB.BASEBOARD_FAB2(SCH_1):PAGE56
   W66 TP_CPU1_RSVD_258 @BASEBOARD_FAB2_LIB.BASEBOARD_FAB2(SCH_1):TP_CPU1_RSVD_258   I169 @BASEBOARD_FAB2_LIB.BASEBOARD_FAB2(SCH_1):PAGE56
   Y23 FM_CPU1_RC_ERROR_N @BASEBOARD_FAB2_LIB.BASEBOARD_FAB2(SCH_1):FM_CPU1_RC_ERROR_N   I169 @BASEBOARD_FAB2_LIB.BASEBOARD_FAB2(SCH_1):PAGE56
   Y65 TP_CPU1_RSVD_256 @BASEBOARD_FAB2_LIB.BASEBOARD_FAB2(SCH_1):TP_CPU1_RSVD_256   I169 @BASEBOARD_FAB2_LIB.BASEBOARD_FAB2(SCH_1):PAGE56
  AD47 TP_CPU1_RSVD_254 @BASEBOARD_FAB2_LIB.BASEBOARD_FAB2(SCH_1):TP_CPU1_RSVD_254   I169 @BASEBOARD_FAB2_LIB.BASEBOARD_FAB2(SCH_1):PAGE56
  AD49 TP_CPU1_RSVD_253 @BASEBOARD_FAB2_LIB.BASEBOARD_FAB2(SCH_1):TP_CPU1_RSVD_253   I169 @BASEBOARD_FAB2_LIB.BASEBOARD_FAB2(SCH_1):PAGE56
  AD51 TP_CPU1_RSVD_252 @BASEBOARD_FAB2_LIB.BASEBOARD_FAB2(SCH_1):TP_CPU1_RSVD_252   I169 @BASEBOARD_FAB2_LIB.BASEBOARD_FAB2(SCH_1):PAGE56
  AE46 TP_CPU1_RSVD_251 @BASEBOARD_FAB2_LIB.BASEBOARD_FAB2(SCH_1):TP_CPU1_RSVD_251   I169 @BASEBOARD_FAB2_LIB.BASEBOARD_FAB2(SCH_1):PAGE56
  AE48 TP_CPU1_RSVD_250 @BASEBOARD_FAB2_LIB.BASEBOARD_FAB2(SCH_1):TP_CPU1_RSVD_250   I169 @BASEBOARD_FAB2_LIB.BASEBOARD_FAB2(SCH_1):PAGE56
  AE50 TP_CPU1_RSVD_249 @BASEBOARD_FAB2_LIB.BASEBOARD_FAB2(SCH_1):TP_CPU1_RSVD_249   I169 @BASEBOARD_FAB2_LIB.BASEBOARD_FAB2(SCH_1):PAGE56
  AE52 TP_CPU1_RSVD_248 @BASEBOARD_FAB2_LIB.BASEBOARD_FAB2(SCH_1):TP_CPU1_RSVD_248   I169 @BASEBOARD_FAB2_LIB.BASEBOARD_FAB2(SCH_1):PAGE56
  AE72 TP_CPU1_RSVD_247 @BASEBOARD_FAB2_LIB.BASEBOARD_FAB2(SCH_1):TP_CPU1_RSVD_247   I169 @BASEBOARD_FAB2_LIB.BASEBOARD_FAB2(SCH_1):PAGE56
  AF19 TP_CPU1_RSVD_246 @BASEBOARD_FAB2_LIB.BASEBOARD_FAB2(SCH_1):TP_CPU1_RSVD_246   I169 @BASEBOARD_FAB2_LIB.BASEBOARD_FAB2(SCH_1):PAGE56
  AF47 TP_CPU1_RSVD_245 @BASEBOARD_FAB2_LIB.BASEBOARD_FAB2(SCH_1):TP_CPU1_RSVD_245   I169 @BASEBOARD_FAB2_LIB.BASEBOARD_FAB2(SCH_1):PAGE56
  AF49 TP_CPU1_RSVD_244 @BASEBOARD_FAB2_LIB.BASEBOARD_FAB2(SCH_1):TP_CPU1_RSVD_244   I169 @BASEBOARD_FAB2_LIB.BASEBOARD_FAB2(SCH_1):PAGE56
  AF51 TP_CPU1_RSVD_243 @BASEBOARD_FAB2_LIB.BASEBOARD_FAB2(SCH_1):TP_CPU1_RSVD_243   I169 @BASEBOARD_FAB2_LIB.BASEBOARD_FAB2(SCH_1):PAGE56
  AF53 TP_CPU1_RSVD_242 @BASEBOARD_FAB2_LIB.BASEBOARD_FAB2(SCH_1):TP_CPU1_RSVD_242   I169 @BASEBOARD_FAB2_LIB.BASEBOARD_FAB2(SCH_1):PAGE56
  AF71 TP_CPU1_RSVD_241 @BASEBOARD_FAB2_LIB.BASEBOARD_FAB2(SCH_1):TP_CPU1_RSVD_241   I169 @BASEBOARD_FAB2_LIB.BASEBOARD_FAB2(SCH_1):PAGE56
  AG20 TP_CPU1_RSVD_240 @BASEBOARD_FAB2_LIB.BASEBOARD_FAB2(SCH_1):TP_CPU1_RSVD_240   I169 @BASEBOARD_FAB2_LIB.BASEBOARD_FAB2(SCH_1):PAGE56
  AG48 TP_CPU1_RSVD_239 @BASEBOARD_FAB2_LIB.BASEBOARD_FAB2(SCH_1):TP_CPU1_RSVD_239   I169 @BASEBOARD_FAB2_LIB.BASEBOARD_FAB2(SCH_1):PAGE56
  AG50 TP_CPU1_RSVD_238 @BASEBOARD_FAB2_LIB.BASEBOARD_FAB2(SCH_1):TP_CPU1_RSVD_238   I169 @BASEBOARD_FAB2_LIB.BASEBOARD_FAB2(SCH_1):PAGE56
  AG52 TP_CPU1_RSVD_237 @BASEBOARD_FAB2_LIB.BASEBOARD_FAB2(SCH_1):TP_CPU1_RSVD_237   I169 @BASEBOARD_FAB2_LIB.BASEBOARD_FAB2(SCH_1):PAGE56
  AG54 TP_CPU1_RSVD_236 @BASEBOARD_FAB2_LIB.BASEBOARD_FAB2(SCH_1):TP_CPU1_RSVD_236   I169 @BASEBOARD_FAB2_LIB.BASEBOARD_FAB2(SCH_1):PAGE56
  AG56 TP_CPU1_RSVD_235 @BASEBOARD_FAB2_LIB.BASEBOARD_FAB2(SCH_1):TP_CPU1_RSVD_235   I169 @BASEBOARD_FAB2_LIB.BASEBOARD_FAB2(SCH_1):PAGE56
  AG72 TP_CPU1_RSVD_234 @BASEBOARD_FAB2_LIB.BASEBOARD_FAB2(SCH_1):TP_CPU1_RSVD_234   I169 @BASEBOARD_FAB2_LIB.BASEBOARD_FAB2(SCH_1):PAGE56
  AH15 TP_CPU1_RSVD_233 @BASEBOARD_FAB2_LIB.BASEBOARD_FAB2(SCH_1):TP_CPU1_RSVD_233   I169 @BASEBOARD_FAB2_LIB.BASEBOARD_FAB2(SCH_1):PAGE56
  AH19 TP_CPU1_RSVD_232 @BASEBOARD_FAB2_LIB.BASEBOARD_FAB2(SCH_1):TP_CPU1_RSVD_232   I169 @BASEBOARD_FAB2_LIB.BASEBOARD_FAB2(SCH_1):PAGE56
  AH55 TP_CPU1_RSVD_231 @BASEBOARD_FAB2_LIB.BASEBOARD_FAB2(SCH_1):TP_CPU1_RSVD_231   I169 @BASEBOARD_FAB2_LIB.BASEBOARD_FAB2(SCH_1):PAGE56
  AH57 TP_CPU1_RSVD_230 @BASEBOARD_FAB2_LIB.BASEBOARD_FAB2(SCH_1):TP_CPU1_RSVD_230   I169 @BASEBOARD_FAB2_LIB.BASEBOARD_FAB2(SCH_1):PAGE56
  AH71 TP_CPU1_RSVD_229 @BASEBOARD_FAB2_LIB.BASEBOARD_FAB2(SCH_1):TP_CPU1_RSVD_229   I169 @BASEBOARD_FAB2_LIB.BASEBOARD_FAB2(SCH_1):PAGE56
  AH73 TP_CPU1_RSVD_228 @BASEBOARD_FAB2_LIB.BASEBOARD_FAB2(SCH_1):TP_CPU1_RSVD_228   I169 @BASEBOARD_FAB2_LIB.BASEBOARD_FAB2(SCH_1):PAGE56
  AJ20 TP_CPU1_RSVD_227 @BASEBOARD_FAB2_LIB.BASEBOARD_FAB2(SCH_1):TP_CPU1_RSVD_227   I169 @BASEBOARD_FAB2_LIB.BASEBOARD_FAB2(SCH_1):PAGE56
  AJ56 TP_CPU1_RSVD_226 @BASEBOARD_FAB2_LIB.BASEBOARD_FAB2(SCH_1):TP_CPU1_RSVD_226   I169 @BASEBOARD_FAB2_LIB.BASEBOARD_FAB2(SCH_1):PAGE56
  AJ58 TP_CPU1_RSVD_225 @BASEBOARD_FAB2_LIB.BASEBOARD_FAB2(SCH_1):TP_CPU1_RSVD_225   I169 @BASEBOARD_FAB2_LIB.BASEBOARD_FAB2(SCH_1):PAGE56
  AJ60 TP_CPU1_RSVD_224 @BASEBOARD_FAB2_LIB.BASEBOARD_FAB2(SCH_1):TP_CPU1_RSVD_224   I169 @BASEBOARD_FAB2_LIB.BASEBOARD_FAB2(SCH_1):PAGE56
  AJ62 TP_CPU1_RSVD_223 @BASEBOARD_FAB2_LIB.BASEBOARD_FAB2(SCH_1):TP_CPU1_RSVD_223   I169 @BASEBOARD_FAB2_LIB.BASEBOARD_FAB2(SCH_1):PAGE56
  AJ70 TP_CPU1_RSVD_222 @BASEBOARD_FAB2_LIB.BASEBOARD_FAB2(SCH_1):TP_CPU1_RSVD_222   I169 @BASEBOARD_FAB2_LIB.BASEBOARD_FAB2(SCH_1):PAGE56
  AK21 VSENSE_P1V8MCP_CPU1_SKT_VSEN @BASEBOARD_FAB2_LIB.BASEBOARD_FAB2(SCH_1):VSENSE_P1V8MCP_CPU1_SKT_VSEN   I169 @BASEBOARD_FAB2_LIB.BASEBOARD_FAB2(SCH_1):PAGE56
  AK27 CLK_322M_OSC_CPU1_RC_DP @BASEBOARD_FAB2_LIB.BASEBOARD_FAB2(SCH_1):CLK_322M_OSC_CPU1_RC_DP   I169 @BASEBOARD_FAB2_LIB.BASEBOARD_FAB2(SCH_1):PAGE56
  AK57 TP_CPU1_RSVD_219 @BASEBOARD_FAB2_LIB.BASEBOARD_FAB2(SCH_1):TP_CPU1_RSVD_219   I169 @BASEBOARD_FAB2_LIB.BASEBOARD_FAB2(SCH_1):PAGE56
  AK59 TP_CPU1_RSVD_218 @BASEBOARD_FAB2_LIB.BASEBOARD_FAB2(SCH_1):TP_CPU1_RSVD_218   I169 @BASEBOARD_FAB2_LIB.BASEBOARD_FAB2(SCH_1):PAGE56
  AK61 TP_CPU1_RSVD_217 @BASEBOARD_FAB2_LIB.BASEBOARD_FAB2(SCH_1):TP_CPU1_RSVD_217   I169 @BASEBOARD_FAB2_LIB.BASEBOARD_FAB2(SCH_1):PAGE56
  AK69 TP_CPU1_RSVD_216 @BASEBOARD_FAB2_LIB.BASEBOARD_FAB2(SCH_1):TP_CPU1_RSVD_216   I169 @BASEBOARD_FAB2_LIB.BASEBOARD_FAB2(SCH_1):PAGE56
  AL20 VSENSE_P1V8MCP_CPU1_SKT_VRTN @BASEBOARD_FAB2_LIB.BASEBOARD_FAB2(SCH_1):VSENSE_P1V8MCP_CPU1_SKT_VRTN   I169 @BASEBOARD_FAB2_LIB.BASEBOARD_FAB2(SCH_1):PAGE56
  AL22 TP_CPU1_RSVD_214 @BASEBOARD_FAB2_LIB.BASEBOARD_FAB2(SCH_1):TP_CPU1_RSVD_214   I169 @BASEBOARD_FAB2_LIB.BASEBOARD_FAB2(SCH_1):PAGE56
  AL26 CLK_322M_OSC_CPU1_RC_DN @BASEBOARD_FAB2_LIB.BASEBOARD_FAB2(SCH_1):CLK_322M_OSC_CPU1_RC_DN   I169 @BASEBOARD_FAB2_LIB.BASEBOARD_FAB2(SCH_1):PAGE56
  AL58 TP_CPU1_RSVD_212 @BASEBOARD_FAB2_LIB.BASEBOARD_FAB2(SCH_1):TP_CPU1_RSVD_212   I169 @BASEBOARD_FAB2_LIB.BASEBOARD_FAB2(SCH_1):PAGE56
  AL60 TP_CPU1_RSVD_211 @BASEBOARD_FAB2_LIB.BASEBOARD_FAB2(SCH_1):TP_CPU1_RSVD_211   I169 @BASEBOARD_FAB2_LIB.BASEBOARD_FAB2(SCH_1):PAGE56
  AL62 TP_CPU1_RSVD_210 @BASEBOARD_FAB2_LIB.BASEBOARD_FAB2(SCH_1):TP_CPU1_RSVD_210   I169 @BASEBOARD_FAB2_LIB.BASEBOARD_FAB2(SCH_1):PAGE56
  AM21 PVCCMCP_CPU1 @BASEBOARD_FAB2_LIB.BASEBOARD_FAB2(SCH_1):PVCCMCP_CPU1   I169 @BASEBOARD_FAB2_LIB.BASEBOARD_FAB2(SCH_1):PAGE56
  AM23 TP_CPU1_RSVD_208 @BASEBOARD_FAB2_LIB.BASEBOARD_FAB2(SCH_1):TP_CPU1_RSVD_208   I169 @BASEBOARD_FAB2_LIB.BASEBOARD_FAB2(SCH_1):PAGE56
  AM25 PVCCMCP_CPU1 @BASEBOARD_FAB2_LIB.BASEBOARD_FAB2(SCH_1):PVCCMCP_CPU1   I169 @BASEBOARD_FAB2_LIB.BASEBOARD_FAB2(SCH_1):PAGE56
  AM27 CLK_100M_CPU1_RC_REFCLK0_DP @BASEBOARD_FAB2_LIB.BASEBOARD_FAB2(SCH_1):CLK_100M_CPU1_RC_REFCLK0_DP   I169 @BASEBOARD_FAB2_LIB.BASEBOARD_FAB2(SCH_1):PAGE56
  AM59 TP_CPU1_RSVD_205 @BASEBOARD_FAB2_LIB.BASEBOARD_FAB2(SCH_1):TP_CPU1_RSVD_205   I169 @BASEBOARD_FAB2_LIB.BASEBOARD_FAB2(SCH_1):PAGE56
  AM61 TP_CPU1_RSVD_204 @BASEBOARD_FAB2_LIB.BASEBOARD_FAB2(SCH_1):TP_CPU1_RSVD_204   I169 @BASEBOARD_FAB2_LIB.BASEBOARD_FAB2(SCH_1):PAGE56
  AN18 PVCCMCP_CPU1 @BASEBOARD_FAB2_LIB.BASEBOARD_FAB2(SCH_1):PVCCMCP_CPU1   I169 @BASEBOARD_FAB2_LIB.BASEBOARD_FAB2(SCH_1):PAGE56
  AN22 PVCCMCP_CPU1 @BASEBOARD_FAB2_LIB.BASEBOARD_FAB2(SCH_1):PVCCMCP_CPU1   I169 @BASEBOARD_FAB2_LIB.BASEBOARD_FAB2(SCH_1):PAGE56
  AN24 PVCCMCP_CPU1 @BASEBOARD_FAB2_LIB.BASEBOARD_FAB2(SCH_1):PVCCMCP_CPU1   I169 @BASEBOARD_FAB2_LIB.BASEBOARD_FAB2(SCH_1):PAGE56
  AN26 PVCCMCP_CPU1 @BASEBOARD_FAB2_LIB.BASEBOARD_FAB2(SCH_1):PVCCMCP_CPU1   I169 @BASEBOARD_FAB2_LIB.BASEBOARD_FAB2(SCH_1):PAGE56
  AN60 TP_CPU1_RSVD_199 @BASEBOARD_FAB2_LIB.BASEBOARD_FAB2(SCH_1):TP_CPU1_RSVD_199   I169 @BASEBOARD_FAB2_LIB.BASEBOARD_FAB2(SCH_1):PAGE56
  AN62 TP_CPU1_RSVD_198 @BASEBOARD_FAB2_LIB.BASEBOARD_FAB2(SCH_1):TP_CPU1_RSVD_198   I169 @BASEBOARD_FAB2_LIB.BASEBOARD_FAB2(SCH_1):PAGE56
  AP23 PVCCMCP_CPU1 @BASEBOARD_FAB2_LIB.BASEBOARD_FAB2(SCH_1):PVCCMCP_CPU1   I169 @BASEBOARD_FAB2_LIB.BASEBOARD_FAB2(SCH_1):PAGE56
  AP25 PVCCMCP_CPU1 @BASEBOARD_FAB2_LIB.BASEBOARD_FAB2(SCH_1):PVCCMCP_CPU1   I169 @BASEBOARD_FAB2_LIB.BASEBOARD_FAB2(SCH_1):PAGE56
  AP27 CLK_100M_CPU1_RC_REFCLK0_DN @BASEBOARD_FAB2_LIB.BASEBOARD_FAB2(SCH_1):CLK_100M_CPU1_RC_REFCLK0_DN   I169 @BASEBOARD_FAB2_LIB.BASEBOARD_FAB2(SCH_1):PAGE56
  AP61 TP_CPU1_RSVD_194 @BASEBOARD_FAB2_LIB.BASEBOARD_FAB2(SCH_1):TP_CPU1_RSVD_194   I169 @BASEBOARD_FAB2_LIB.BASEBOARD_FAB2(SCH_1):PAGE56
  AF45 PD_CPU1_RSVD_TEST_1 @BASEBOARD_FAB2_LIB.BASEBOARD_FAB2(SCH_1):PD_CPU1_RSVD_TEST_1   I169 @BASEBOARD_FAB2_LIB.BASEBOARD_FAB2(SCH_1):PAGE56
  AY13 TP_CPU1_RSVD_TEST_11 @BASEBOARD_FAB2_LIB.BASEBOARD_FAB2(SCH_1):TP_CPU1_RSVD_TEST_11   I169 @BASEBOARD_FAB2_LIB.BASEBOARD_FAB2(SCH_1):PAGE56
  AG46 PD_CPU1_RSVD_TEST_2 @BASEBOARD_FAB2_LIB.BASEBOARD_FAB2(SCH_1):PD_CPU1_RSVD_TEST_2   I169 @BASEBOARD_FAB2_LIB.BASEBOARD_FAB2(SCH_1):PAGE56
  AM13 TP_CPU1_RSVD_TEST_3 @BASEBOARD_FAB2_LIB.BASEBOARD_FAB2(SCH_1):TP_CPU1_RSVD_TEST_3   I169 @BASEBOARD_FAB2_LIB.BASEBOARD_FAB2(SCH_1):PAGE56
  AN12 TP_CPU1_RSVD_TEST_4 @BASEBOARD_FAB2_LIB.BASEBOARD_FAB2(SCH_1):TP_CPU1_RSVD_TEST_4   I169 @BASEBOARD_FAB2_LIB.BASEBOARD_FAB2(SCH_1):PAGE56
  AN14 TP_CPU1_RSVD_TEST_5 @BASEBOARD_FAB2_LIB.BASEBOARD_FAB2(SCH_1):TP_CPU1_RSVD_TEST_5   I169 @BASEBOARD_FAB2_LIB.BASEBOARD_FAB2(SCH_1):PAGE56
   J60 M_G_ACT_N @BASEBOARD_FAB2_LIB.BASEBOARD_FAB2(SCH_1):M_G_ACT_N   I172 @BASEBOARD_FAB2_LIB.BASEBOARD_FAB2(SCH_1):PAGE57
   B61 M_G_ALERT_N @BASEBOARD_FAB2_LIB.BASEBOARD_FAB2(SCH_1):M_G_ALERT_N   I172 @BASEBOARD_FAB2_LIB.BASEBOARD_FAB2(SCH_1):PAGE57
   G54 M_G_BA<1> @BASEBOARD_FAB2_LIB.BASEBOARD_FAB2(SCH_1):M_G_BA(1)   I172 @BASEBOARD_FAB2_LIB.BASEBOARD_FAB2(SCH_1):PAGE57
   C52 M_G_BA<0> @BASEBOARD_FAB2_LIB.BASEBOARD_FAB2(SCH_1):M_G_BA(0)   I172 @BASEBOARD_FAB2_LIB.BASEBOARD_FAB2(SCH_1):PAGE57
   F63 M_G_BG<1> @BASEBOARD_FAB2_LIB.BASEBOARD_FAB2(SCH_1):M_G_BG(1)   I172 @BASEBOARD_FAB2_LIB.BASEBOARD_FAB2(SCH_1):PAGE57
   D61 M_G_BG<0> @BASEBOARD_FAB2_LIB.BASEBOARD_FAB2(SCH_1):M_G_BG(0)   I172 @BASEBOARD_FAB2_LIB.BASEBOARD_FAB2(SCH_1):PAGE57
   G46 M_G_C<2> @BASEBOARD_FAB2_LIB.BASEBOARD_FAB2(SCH_1):M_G_C(2)   I172 @BASEBOARD_FAB2_LIB.BASEBOARD_FAB2(SCH_1):PAGE57
   D63 M_G_CKE<3> @BASEBOARD_FAB2_LIB.BASEBOARD_FAB2(SCH_1):M_G_CKE(3)   I172 @BASEBOARD_FAB2_LIB.BASEBOARD_FAB2(SCH_1):PAGE57
   B63 M_G_CKE<2> @BASEBOARD_FAB2_LIB.BASEBOARD_FAB2(SCH_1):M_G_CKE(2)   I172 @BASEBOARD_FAB2_LIB.BASEBOARD_FAB2(SCH_1):PAGE57
   C64 M_G_CKE<1> @BASEBOARD_FAB2_LIB.BASEBOARD_FAB2(SCH_1):M_G_CKE(1)   I172 @BASEBOARD_FAB2_LIB.BASEBOARD_FAB2(SCH_1):PAGE57
   C62 M_G_CKE<0> @BASEBOARD_FAB2_LIB.BASEBOARD_FAB2(SCH_1):M_G_CKE(0)   I172 @BASEBOARD_FAB2_LIB.BASEBOARD_FAB2(SCH_1):PAGE57
   C56 M_G_CLK_DN<3> @BASEBOARD_FAB2_LIB.BASEBOARD_FAB2(SCH_1):M_G_CLK_DN(3)   I172 @BASEBOARD_FAB2_LIB.BASEBOARD_FAB2(SCH_1):PAGE57
   J56 M_G_CLK_DN<2> @BASEBOARD_FAB2_LIB.BASEBOARD_FAB2(SCH_1):M_G_CLK_DN(2)   I172 @BASEBOARD_FAB2_LIB.BASEBOARD_FAB2(SCH_1):PAGE57
   C54 M_G_CLK_DN<1> @BASEBOARD_FAB2_LIB.BASEBOARD_FAB2(SCH_1):M_G_CLK_DN(1)   I172 @BASEBOARD_FAB2_LIB.BASEBOARD_FAB2(SCH_1):PAGE57
   F55 M_G_CLK_DN<0> @BASEBOARD_FAB2_LIB.BASEBOARD_FAB2(SCH_1):M_G_CLK_DN(0)   I172 @BASEBOARD_FAB2_LIB.BASEBOARD_FAB2(SCH_1):PAGE57
   B57 M_G_CLK_DP<3> @BASEBOARD_FAB2_LIB.BASEBOARD_FAB2(SCH_1):M_G_CLK_DP(3)   I172 @BASEBOARD_FAB2_LIB.BASEBOARD_FAB2(SCH_1):PAGE57
   G56 M_G_CLK_DP<2> @BASEBOARD_FAB2_LIB.BASEBOARD_FAB2(SCH_1):M_G_CLK_DP(2)   I172 @BASEBOARD_FAB2_LIB.BASEBOARD_FAB2(SCH_1):PAGE57
   B55 M_G_CLK_DP<1> @BASEBOARD_FAB2_LIB.BASEBOARD_FAB2(SCH_1):M_G_CLK_DP(1)   I172 @BASEBOARD_FAB2_LIB.BASEBOARD_FAB2(SCH_1):PAGE57
   D55 M_G_CLK_DP<0> @BASEBOARD_FAB2_LIB.BASEBOARD_FAB2(SCH_1):M_G_CLK_DP(0)   I172 @BASEBOARD_FAB2_LIB.BASEBOARD_FAB2(SCH_1):PAGE57
   K45 M_G_CS_N<7> @BASEBOARD_FAB2_LIB.BASEBOARD_FAB2(SCH_1):M_G_CS_N(7)   I172 @BASEBOARD_FAB2_LIB.BASEBOARD_FAB2(SCH_1):PAGE57
   F45 M_G_CS_N<6> @BASEBOARD_FAB2_LIB.BASEBOARD_FAB2(SCH_1):M_G_CS_N(6)   I172 @BASEBOARD_FAB2_LIB.BASEBOARD_FAB2(SCH_1):PAGE57
   D49 M_G_CS_N<5> @BASEBOARD_FAB2_LIB.BASEBOARD_FAB2(SCH_1):M_G_CS_N(5)   I172 @BASEBOARD_FAB2_LIB.BASEBOARD_FAB2(SCH_1):PAGE57
   B51 M_G_CS_N<4> @BASEBOARD_FAB2_LIB.BASEBOARD_FAB2(SCH_1):M_G_CS_N(4)   I172 @BASEBOARD_FAB2_LIB.BASEBOARD_FAB2(SCH_1):PAGE57
   F47 M_G_CS_N<3> @BASEBOARD_FAB2_LIB.BASEBOARD_FAB2(SCH_1):M_G_CS_N(3)   I172 @BASEBOARD_FAB2_LIB.BASEBOARD_FAB2(SCH_1):PAGE57
   D47 M_G_CS_N<2> @BASEBOARD_FAB2_LIB.BASEBOARD_FAB2(SCH_1):M_G_CS_N(2)   I172 @BASEBOARD_FAB2_LIB.BASEBOARD_FAB2(SCH_1):PAGE57
   F49 M_G_CS_N<1> @BASEBOARD_FAB2_LIB.BASEBOARD_FAB2(SCH_1):M_G_CS_N(1)   I172 @BASEBOARD_FAB2_LIB.BASEBOARD_FAB2(SCH_1):PAGE57
   G52 M_G_CS_N<0> @BASEBOARD_FAB2_LIB.BASEBOARD_FAB2(SCH_1):M_G_CS_N(0)   I172 @BASEBOARD_FAB2_LIB.BASEBOARD_FAB2(SCH_1):PAGE57
   K23 M_G_DQ<63> @BASEBOARD_FAB2_LIB.BASEBOARD_FAB2(SCH_1):M_G_DQ(63)   I172 @BASEBOARD_FAB2_LIB.BASEBOARD_FAB2(SCH_1):PAGE57
   H23 M_G_DQ<62> @BASEBOARD_FAB2_LIB.BASEBOARD_FAB2(SCH_1):M_G_DQ(62)   I172 @BASEBOARD_FAB2_LIB.BASEBOARD_FAB2(SCH_1):PAGE57
   N26 M_G_DQ<61> @BASEBOARD_FAB2_LIB.BASEBOARD_FAB2(SCH_1):M_G_DQ(61)   I172 @BASEBOARD_FAB2_LIB.BASEBOARD_FAB2(SCH_1):PAGE57
   L26 M_G_DQ<60> @BASEBOARD_FAB2_LIB.BASEBOARD_FAB2(SCH_1):M_G_DQ(60)   I172 @BASEBOARD_FAB2_LIB.BASEBOARD_FAB2(SCH_1):PAGE57
   T23 M_G_DQ<59> @BASEBOARD_FAB2_LIB.BASEBOARD_FAB2(SCH_1):M_G_DQ(59)   I172 @BASEBOARD_FAB2_LIB.BASEBOARD_FAB2(SCH_1):PAGE57
   P23 M_G_DQ<58> @BASEBOARD_FAB2_LIB.BASEBOARD_FAB2(SCH_1):M_G_DQ(58)   I172 @BASEBOARD_FAB2_LIB.BASEBOARD_FAB2(SCH_1):PAGE57
   P25 M_G_DQ<57> @BASEBOARD_FAB2_LIB.BASEBOARD_FAB2(SCH_1):M_G_DQ(57)   I172 @BASEBOARD_FAB2_LIB.BASEBOARD_FAB2(SCH_1):PAGE57
   K25 M_G_DQ<56> @BASEBOARD_FAB2_LIB.BASEBOARD_FAB2(SCH_1):M_G_DQ(56)   I172 @BASEBOARD_FAB2_LIB.BASEBOARD_FAB2(SCH_1):PAGE57
   P29 M_G_DQ<55> @BASEBOARD_FAB2_LIB.BASEBOARD_FAB2(SCH_1):M_G_DQ(55)   I172 @BASEBOARD_FAB2_LIB.BASEBOARD_FAB2(SCH_1):PAGE57
   K29 M_G_DQ<54> @BASEBOARD_FAB2_LIB.BASEBOARD_FAB2(SCH_1):M_G_DQ(54)   I172 @BASEBOARD_FAB2_LIB.BASEBOARD_FAB2(SCH_1):PAGE57
   N32 M_G_DQ<53> @BASEBOARD_FAB2_LIB.BASEBOARD_FAB2(SCH_1):M_G_DQ(53)   I172 @BASEBOARD_FAB2_LIB.BASEBOARD_FAB2(SCH_1):PAGE57
   L32 M_G_DQ<52> @BASEBOARD_FAB2_LIB.BASEBOARD_FAB2(SCH_1):M_G_DQ(52)   I172 @BASEBOARD_FAB2_LIB.BASEBOARD_FAB2(SCH_1):PAGE57
   N28 M_G_DQ<51> @BASEBOARD_FAB2_LIB.BASEBOARD_FAB2(SCH_1):M_G_DQ(51)   I172 @BASEBOARD_FAB2_LIB.BASEBOARD_FAB2(SCH_1):PAGE57
   L28 M_G_DQ<50> @BASEBOARD_FAB2_LIB.BASEBOARD_FAB2(SCH_1):M_G_DQ(50)   I172 @BASEBOARD_FAB2_LIB.BASEBOARD_FAB2(SCH_1):PAGE57
   P31 M_G_DQ<49> @BASEBOARD_FAB2_LIB.BASEBOARD_FAB2(SCH_1):M_G_DQ(49)   I172 @BASEBOARD_FAB2_LIB.BASEBOARD_FAB2(SCH_1):PAGE57
   K31 M_G_DQ<48> @BASEBOARD_FAB2_LIB.BASEBOARD_FAB2(SCH_1):M_G_DQ(48)   I172 @BASEBOARD_FAB2_LIB.BASEBOARD_FAB2(SCH_1):PAGE57
   P35 M_G_DQ<47> @BASEBOARD_FAB2_LIB.BASEBOARD_FAB2(SCH_1):M_G_DQ(47)   I172 @BASEBOARD_FAB2_LIB.BASEBOARD_FAB2(SCH_1):PAGE57
   K35 M_G_DQ<46> @BASEBOARD_FAB2_LIB.BASEBOARD_FAB2(SCH_1):M_G_DQ(46)   I172 @BASEBOARD_FAB2_LIB.BASEBOARD_FAB2(SCH_1):PAGE57
   N38 M_G_DQ<45> @BASEBOARD_FAB2_LIB.BASEBOARD_FAB2(SCH_1):M_G_DQ(45)   I172 @BASEBOARD_FAB2_LIB.BASEBOARD_FAB2(SCH_1):PAGE57
   L38 M_G_DQ<44> @BASEBOARD_FAB2_LIB.BASEBOARD_FAB2(SCH_1):M_G_DQ(44)   I172 @BASEBOARD_FAB2_LIB.BASEBOARD_FAB2(SCH_1):PAGE57
   N34 M_G_DQ<43> @BASEBOARD_FAB2_LIB.BASEBOARD_FAB2(SCH_1):M_G_DQ(43)   I172 @BASEBOARD_FAB2_LIB.BASEBOARD_FAB2(SCH_1):PAGE57
   L34 M_G_DQ<42> @BASEBOARD_FAB2_LIB.BASEBOARD_FAB2(SCH_1):M_G_DQ(42)   I172 @BASEBOARD_FAB2_LIB.BASEBOARD_FAB2(SCH_1):PAGE57
   P37 M_G_DQ<41> @BASEBOARD_FAB2_LIB.BASEBOARD_FAB2(SCH_1):M_G_DQ(41)   I172 @BASEBOARD_FAB2_LIB.BASEBOARD_FAB2(SCH_1):PAGE57
   K37 M_G_DQ<40> @BASEBOARD_FAB2_LIB.BASEBOARD_FAB2(SCH_1):M_G_DQ(40)   I172 @BASEBOARD_FAB2_LIB.BASEBOARD_FAB2(SCH_1):PAGE57
   F39 M_G_DQ<39> @BASEBOARD_FAB2_LIB.BASEBOARD_FAB2(SCH_1):M_G_DQ(39)   I172 @BASEBOARD_FAB2_LIB.BASEBOARD_FAB2(SCH_1):PAGE57
   B39 M_G_DQ<38> @BASEBOARD_FAB2_LIB.BASEBOARD_FAB2(SCH_1):M_G_DQ(38)   I172 @BASEBOARD_FAB2_LIB.BASEBOARD_FAB2(SCH_1):PAGE57
   F41 M_G_DQ<37> @BASEBOARD_FAB2_LIB.BASEBOARD_FAB2(SCH_1):M_G_DQ(37)   I172 @BASEBOARD_FAB2_LIB.BASEBOARD_FAB2(SCH_1):PAGE57
   E42 M_G_DQ<36> @BASEBOARD_FAB2_LIB.BASEBOARD_FAB2(SCH_1):M_G_DQ(36)   I172 @BASEBOARD_FAB2_LIB.BASEBOARD_FAB2(SCH_1):PAGE57
   E38 M_G_DQ<35> @BASEBOARD_FAB2_LIB.BASEBOARD_FAB2(SCH_1):M_G_DQ(35)   I172 @BASEBOARD_FAB2_LIB.BASEBOARD_FAB2(SCH_1):PAGE57
   C38 M_G_DQ<34> @BASEBOARD_FAB2_LIB.BASEBOARD_FAB2(SCH_1):M_G_DQ(34)   I172 @BASEBOARD_FAB2_LIB.BASEBOARD_FAB2(SCH_1):PAGE57
   B41 M_G_DQ<33> @BASEBOARD_FAB2_LIB.BASEBOARD_FAB2(SCH_1):M_G_DQ(33)   I172 @BASEBOARD_FAB2_LIB.BASEBOARD_FAB2(SCH_1):PAGE57
   C42 M_G_DQ<32> @BASEBOARD_FAB2_LIB.BASEBOARD_FAB2(SCH_1):M_G_DQ(32)   I172 @BASEBOARD_FAB2_LIB.BASEBOARD_FAB2(SCH_1):PAGE57
   R74 M_G_DQ<31> @BASEBOARD_FAB2_LIB.BASEBOARD_FAB2(SCH_1):M_G_DQ(31)   I172 @BASEBOARD_FAB2_LIB.BASEBOARD_FAB2(SCH_1):PAGE57
   L74 M_G_DQ<30> @BASEBOARD_FAB2_LIB.BASEBOARD_FAB2(SCH_1):M_G_DQ(30)   I172 @BASEBOARD_FAB2_LIB.BASEBOARD_FAB2(SCH_1):PAGE57
   P77 M_G_DQ<29> @BASEBOARD_FAB2_LIB.BASEBOARD_FAB2(SCH_1):M_G_DQ(29)   I172 @BASEBOARD_FAB2_LIB.BASEBOARD_FAB2(SCH_1):PAGE57
   M77 M_G_DQ<28> @BASEBOARD_FAB2_LIB.BASEBOARD_FAB2(SCH_1):M_G_DQ(28)   I172 @BASEBOARD_FAB2_LIB.BASEBOARD_FAB2(SCH_1):PAGE57
   P73 M_G_DQ<27> @BASEBOARD_FAB2_LIB.BASEBOARD_FAB2(SCH_1):M_G_DQ(27)   I172 @BASEBOARD_FAB2_LIB.BASEBOARD_FAB2(SCH_1):PAGE57
   M73 M_G_DQ<26> @BASEBOARD_FAB2_LIB.BASEBOARD_FAB2(SCH_1):M_G_DQ(26)   I172 @BASEBOARD_FAB2_LIB.BASEBOARD_FAB2(SCH_1):PAGE57
   R76 M_G_DQ<25> @BASEBOARD_FAB2_LIB.BASEBOARD_FAB2(SCH_1):M_G_DQ(25)   I172 @BASEBOARD_FAB2_LIB.BASEBOARD_FAB2(SCH_1):PAGE57
   L76 M_G_DQ<24> @BASEBOARD_FAB2_LIB.BASEBOARD_FAB2(SCH_1):M_G_DQ(24)   I172 @BASEBOARD_FAB2_LIB.BASEBOARD_FAB2(SCH_1):PAGE57
   N80 M_G_DQ<23> @BASEBOARD_FAB2_LIB.BASEBOARD_FAB2(SCH_1):M_G_DQ(23)   I172 @BASEBOARD_FAB2_LIB.BASEBOARD_FAB2(SCH_1):PAGE57
   R82 M_G_DQ<22> @BASEBOARD_FAB2_LIB.BASEBOARD_FAB2(SCH_1):M_G_DQ(22)   I172 @BASEBOARD_FAB2_LIB.BASEBOARD_FAB2(SCH_1):PAGE57
   V79 M_G_DQ<21> @BASEBOARD_FAB2_LIB.BASEBOARD_FAB2(SCH_1):M_G_DQ(21)   I172 @BASEBOARD_FAB2_LIB.BASEBOARD_FAB2(SCH_1):PAGE57
   W80 M_G_DQ<20> @BASEBOARD_FAB2_LIB.BASEBOARD_FAB2(SCH_1):M_G_DQ(20)   I172 @BASEBOARD_FAB2_LIB.BASEBOARD_FAB2(SCH_1):PAGE57
   M81 M_G_DQ<19> @BASEBOARD_FAB2_LIB.BASEBOARD_FAB2(SCH_1):M_G_DQ(19)   I172 @BASEBOARD_FAB2_LIB.BASEBOARD_FAB2(SCH_1):PAGE57
   N82 M_G_DQ<18> @BASEBOARD_FAB2_LIB.BASEBOARD_FAB2(SCH_1):M_G_DQ(18)   I172 @BASEBOARD_FAB2_LIB.BASEBOARD_FAB2(SCH_1):PAGE57
   T79 M_G_DQ<17> @BASEBOARD_FAB2_LIB.BASEBOARD_FAB2(SCH_1):M_G_DQ(17)   I172 @BASEBOARD_FAB2_LIB.BASEBOARD_FAB2(SCH_1):PAGE57
   V81 M_G_DQ<16> @BASEBOARD_FAB2_LIB.BASEBOARD_FAB2(SCH_1):M_G_DQ(16)   I172 @BASEBOARD_FAB2_LIB.BASEBOARD_FAB2(SCH_1):PAGE57
   N84 M_G_DQ<15> @BASEBOARD_FAB2_LIB.BASEBOARD_FAB2(SCH_1):M_G_DQ(15)   I172 @BASEBOARD_FAB2_LIB.BASEBOARD_FAB2(SCH_1):PAGE57
   N86 M_G_DQ<14> @BASEBOARD_FAB2_LIB.BASEBOARD_FAB2(SCH_1):M_G_DQ(14)   I172 @BASEBOARD_FAB2_LIB.BASEBOARD_FAB2(SCH_1):PAGE57
  AA84 M_G_DQ<13> @BASEBOARD_FAB2_LIB.BASEBOARD_FAB2(SCH_1):M_G_DQ(13)   I172 @BASEBOARD_FAB2_LIB.BASEBOARD_FAB2(SCH_1):PAGE57
  AA86 M_G_DQ<12> @BASEBOARD_FAB2_LIB.BASEBOARD_FAB2(SCH_1):M_G_DQ(12)   I172 @BASEBOARD_FAB2_LIB.BASEBOARD_FAB2(SCH_1):PAGE57
   L84 M_G_DQ<11> @BASEBOARD_FAB2_LIB.BASEBOARD_FAB2(SCH_1):M_G_DQ(11)   I172 @BASEBOARD_FAB2_LIB.BASEBOARD_FAB2(SCH_1):PAGE57
   L86 M_G_DQ<10> @BASEBOARD_FAB2_LIB.BASEBOARD_FAB2(SCH_1):M_G_DQ(10)   I172 @BASEBOARD_FAB2_LIB.BASEBOARD_FAB2(SCH_1):PAGE57
   W84 M_G_DQ<9> @BASEBOARD_FAB2_LIB.BASEBOARD_FAB2(SCH_1):M_G_DQ(9)   I172 @BASEBOARD_FAB2_LIB.BASEBOARD_FAB2(SCH_1):PAGE57
   W86 M_G_DQ<8> @BASEBOARD_FAB2_LIB.BASEBOARD_FAB2(SCH_1):M_G_DQ(8)   I172 @BASEBOARD_FAB2_LIB.BASEBOARD_FAB2(SCH_1):PAGE57
  AG84 M_G_DQ<7> @BASEBOARD_FAB2_LIB.BASEBOARD_FAB2(SCH_1):M_G_DQ(7)   I172 @BASEBOARD_FAB2_LIB.BASEBOARD_FAB2(SCH_1):PAGE57
  AG86 M_G_DQ<6> @BASEBOARD_FAB2_LIB.BASEBOARD_FAB2(SCH_1):M_G_DQ(6)   I172 @BASEBOARD_FAB2_LIB.BASEBOARD_FAB2(SCH_1):PAGE57
  AR84 M_G_DQ<5> @BASEBOARD_FAB2_LIB.BASEBOARD_FAB2(SCH_1):M_G_DQ(5)   I172 @BASEBOARD_FAB2_LIB.BASEBOARD_FAB2(SCH_1):PAGE57
  AR86 M_G_DQ<4> @BASEBOARD_FAB2_LIB.BASEBOARD_FAB2(SCH_1):M_G_DQ(4)   I172 @BASEBOARD_FAB2_LIB.BASEBOARD_FAB2(SCH_1):PAGE57
  AE84 M_G_DQ<3> @BASEBOARD_FAB2_LIB.BASEBOARD_FAB2(SCH_1):M_G_DQ(3)   I172 @BASEBOARD_FAB2_LIB.BASEBOARD_FAB2(SCH_1):PAGE57
  AE86 M_G_DQ<2> @BASEBOARD_FAB2_LIB.BASEBOARD_FAB2(SCH_1):M_G_DQ(2)   I172 @BASEBOARD_FAB2_LIB.BASEBOARD_FAB2(SCH_1):PAGE57
  AN84 M_G_DQ<1> @BASEBOARD_FAB2_LIB.BASEBOARD_FAB2(SCH_1):M_G_DQ(1)   I172 @BASEBOARD_FAB2_LIB.BASEBOARD_FAB2(SCH_1):PAGE57
  AN86 M_G_DQ<0> @BASEBOARD_FAB2_LIB.BASEBOARD_FAB2(SCH_1):M_G_DQ(0)   I172 @BASEBOARD_FAB2_LIB.BASEBOARD_FAB2(SCH_1):PAGE57
  AB67 M_G_DQS_DN<17> @BASEBOARD_FAB2_LIB.BASEBOARD_FAB2(SCH_1):M_G_DQS_DN(17)   I172 @BASEBOARD_FAB2_LIB.BASEBOARD_FAB2(SCH_1):PAGE57
   J24 M_G_DQS_DN<16> @BASEBOARD_FAB2_LIB.BASEBOARD_FAB2(SCH_1):M_G_DQS_DN(16)   I172 @BASEBOARD_FAB2_LIB.BASEBOARD_FAB2(SCH_1):PAGE57
   J30 M_G_DQS_DN<15> @BASEBOARD_FAB2_LIB.BASEBOARD_FAB2(SCH_1):M_G_DQS_DN(15)   I172 @BASEBOARD_FAB2_LIB.BASEBOARD_FAB2(SCH_1):PAGE57
   J36 M_G_DQS_DN<14> @BASEBOARD_FAB2_LIB.BASEBOARD_FAB2(SCH_1):M_G_DQS_DN(14)   I172 @BASEBOARD_FAB2_LIB.BASEBOARD_FAB2(SCH_1):PAGE57
   A40 M_G_DQS_DN<13> @BASEBOARD_FAB2_LIB.BASEBOARD_FAB2(SCH_1):M_G_DQS_DN(13)   I172 @BASEBOARD_FAB2_LIB.BASEBOARD_FAB2(SCH_1):PAGE57
   K75 M_G_DQS_DN<12> @BASEBOARD_FAB2_LIB.BASEBOARD_FAB2(SCH_1):M_G_DQS_DN(12)   I172 @BASEBOARD_FAB2_LIB.BASEBOARD_FAB2(SCH_1):PAGE57
   U82 M_G_DQS_DN<11> @BASEBOARD_FAB2_LIB.BASEBOARD_FAB2(SCH_1):M_G_DQS_DN(11)   I172 @BASEBOARD_FAB2_LIB.BASEBOARD_FAB2(SCH_1):PAGE57
   U84 M_G_DQS_DN<10> @BASEBOARD_FAB2_LIB.BASEBOARD_FAB2(SCH_1):M_G_DQS_DN(10)   I172 @BASEBOARD_FAB2_LIB.BASEBOARD_FAB2(SCH_1):PAGE57
  AL84 M_G_DQS_DN<9> @BASEBOARD_FAB2_LIB.BASEBOARD_FAB2(SCH_1):M_G_DQS_DN(9)   I172 @BASEBOARD_FAB2_LIB.BASEBOARD_FAB2(SCH_1):PAGE57
  AH67 M_G_DQS_DN<8> @BASEBOARD_FAB2_LIB.BASEBOARD_FAB2(SCH_1):M_G_DQS_DN(8)   I172 @BASEBOARD_FAB2_LIB.BASEBOARD_FAB2(SCH_1):PAGE57
   N24 M_G_DQS_DN<7> @BASEBOARD_FAB2_LIB.BASEBOARD_FAB2(SCH_1):M_G_DQS_DN(7)   I172 @BASEBOARD_FAB2_LIB.BASEBOARD_FAB2(SCH_1):PAGE57
   R30 M_G_DQS_DN<6> @BASEBOARD_FAB2_LIB.BASEBOARD_FAB2(SCH_1):M_G_DQS_DN(6)   I172 @BASEBOARD_FAB2_LIB.BASEBOARD_FAB2(SCH_1):PAGE57
   R36 M_G_DQS_DN<5> @BASEBOARD_FAB2_LIB.BASEBOARD_FAB2(SCH_1):M_G_DQS_DN(5)   I172 @BASEBOARD_FAB2_LIB.BASEBOARD_FAB2(SCH_1):PAGE57
   G40 M_G_DQS_DN<4> @BASEBOARD_FAB2_LIB.BASEBOARD_FAB2(SCH_1):M_G_DQS_DN(4)   I172 @BASEBOARD_FAB2_LIB.BASEBOARD_FAB2(SCH_1):PAGE57
   T75 M_G_DQS_DN<3> @BASEBOARD_FAB2_LIB.BASEBOARD_FAB2(SCH_1):M_G_DQS_DN(3)   I172 @BASEBOARD_FAB2_LIB.BASEBOARD_FAB2(SCH_1):PAGE57
   P79 M_G_DQS_DN<2> @BASEBOARD_FAB2_LIB.BASEBOARD_FAB2(SCH_1):M_G_DQS_DN(2)   I172 @BASEBOARD_FAB2_LIB.BASEBOARD_FAB2(SCH_1):PAGE57
   R84 M_G_DQS_DN<1> @BASEBOARD_FAB2_LIB.BASEBOARD_FAB2(SCH_1):M_G_DQS_DN(1)   I172 @BASEBOARD_FAB2_LIB.BASEBOARD_FAB2(SCH_1):PAGE57
  AJ84 M_G_DQS_DN<0> @BASEBOARD_FAB2_LIB.BASEBOARD_FAB2(SCH_1):M_G_DQS_DN(0)   I172 @BASEBOARD_FAB2_LIB.BASEBOARD_FAB2(SCH_1):PAGE57
  AD67 M_G_DQS_DP<17> @BASEBOARD_FAB2_LIB.BASEBOARD_FAB2(SCH_1):M_G_DQS_DP(17)   I172 @BASEBOARD_FAB2_LIB.BASEBOARD_FAB2(SCH_1):PAGE57
   L24 M_G_DQS_DP<16> @BASEBOARD_FAB2_LIB.BASEBOARD_FAB2(SCH_1):M_G_DQS_DP(16)   I172 @BASEBOARD_FAB2_LIB.BASEBOARD_FAB2(SCH_1):PAGE57
   L30 M_G_DQS_DP<15> @BASEBOARD_FAB2_LIB.BASEBOARD_FAB2(SCH_1):M_G_DQS_DP(15)   I172 @BASEBOARD_FAB2_LIB.BASEBOARD_FAB2(SCH_1):PAGE57
   L36 M_G_DQS_DP<14> @BASEBOARD_FAB2_LIB.BASEBOARD_FAB2(SCH_1):M_G_DQS_DP(14)   I172 @BASEBOARD_FAB2_LIB.BASEBOARD_FAB2(SCH_1):PAGE57
   C40 M_G_DQS_DP<13> @BASEBOARD_FAB2_LIB.BASEBOARD_FAB2(SCH_1):M_G_DQS_DP(13)   I172 @BASEBOARD_FAB2_LIB.BASEBOARD_FAB2(SCH_1):PAGE57
   M75 M_G_DQS_DP<12> @BASEBOARD_FAB2_LIB.BASEBOARD_FAB2(SCH_1):M_G_DQS_DP(12)   I172 @BASEBOARD_FAB2_LIB.BASEBOARD_FAB2(SCH_1):PAGE57
   T81 M_G_DQS_DP<11> @BASEBOARD_FAB2_LIB.BASEBOARD_FAB2(SCH_1):M_G_DQS_DP(11)   I172 @BASEBOARD_FAB2_LIB.BASEBOARD_FAB2(SCH_1):PAGE57
   V85 M_G_DQS_DP<10> @BASEBOARD_FAB2_LIB.BASEBOARD_FAB2(SCH_1):M_G_DQS_DP(10)   I172 @BASEBOARD_FAB2_LIB.BASEBOARD_FAB2(SCH_1):PAGE57
  AM85 M_G_DQS_DP<9> @BASEBOARD_FAB2_LIB.BASEBOARD_FAB2(SCH_1):M_G_DQS_DP(9)   I172 @BASEBOARD_FAB2_LIB.BASEBOARD_FAB2(SCH_1):PAGE57
  AF67 M_G_DQS_DP<8> @BASEBOARD_FAB2_LIB.BASEBOARD_FAB2(SCH_1):M_G_DQS_DP(8)   I172 @BASEBOARD_FAB2_LIB.BASEBOARD_FAB2(SCH_1):PAGE57
   R24 M_G_DQS_DP<7> @BASEBOARD_FAB2_LIB.BASEBOARD_FAB2(SCH_1):M_G_DQS_DP(7)   I172 @BASEBOARD_FAB2_LIB.BASEBOARD_FAB2(SCH_1):PAGE57
   N30 M_G_DQS_DP<6> @BASEBOARD_FAB2_LIB.BASEBOARD_FAB2(SCH_1):M_G_DQS_DP(6)   I172 @BASEBOARD_FAB2_LIB.BASEBOARD_FAB2(SCH_1):PAGE57
   N36 M_G_DQS_DP<5> @BASEBOARD_FAB2_LIB.BASEBOARD_FAB2(SCH_1):M_G_DQS_DP(5)   I172 @BASEBOARD_FAB2_LIB.BASEBOARD_FAB2(SCH_1):PAGE57
   E40 M_G_DQS_DP<4> @BASEBOARD_FAB2_LIB.BASEBOARD_FAB2(SCH_1):M_G_DQS_DP(4)   I172 @BASEBOARD_FAB2_LIB.BASEBOARD_FAB2(SCH_1):PAGE57
   P75 M_G_DQS_DP<3> @BASEBOARD_FAB2_LIB.BASEBOARD_FAB2(SCH_1):M_G_DQS_DP(3)   I172 @BASEBOARD_FAB2_LIB.BASEBOARD_FAB2(SCH_1):PAGE57
   R80 M_G_DQS_DP<2> @BASEBOARD_FAB2_LIB.BASEBOARD_FAB2(SCH_1):M_G_DQS_DP(2)   I172 @BASEBOARD_FAB2_LIB.BASEBOARD_FAB2(SCH_1):PAGE57
   P85 M_G_DQS_DP<1> @BASEBOARD_FAB2_LIB.BASEBOARD_FAB2(SCH_1):M_G_DQS_DP(1)   I172 @BASEBOARD_FAB2_LIB.BASEBOARD_FAB2(SCH_1):PAGE57
  AH85 M_G_DQS_DP<0> @BASEBOARD_FAB2_LIB.BASEBOARD_FAB2(SCH_1):M_G_DQS_DP(0)   I172 @BASEBOARD_FAB2_LIB.BASEBOARD_FAB2(SCH_1):PAGE57
  AG66 M_G_ECC<7> @BASEBOARD_FAB2_LIB.BASEBOARD_FAB2(SCH_1):M_G_ECC(7)   I172 @BASEBOARD_FAB2_LIB.BASEBOARD_FAB2(SCH_1):PAGE57
  AC66 M_G_ECC<6> @BASEBOARD_FAB2_LIB.BASEBOARD_FAB2(SCH_1):M_G_ECC(6)   I172 @BASEBOARD_FAB2_LIB.BASEBOARD_FAB2(SCH_1):PAGE57
  AF69 M_G_ECC<5> @BASEBOARD_FAB2_LIB.BASEBOARD_FAB2(SCH_1):M_G_ECC(5)   I172 @BASEBOARD_FAB2_LIB.BASEBOARD_FAB2(SCH_1):PAGE57
  AD69 M_G_ECC<4> @BASEBOARD_FAB2_LIB.BASEBOARD_FAB2(SCH_1):M_G_ECC(4)   I172 @BASEBOARD_FAB2_LIB.BASEBOARD_FAB2(SCH_1):PAGE57
  AF65 M_G_ECC<3> @BASEBOARD_FAB2_LIB.BASEBOARD_FAB2(SCH_1):M_G_ECC(3)   I172 @BASEBOARD_FAB2_LIB.BASEBOARD_FAB2(SCH_1):PAGE57
  AD65 M_G_ECC<2> @BASEBOARD_FAB2_LIB.BASEBOARD_FAB2(SCH_1):M_G_ECC(2)   I172 @BASEBOARD_FAB2_LIB.BASEBOARD_FAB2(SCH_1):PAGE57
  AG68 M_G_ECC<1> @BASEBOARD_FAB2_LIB.BASEBOARD_FAB2(SCH_1):M_G_ECC(1)   I172 @BASEBOARD_FAB2_LIB.BASEBOARD_FAB2(SCH_1):PAGE57
  AC68 M_G_ECC<0> @BASEBOARD_FAB2_LIB.BASEBOARD_FAB2(SCH_1):M_G_ECC(0)   I172 @BASEBOARD_FAB2_LIB.BASEBOARD_FAB2(SCH_1):PAGE57
   K47 M_G_MA<17> @BASEBOARD_FAB2_LIB.BASEBOARD_FAB2(SCH_1):M_G_MA(17)   I172 @BASEBOARD_FAB2_LIB.BASEBOARD_FAB2(SCH_1):PAGE57
   D51 M_G_MA<16> @BASEBOARD_FAB2_LIB.BASEBOARD_FAB2(SCH_1):M_G_MA(16)   I172 @BASEBOARD_FAB2_LIB.BASEBOARD_FAB2(SCH_1):PAGE57
   K49 M_G_MA<15> @BASEBOARD_FAB2_LIB.BASEBOARD_FAB2(SCH_1):M_G_MA(15)   I172 @BASEBOARD_FAB2_LIB.BASEBOARD_FAB2(SCH_1):PAGE57
   F51 M_G_MA<14> @BASEBOARD_FAB2_LIB.BASEBOARD_FAB2(SCH_1):M_G_MA(14)   I172 @BASEBOARD_FAB2_LIB.BASEBOARD_FAB2(SCH_1):PAGE57
   J48 M_G_MA<13> @BASEBOARD_FAB2_LIB.BASEBOARD_FAB2(SCH_1):M_G_MA(13)   I172 @BASEBOARD_FAB2_LIB.BASEBOARD_FAB2(SCH_1):PAGE57
   J64 M_G_MA<12> @BASEBOARD_FAB2_LIB.BASEBOARD_FAB2(SCH_1):M_G_MA(12)   I172 @BASEBOARD_FAB2_LIB.BASEBOARD_FAB2(SCH_1):PAGE57
   G62 M_G_MA<11> @BASEBOARD_FAB2_LIB.BASEBOARD_FAB2(SCH_1):M_G_MA(11)   I172 @BASEBOARD_FAB2_LIB.BASEBOARD_FAB2(SCH_1):PAGE57
   J54 M_G_MA<10> @BASEBOARD_FAB2_LIB.BASEBOARD_FAB2(SCH_1):M_G_MA(10)   I172 @BASEBOARD_FAB2_LIB.BASEBOARD_FAB2(SCH_1):PAGE57
   F61 M_G_MA<9> @BASEBOARD_FAB2_LIB.BASEBOARD_FAB2(SCH_1):M_G_MA(9)   I172 @BASEBOARD_FAB2_LIB.BASEBOARD_FAB2(SCH_1):PAGE57
   C60 M_G_MA<8> @BASEBOARD_FAB2_LIB.BASEBOARD_FAB2(SCH_1):M_G_MA(8)   I172 @BASEBOARD_FAB2_LIB.BASEBOARD_FAB2(SCH_1):PAGE57
   G60 M_G_MA<7> @BASEBOARD_FAB2_LIB.BASEBOARD_FAB2(SCH_1):M_G_MA(7)   I172 @BASEBOARD_FAB2_LIB.BASEBOARD_FAB2(SCH_1):PAGE57
   D59 M_G_MA<6> @BASEBOARD_FAB2_LIB.BASEBOARD_FAB2(SCH_1):M_G_MA(6)   I172 @BASEBOARD_FAB2_LIB.BASEBOARD_FAB2(SCH_1):PAGE57
   F59 M_G_MA<5> @BASEBOARD_FAB2_LIB.BASEBOARD_FAB2(SCH_1):M_G_MA(5)   I172 @BASEBOARD_FAB2_LIB.BASEBOARD_FAB2(SCH_1):PAGE57
   G58 M_G_MA<4> @BASEBOARD_FAB2_LIB.BASEBOARD_FAB2(SCH_1):M_G_MA(4)   I172 @BASEBOARD_FAB2_LIB.BASEBOARD_FAB2(SCH_1):PAGE57
   C58 M_G_MA<3> @BASEBOARD_FAB2_LIB.BASEBOARD_FAB2(SCH_1):M_G_MA(3)   I172 @BASEBOARD_FAB2_LIB.BASEBOARD_FAB2(SCH_1):PAGE57
   D57 M_G_MA<2> @BASEBOARD_FAB2_LIB.BASEBOARD_FAB2(SCH_1):M_G_MA(2)   I172 @BASEBOARD_FAB2_LIB.BASEBOARD_FAB2(SCH_1):PAGE57
   F57 M_G_MA<1> @BASEBOARD_FAB2_LIB.BASEBOARD_FAB2(SCH_1):M_G_MA(1)   I172 @BASEBOARD_FAB2_LIB.BASEBOARD_FAB2(SCH_1):PAGE57
   F53 M_G_MA<0> @BASEBOARD_FAB2_LIB.BASEBOARD_FAB2(SCH_1):M_G_MA(0)   I172 @BASEBOARD_FAB2_LIB.BASEBOARD_FAB2(SCH_1):PAGE57
   G48 M_G_ODT<3> @BASEBOARD_FAB2_LIB.BASEBOARD_FAB2(SCH_1):M_G_ODT(3)   I172 @BASEBOARD_FAB2_LIB.BASEBOARD_FAB2(SCH_1):PAGE57
   G50 M_G_ODT<2> @BASEBOARD_FAB2_LIB.BASEBOARD_FAB2(SCH_1):M_G_ODT(2)   I172 @BASEBOARD_FAB2_LIB.BASEBOARD_FAB2(SCH_1):PAGE57
   C48 M_G_ODT<1> @BASEBOARD_FAB2_LIB.BASEBOARD_FAB2(SCH_1):M_G_ODT(1)   I172 @BASEBOARD_FAB2_LIB.BASEBOARD_FAB2(SCH_1):PAGE57
   C50 M_G_ODT<0> @BASEBOARD_FAB2_LIB.BASEBOARD_FAB2(SCH_1):M_G_ODT(0)   I172 @BASEBOARD_FAB2_LIB.BASEBOARD_FAB2(SCH_1):PAGE57
   D53 M_G_PAR @BASEBOARD_FAB2_LIB.BASEBOARD_FAB2(SCH_1):M_G_PAR   I172 @BASEBOARD_FAB2_LIB.BASEBOARD_FAB2(SCH_1):PAGE57
   T63 M_H_ACT_N @BASEBOARD_FAB2_LIB.BASEBOARD_FAB2(SCH_1):M_H_ACT_N   I172 @BASEBOARD_FAB2_LIB.BASEBOARD_FAB2(SCH_1):PAGE58
   W62 M_H_ALERT_N @BASEBOARD_FAB2_LIB.BASEBOARD_FAB2(SCH_1):M_H_ALERT_N   I172 @BASEBOARD_FAB2_LIB.BASEBOARD_FAB2(SCH_1):PAGE58
   K55 M_H_BA<1> @BASEBOARD_FAB2_LIB.BASEBOARD_FAB2(SCH_1):M_H_BA(1)   I172 @BASEBOARD_FAB2_LIB.BASEBOARD_FAB2(SCH_1):PAGE58
   T53 M_H_BA<0> @BASEBOARD_FAB2_LIB.BASEBOARD_FAB2(SCH_1):M_H_BA(0)   I172 @BASEBOARD_FAB2_LIB.BASEBOARD_FAB2(SCH_1):PAGE58
   N60 M_H_BG<1> @BASEBOARD_FAB2_LIB.BASEBOARD_FAB2(SCH_1):M_H_BG(1)   I172 @BASEBOARD_FAB2_LIB.BASEBOARD_FAB2(SCH_1):PAGE58
   M61 M_H_BG<0> @BASEBOARD_FAB2_LIB.BASEBOARD_FAB2(SCH_1):M_H_BG(0)   I172 @BASEBOARD_FAB2_LIB.BASEBOARD_FAB2(SCH_1):PAGE58
   M47 M_H_C<2> @BASEBOARD_FAB2_LIB.BASEBOARD_FAB2(SCH_1):M_H_C(2)   I172 @BASEBOARD_FAB2_LIB.BASEBOARD_FAB2(SCH_1):PAGE58
   L64 M_H_CKE<3> @BASEBOARD_FAB2_LIB.BASEBOARD_FAB2(SCH_1):M_H_CKE(3)   I172 @BASEBOARD_FAB2_LIB.BASEBOARD_FAB2(SCH_1):PAGE58
   K63 M_H_CKE<2> @BASEBOARD_FAB2_LIB.BASEBOARD_FAB2(SCH_1):M_H_CKE(2)   I172 @BASEBOARD_FAB2_LIB.BASEBOARD_FAB2(SCH_1):PAGE58
   R64 M_H_CKE<1> @BASEBOARD_FAB2_LIB.BASEBOARD_FAB2(SCH_1):M_H_CKE(1)   I172 @BASEBOARD_FAB2_LIB.BASEBOARD_FAB2(SCH_1):PAGE58
   N62 M_H_CKE<0> @BASEBOARD_FAB2_LIB.BASEBOARD_FAB2(SCH_1):M_H_CKE(0)   I172 @BASEBOARD_FAB2_LIB.BASEBOARD_FAB2(SCH_1):PAGE58
   R56 M_H_CLK_DN<3> @BASEBOARD_FAB2_LIB.BASEBOARD_FAB2(SCH_1):M_H_CLK_DN(3)   I172 @BASEBOARD_FAB2_LIB.BASEBOARD_FAB2(SCH_1):PAGE58
   N56 M_H_CLK_DN<2> @BASEBOARD_FAB2_LIB.BASEBOARD_FAB2(SCH_1):M_H_CLK_DN(2)   I172 @BASEBOARD_FAB2_LIB.BASEBOARD_FAB2(SCH_1):PAGE58
   R54 M_H_CLK_DN<1> @BASEBOARD_FAB2_LIB.BASEBOARD_FAB2(SCH_1):M_H_CLK_DN(1)   I172 @BASEBOARD_FAB2_LIB.BASEBOARD_FAB2(SCH_1):PAGE58
   M53 M_H_CLK_DN<0> @BASEBOARD_FAB2_LIB.BASEBOARD_FAB2(SCH_1):M_H_CLK_DN(0)   I172 @BASEBOARD_FAB2_LIB.BASEBOARD_FAB2(SCH_1):PAGE58
   T57 M_H_CLK_DP<3> @BASEBOARD_FAB2_LIB.BASEBOARD_FAB2(SCH_1):M_H_CLK_DP(3)   I172 @BASEBOARD_FAB2_LIB.BASEBOARD_FAB2(SCH_1):PAGE58
   M57 M_H_CLK_DP<2> @BASEBOARD_FAB2_LIB.BASEBOARD_FAB2(SCH_1):M_H_CLK_DP(2)   I172 @BASEBOARD_FAB2_LIB.BASEBOARD_FAB2(SCH_1):PAGE58
   T55 M_H_CLK_DP<1> @BASEBOARD_FAB2_LIB.BASEBOARD_FAB2(SCH_1):M_H_CLK_DP(1)   I172 @BASEBOARD_FAB2_LIB.BASEBOARD_FAB2(SCH_1):PAGE58
   N54 M_H_CLK_DP<0> @BASEBOARD_FAB2_LIB.BASEBOARD_FAB2(SCH_1):M_H_CLK_DP(0)   I172 @BASEBOARD_FAB2_LIB.BASEBOARD_FAB2(SCH_1):PAGE58
   R46 M_H_CS_N<7> @BASEBOARD_FAB2_LIB.BASEBOARD_FAB2(SCH_1):M_H_CS_N(7)   I172 @BASEBOARD_FAB2_LIB.BASEBOARD_FAB2(SCH_1):PAGE58
   M45 M_H_CS_N<6> @BASEBOARD_FAB2_LIB.BASEBOARD_FAB2(SCH_1):M_H_CS_N(6)   I172 @BASEBOARD_FAB2_LIB.BASEBOARD_FAB2(SCH_1):PAGE58
   T49 M_H_CS_N<5> @BASEBOARD_FAB2_LIB.BASEBOARD_FAB2(SCH_1):M_H_CS_N(5)   I172 @BASEBOARD_FAB2_LIB.BASEBOARD_FAB2(SCH_1):PAGE58
   J50 M_H_CS_N<4> @BASEBOARD_FAB2_LIB.BASEBOARD_FAB2(SCH_1):M_H_CS_N(4)   I172 @BASEBOARD_FAB2_LIB.BASEBOARD_FAB2(SCH_1):PAGE58
   V47 M_H_CS_N<3> @BASEBOARD_FAB2_LIB.BASEBOARD_FAB2(SCH_1):M_H_CS_N(3)   I172 @BASEBOARD_FAB2_LIB.BASEBOARD_FAB2(SCH_1):PAGE58
   N46 M_H_CS_N<2> @BASEBOARD_FAB2_LIB.BASEBOARD_FAB2(SCH_1):M_H_CS_N(2)   I172 @BASEBOARD_FAB2_LIB.BASEBOARD_FAB2(SCH_1):PAGE58
   R50 M_H_CS_N<1> @BASEBOARD_FAB2_LIB.BASEBOARD_FAB2(SCH_1):M_H_CS_N(1)   I172 @BASEBOARD_FAB2_LIB.BASEBOARD_FAB2(SCH_1):PAGE58
   K51 M_H_CS_N<0> @BASEBOARD_FAB2_LIB.BASEBOARD_FAB2(SCH_1):M_H_CS_N(0)   I172 @BASEBOARD_FAB2_LIB.BASEBOARD_FAB2(SCH_1):PAGE58
  AA26 M_H_DQ<63> @BASEBOARD_FAB2_LIB.BASEBOARD_FAB2(SCH_1):M_H_DQ(63)   I172 @BASEBOARD_FAB2_LIB.BASEBOARD_FAB2(SCH_1):PAGE58
   U26 M_H_DQ<62> @BASEBOARD_FAB2_LIB.BASEBOARD_FAB2(SCH_1):M_H_DQ(62)   I172 @BASEBOARD_FAB2_LIB.BASEBOARD_FAB2(SCH_1):PAGE58
   Y29 M_H_DQ<61> @BASEBOARD_FAB2_LIB.BASEBOARD_FAB2(SCH_1):M_H_DQ(61)   I172 @BASEBOARD_FAB2_LIB.BASEBOARD_FAB2(SCH_1):PAGE58
   V29 M_H_DQ<60> @BASEBOARD_FAB2_LIB.BASEBOARD_FAB2(SCH_1):M_H_DQ(60)   I172 @BASEBOARD_FAB2_LIB.BASEBOARD_FAB2(SCH_1):PAGE58
   Y25 M_H_DQ<59> @BASEBOARD_FAB2_LIB.BASEBOARD_FAB2(SCH_1):M_H_DQ(59)   I172 @BASEBOARD_FAB2_LIB.BASEBOARD_FAB2(SCH_1):PAGE58
   V25 M_H_DQ<58> @BASEBOARD_FAB2_LIB.BASEBOARD_FAB2(SCH_1):M_H_DQ(58)   I172 @BASEBOARD_FAB2_LIB.BASEBOARD_FAB2(SCH_1):PAGE58
  AA28 M_H_DQ<57> @BASEBOARD_FAB2_LIB.BASEBOARD_FAB2(SCH_1):M_H_DQ(57)   I172 @BASEBOARD_FAB2_LIB.BASEBOARD_FAB2(SCH_1):PAGE58
   U28 M_H_DQ<56> @BASEBOARD_FAB2_LIB.BASEBOARD_FAB2(SCH_1):M_H_DQ(56)   I172 @BASEBOARD_FAB2_LIB.BASEBOARD_FAB2(SCH_1):PAGE58
   F27 M_H_DQ<55> @BASEBOARD_FAB2_LIB.BASEBOARD_FAB2(SCH_1):M_H_DQ(55)   I172 @BASEBOARD_FAB2_LIB.BASEBOARD_FAB2(SCH_1):PAGE58
   B27 M_H_DQ<54> @BASEBOARD_FAB2_LIB.BASEBOARD_FAB2(SCH_1):M_H_DQ(54)   I172 @BASEBOARD_FAB2_LIB.BASEBOARD_FAB2(SCH_1):PAGE58
   F29 M_H_DQ<53> @BASEBOARD_FAB2_LIB.BASEBOARD_FAB2(SCH_1):M_H_DQ(53)   I172 @BASEBOARD_FAB2_LIB.BASEBOARD_FAB2(SCH_1):PAGE58
   E30 M_H_DQ<52> @BASEBOARD_FAB2_LIB.BASEBOARD_FAB2(SCH_1):M_H_DQ(52)   I172 @BASEBOARD_FAB2_LIB.BASEBOARD_FAB2(SCH_1):PAGE58
   E26 M_H_DQ<51> @BASEBOARD_FAB2_LIB.BASEBOARD_FAB2(SCH_1):M_H_DQ(51)   I172 @BASEBOARD_FAB2_LIB.BASEBOARD_FAB2(SCH_1):PAGE58
   C26 M_H_DQ<50> @BASEBOARD_FAB2_LIB.BASEBOARD_FAB2(SCH_1):M_H_DQ(50)   I172 @BASEBOARD_FAB2_LIB.BASEBOARD_FAB2(SCH_1):PAGE58
   B29 M_H_DQ<49> @BASEBOARD_FAB2_LIB.BASEBOARD_FAB2(SCH_1):M_H_DQ(49)   I172 @BASEBOARD_FAB2_LIB.BASEBOARD_FAB2(SCH_1):PAGE58
   C30 M_H_DQ<48> @BASEBOARD_FAB2_LIB.BASEBOARD_FAB2(SCH_1):M_H_DQ(48)   I172 @BASEBOARD_FAB2_LIB.BASEBOARD_FAB2(SCH_1):PAGE58
   F33 M_H_DQ<47> @BASEBOARD_FAB2_LIB.BASEBOARD_FAB2(SCH_1):M_H_DQ(47)   I172 @BASEBOARD_FAB2_LIB.BASEBOARD_FAB2(SCH_1):PAGE58
   B33 M_H_DQ<46> @BASEBOARD_FAB2_LIB.BASEBOARD_FAB2(SCH_1):M_H_DQ(46)   I172 @BASEBOARD_FAB2_LIB.BASEBOARD_FAB2(SCH_1):PAGE58
   F35 M_H_DQ<45> @BASEBOARD_FAB2_LIB.BASEBOARD_FAB2(SCH_1):M_H_DQ(45)   I172 @BASEBOARD_FAB2_LIB.BASEBOARD_FAB2(SCH_1):PAGE58
   E36 M_H_DQ<44> @BASEBOARD_FAB2_LIB.BASEBOARD_FAB2(SCH_1):M_H_DQ(44)   I172 @BASEBOARD_FAB2_LIB.BASEBOARD_FAB2(SCH_1):PAGE58
   E32 M_H_DQ<43> @BASEBOARD_FAB2_LIB.BASEBOARD_FAB2(SCH_1):M_H_DQ(43)   I172 @BASEBOARD_FAB2_LIB.BASEBOARD_FAB2(SCH_1):PAGE58
   C32 M_H_DQ<42> @BASEBOARD_FAB2_LIB.BASEBOARD_FAB2(SCH_1):M_H_DQ(42)   I172 @BASEBOARD_FAB2_LIB.BASEBOARD_FAB2(SCH_1):PAGE58
   B35 M_H_DQ<41> @BASEBOARD_FAB2_LIB.BASEBOARD_FAB2(SCH_1):M_H_DQ(41)   I172 @BASEBOARD_FAB2_LIB.BASEBOARD_FAB2(SCH_1):PAGE58
   C36 M_H_DQ<40> @BASEBOARD_FAB2_LIB.BASEBOARD_FAB2(SCH_1):M_H_DQ(40)   I172 @BASEBOARD_FAB2_LIB.BASEBOARD_FAB2(SCH_1):PAGE58
   P41 M_H_DQ<39> @BASEBOARD_FAB2_LIB.BASEBOARD_FAB2(SCH_1):M_H_DQ(39)   I172 @BASEBOARD_FAB2_LIB.BASEBOARD_FAB2(SCH_1):PAGE58
   K41 M_H_DQ<38> @BASEBOARD_FAB2_LIB.BASEBOARD_FAB2(SCH_1):M_H_DQ(38)   I172 @BASEBOARD_FAB2_LIB.BASEBOARD_FAB2(SCH_1):PAGE58
   T43 M_H_DQ<37> @BASEBOARD_FAB2_LIB.BASEBOARD_FAB2(SCH_1):M_H_DQ(37)   I172 @BASEBOARD_FAB2_LIB.BASEBOARD_FAB2(SCH_1):PAGE58
   P43 M_H_DQ<36> @BASEBOARD_FAB2_LIB.BASEBOARD_FAB2(SCH_1):M_H_DQ(36)   I172 @BASEBOARD_FAB2_LIB.BASEBOARD_FAB2(SCH_1):PAGE58
   N40 M_H_DQ<35> @BASEBOARD_FAB2_LIB.BASEBOARD_FAB2(SCH_1):M_H_DQ(35)   I172 @BASEBOARD_FAB2_LIB.BASEBOARD_FAB2(SCH_1):PAGE58
   L40 M_H_DQ<34> @BASEBOARD_FAB2_LIB.BASEBOARD_FAB2(SCH_1):M_H_DQ(34)   I172 @BASEBOARD_FAB2_LIB.BASEBOARD_FAB2(SCH_1):PAGE58
   H43 M_H_DQ<33> @BASEBOARD_FAB2_LIB.BASEBOARD_FAB2(SCH_1):M_H_DQ(33)   I172 @BASEBOARD_FAB2_LIB.BASEBOARD_FAB2(SCH_1):PAGE58
   K43 M_H_DQ<32> @BASEBOARD_FAB2_LIB.BASEBOARD_FAB2(SCH_1):M_H_DQ(32)   I172 @BASEBOARD_FAB2_LIB.BASEBOARD_FAB2(SCH_1):PAGE58
   G72 M_H_DQ<31> @BASEBOARD_FAB2_LIB.BASEBOARD_FAB2(SCH_1):M_H_DQ(31)   I172 @BASEBOARD_FAB2_LIB.BASEBOARD_FAB2(SCH_1):PAGE58
   C72 M_H_DQ<30> @BASEBOARD_FAB2_LIB.BASEBOARD_FAB2(SCH_1):M_H_DQ(30)   I172 @BASEBOARD_FAB2_LIB.BASEBOARD_FAB2(SCH_1):PAGE58
   G74 M_H_DQ<29> @BASEBOARD_FAB2_LIB.BASEBOARD_FAB2(SCH_1):M_H_DQ(29)   I172 @BASEBOARD_FAB2_LIB.BASEBOARD_FAB2(SCH_1):PAGE58
   F75 M_H_DQ<28> @BASEBOARD_FAB2_LIB.BASEBOARD_FAB2(SCH_1):M_H_DQ(28)   I172 @BASEBOARD_FAB2_LIB.BASEBOARD_FAB2(SCH_1):PAGE58
   F71 M_H_DQ<27> @BASEBOARD_FAB2_LIB.BASEBOARD_FAB2(SCH_1):M_H_DQ(27)   I172 @BASEBOARD_FAB2_LIB.BASEBOARD_FAB2(SCH_1):PAGE58
   D71 M_H_DQ<26> @BASEBOARD_FAB2_LIB.BASEBOARD_FAB2(SCH_1):M_H_DQ(26)   I172 @BASEBOARD_FAB2_LIB.BASEBOARD_FAB2(SCH_1):PAGE58
   C74 M_H_DQ<25> @BASEBOARD_FAB2_LIB.BASEBOARD_FAB2(SCH_1):M_H_DQ(25)   I172 @BASEBOARD_FAB2_LIB.BASEBOARD_FAB2(SCH_1):PAGE58
   D75 M_H_DQ<24> @BASEBOARD_FAB2_LIB.BASEBOARD_FAB2(SCH_1):M_H_DQ(24)   I172 @BASEBOARD_FAB2_LIB.BASEBOARD_FAB2(SCH_1):PAGE58
   J78 M_H_DQ<23> @BASEBOARD_FAB2_LIB.BASEBOARD_FAB2(SCH_1):M_H_DQ(23)   I172 @BASEBOARD_FAB2_LIB.BASEBOARD_FAB2(SCH_1):PAGE58
   E78 M_H_DQ<22> @BASEBOARD_FAB2_LIB.BASEBOARD_FAB2(SCH_1):M_H_DQ(22)   I172 @BASEBOARD_FAB2_LIB.BASEBOARD_FAB2(SCH_1):PAGE58
   H81 M_H_DQ<21> @BASEBOARD_FAB2_LIB.BASEBOARD_FAB2(SCH_1):M_H_DQ(21)   I172 @BASEBOARD_FAB2_LIB.BASEBOARD_FAB2(SCH_1):PAGE58
   F81 M_H_DQ<20> @BASEBOARD_FAB2_LIB.BASEBOARD_FAB2(SCH_1):M_H_DQ(20)   I172 @BASEBOARD_FAB2_LIB.BASEBOARD_FAB2(SCH_1):PAGE58
   H77 M_H_DQ<19> @BASEBOARD_FAB2_LIB.BASEBOARD_FAB2(SCH_1):M_H_DQ(19)   I172 @BASEBOARD_FAB2_LIB.BASEBOARD_FAB2(SCH_1):PAGE58
   F77 M_H_DQ<18> @BASEBOARD_FAB2_LIB.BASEBOARD_FAB2(SCH_1):M_H_DQ(18)   I172 @BASEBOARD_FAB2_LIB.BASEBOARD_FAB2(SCH_1):PAGE58
   J80 M_H_DQ<17> @BASEBOARD_FAB2_LIB.BASEBOARD_FAB2(SCH_1):M_H_DQ(17)   I172 @BASEBOARD_FAB2_LIB.BASEBOARD_FAB2(SCH_1):PAGE58
   E80 M_H_DQ<16> @BASEBOARD_FAB2_LIB.BASEBOARD_FAB2(SCH_1):M_H_DQ(16)   I172 @BASEBOARD_FAB2_LIB.BASEBOARD_FAB2(SCH_1):PAGE58
  AC80 M_H_DQ<15> @BASEBOARD_FAB2_LIB.BASEBOARD_FAB2(SCH_1):M_H_DQ(15)   I172 @BASEBOARD_FAB2_LIB.BASEBOARD_FAB2(SCH_1):PAGE58
  AE82 M_H_DQ<14> @BASEBOARD_FAB2_LIB.BASEBOARD_FAB2(SCH_1):M_H_DQ(14)   I172 @BASEBOARD_FAB2_LIB.BASEBOARD_FAB2(SCH_1):PAGE58
  AH79 M_H_DQ<13> @BASEBOARD_FAB2_LIB.BASEBOARD_FAB2(SCH_1):M_H_DQ(13)   I172 @BASEBOARD_FAB2_LIB.BASEBOARD_FAB2(SCH_1):PAGE58
  AJ80 M_H_DQ<12> @BASEBOARD_FAB2_LIB.BASEBOARD_FAB2(SCH_1):M_H_DQ(12)   I172 @BASEBOARD_FAB2_LIB.BASEBOARD_FAB2(SCH_1):PAGE58
  AB81 M_H_DQ<11> @BASEBOARD_FAB2_LIB.BASEBOARD_FAB2(SCH_1):M_H_DQ(11)   I172 @BASEBOARD_FAB2_LIB.BASEBOARD_FAB2(SCH_1):PAGE58
  AC82 M_H_DQ<10> @BASEBOARD_FAB2_LIB.BASEBOARD_FAB2(SCH_1):M_H_DQ(10)   I172 @BASEBOARD_FAB2_LIB.BASEBOARD_FAB2(SCH_1):PAGE58
  AF79 M_H_DQ<9> @BASEBOARD_FAB2_LIB.BASEBOARD_FAB2(SCH_1):M_H_DQ(9)   I172 @BASEBOARD_FAB2_LIB.BASEBOARD_FAB2(SCH_1):PAGE58
  AH81 M_H_DQ<8> @BASEBOARD_FAB2_LIB.BASEBOARD_FAB2(SCH_1):M_H_DQ(8)   I172 @BASEBOARD_FAB2_LIB.BASEBOARD_FAB2(SCH_1):PAGE58
  AN80 M_H_DQ<7> @BASEBOARD_FAB2_LIB.BASEBOARD_FAB2(SCH_1):M_H_DQ(7)   I172 @BASEBOARD_FAB2_LIB.BASEBOARD_FAB2(SCH_1):PAGE58
  AR82 M_H_DQ<6> @BASEBOARD_FAB2_LIB.BASEBOARD_FAB2(SCH_1):M_H_DQ(6)   I172 @BASEBOARD_FAB2_LIB.BASEBOARD_FAB2(SCH_1):PAGE58
  AV79 M_H_DQ<5> @BASEBOARD_FAB2_LIB.BASEBOARD_FAB2(SCH_1):M_H_DQ(5)   I172 @BASEBOARD_FAB2_LIB.BASEBOARD_FAB2(SCH_1):PAGE58
  AW80 M_H_DQ<4> @BASEBOARD_FAB2_LIB.BASEBOARD_FAB2(SCH_1):M_H_DQ(4)   I172 @BASEBOARD_FAB2_LIB.BASEBOARD_FAB2(SCH_1):PAGE58
  AM81 M_H_DQ<3> @BASEBOARD_FAB2_LIB.BASEBOARD_FAB2(SCH_1):M_H_DQ(3)   I172 @BASEBOARD_FAB2_LIB.BASEBOARD_FAB2(SCH_1):PAGE58
  AN82 M_H_DQ<2> @BASEBOARD_FAB2_LIB.BASEBOARD_FAB2(SCH_1):M_H_DQ(2)   I172 @BASEBOARD_FAB2_LIB.BASEBOARD_FAB2(SCH_1):PAGE58
  AT79 M_H_DQ<1> @BASEBOARD_FAB2_LIB.BASEBOARD_FAB2(SCH_1):M_H_DQ(1)   I172 @BASEBOARD_FAB2_LIB.BASEBOARD_FAB2(SCH_1):PAGE58
  AV81 M_H_DQ<0> @BASEBOARD_FAB2_LIB.BASEBOARD_FAB2(SCH_1):M_H_DQ(0)   I172 @BASEBOARD_FAB2_LIB.BASEBOARD_FAB2(SCH_1):PAGE58
   G68 M_H_DQS_DN<17> @BASEBOARD_FAB2_LIB.BASEBOARD_FAB2(SCH_1):M_H_DQS_DN(17)   I172 @BASEBOARD_FAB2_LIB.BASEBOARD_FAB2(SCH_1):PAGE58
   T27 M_H_DQS_DN<16> @BASEBOARD_FAB2_LIB.BASEBOARD_FAB2(SCH_1):M_H_DQS_DN(16)   I172 @BASEBOARD_FAB2_LIB.BASEBOARD_FAB2(SCH_1):PAGE58
   A28 M_H_DQS_DN<15> @BASEBOARD_FAB2_LIB.BASEBOARD_FAB2(SCH_1):M_H_DQS_DN(15)   I172 @BASEBOARD_FAB2_LIB.BASEBOARD_FAB2(SCH_1):PAGE58
   A34 M_H_DQS_DN<14> @BASEBOARD_FAB2_LIB.BASEBOARD_FAB2(SCH_1):M_H_DQS_DN(14)   I172 @BASEBOARD_FAB2_LIB.BASEBOARD_FAB2(SCH_1):PAGE58
   J42 M_H_DQS_DN<13> @BASEBOARD_FAB2_LIB.BASEBOARD_FAB2(SCH_1):M_H_DQS_DN(13)   I172 @BASEBOARD_FAB2_LIB.BASEBOARD_FAB2(SCH_1):PAGE58
   B73 M_H_DQS_DN<12> @BASEBOARD_FAB2_LIB.BASEBOARD_FAB2(SCH_1):M_H_DQS_DN(12)   I172 @BASEBOARD_FAB2_LIB.BASEBOARD_FAB2(SCH_1):PAGE58
   D79 M_H_DQS_DN<11> @BASEBOARD_FAB2_LIB.BASEBOARD_FAB2(SCH_1):M_H_DQS_DN(11)   I172 @BASEBOARD_FAB2_LIB.BASEBOARD_FAB2(SCH_1):PAGE58
  AG82 M_H_DQS_DN<10> @BASEBOARD_FAB2_LIB.BASEBOARD_FAB2(SCH_1):M_H_DQS_DN(10)   I172 @BASEBOARD_FAB2_LIB.BASEBOARD_FAB2(SCH_1):PAGE58
  AU82 M_H_DQS_DN<9> @BASEBOARD_FAB2_LIB.BASEBOARD_FAB2(SCH_1):M_H_DQS_DN(9)   I172 @BASEBOARD_FAB2_LIB.BASEBOARD_FAB2(SCH_1):PAGE58
   N68 M_H_DQS_DN<8> @BASEBOARD_FAB2_LIB.BASEBOARD_FAB2(SCH_1):M_H_DQS_DN(8)   I172 @BASEBOARD_FAB2_LIB.BASEBOARD_FAB2(SCH_1):PAGE58
  AB27 M_H_DQS_DN<7> @BASEBOARD_FAB2_LIB.BASEBOARD_FAB2(SCH_1):M_H_DQS_DN(7)   I172 @BASEBOARD_FAB2_LIB.BASEBOARD_FAB2(SCH_1):PAGE58
   G28 M_H_DQS_DN<6> @BASEBOARD_FAB2_LIB.BASEBOARD_FAB2(SCH_1):M_H_DQS_DN(6)   I172 @BASEBOARD_FAB2_LIB.BASEBOARD_FAB2(SCH_1):PAGE58
   G34 M_H_DQS_DN<5> @BASEBOARD_FAB2_LIB.BASEBOARD_FAB2(SCH_1):M_H_DQS_DN(5)   I172 @BASEBOARD_FAB2_LIB.BASEBOARD_FAB2(SCH_1):PAGE58
   N42 M_H_DQS_DN<4> @BASEBOARD_FAB2_LIB.BASEBOARD_FAB2(SCH_1):M_H_DQS_DN(4)   I172 @BASEBOARD_FAB2_LIB.BASEBOARD_FAB2(SCH_1):PAGE58
   H73 M_H_DQS_DN<3> @BASEBOARD_FAB2_LIB.BASEBOARD_FAB2(SCH_1):M_H_DQS_DN(3)   I172 @BASEBOARD_FAB2_LIB.BASEBOARD_FAB2(SCH_1):PAGE58
   K79 M_H_DQS_DN<2> @BASEBOARD_FAB2_LIB.BASEBOARD_FAB2(SCH_1):M_H_DQS_DN(2)   I172 @BASEBOARD_FAB2_LIB.BASEBOARD_FAB2(SCH_1):PAGE58
  AD79 M_H_DQS_DN<1> @BASEBOARD_FAB2_LIB.BASEBOARD_FAB2(SCH_1):M_H_DQS_DN(1)   I172 @BASEBOARD_FAB2_LIB.BASEBOARD_FAB2(SCH_1):PAGE58
  AP79 M_H_DQS_DN<0> @BASEBOARD_FAB2_LIB.BASEBOARD_FAB2(SCH_1):M_H_DQS_DN(0)   I172 @BASEBOARD_FAB2_LIB.BASEBOARD_FAB2(SCH_1):PAGE58
   J68 M_H_DQS_DP<17> @BASEBOARD_FAB2_LIB.BASEBOARD_FAB2(SCH_1):M_H_DQS_DP(17)   I172 @BASEBOARD_FAB2_LIB.BASEBOARD_FAB2(SCH_1):PAGE58
   V27 M_H_DQS_DP<16> @BASEBOARD_FAB2_LIB.BASEBOARD_FAB2(SCH_1):M_H_DQS_DP(16)   I172 @BASEBOARD_FAB2_LIB.BASEBOARD_FAB2(SCH_1):PAGE58
   C28 M_H_DQS_DP<15> @BASEBOARD_FAB2_LIB.BASEBOARD_FAB2(SCH_1):M_H_DQS_DP(15)   I172 @BASEBOARD_FAB2_LIB.BASEBOARD_FAB2(SCH_1):PAGE58
   C34 M_H_DQS_DP<14> @BASEBOARD_FAB2_LIB.BASEBOARD_FAB2(SCH_1):M_H_DQS_DP(14)   I172 @BASEBOARD_FAB2_LIB.BASEBOARD_FAB2(SCH_1):PAGE58
   L42 M_H_DQS_DP<13> @BASEBOARD_FAB2_LIB.BASEBOARD_FAB2(SCH_1):M_H_DQS_DP(13)   I172 @BASEBOARD_FAB2_LIB.BASEBOARD_FAB2(SCH_1):PAGE58
   D73 M_H_DQS_DP<12> @BASEBOARD_FAB2_LIB.BASEBOARD_FAB2(SCH_1):M_H_DQS_DP(12)   I172 @BASEBOARD_FAB2_LIB.BASEBOARD_FAB2(SCH_1):PAGE58
   F79 M_H_DQS_DP<11> @BASEBOARD_FAB2_LIB.BASEBOARD_FAB2(SCH_1):M_H_DQS_DP(11)   I172 @BASEBOARD_FAB2_LIB.BASEBOARD_FAB2(SCH_1):PAGE58
  AF81 M_H_DQS_DP<10> @BASEBOARD_FAB2_LIB.BASEBOARD_FAB2(SCH_1):M_H_DQS_DP(10)   I172 @BASEBOARD_FAB2_LIB.BASEBOARD_FAB2(SCH_1):PAGE58
  AT81 M_H_DQS_DP<9> @BASEBOARD_FAB2_LIB.BASEBOARD_FAB2(SCH_1):M_H_DQS_DP(9)   I172 @BASEBOARD_FAB2_LIB.BASEBOARD_FAB2(SCH_1):PAGE58
   L68 M_H_DQS_DP<8> @BASEBOARD_FAB2_LIB.BASEBOARD_FAB2(SCH_1):M_H_DQS_DP(8)   I172 @BASEBOARD_FAB2_LIB.BASEBOARD_FAB2(SCH_1):PAGE58
   Y27 M_H_DQS_DP<7> @BASEBOARD_FAB2_LIB.BASEBOARD_FAB2(SCH_1):M_H_DQS_DP(7)   I172 @BASEBOARD_FAB2_LIB.BASEBOARD_FAB2(SCH_1):PAGE58
   E28 M_H_DQS_DP<6> @BASEBOARD_FAB2_LIB.BASEBOARD_FAB2(SCH_1):M_H_DQS_DP(6)   I172 @BASEBOARD_FAB2_LIB.BASEBOARD_FAB2(SCH_1):PAGE58
   E34 M_H_DQS_DP<5> @BASEBOARD_FAB2_LIB.BASEBOARD_FAB2(SCH_1):M_H_DQS_DP(5)   I172 @BASEBOARD_FAB2_LIB.BASEBOARD_FAB2(SCH_1):PAGE58
   R42 M_H_DQS_DP<4> @BASEBOARD_FAB2_LIB.BASEBOARD_FAB2(SCH_1):M_H_DQS_DP(4)   I172 @BASEBOARD_FAB2_LIB.BASEBOARD_FAB2(SCH_1):PAGE58
   F73 M_H_DQS_DP<3> @BASEBOARD_FAB2_LIB.BASEBOARD_FAB2(SCH_1):M_H_DQS_DP(3)   I172 @BASEBOARD_FAB2_LIB.BASEBOARD_FAB2(SCH_1):PAGE58
   H79 M_H_DQS_DP<2> @BASEBOARD_FAB2_LIB.BASEBOARD_FAB2(SCH_1):M_H_DQS_DP(2)   I172 @BASEBOARD_FAB2_LIB.BASEBOARD_FAB2(SCH_1):PAGE58
  AE80 M_H_DQS_DP<1> @BASEBOARD_FAB2_LIB.BASEBOARD_FAB2(SCH_1):M_H_DQS_DP(1)   I172 @BASEBOARD_FAB2_LIB.BASEBOARD_FAB2(SCH_1):PAGE58
  AR80 M_H_DQS_DP<0> @BASEBOARD_FAB2_LIB.BASEBOARD_FAB2(SCH_1):M_H_DQS_DP(0)   I172 @BASEBOARD_FAB2_LIB.BASEBOARD_FAB2(SCH_1):PAGE58
   M67 M_H_ECC<7> @BASEBOARD_FAB2_LIB.BASEBOARD_FAB2(SCH_1):M_H_ECC(7)   I172 @BASEBOARD_FAB2_LIB.BASEBOARD_FAB2(SCH_1):PAGE58
   H67 M_H_ECC<6> @BASEBOARD_FAB2_LIB.BASEBOARD_FAB2(SCH_1):M_H_ECC(6)   I172 @BASEBOARD_FAB2_LIB.BASEBOARD_FAB2(SCH_1):PAGE58
   M69 M_H_ECC<5> @BASEBOARD_FAB2_LIB.BASEBOARD_FAB2(SCH_1):M_H_ECC(5)   I172 @BASEBOARD_FAB2_LIB.BASEBOARD_FAB2(SCH_1):PAGE58
   L70 M_H_ECC<4> @BASEBOARD_FAB2_LIB.BASEBOARD_FAB2(SCH_1):M_H_ECC(4)   I172 @BASEBOARD_FAB2_LIB.BASEBOARD_FAB2(SCH_1):PAGE58
   L66 M_H_ECC<3> @BASEBOARD_FAB2_LIB.BASEBOARD_FAB2(SCH_1):M_H_ECC(3)   I172 @BASEBOARD_FAB2_LIB.BASEBOARD_FAB2(SCH_1):PAGE58
   J66 M_H_ECC<2> @BASEBOARD_FAB2_LIB.BASEBOARD_FAB2(SCH_1):M_H_ECC(2)   I172 @BASEBOARD_FAB2_LIB.BASEBOARD_FAB2(SCH_1):PAGE58
   H69 M_H_ECC<1> @BASEBOARD_FAB2_LIB.BASEBOARD_FAB2(SCH_1):M_H_ECC(1)   I172 @BASEBOARD_FAB2_LIB.BASEBOARD_FAB2(SCH_1):PAGE58
   J70 M_H_ECC<0> @BASEBOARD_FAB2_LIB.BASEBOARD_FAB2(SCH_1):M_H_ECC(0)   I172 @BASEBOARD_FAB2_LIB.BASEBOARD_FAB2(SCH_1):PAGE58
   N48 M_H_MA<17> @BASEBOARD_FAB2_LIB.BASEBOARD_FAB2(SCH_1):M_H_MA(17)   I172 @BASEBOARD_FAB2_LIB.BASEBOARD_FAB2(SCH_1):PAGE58
   R52 M_H_MA<16> @BASEBOARD_FAB2_LIB.BASEBOARD_FAB2(SCH_1):M_H_MA(16)   I172 @BASEBOARD_FAB2_LIB.BASEBOARD_FAB2(SCH_1):PAGE58
   N52 M_H_MA<15> @BASEBOARD_FAB2_LIB.BASEBOARD_FAB2(SCH_1):M_H_MA(15)   I172 @BASEBOARD_FAB2_LIB.BASEBOARD_FAB2(SCH_1):PAGE58
   T51 M_H_MA<14> @BASEBOARD_FAB2_LIB.BASEBOARD_FAB2(SCH_1):M_H_MA(14)   I172 @BASEBOARD_FAB2_LIB.BASEBOARD_FAB2(SCH_1):PAGE58
   M51 M_H_MA<13> @BASEBOARD_FAB2_LIB.BASEBOARD_FAB2(SCH_1):M_H_MA(13)   I172 @BASEBOARD_FAB2_LIB.BASEBOARD_FAB2(SCH_1):PAGE58
   T61 M_H_MA<12> @BASEBOARD_FAB2_LIB.BASEBOARD_FAB2(SCH_1):M_H_MA(12)   I172 @BASEBOARD_FAB2_LIB.BASEBOARD_FAB2(SCH_1):PAGE58
   R60 M_H_MA<11> @BASEBOARD_FAB2_LIB.BASEBOARD_FAB2(SCH_1):M_H_MA(11)   I172 @BASEBOARD_FAB2_LIB.BASEBOARD_FAB2(SCH_1):PAGE58
   M55 M_H_MA<10> @BASEBOARD_FAB2_LIB.BASEBOARD_FAB2(SCH_1):M_H_MA(10)   I172 @BASEBOARD_FAB2_LIB.BASEBOARD_FAB2(SCH_1):PAGE58
   K59 M_H_MA<9> @BASEBOARD_FAB2_LIB.BASEBOARD_FAB2(SCH_1):M_H_MA(9)   I172 @BASEBOARD_FAB2_LIB.BASEBOARD_FAB2(SCH_1):PAGE58
   W60 M_H_MA<8> @BASEBOARD_FAB2_LIB.BASEBOARD_FAB2(SCH_1):M_H_MA(8)   I172 @BASEBOARD_FAB2_LIB.BASEBOARD_FAB2(SCH_1):PAGE58
   V61 M_H_MA<7> @BASEBOARD_FAB2_LIB.BASEBOARD_FAB2(SCH_1):M_H_MA(7)   I172 @BASEBOARD_FAB2_LIB.BASEBOARD_FAB2(SCH_1):PAGE58
   T59 M_H_MA<6> @BASEBOARD_FAB2_LIB.BASEBOARD_FAB2(SCH_1):M_H_MA(6)   I172 @BASEBOARD_FAB2_LIB.BASEBOARD_FAB2(SCH_1):PAGE58
   R58 M_H_MA<5> @BASEBOARD_FAB2_LIB.BASEBOARD_FAB2(SCH_1):M_H_MA(5)   I172 @BASEBOARD_FAB2_LIB.BASEBOARD_FAB2(SCH_1):PAGE58
   M59 M_H_MA<4> @BASEBOARD_FAB2_LIB.BASEBOARD_FAB2(SCH_1):M_H_MA(4)   I172 @BASEBOARD_FAB2_LIB.BASEBOARD_FAB2(SCH_1):PAGE58
   N58 M_H_MA<3> @BASEBOARD_FAB2_LIB.BASEBOARD_FAB2(SCH_1):M_H_MA(3)   I172 @BASEBOARD_FAB2_LIB.BASEBOARD_FAB2(SCH_1):PAGE58
   K57 M_H_MA<2> @BASEBOARD_FAB2_LIB.BASEBOARD_FAB2(SCH_1):M_H_MA(2)   I172 @BASEBOARD_FAB2_LIB.BASEBOARD_FAB2(SCH_1):PAGE58
   J58 M_H_MA<1> @BASEBOARD_FAB2_LIB.BASEBOARD_FAB2(SCH_1):M_H_MA(1)   I172 @BASEBOARD_FAB2_LIB.BASEBOARD_FAB2(SCH_1):PAGE58
   J52 M_H_MA<0> @BASEBOARD_FAB2_LIB.BASEBOARD_FAB2(SCH_1):M_H_MA(0)   I172 @BASEBOARD_FAB2_LIB.BASEBOARD_FAB2(SCH_1):PAGE58
   T47 M_H_ODT<3> @BASEBOARD_FAB2_LIB.BASEBOARD_FAB2(SCH_1):M_H_ODT(3)   I172 @BASEBOARD_FAB2_LIB.BASEBOARD_FAB2(SCH_1):PAGE58
   M49 M_H_ODT<2> @BASEBOARD_FAB2_LIB.BASEBOARD_FAB2(SCH_1):M_H_ODT(2)   I172 @BASEBOARD_FAB2_LIB.BASEBOARD_FAB2(SCH_1):PAGE58
   R48 M_H_ODT<1> @BASEBOARD_FAB2_LIB.BASEBOARD_FAB2(SCH_1):M_H_ODT(1)   I172 @BASEBOARD_FAB2_LIB.BASEBOARD_FAB2(SCH_1):PAGE58
   N50 M_H_ODT<0> @BASEBOARD_FAB2_LIB.BASEBOARD_FAB2(SCH_1):M_H_ODT(0)   I172 @BASEBOARD_FAB2_LIB.BASEBOARD_FAB2(SCH_1):PAGE58
   K53 M_H_PAR @BASEBOARD_FAB2_LIB.BASEBOARD_FAB2(SCH_1):M_H_PAR   I172 @BASEBOARD_FAB2_LIB.BASEBOARD_FAB2(SCH_1):PAGE58
  AB61 M_J_ACT_N @BASEBOARD_FAB2_LIB.BASEBOARD_FAB2(SCH_1):M_J_ACT_N   I172 @BASEBOARD_FAB2_LIB.BASEBOARD_FAB2(SCH_1):PAGE59
  AD61 M_J_ALERT_N @BASEBOARD_FAB2_LIB.BASEBOARD_FAB2(SCH_1):M_J_ALERT_N   I172 @BASEBOARD_FAB2_LIB.BASEBOARD_FAB2(SCH_1):PAGE59
  AE56 M_J_BA<1> @BASEBOARD_FAB2_LIB.BASEBOARD_FAB2(SCH_1):M_J_BA(1)   I172 @BASEBOARD_FAB2_LIB.BASEBOARD_FAB2(SCH_1):PAGE59
   W52 M_J_BA<0> @BASEBOARD_FAB2_LIB.BASEBOARD_FAB2(SCH_1):M_J_BA(0)   I172 @BASEBOARD_FAB2_LIB.BASEBOARD_FAB2(SCH_1):PAGE59
  AE62 M_J_BG<1> @BASEBOARD_FAB2_LIB.BASEBOARD_FAB2(SCH_1):M_J_BG(1)   I172 @BASEBOARD_FAB2_LIB.BASEBOARD_FAB2(SCH_1):PAGE59
  AA60 M_J_BG<0> @BASEBOARD_FAB2_LIB.BASEBOARD_FAB2(SCH_1):M_J_BG(0)   I172 @BASEBOARD_FAB2_LIB.BASEBOARD_FAB2(SCH_1):PAGE59
  AB45 M_J_C<2> @BASEBOARD_FAB2_LIB.BASEBOARD_FAB2(SCH_1):M_J_C(2)   I172 @BASEBOARD_FAB2_LIB.BASEBOARD_FAB2(SCH_1):PAGE59
  AB63 M_J_CKE<3> @BASEBOARD_FAB2_LIB.BASEBOARD_FAB2(SCH_1):M_J_CKE(3)   I172 @BASEBOARD_FAB2_LIB.BASEBOARD_FAB2(SCH_1):PAGE59
   V63 M_J_CKE<2> @BASEBOARD_FAB2_LIB.BASEBOARD_FAB2(SCH_1):M_J_CKE(2)   I172 @BASEBOARD_FAB2_LIB.BASEBOARD_FAB2(SCH_1):PAGE59
  AD63 M_J_CKE<1> @BASEBOARD_FAB2_LIB.BASEBOARD_FAB2(SCH_1):M_J_CKE(1)   I172 @BASEBOARD_FAB2_LIB.BASEBOARD_FAB2(SCH_1):PAGE59
  AA62 M_J_CKE<0> @BASEBOARD_FAB2_LIB.BASEBOARD_FAB2(SCH_1):M_J_CKE(0)   I172 @BASEBOARD_FAB2_LIB.BASEBOARD_FAB2(SCH_1):PAGE59
   W56 M_J_CLK_DN<3> @BASEBOARD_FAB2_LIB.BASEBOARD_FAB2(SCH_1):M_J_CLK_DN(3)   I172 @BASEBOARD_FAB2_LIB.BASEBOARD_FAB2(SCH_1):PAGE59
  AA56 M_J_CLK_DN<2> @BASEBOARD_FAB2_LIB.BASEBOARD_FAB2(SCH_1):M_J_CLK_DN(2)   I172 @BASEBOARD_FAB2_LIB.BASEBOARD_FAB2(SCH_1):PAGE59
   W54 M_J_CLK_DN<1> @BASEBOARD_FAB2_LIB.BASEBOARD_FAB2(SCH_1):M_J_CLK_DN(1)   I172 @BASEBOARD_FAB2_LIB.BASEBOARD_FAB2(SCH_1):PAGE59
  AA54 M_J_CLK_DN<0> @BASEBOARD_FAB2_LIB.BASEBOARD_FAB2(SCH_1):M_J_CLK_DN(0)   I172 @BASEBOARD_FAB2_LIB.BASEBOARD_FAB2(SCH_1):PAGE59
   V57 M_J_CLK_DP<3> @BASEBOARD_FAB2_LIB.BASEBOARD_FAB2(SCH_1):M_J_CLK_DP(3)   I172 @BASEBOARD_FAB2_LIB.BASEBOARD_FAB2(SCH_1):PAGE59
  AB57 M_J_CLK_DP<2> @BASEBOARD_FAB2_LIB.BASEBOARD_FAB2(SCH_1):M_J_CLK_DP(2)   I172 @BASEBOARD_FAB2_LIB.BASEBOARD_FAB2(SCH_1):PAGE59
   V55 M_J_CLK_DP<1> @BASEBOARD_FAB2_LIB.BASEBOARD_FAB2(SCH_1):M_J_CLK_DP(1)   I172 @BASEBOARD_FAB2_LIB.BASEBOARD_FAB2(SCH_1):PAGE59
  AB55 M_J_CLK_DP<0> @BASEBOARD_FAB2_LIB.BASEBOARD_FAB2(SCH_1):M_J_CLK_DP(0)   I172 @BASEBOARD_FAB2_LIB.BASEBOARD_FAB2(SCH_1):PAGE59
   V45 M_J_CS_N<7> @BASEBOARD_FAB2_LIB.BASEBOARD_FAB2(SCH_1):M_J_CS_N(7)   I172 @BASEBOARD_FAB2_LIB.BASEBOARD_FAB2(SCH_1):PAGE59
   T45 M_J_CS_N<6> @BASEBOARD_FAB2_LIB.BASEBOARD_FAB2(SCH_1):M_J_CS_N(6)   I172 @BASEBOARD_FAB2_LIB.BASEBOARD_FAB2(SCH_1):PAGE59
   W48 M_J_CS_N<5> @BASEBOARD_FAB2_LIB.BASEBOARD_FAB2(SCH_1):M_J_CS_N(5)   I172 @BASEBOARD_FAB2_LIB.BASEBOARD_FAB2(SCH_1):PAGE59
  AB51 M_J_CS_N<4> @BASEBOARD_FAB2_LIB.BASEBOARD_FAB2(SCH_1):M_J_CS_N(4)   I172 @BASEBOARD_FAB2_LIB.BASEBOARD_FAB2(SCH_1):PAGE59
  AA46 M_J_CS_N<3> @BASEBOARD_FAB2_LIB.BASEBOARD_FAB2(SCH_1):M_J_CS_N(3)   I172 @BASEBOARD_FAB2_LIB.BASEBOARD_FAB2(SCH_1):PAGE59
   W46 M_J_CS_N<2> @BASEBOARD_FAB2_LIB.BASEBOARD_FAB2(SCH_1):M_J_CS_N(2)   I172 @BASEBOARD_FAB2_LIB.BASEBOARD_FAB2(SCH_1):PAGE59
  AB49 M_J_CS_N<1> @BASEBOARD_FAB2_LIB.BASEBOARD_FAB2(SCH_1):M_J_CS_N(1)   I172 @BASEBOARD_FAB2_LIB.BASEBOARD_FAB2(SCH_1):PAGE59
   V51 M_J_CS_N<0> @BASEBOARD_FAB2_LIB.BASEBOARD_FAB2(SCH_1):M_J_CS_N(0)   I172 @BASEBOARD_FAB2_LIB.BASEBOARD_FAB2(SCH_1):PAGE59
  AH23 M_J_DQ<63> @BASEBOARD_FAB2_LIB.BASEBOARD_FAB2(SCH_1):M_J_DQ(63)   I172 @BASEBOARD_FAB2_LIB.BASEBOARD_FAB2(SCH_1):PAGE59
  AD23 M_J_DQ<62> @BASEBOARD_FAB2_LIB.BASEBOARD_FAB2(SCH_1):M_J_DQ(62)   I172 @BASEBOARD_FAB2_LIB.BASEBOARD_FAB2(SCH_1):PAGE59
  AG26 M_J_DQ<61> @BASEBOARD_FAB2_LIB.BASEBOARD_FAB2(SCH_1):M_J_DQ(61)   I172 @BASEBOARD_FAB2_LIB.BASEBOARD_FAB2(SCH_1):PAGE59
  AE26 M_J_DQ<60> @BASEBOARD_FAB2_LIB.BASEBOARD_FAB2(SCH_1):M_J_DQ(60)   I172 @BASEBOARD_FAB2_LIB.BASEBOARD_FAB2(SCH_1):PAGE59
  AG22 M_J_DQ<59> @BASEBOARD_FAB2_LIB.BASEBOARD_FAB2(SCH_1):M_J_DQ(59)   I172 @BASEBOARD_FAB2_LIB.BASEBOARD_FAB2(SCH_1):PAGE59
  AE22 M_J_DQ<58> @BASEBOARD_FAB2_LIB.BASEBOARD_FAB2(SCH_1):M_J_DQ(58)   I172 @BASEBOARD_FAB2_LIB.BASEBOARD_FAB2(SCH_1):PAGE59
  AH25 M_J_DQ<57> @BASEBOARD_FAB2_LIB.BASEBOARD_FAB2(SCH_1):M_J_DQ(57)   I172 @BASEBOARD_FAB2_LIB.BASEBOARD_FAB2(SCH_1):PAGE59
  AD25 M_J_DQ<56> @BASEBOARD_FAB2_LIB.BASEBOARD_FAB2(SCH_1):M_J_DQ(56)   I172 @BASEBOARD_FAB2_LIB.BASEBOARD_FAB2(SCH_1):PAGE59
  AH29 M_J_DQ<55> @BASEBOARD_FAB2_LIB.BASEBOARD_FAB2(SCH_1):M_J_DQ(55)   I172 @BASEBOARD_FAB2_LIB.BASEBOARD_FAB2(SCH_1):PAGE59
  AD29 M_J_DQ<54> @BASEBOARD_FAB2_LIB.BASEBOARD_FAB2(SCH_1):M_J_DQ(54)   I172 @BASEBOARD_FAB2_LIB.BASEBOARD_FAB2(SCH_1):PAGE59
  AG32 M_J_DQ<53> @BASEBOARD_FAB2_LIB.BASEBOARD_FAB2(SCH_1):M_J_DQ(53)   I172 @BASEBOARD_FAB2_LIB.BASEBOARD_FAB2(SCH_1):PAGE59
  AE32 M_J_DQ<52> @BASEBOARD_FAB2_LIB.BASEBOARD_FAB2(SCH_1):M_J_DQ(52)   I172 @BASEBOARD_FAB2_LIB.BASEBOARD_FAB2(SCH_1):PAGE59
  AG28 M_J_DQ<51> @BASEBOARD_FAB2_LIB.BASEBOARD_FAB2(SCH_1):M_J_DQ(51)   I172 @BASEBOARD_FAB2_LIB.BASEBOARD_FAB2(SCH_1):PAGE59
  AE28 M_J_DQ<50> @BASEBOARD_FAB2_LIB.BASEBOARD_FAB2(SCH_1):M_J_DQ(50)   I172 @BASEBOARD_FAB2_LIB.BASEBOARD_FAB2(SCH_1):PAGE59
  AH31 M_J_DQ<49> @BASEBOARD_FAB2_LIB.BASEBOARD_FAB2(SCH_1):M_J_DQ(49)   I172 @BASEBOARD_FAB2_LIB.BASEBOARD_FAB2(SCH_1):PAGE59
  AD31 M_J_DQ<48> @BASEBOARD_FAB2_LIB.BASEBOARD_FAB2(SCH_1):M_J_DQ(48)   I172 @BASEBOARD_FAB2_LIB.BASEBOARD_FAB2(SCH_1):PAGE59
  AA32 M_J_DQ<47> @BASEBOARD_FAB2_LIB.BASEBOARD_FAB2(SCH_1):M_J_DQ(47)   I172 @BASEBOARD_FAB2_LIB.BASEBOARD_FAB2(SCH_1):PAGE59
   U32 M_J_DQ<46> @BASEBOARD_FAB2_LIB.BASEBOARD_FAB2(SCH_1):M_J_DQ(46)   I172 @BASEBOARD_FAB2_LIB.BASEBOARD_FAB2(SCH_1):PAGE59
   Y35 M_J_DQ<45> @BASEBOARD_FAB2_LIB.BASEBOARD_FAB2(SCH_1):M_J_DQ(45)   I172 @BASEBOARD_FAB2_LIB.BASEBOARD_FAB2(SCH_1):PAGE59
   V35 M_J_DQ<44> @BASEBOARD_FAB2_LIB.BASEBOARD_FAB2(SCH_1):M_J_DQ(44)   I172 @BASEBOARD_FAB2_LIB.BASEBOARD_FAB2(SCH_1):PAGE59
   Y31 M_J_DQ<43> @BASEBOARD_FAB2_LIB.BASEBOARD_FAB2(SCH_1):M_J_DQ(43)   I172 @BASEBOARD_FAB2_LIB.BASEBOARD_FAB2(SCH_1):PAGE59
   V31 M_J_DQ<42> @BASEBOARD_FAB2_LIB.BASEBOARD_FAB2(SCH_1):M_J_DQ(42)   I172 @BASEBOARD_FAB2_LIB.BASEBOARD_FAB2(SCH_1):PAGE59
  AA34 M_J_DQ<41> @BASEBOARD_FAB2_LIB.BASEBOARD_FAB2(SCH_1):M_J_DQ(41)   I172 @BASEBOARD_FAB2_LIB.BASEBOARD_FAB2(SCH_1):PAGE59
   U34 M_J_DQ<40> @BASEBOARD_FAB2_LIB.BASEBOARD_FAB2(SCH_1):M_J_DQ(40)   I172 @BASEBOARD_FAB2_LIB.BASEBOARD_FAB2(SCH_1):PAGE59
  AA38 M_J_DQ<39> @BASEBOARD_FAB2_LIB.BASEBOARD_FAB2(SCH_1):M_J_DQ(39)   I172 @BASEBOARD_FAB2_LIB.BASEBOARD_FAB2(SCH_1):PAGE59
   U38 M_J_DQ<38> @BASEBOARD_FAB2_LIB.BASEBOARD_FAB2(SCH_1):M_J_DQ(38)   I172 @BASEBOARD_FAB2_LIB.BASEBOARD_FAB2(SCH_1):PAGE59
   Y41 M_J_DQ<37> @BASEBOARD_FAB2_LIB.BASEBOARD_FAB2(SCH_1):M_J_DQ(37)   I172 @BASEBOARD_FAB2_LIB.BASEBOARD_FAB2(SCH_1):PAGE59
   V41 M_J_DQ<36> @BASEBOARD_FAB2_LIB.BASEBOARD_FAB2(SCH_1):M_J_DQ(36)   I172 @BASEBOARD_FAB2_LIB.BASEBOARD_FAB2(SCH_1):PAGE59
   Y37 M_J_DQ<35> @BASEBOARD_FAB2_LIB.BASEBOARD_FAB2(SCH_1):M_J_DQ(35)   I172 @BASEBOARD_FAB2_LIB.BASEBOARD_FAB2(SCH_1):PAGE59
   V37 M_J_DQ<34> @BASEBOARD_FAB2_LIB.BASEBOARD_FAB2(SCH_1):M_J_DQ(34)   I172 @BASEBOARD_FAB2_LIB.BASEBOARD_FAB2(SCH_1):PAGE59
  AA40 M_J_DQ<33> @BASEBOARD_FAB2_LIB.BASEBOARD_FAB2(SCH_1):M_J_DQ(33)   I172 @BASEBOARD_FAB2_LIB.BASEBOARD_FAB2(SCH_1):PAGE59
   U40 M_J_DQ<32> @BASEBOARD_FAB2_LIB.BASEBOARD_FAB2(SCH_1):M_J_DQ(32)   I172 @BASEBOARD_FAB2_LIB.BASEBOARD_FAB2(SCH_1):PAGE59
  AT65 M_J_DQ<31> @BASEBOARD_FAB2_LIB.BASEBOARD_FAB2(SCH_1):M_J_DQ(31)   I172 @BASEBOARD_FAB2_LIB.BASEBOARD_FAB2(SCH_1):PAGE59
  AM65 M_J_DQ<30> @BASEBOARD_FAB2_LIB.BASEBOARD_FAB2(SCH_1):M_J_DQ(30)   I172 @BASEBOARD_FAB2_LIB.BASEBOARD_FAB2(SCH_1):PAGE59
  AR68 M_J_DQ<29> @BASEBOARD_FAB2_LIB.BASEBOARD_FAB2(SCH_1):M_J_DQ(29)   I172 @BASEBOARD_FAB2_LIB.BASEBOARD_FAB2(SCH_1):PAGE59
  AN68 M_J_DQ<28> @BASEBOARD_FAB2_LIB.BASEBOARD_FAB2(SCH_1):M_J_DQ(28)   I172 @BASEBOARD_FAB2_LIB.BASEBOARD_FAB2(SCH_1):PAGE59
  AR64 M_J_DQ<27> @BASEBOARD_FAB2_LIB.BASEBOARD_FAB2(SCH_1):M_J_DQ(27)   I172 @BASEBOARD_FAB2_LIB.BASEBOARD_FAB2(SCH_1):PAGE59
  AN64 M_J_DQ<26> @BASEBOARD_FAB2_LIB.BASEBOARD_FAB2(SCH_1):M_J_DQ(26)   I172 @BASEBOARD_FAB2_LIB.BASEBOARD_FAB2(SCH_1):PAGE59
  AT67 M_J_DQ<25> @BASEBOARD_FAB2_LIB.BASEBOARD_FAB2(SCH_1):M_J_DQ(25)   I172 @BASEBOARD_FAB2_LIB.BASEBOARD_FAB2(SCH_1):PAGE59
  AM67 M_J_DQ<24> @BASEBOARD_FAB2_LIB.BASEBOARD_FAB2(SCH_1):M_J_DQ(24)   I172 @BASEBOARD_FAB2_LIB.BASEBOARD_FAB2(SCH_1):PAGE59
   V69 M_J_DQ<23> @BASEBOARD_FAB2_LIB.BASEBOARD_FAB2(SCH_1):M_J_DQ(23)   I172 @BASEBOARD_FAB2_LIB.BASEBOARD_FAB2(SCH_1):PAGE59
   T71 M_J_DQ<22> @BASEBOARD_FAB2_LIB.BASEBOARD_FAB2(SCH_1):M_J_DQ(22)   I172 @BASEBOARD_FAB2_LIB.BASEBOARD_FAB2(SCH_1):PAGE59
  AB71 M_J_DQ<21> @BASEBOARD_FAB2_LIB.BASEBOARD_FAB2(SCH_1):M_J_DQ(21)   I172 @BASEBOARD_FAB2_LIB.BASEBOARD_FAB2(SCH_1):PAGE59
  AA72 M_J_DQ<20> @BASEBOARD_FAB2_LIB.BASEBOARD_FAB2(SCH_1):M_J_DQ(20)   I172 @BASEBOARD_FAB2_LIB.BASEBOARD_FAB2(SCH_1):PAGE59
   T69 M_J_DQ<19> @BASEBOARD_FAB2_LIB.BASEBOARD_FAB2(SCH_1):M_J_DQ(19)   I172 @BASEBOARD_FAB2_LIB.BASEBOARD_FAB2(SCH_1):PAGE59
   R70 M_J_DQ<18> @BASEBOARD_FAB2_LIB.BASEBOARD_FAB2(SCH_1):M_J_DQ(18)   I172 @BASEBOARD_FAB2_LIB.BASEBOARD_FAB2(SCH_1):PAGE59
  AA70 M_J_DQ<17> @BASEBOARD_FAB2_LIB.BASEBOARD_FAB2(SCH_1):M_J_DQ(17)   I172 @BASEBOARD_FAB2_LIB.BASEBOARD_FAB2(SCH_1):PAGE59
   W72 M_J_DQ<16> @BASEBOARD_FAB2_LIB.BASEBOARD_FAB2(SCH_1):M_J_DQ(16)   I172 @BASEBOARD_FAB2_LIB.BASEBOARD_FAB2(SCH_1):PAGE59
   Y75 M_J_DQ<15> @BASEBOARD_FAB2_LIB.BASEBOARD_FAB2(SCH_1):M_J_DQ(15)   I172 @BASEBOARD_FAB2_LIB.BASEBOARD_FAB2(SCH_1):PAGE59
  AB77 M_J_DQ<14> @BASEBOARD_FAB2_LIB.BASEBOARD_FAB2(SCH_1):M_J_DQ(14)   I172 @BASEBOARD_FAB2_LIB.BASEBOARD_FAB2(SCH_1):PAGE59
  AE74 M_J_DQ<13> @BASEBOARD_FAB2_LIB.BASEBOARD_FAB2(SCH_1):M_J_DQ(13)   I172 @BASEBOARD_FAB2_LIB.BASEBOARD_FAB2(SCH_1):PAGE59
  AF75 M_J_DQ<12> @BASEBOARD_FAB2_LIB.BASEBOARD_FAB2(SCH_1):M_J_DQ(12)   I172 @BASEBOARD_FAB2_LIB.BASEBOARD_FAB2(SCH_1):PAGE59
   W76 M_J_DQ<11> @BASEBOARD_FAB2_LIB.BASEBOARD_FAB2(SCH_1):M_J_DQ(11)   I172 @BASEBOARD_FAB2_LIB.BASEBOARD_FAB2(SCH_1):PAGE59
   Y77 M_J_DQ<10> @BASEBOARD_FAB2_LIB.BASEBOARD_FAB2(SCH_1):M_J_DQ(10)   I172 @BASEBOARD_FAB2_LIB.BASEBOARD_FAB2(SCH_1):PAGE59
  AC74 M_J_DQ<9> @BASEBOARD_FAB2_LIB.BASEBOARD_FAB2(SCH_1):M_J_DQ(9)   I172 @BASEBOARD_FAB2_LIB.BASEBOARD_FAB2(SCH_1):PAGE59
  AE76 M_J_DQ<8> @BASEBOARD_FAB2_LIB.BASEBOARD_FAB2(SCH_1):M_J_DQ(8)   I172 @BASEBOARD_FAB2_LIB.BASEBOARD_FAB2(SCH_1):PAGE59
  AK75 M_J_DQ<7> @BASEBOARD_FAB2_LIB.BASEBOARD_FAB2(SCH_1):M_J_DQ(7)   I172 @BASEBOARD_FAB2_LIB.BASEBOARD_FAB2(SCH_1):PAGE59
  AM77 M_J_DQ<6> @BASEBOARD_FAB2_LIB.BASEBOARD_FAB2(SCH_1):M_J_DQ(6)   I172 @BASEBOARD_FAB2_LIB.BASEBOARD_FAB2(SCH_1):PAGE59
  AR74 M_J_DQ<5> @BASEBOARD_FAB2_LIB.BASEBOARD_FAB2(SCH_1):M_J_DQ(5)   I172 @BASEBOARD_FAB2_LIB.BASEBOARD_FAB2(SCH_1):PAGE59
  AT75 M_J_DQ<4> @BASEBOARD_FAB2_LIB.BASEBOARD_FAB2(SCH_1):M_J_DQ(4)   I172 @BASEBOARD_FAB2_LIB.BASEBOARD_FAB2(SCH_1):PAGE59
  AJ76 M_J_DQ<3> @BASEBOARD_FAB2_LIB.BASEBOARD_FAB2(SCH_1):M_J_DQ(3)   I172 @BASEBOARD_FAB2_LIB.BASEBOARD_FAB2(SCH_1):PAGE59
  AK77 M_J_DQ<2> @BASEBOARD_FAB2_LIB.BASEBOARD_FAB2(SCH_1):M_J_DQ(2)   I172 @BASEBOARD_FAB2_LIB.BASEBOARD_FAB2(SCH_1):PAGE59
  AN74 M_J_DQ<1> @BASEBOARD_FAB2_LIB.BASEBOARD_FAB2(SCH_1):M_J_DQ(1)   I172 @BASEBOARD_FAB2_LIB.BASEBOARD_FAB2(SCH_1):PAGE59
  AR76 M_J_DQ<0> @BASEBOARD_FAB2_LIB.BASEBOARD_FAB2(SCH_1):M_J_DQ(0)   I172 @BASEBOARD_FAB2_LIB.BASEBOARD_FAB2(SCH_1):PAGE59
  AT71 M_J_DQS_DN<17> @BASEBOARD_FAB2_LIB.BASEBOARD_FAB2(SCH_1):M_J_DQS_DN(17)   I172 @BASEBOARD_FAB2_LIB.BASEBOARD_FAB2(SCH_1):PAGE59
  AC24 M_J_DQS_DN<16> @BASEBOARD_FAB2_LIB.BASEBOARD_FAB2(SCH_1):M_J_DQS_DN(16)   I172 @BASEBOARD_FAB2_LIB.BASEBOARD_FAB2(SCH_1):PAGE59
  AC30 M_J_DQS_DN<15> @BASEBOARD_FAB2_LIB.BASEBOARD_FAB2(SCH_1):M_J_DQS_DN(15)   I172 @BASEBOARD_FAB2_LIB.BASEBOARD_FAB2(SCH_1):PAGE59
   T33 M_J_DQS_DN<14> @BASEBOARD_FAB2_LIB.BASEBOARD_FAB2(SCH_1):M_J_DQS_DN(14)   I172 @BASEBOARD_FAB2_LIB.BASEBOARD_FAB2(SCH_1):PAGE59
   T39 M_J_DQS_DN<13> @BASEBOARD_FAB2_LIB.BASEBOARD_FAB2(SCH_1):M_J_DQS_DN(13)   I172 @BASEBOARD_FAB2_LIB.BASEBOARD_FAB2(SCH_1):PAGE59
  AL66 M_J_DQS_DN<12> @BASEBOARD_FAB2_LIB.BASEBOARD_FAB2(SCH_1):M_J_DQS_DN(12)   I172 @BASEBOARD_FAB2_LIB.BASEBOARD_FAB2(SCH_1):PAGE59
   U72 M_J_DQS_DN<11> @BASEBOARD_FAB2_LIB.BASEBOARD_FAB2(SCH_1):M_J_DQS_DN(11)   I172 @BASEBOARD_FAB2_LIB.BASEBOARD_FAB2(SCH_1):PAGE59
  AD77 M_J_DQS_DN<10> @BASEBOARD_FAB2_LIB.BASEBOARD_FAB2(SCH_1):M_J_DQS_DN(10)   I172 @BASEBOARD_FAB2_LIB.BASEBOARD_FAB2(SCH_1):PAGE59
  AP77 M_J_DQS_DN<9> @BASEBOARD_FAB2_LIB.BASEBOARD_FAB2(SCH_1):M_J_DQS_DN(9)   I172 @BASEBOARD_FAB2_LIB.BASEBOARD_FAB2(SCH_1):PAGE59
  BB71 M_J_DQS_DN<8> @BASEBOARD_FAB2_LIB.BASEBOARD_FAB2(SCH_1):M_J_DQS_DN(8)   I172 @BASEBOARD_FAB2_LIB.BASEBOARD_FAB2(SCH_1):PAGE59
  AJ24 M_J_DQS_DN<7> @BASEBOARD_FAB2_LIB.BASEBOARD_FAB2(SCH_1):M_J_DQS_DN(7)   I172 @BASEBOARD_FAB2_LIB.BASEBOARD_FAB2(SCH_1):PAGE59
  AJ30 M_J_DQS_DN<6> @BASEBOARD_FAB2_LIB.BASEBOARD_FAB2(SCH_1):M_J_DQS_DN(6)   I172 @BASEBOARD_FAB2_LIB.BASEBOARD_FAB2(SCH_1):PAGE59
  AB33 M_J_DQS_DN<5> @BASEBOARD_FAB2_LIB.BASEBOARD_FAB2(SCH_1):M_J_DQS_DN(5)   I172 @BASEBOARD_FAB2_LIB.BASEBOARD_FAB2(SCH_1):PAGE59
  AB39 M_J_DQS_DN<4> @BASEBOARD_FAB2_LIB.BASEBOARD_FAB2(SCH_1):M_J_DQS_DN(4)   I172 @BASEBOARD_FAB2_LIB.BASEBOARD_FAB2(SCH_1):PAGE59
  AU66 M_J_DQS_DN<3> @BASEBOARD_FAB2_LIB.BASEBOARD_FAB2(SCH_1):M_J_DQS_DN(3)   I172 @BASEBOARD_FAB2_LIB.BASEBOARD_FAB2(SCH_1):PAGE59
   Y69 M_J_DQS_DN<2> @BASEBOARD_FAB2_LIB.BASEBOARD_FAB2(SCH_1):M_J_DQS_DN(2)   I172 @BASEBOARD_FAB2_LIB.BASEBOARD_FAB2(SCH_1):PAGE59
  AA74 M_J_DQS_DN<1> @BASEBOARD_FAB2_LIB.BASEBOARD_FAB2(SCH_1):M_J_DQS_DN(1)   I172 @BASEBOARD_FAB2_LIB.BASEBOARD_FAB2(SCH_1):PAGE59
  AL74 M_J_DQS_DN<0> @BASEBOARD_FAB2_LIB.BASEBOARD_FAB2(SCH_1):M_J_DQS_DN(0)   I172 @BASEBOARD_FAB2_LIB.BASEBOARD_FAB2(SCH_1):PAGE59
  AV71 M_J_DQS_DP<17> @BASEBOARD_FAB2_LIB.BASEBOARD_FAB2(SCH_1):M_J_DQS_DP(17)   I172 @BASEBOARD_FAB2_LIB.BASEBOARD_FAB2(SCH_1):PAGE59
  AE24 M_J_DQS_DP<16> @BASEBOARD_FAB2_LIB.BASEBOARD_FAB2(SCH_1):M_J_DQS_DP(16)   I172 @BASEBOARD_FAB2_LIB.BASEBOARD_FAB2(SCH_1):PAGE59
  AE30 M_J_DQS_DP<15> @BASEBOARD_FAB2_LIB.BASEBOARD_FAB2(SCH_1):M_J_DQS_DP(15)   I172 @BASEBOARD_FAB2_LIB.BASEBOARD_FAB2(SCH_1):PAGE59
   V33 M_J_DQS_DP<14> @BASEBOARD_FAB2_LIB.BASEBOARD_FAB2(SCH_1):M_J_DQS_DP(14)   I172 @BASEBOARD_FAB2_LIB.BASEBOARD_FAB2(SCH_1):PAGE59
   V39 M_J_DQS_DP<13> @BASEBOARD_FAB2_LIB.BASEBOARD_FAB2(SCH_1):M_J_DQS_DP(13)   I172 @BASEBOARD_FAB2_LIB.BASEBOARD_FAB2(SCH_1):PAGE59
  AN66 M_J_DQS_DP<12> @BASEBOARD_FAB2_LIB.BASEBOARD_FAB2(SCH_1):M_J_DQS_DP(12)   I172 @BASEBOARD_FAB2_LIB.BASEBOARD_FAB2(SCH_1):PAGE59
   V71 M_J_DQS_DP<11> @BASEBOARD_FAB2_LIB.BASEBOARD_FAB2(SCH_1):M_J_DQS_DP(11)   I172 @BASEBOARD_FAB2_LIB.BASEBOARD_FAB2(SCH_1):PAGE59
  AC76 M_J_DQS_DP<10> @BASEBOARD_FAB2_LIB.BASEBOARD_FAB2(SCH_1):M_J_DQS_DP(10)   I172 @BASEBOARD_FAB2_LIB.BASEBOARD_FAB2(SCH_1):PAGE59
  AN76 M_J_DQS_DP<9> @BASEBOARD_FAB2_LIB.BASEBOARD_FAB2(SCH_1):M_J_DQS_DP(9)   I172 @BASEBOARD_FAB2_LIB.BASEBOARD_FAB2(SCH_1):PAGE59
  AY71 M_J_DQS_DP<8> @BASEBOARD_FAB2_LIB.BASEBOARD_FAB2(SCH_1):M_J_DQS_DP(8)   I172 @BASEBOARD_FAB2_LIB.BASEBOARD_FAB2(SCH_1):PAGE59
  AG24 M_J_DQS_DP<7> @BASEBOARD_FAB2_LIB.BASEBOARD_FAB2(SCH_1):M_J_DQS_DP(7)   I172 @BASEBOARD_FAB2_LIB.BASEBOARD_FAB2(SCH_1):PAGE59
  AG30 M_J_DQS_DP<6> @BASEBOARD_FAB2_LIB.BASEBOARD_FAB2(SCH_1):M_J_DQS_DP(6)   I172 @BASEBOARD_FAB2_LIB.BASEBOARD_FAB2(SCH_1):PAGE59
   Y33 M_J_DQS_DP<5> @BASEBOARD_FAB2_LIB.BASEBOARD_FAB2(SCH_1):M_J_DQS_DP(5)   I172 @BASEBOARD_FAB2_LIB.BASEBOARD_FAB2(SCH_1):PAGE59
   Y39 M_J_DQS_DP<4> @BASEBOARD_FAB2_LIB.BASEBOARD_FAB2(SCH_1):M_J_DQS_DP(4)   I172 @BASEBOARD_FAB2_LIB.BASEBOARD_FAB2(SCH_1):PAGE59
  AR66 M_J_DQS_DP<3> @BASEBOARD_FAB2_LIB.BASEBOARD_FAB2(SCH_1):M_J_DQS_DP(3)   I172 @BASEBOARD_FAB2_LIB.BASEBOARD_FAB2(SCH_1):PAGE59
   W70 M_J_DQS_DP<2> @BASEBOARD_FAB2_LIB.BASEBOARD_FAB2(SCH_1):M_J_DQS_DP(2)   I172 @BASEBOARD_FAB2_LIB.BASEBOARD_FAB2(SCH_1):PAGE59
  AB75 M_J_DQS_DP<1> @BASEBOARD_FAB2_LIB.BASEBOARD_FAB2(SCH_1):M_J_DQS_DP(1)   I172 @BASEBOARD_FAB2_LIB.BASEBOARD_FAB2(SCH_1):PAGE59
  AM75 M_J_DQS_DP<0> @BASEBOARD_FAB2_LIB.BASEBOARD_FAB2(SCH_1):M_J_DQS_DP(0)   I172 @BASEBOARD_FAB2_LIB.BASEBOARD_FAB2(SCH_1):PAGE59
  BA70 M_J_ECC<7> @BASEBOARD_FAB2_LIB.BASEBOARD_FAB2(SCH_1):M_J_ECC(7)   I172 @BASEBOARD_FAB2_LIB.BASEBOARD_FAB2(SCH_1):PAGE59
  AU70 M_J_ECC<6> @BASEBOARD_FAB2_LIB.BASEBOARD_FAB2(SCH_1):M_J_ECC(6)   I172 @BASEBOARD_FAB2_LIB.BASEBOARD_FAB2(SCH_1):PAGE59
  AY73 M_J_ECC<5> @BASEBOARD_FAB2_LIB.BASEBOARD_FAB2(SCH_1):M_J_ECC(5)   I172 @BASEBOARD_FAB2_LIB.BASEBOARD_FAB2(SCH_1):PAGE59
  AV73 M_J_ECC<4> @BASEBOARD_FAB2_LIB.BASEBOARD_FAB2(SCH_1):M_J_ECC(4)   I172 @BASEBOARD_FAB2_LIB.BASEBOARD_FAB2(SCH_1):PAGE59
  AY69 M_J_ECC<3> @BASEBOARD_FAB2_LIB.BASEBOARD_FAB2(SCH_1):M_J_ECC(3)   I172 @BASEBOARD_FAB2_LIB.BASEBOARD_FAB2(SCH_1):PAGE59
  AV69 M_J_ECC<2> @BASEBOARD_FAB2_LIB.BASEBOARD_FAB2(SCH_1):M_J_ECC(2)   I172 @BASEBOARD_FAB2_LIB.BASEBOARD_FAB2(SCH_1):PAGE59
  BA72 M_J_ECC<1> @BASEBOARD_FAB2_LIB.BASEBOARD_FAB2(SCH_1):M_J_ECC(1)   I172 @BASEBOARD_FAB2_LIB.BASEBOARD_FAB2(SCH_1):PAGE59
  AU72 M_J_ECC<0> @BASEBOARD_FAB2_LIB.BASEBOARD_FAB2(SCH_1):M_J_ECC(0)   I172 @BASEBOARD_FAB2_LIB.BASEBOARD_FAB2(SCH_1):PAGE59
  AC46 M_J_MA<17> @BASEBOARD_FAB2_LIB.BASEBOARD_FAB2(SCH_1):M_J_MA(17)   I172 @BASEBOARD_FAB2_LIB.BASEBOARD_FAB2(SCH_1):PAGE59
  AA52 M_J_MA<16> @BASEBOARD_FAB2_LIB.BASEBOARD_FAB2(SCH_1):M_J_MA(16)   I172 @BASEBOARD_FAB2_LIB.BASEBOARD_FAB2(SCH_1):PAGE59
  AE54 M_J_MA<15> @BASEBOARD_FAB2_LIB.BASEBOARD_FAB2(SCH_1):M_J_MA(15)   I172 @BASEBOARD_FAB2_LIB.BASEBOARD_FAB2(SCH_1):PAGE59
   W50 M_J_MA<14> @BASEBOARD_FAB2_LIB.BASEBOARD_FAB2(SCH_1):M_J_MA(14)   I172 @BASEBOARD_FAB2_LIB.BASEBOARD_FAB2(SCH_1):PAGE59
  AD53 M_J_MA<13> @BASEBOARD_FAB2_LIB.BASEBOARD_FAB2(SCH_1):M_J_MA(13)   I172 @BASEBOARD_FAB2_LIB.BASEBOARD_FAB2(SCH_1):PAGE59
  AG62 M_J_MA<12> @BASEBOARD_FAB2_LIB.BASEBOARD_FAB2(SCH_1):M_J_MA(12)   I172 @BASEBOARD_FAB2_LIB.BASEBOARD_FAB2(SCH_1):PAGE59
  AG60 M_J_MA<11> @BASEBOARD_FAB2_LIB.BASEBOARD_FAB2(SCH_1):M_J_MA(11)   I172 @BASEBOARD_FAB2_LIB.BASEBOARD_FAB2(SCH_1):PAGE59
  AD55 M_J_MA<10> @BASEBOARD_FAB2_LIB.BASEBOARD_FAB2(SCH_1):M_J_MA(10)   I172 @BASEBOARD_FAB2_LIB.BASEBOARD_FAB2(SCH_1):PAGE59
  AG58 M_J_MA<9> @BASEBOARD_FAB2_LIB.BASEBOARD_FAB2(SCH_1):M_J_MA(9)   I172 @BASEBOARD_FAB2_LIB.BASEBOARD_FAB2(SCH_1):PAGE59
  AD59 M_J_MA<8> @BASEBOARD_FAB2_LIB.BASEBOARD_FAB2(SCH_1):M_J_MA(8)   I172 @BASEBOARD_FAB2_LIB.BASEBOARD_FAB2(SCH_1):PAGE59
  AE60 M_J_MA<7> @BASEBOARD_FAB2_LIB.BASEBOARD_FAB2(SCH_1):M_J_MA(7)   I172 @BASEBOARD_FAB2_LIB.BASEBOARD_FAB2(SCH_1):PAGE59
  AB59 M_J_MA<6> @BASEBOARD_FAB2_LIB.BASEBOARD_FAB2(SCH_1):M_J_MA(6)   I172 @BASEBOARD_FAB2_LIB.BASEBOARD_FAB2(SCH_1):PAGE59
   V59 M_J_MA<5> @BASEBOARD_FAB2_LIB.BASEBOARD_FAB2(SCH_1):M_J_MA(5)   I172 @BASEBOARD_FAB2_LIB.BASEBOARD_FAB2(SCH_1):PAGE59
  AA58 M_J_MA<4> @BASEBOARD_FAB2_LIB.BASEBOARD_FAB2(SCH_1):M_J_MA(4)   I172 @BASEBOARD_FAB2_LIB.BASEBOARD_FAB2(SCH_1):PAGE59
   W58 M_J_MA<3> @BASEBOARD_FAB2_LIB.BASEBOARD_FAB2(SCH_1):M_J_MA(3)   I172 @BASEBOARD_FAB2_LIB.BASEBOARD_FAB2(SCH_1):PAGE59
  AD57 M_J_MA<2> @BASEBOARD_FAB2_LIB.BASEBOARD_FAB2(SCH_1):M_J_MA(2)   I172 @BASEBOARD_FAB2_LIB.BASEBOARD_FAB2(SCH_1):PAGE59
  AE58 M_J_MA<1> @BASEBOARD_FAB2_LIB.BASEBOARD_FAB2(SCH_1):M_J_MA(1)   I172 @BASEBOARD_FAB2_LIB.BASEBOARD_FAB2(SCH_1):PAGE59
  AB53 M_J_MA<0> @BASEBOARD_FAB2_LIB.BASEBOARD_FAB2(SCH_1):M_J_MA(0)   I172 @BASEBOARD_FAB2_LIB.BASEBOARD_FAB2(SCH_1):PAGE59
  AB47 M_J_ODT<3> @BASEBOARD_FAB2_LIB.BASEBOARD_FAB2(SCH_1):M_J_ODT(3)   I172 @BASEBOARD_FAB2_LIB.BASEBOARD_FAB2(SCH_1):PAGE59
   V49 M_J_ODT<2> @BASEBOARD_FAB2_LIB.BASEBOARD_FAB2(SCH_1):M_J_ODT(2)   I172 @BASEBOARD_FAB2_LIB.BASEBOARD_FAB2(SCH_1):PAGE59
  AA48 M_J_ODT<1> @BASEBOARD_FAB2_LIB.BASEBOARD_FAB2(SCH_1):M_J_ODT(1)   I172 @BASEBOARD_FAB2_LIB.BASEBOARD_FAB2(SCH_1):PAGE59
  AA50 M_J_ODT<0> @BASEBOARD_FAB2_LIB.BASEBOARD_FAB2(SCH_1):M_J_ODT(0)   I172 @BASEBOARD_FAB2_LIB.BASEBOARD_FAB2(SCH_1):PAGE59
   V53 M_J_PAR @BASEBOARD_FAB2_LIB.BASEBOARD_FAB2(SCH_1):M_J_PAR   I172 @BASEBOARD_FAB2_LIB.BASEBOARD_FAB2(SCH_1):PAGE59
  DW60 M_K_ACT_N @BASEBOARD_FAB2_LIB.BASEBOARD_FAB2(SCH_1):M_K_ACT_N   I172 @BASEBOARD_FAB2_LIB.BASEBOARD_FAB2(SCH_1):PAGE60
  ED63 M_K_ALERT_N @BASEBOARD_FAB2_LIB.BASEBOARD_FAB2(SCH_1):M_K_ALERT_N   I172 @BASEBOARD_FAB2_LIB.BASEBOARD_FAB2(SCH_1):PAGE60
  EA54 M_K_BA<1> @BASEBOARD_FAB2_LIB.BASEBOARD_FAB2(SCH_1):M_K_BA(1)   I172 @BASEBOARD_FAB2_LIB.BASEBOARD_FAB2(SCH_1):PAGE60
  EE52 M_K_BA<0> @BASEBOARD_FAB2_LIB.BASEBOARD_FAB2(SCH_1):M_K_BA(0)   I172 @BASEBOARD_FAB2_LIB.BASEBOARD_FAB2(SCH_1):PAGE60
  DW62 M_K_BG<1> @BASEBOARD_FAB2_LIB.BASEBOARD_FAB2(SCH_1):M_K_BG(1)   I172 @BASEBOARD_FAB2_LIB.BASEBOARD_FAB2(SCH_1):PAGE60
  ED61 M_K_BG<0> @BASEBOARD_FAB2_LIB.BASEBOARD_FAB2(SCH_1):M_K_BG(0)   I172 @BASEBOARD_FAB2_LIB.BASEBOARD_FAB2(SCH_1):PAGE60
  DV47 M_K_C<2> @BASEBOARD_FAB2_LIB.BASEBOARD_FAB2(SCH_1):M_K_C(2)   I172 @BASEBOARD_FAB2_LIB.BASEBOARD_FAB2(SCH_1):PAGE60
  EB63 M_K_CKE<3> @BASEBOARD_FAB2_LIB.BASEBOARD_FAB2(SCH_1):M_K_CKE(3)   I172 @BASEBOARD_FAB2_LIB.BASEBOARD_FAB2(SCH_1):PAGE60
  EA62 M_K_CKE<2> @BASEBOARD_FAB2_LIB.BASEBOARD_FAB2(SCH_1):M_K_CKE(2)   I172 @BASEBOARD_FAB2_LIB.BASEBOARD_FAB2(SCH_1):PAGE60
  EF63 M_K_CKE<1> @BASEBOARD_FAB2_LIB.BASEBOARD_FAB2(SCH_1):M_K_CKE(1)   I172 @BASEBOARD_FAB2_LIB.BASEBOARD_FAB2(SCH_1):PAGE60
  EE62 M_K_CKE<0> @BASEBOARD_FAB2_LIB.BASEBOARD_FAB2(SCH_1):M_K_CKE(0)   I172 @BASEBOARD_FAB2_LIB.BASEBOARD_FAB2(SCH_1):PAGE60
  EF57 M_K_CLK_DN<3> @BASEBOARD_FAB2_LIB.BASEBOARD_FAB2(SCH_1):M_K_CLK_DN(3)   I172 @BASEBOARD_FAB2_LIB.BASEBOARD_FAB2(SCH_1):PAGE60
  DW56 M_K_CLK_DN<2> @BASEBOARD_FAB2_LIB.BASEBOARD_FAB2(SCH_1):M_K_CLK_DN(2)   I172 @BASEBOARD_FAB2_LIB.BASEBOARD_FAB2(SCH_1):PAGE60
  EF55 M_K_CLK_DN<1> @BASEBOARD_FAB2_LIB.BASEBOARD_FAB2(SCH_1):M_K_CLK_DN(1)   I172 @BASEBOARD_FAB2_LIB.BASEBOARD_FAB2(SCH_1):PAGE60
  ED55 M_K_CLK_DN<0> @BASEBOARD_FAB2_LIB.BASEBOARD_FAB2(SCH_1):M_K_CLK_DN(0)   I172 @BASEBOARD_FAB2_LIB.BASEBOARD_FAB2(SCH_1):PAGE60
  EE56 M_K_CLK_DP<3> @BASEBOARD_FAB2_LIB.BASEBOARD_FAB2(SCH_1):M_K_CLK_DP(3)   I172 @BASEBOARD_FAB2_LIB.BASEBOARD_FAB2(SCH_1):PAGE60
  EA56 M_K_CLK_DP<2> @BASEBOARD_FAB2_LIB.BASEBOARD_FAB2(SCH_1):M_K_CLK_DP(2)   I172 @BASEBOARD_FAB2_LIB.BASEBOARD_FAB2(SCH_1):PAGE60
  EE54 M_K_CLK_DP<1> @BASEBOARD_FAB2_LIB.BASEBOARD_FAB2(SCH_1):M_K_CLK_DP(1)   I172 @BASEBOARD_FAB2_LIB.BASEBOARD_FAB2(SCH_1):PAGE60
  EB55 M_K_CLK_DP<0> @BASEBOARD_FAB2_LIB.BASEBOARD_FAB2(SCH_1):M_K_CLK_DP(0)   I172 @BASEBOARD_FAB2_LIB.BASEBOARD_FAB2(SCH_1):PAGE60
  EB45 M_K_CS_N<7> @BASEBOARD_FAB2_LIB.BASEBOARD_FAB2(SCH_1):M_K_CS_N(7)   I172 @BASEBOARD_FAB2_LIB.BASEBOARD_FAB2(SCH_1):PAGE60
  DV45 M_K_CS_N<6> @BASEBOARD_FAB2_LIB.BASEBOARD_FAB2(SCH_1):M_K_CS_N(6)   I172 @BASEBOARD_FAB2_LIB.BASEBOARD_FAB2(SCH_1):PAGE60
  EB49 M_K_CS_N<5> @BASEBOARD_FAB2_LIB.BASEBOARD_FAB2(SCH_1):M_K_CS_N(5)   I172 @BASEBOARD_FAB2_LIB.BASEBOARD_FAB2(SCH_1):PAGE60
  EB51 M_K_CS_N<4> @BASEBOARD_FAB2_LIB.BASEBOARD_FAB2(SCH_1):M_K_CS_N(4)   I172 @BASEBOARD_FAB2_LIB.BASEBOARD_FAB2(SCH_1):PAGE60
  EB47 M_K_CS_N<3> @BASEBOARD_FAB2_LIB.BASEBOARD_FAB2(SCH_1):M_K_CS_N(3)   I172 @BASEBOARD_FAB2_LIB.BASEBOARD_FAB2(SCH_1):PAGE60
  ED47 M_K_CS_N<2> @BASEBOARD_FAB2_LIB.BASEBOARD_FAB2(SCH_1):M_K_CS_N(2)   I172 @BASEBOARD_FAB2_LIB.BASEBOARD_FAB2(SCH_1):PAGE60
  ED49 M_K_CS_N<1> @BASEBOARD_FAB2_LIB.BASEBOARD_FAB2(SCH_1):M_K_CS_N(1)   I172 @BASEBOARD_FAB2_LIB.BASEBOARD_FAB2(SCH_1):PAGE60
  EF51 M_K_CS_N<0> @BASEBOARD_FAB2_LIB.BASEBOARD_FAB2(SCH_1):M_K_CS_N(0)   I172 @BASEBOARD_FAB2_LIB.BASEBOARD_FAB2(SCH_1):PAGE60
  DW22 M_K_DQ<63> @BASEBOARD_FAB2_LIB.BASEBOARD_FAB2(SCH_1):M_K_DQ(63)   I172 @BASEBOARD_FAB2_LIB.BASEBOARD_FAB2(SCH_1):PAGE60
  EC22 M_K_DQ<62> @BASEBOARD_FAB2_LIB.BASEBOARD_FAB2(SCH_1):M_K_DQ(62)   I172 @BASEBOARD_FAB2_LIB.BASEBOARD_FAB2(SCH_1):PAGE60
  DT25 M_K_DQ<61> @BASEBOARD_FAB2_LIB.BASEBOARD_FAB2(SCH_1):M_K_DQ(61)   I172 @BASEBOARD_FAB2_LIB.BASEBOARD_FAB2(SCH_1):PAGE60
  DP25 M_K_DQ<60> @BASEBOARD_FAB2_LIB.BASEBOARD_FAB2(SCH_1):M_K_DQ(60)   I172 @BASEBOARD_FAB2_LIB.BASEBOARD_FAB2(SCH_1):PAGE60
  EB21 M_K_DQ<59> @BASEBOARD_FAB2_LIB.BASEBOARD_FAB2(SCH_1):M_K_DQ(59)   I172 @BASEBOARD_FAB2_LIB.BASEBOARD_FAB2(SCH_1):PAGE60
  DY21 M_K_DQ<58> @BASEBOARD_FAB2_LIB.BASEBOARD_FAB2(SCH_1):M_K_DQ(58)   I172 @BASEBOARD_FAB2_LIB.BASEBOARD_FAB2(SCH_1):PAGE60
  DU24 M_K_DQ<57> @BASEBOARD_FAB2_LIB.BASEBOARD_FAB2(SCH_1):M_K_DQ(57)   I172 @BASEBOARD_FAB2_LIB.BASEBOARD_FAB2(SCH_1):PAGE60
  DN24 M_K_DQ<56> @BASEBOARD_FAB2_LIB.BASEBOARD_FAB2(SCH_1):M_K_DQ(56)   I172 @BASEBOARD_FAB2_LIB.BASEBOARD_FAB2(SCH_1):PAGE60
  DU28 M_K_DQ<55> @BASEBOARD_FAB2_LIB.BASEBOARD_FAB2(SCH_1):M_K_DQ(55)   I172 @BASEBOARD_FAB2_LIB.BASEBOARD_FAB2(SCH_1):PAGE60
  DN28 M_K_DQ<54> @BASEBOARD_FAB2_LIB.BASEBOARD_FAB2(SCH_1):M_K_DQ(54)   I172 @BASEBOARD_FAB2_LIB.BASEBOARD_FAB2(SCH_1):PAGE60
  DT31 M_K_DQ<53> @BASEBOARD_FAB2_LIB.BASEBOARD_FAB2(SCH_1):M_K_DQ(53)   I172 @BASEBOARD_FAB2_LIB.BASEBOARD_FAB2(SCH_1):PAGE60
  DP31 M_K_DQ<52> @BASEBOARD_FAB2_LIB.BASEBOARD_FAB2(SCH_1):M_K_DQ(52)   I172 @BASEBOARD_FAB2_LIB.BASEBOARD_FAB2(SCH_1):PAGE60
  DT27 M_K_DQ<51> @BASEBOARD_FAB2_LIB.BASEBOARD_FAB2(SCH_1):M_K_DQ(51)   I172 @BASEBOARD_FAB2_LIB.BASEBOARD_FAB2(SCH_1):PAGE60
  DP27 M_K_DQ<50> @BASEBOARD_FAB2_LIB.BASEBOARD_FAB2(SCH_1):M_K_DQ(50)   I172 @BASEBOARD_FAB2_LIB.BASEBOARD_FAB2(SCH_1):PAGE60
  DU30 M_K_DQ<49> @BASEBOARD_FAB2_LIB.BASEBOARD_FAB2(SCH_1):M_K_DQ(49)   I172 @BASEBOARD_FAB2_LIB.BASEBOARD_FAB2(SCH_1):PAGE60
  DN30 M_K_DQ<48> @BASEBOARD_FAB2_LIB.BASEBOARD_FAB2(SCH_1):M_K_DQ(48)   I172 @BASEBOARD_FAB2_LIB.BASEBOARD_FAB2(SCH_1):PAGE60
  DU34 M_K_DQ<47> @BASEBOARD_FAB2_LIB.BASEBOARD_FAB2(SCH_1):M_K_DQ(47)   I172 @BASEBOARD_FAB2_LIB.BASEBOARD_FAB2(SCH_1):PAGE60
  DN34 M_K_DQ<46> @BASEBOARD_FAB2_LIB.BASEBOARD_FAB2(SCH_1):M_K_DQ(46)   I172 @BASEBOARD_FAB2_LIB.BASEBOARD_FAB2(SCH_1):PAGE60
  DT37 M_K_DQ<45> @BASEBOARD_FAB2_LIB.BASEBOARD_FAB2(SCH_1):M_K_DQ(45)   I172 @BASEBOARD_FAB2_LIB.BASEBOARD_FAB2(SCH_1):PAGE60
  DP37 M_K_DQ<44> @BASEBOARD_FAB2_LIB.BASEBOARD_FAB2(SCH_1):M_K_DQ(44)   I172 @BASEBOARD_FAB2_LIB.BASEBOARD_FAB2(SCH_1):PAGE60
  DT33 M_K_DQ<43> @BASEBOARD_FAB2_LIB.BASEBOARD_FAB2(SCH_1):M_K_DQ(43)   I172 @BASEBOARD_FAB2_LIB.BASEBOARD_FAB2(SCH_1):PAGE60
  DP33 M_K_DQ<42> @BASEBOARD_FAB2_LIB.BASEBOARD_FAB2(SCH_1):M_K_DQ(42)   I172 @BASEBOARD_FAB2_LIB.BASEBOARD_FAB2(SCH_1):PAGE60
  DU36 M_K_DQ<41> @BASEBOARD_FAB2_LIB.BASEBOARD_FAB2(SCH_1):M_K_DQ(41)   I172 @BASEBOARD_FAB2_LIB.BASEBOARD_FAB2(SCH_1):PAGE60
  DN36 M_K_DQ<40> @BASEBOARD_FAB2_LIB.BASEBOARD_FAB2(SCH_1):M_K_DQ(40)   I172 @BASEBOARD_FAB2_LIB.BASEBOARD_FAB2(SCH_1):PAGE60
  ED37 M_K_DQ<39> @BASEBOARD_FAB2_LIB.BASEBOARD_FAB2(SCH_1):M_K_DQ(39)   I172 @BASEBOARD_FAB2_LIB.BASEBOARD_FAB2(SCH_1):PAGE60
  DY37 M_K_DQ<38> @BASEBOARD_FAB2_LIB.BASEBOARD_FAB2(SCH_1):M_K_DQ(38)   I172 @BASEBOARD_FAB2_LIB.BASEBOARD_FAB2(SCH_1):PAGE60
  EA40 M_K_DQ<37> @BASEBOARD_FAB2_LIB.BASEBOARD_FAB2(SCH_1):M_K_DQ(37)   I172 @BASEBOARD_FAB2_LIB.BASEBOARD_FAB2(SCH_1):PAGE60
  DY39 M_K_DQ<36> @BASEBOARD_FAB2_LIB.BASEBOARD_FAB2(SCH_1):M_K_DQ(36)   I172 @BASEBOARD_FAB2_LIB.BASEBOARD_FAB2(SCH_1):PAGE60
  EC36 M_K_DQ<35> @BASEBOARD_FAB2_LIB.BASEBOARD_FAB2(SCH_1):M_K_DQ(35)   I172 @BASEBOARD_FAB2_LIB.BASEBOARD_FAB2(SCH_1):PAGE60
  EA36 M_K_DQ<34> @BASEBOARD_FAB2_LIB.BASEBOARD_FAB2(SCH_1):M_K_DQ(34)   I172 @BASEBOARD_FAB2_LIB.BASEBOARD_FAB2(SCH_1):PAGE60
  ED39 M_K_DQ<33> @BASEBOARD_FAB2_LIB.BASEBOARD_FAB2(SCH_1):M_K_DQ(33)   I172 @BASEBOARD_FAB2_LIB.BASEBOARD_FAB2(SCH_1):PAGE60
  EC40 M_K_DQ<32> @BASEBOARD_FAB2_LIB.BASEBOARD_FAB2(SCH_1):M_K_DQ(32)   I172 @BASEBOARD_FAB2_LIB.BASEBOARD_FAB2(SCH_1):PAGE60
  DU74 M_K_DQ<31> @BASEBOARD_FAB2_LIB.BASEBOARD_FAB2(SCH_1):M_K_DQ(31)   I172 @BASEBOARD_FAB2_LIB.BASEBOARD_FAB2(SCH_1):PAGE60
  DN74 M_K_DQ<30> @BASEBOARD_FAB2_LIB.BASEBOARD_FAB2(SCH_1):M_K_DQ(30)   I172 @BASEBOARD_FAB2_LIB.BASEBOARD_FAB2(SCH_1):PAGE60
  DT77 M_K_DQ<29> @BASEBOARD_FAB2_LIB.BASEBOARD_FAB2(SCH_1):M_K_DQ(29)   I172 @BASEBOARD_FAB2_LIB.BASEBOARD_FAB2(SCH_1):PAGE60
  DP77 M_K_DQ<28> @BASEBOARD_FAB2_LIB.BASEBOARD_FAB2(SCH_1):M_K_DQ(28)   I172 @BASEBOARD_FAB2_LIB.BASEBOARD_FAB2(SCH_1):PAGE60
  DT73 M_K_DQ<27> @BASEBOARD_FAB2_LIB.BASEBOARD_FAB2(SCH_1):M_K_DQ(27)   I172 @BASEBOARD_FAB2_LIB.BASEBOARD_FAB2(SCH_1):PAGE60
  DP73 M_K_DQ<26> @BASEBOARD_FAB2_LIB.BASEBOARD_FAB2(SCH_1):M_K_DQ(26)   I172 @BASEBOARD_FAB2_LIB.BASEBOARD_FAB2(SCH_1):PAGE60
  DU76 M_K_DQ<25> @BASEBOARD_FAB2_LIB.BASEBOARD_FAB2(SCH_1):M_K_DQ(25)   I172 @BASEBOARD_FAB2_LIB.BASEBOARD_FAB2(SCH_1):PAGE60
  DN76 M_K_DQ<24> @BASEBOARD_FAB2_LIB.BASEBOARD_FAB2(SCH_1):M_K_DQ(24)   I172 @BASEBOARD_FAB2_LIB.BASEBOARD_FAB2(SCH_1):PAGE60
  DN82 M_K_DQ<23> @BASEBOARD_FAB2_LIB.BASEBOARD_FAB2(SCH_1):M_K_DQ(23)   I172 @BASEBOARD_FAB2_LIB.BASEBOARD_FAB2(SCH_1):PAGE60
  DR80 M_K_DQ<22> @BASEBOARD_FAB2_LIB.BASEBOARD_FAB2(SCH_1):M_K_DQ(22)   I172 @BASEBOARD_FAB2_LIB.BASEBOARD_FAB2(SCH_1):PAGE60
  DJ80 M_K_DQ<21> @BASEBOARD_FAB2_LIB.BASEBOARD_FAB2(SCH_1):M_K_DQ(21)   I172 @BASEBOARD_FAB2_LIB.BASEBOARD_FAB2(SCH_1):PAGE60
  DK79 M_K_DQ<20> @BASEBOARD_FAB2_LIB.BASEBOARD_FAB2(SCH_1):M_K_DQ(20)   I172 @BASEBOARD_FAB2_LIB.BASEBOARD_FAB2(SCH_1):PAGE60
  DR82 M_K_DQ<19> @BASEBOARD_FAB2_LIB.BASEBOARD_FAB2(SCH_1):M_K_DQ(19)   I172 @BASEBOARD_FAB2_LIB.BASEBOARD_FAB2(SCH_1):PAGE60
  DT81 M_K_DQ<18> @BASEBOARD_FAB2_LIB.BASEBOARD_FAB2(SCH_1):M_K_DQ(18)   I172 @BASEBOARD_FAB2_LIB.BASEBOARD_FAB2(SCH_1):PAGE60
  DK81 M_K_DQ<17> @BASEBOARD_FAB2_LIB.BASEBOARD_FAB2(SCH_1):M_K_DQ(17)   I172 @BASEBOARD_FAB2_LIB.BASEBOARD_FAB2(SCH_1):PAGE60
  DM79 M_K_DQ<16> @BASEBOARD_FAB2_LIB.BASEBOARD_FAB2(SCH_1):M_K_DQ(16)   I172 @BASEBOARD_FAB2_LIB.BASEBOARD_FAB2(SCH_1):PAGE60
  DV85 M_K_DQ<15> @BASEBOARD_FAB2_LIB.BASEBOARD_FAB2(SCH_1):M_K_DQ(15)   I172 @BASEBOARD_FAB2_LIB.BASEBOARD_FAB2(SCH_1):PAGE60
  DR84 M_K_DQ<14> @BASEBOARD_FAB2_LIB.BASEBOARD_FAB2(SCH_1):M_K_DQ(14)   I172 @BASEBOARD_FAB2_LIB.BASEBOARD_FAB2(SCH_1):PAGE60
  DE84 M_K_DQ<13> @BASEBOARD_FAB2_LIB.BASEBOARD_FAB2(SCH_1):M_K_DQ(13)   I172 @BASEBOARD_FAB2_LIB.BASEBOARD_FAB2(SCH_1):PAGE60
  DD85 M_K_DQ<12> @BASEBOARD_FAB2_LIB.BASEBOARD_FAB2(SCH_1):M_K_DQ(12)   I172 @BASEBOARD_FAB2_LIB.BASEBOARD_FAB2(SCH_1):PAGE60
  DY83 M_K_DQ<11> @BASEBOARD_FAB2_LIB.BASEBOARD_FAB2(SCH_1):M_K_DQ(11)   I172 @BASEBOARD_FAB2_LIB.BASEBOARD_FAB2(SCH_1):PAGE60
  DV83 M_K_DQ<10> @BASEBOARD_FAB2_LIB.BASEBOARD_FAB2(SCH_1):M_K_DQ(10)   I172 @BASEBOARD_FAB2_LIB.BASEBOARD_FAB2(SCH_1):PAGE60
  DH85 M_K_DQ<9> @BASEBOARD_FAB2_LIB.BASEBOARD_FAB2(SCH_1):M_K_DQ(9)   I172 @BASEBOARD_FAB2_LIB.BASEBOARD_FAB2(SCH_1):PAGE60
  DG84 M_K_DQ<8> @BASEBOARD_FAB2_LIB.BASEBOARD_FAB2(SCH_1):M_K_DQ(8)   I172 @BASEBOARD_FAB2_LIB.BASEBOARD_FAB2(SCH_1):PAGE60
  CW84 M_K_DQ<7> @BASEBOARD_FAB2_LIB.BASEBOARD_FAB2(SCH_1):M_K_DQ(7)   I172 @BASEBOARD_FAB2_LIB.BASEBOARD_FAB2(SCH_1):PAGE60
  CW86 M_K_DQ<6> @BASEBOARD_FAB2_LIB.BASEBOARD_FAB2(SCH_1):M_K_DQ(6)   I172 @BASEBOARD_FAB2_LIB.BASEBOARD_FAB2(SCH_1):PAGE60
  CL86 M_K_DQ<5> @BASEBOARD_FAB2_LIB.BASEBOARD_FAB2(SCH_1):M_K_DQ(5)   I172 @BASEBOARD_FAB2_LIB.BASEBOARD_FAB2(SCH_1):PAGE60
  CL84 M_K_DQ<4> @BASEBOARD_FAB2_LIB.BASEBOARD_FAB2(SCH_1):M_K_DQ(4)   I172 @BASEBOARD_FAB2_LIB.BASEBOARD_FAB2(SCH_1):PAGE60
  DA84 M_K_DQ<3> @BASEBOARD_FAB2_LIB.BASEBOARD_FAB2(SCH_1):M_K_DQ(3)   I172 @BASEBOARD_FAB2_LIB.BASEBOARD_FAB2(SCH_1):PAGE60
  DA86 M_K_DQ<2> @BASEBOARD_FAB2_LIB.BASEBOARD_FAB2(SCH_1):M_K_DQ(2)   I172 @BASEBOARD_FAB2_LIB.BASEBOARD_FAB2(SCH_1):PAGE60
  CN86 M_K_DQ<1> @BASEBOARD_FAB2_LIB.BASEBOARD_FAB2(SCH_1):M_K_DQ(1)   I172 @BASEBOARD_FAB2_LIB.BASEBOARD_FAB2(SCH_1):PAGE60
  CN84 M_K_DQ<0> @BASEBOARD_FAB2_LIB.BASEBOARD_FAB2(SCH_1):M_K_DQ(0)   I172 @BASEBOARD_FAB2_LIB.BASEBOARD_FAB2(SCH_1):PAGE60
  DB67 M_K_DQS_DN<17> @BASEBOARD_FAB2_LIB.BASEBOARD_FAB2(SCH_1):M_K_DQS_DN(17)   I172 @BASEBOARD_FAB2_LIB.BASEBOARD_FAB2(SCH_1):PAGE60
  DM23 M_K_DQS_DN<16> @BASEBOARD_FAB2_LIB.BASEBOARD_FAB2(SCH_1):M_K_DQS_DN(16)   I172 @BASEBOARD_FAB2_LIB.BASEBOARD_FAB2(SCH_1):PAGE60
  DM29 M_K_DQS_DN<15> @BASEBOARD_FAB2_LIB.BASEBOARD_FAB2(SCH_1):M_K_DQS_DN(15)   I172 @BASEBOARD_FAB2_LIB.BASEBOARD_FAB2(SCH_1):PAGE60
  DP35 M_K_DQS_DN<14> @BASEBOARD_FAB2_LIB.BASEBOARD_FAB2(SCH_1):M_K_DQS_DN(14)   I172 @BASEBOARD_FAB2_LIB.BASEBOARD_FAB2(SCH_1):PAGE60
  EA38 M_K_DQS_DN<13> @BASEBOARD_FAB2_LIB.BASEBOARD_FAB2(SCH_1):M_K_DQS_DN(13)   I172 @BASEBOARD_FAB2_LIB.BASEBOARD_FAB2(SCH_1):PAGE60
  DP75 M_K_DQS_DN<12> @BASEBOARD_FAB2_LIB.BASEBOARD_FAB2(SCH_1):M_K_DQS_DN(12)   I172 @BASEBOARD_FAB2_LIB.BASEBOARD_FAB2(SCH_1):PAGE60
  DN80 M_K_DQS_DN<11> @BASEBOARD_FAB2_LIB.BASEBOARD_FAB2(SCH_1):M_K_DQS_DN(11)   I172 @BASEBOARD_FAB2_LIB.BASEBOARD_FAB2(SCH_1):PAGE60
  DM85 M_K_DQS_DN<10> @BASEBOARD_FAB2_LIB.BASEBOARD_FAB2(SCH_1):M_K_DQS_DN(10)   I172 @BASEBOARD_FAB2_LIB.BASEBOARD_FAB2(SCH_1):PAGE60
  CR84 M_K_DQS_DN<9> @BASEBOARD_FAB2_LIB.BASEBOARD_FAB2(SCH_1):M_K_DQS_DN(9)   I172 @BASEBOARD_FAB2_LIB.BASEBOARD_FAB2(SCH_1):PAGE60
  DF67 M_K_DQS_DN<8> @BASEBOARD_FAB2_LIB.BASEBOARD_FAB2(SCH_1):M_K_DQS_DN(8)   I172 @BASEBOARD_FAB2_LIB.BASEBOARD_FAB2(SCH_1):PAGE60
  DV23 M_K_DQS_DN<7> @BASEBOARD_FAB2_LIB.BASEBOARD_FAB2(SCH_1):M_K_DQS_DN(7)   I172 @BASEBOARD_FAB2_LIB.BASEBOARD_FAB2(SCH_1):PAGE60
  DV29 M_K_DQS_DN<6> @BASEBOARD_FAB2_LIB.BASEBOARD_FAB2(SCH_1):M_K_DQS_DN(6)   I172 @BASEBOARD_FAB2_LIB.BASEBOARD_FAB2(SCH_1):PAGE60
  DV35 M_K_DQS_DN<5> @BASEBOARD_FAB2_LIB.BASEBOARD_FAB2(SCH_1):M_K_DQS_DN(5)   I172 @BASEBOARD_FAB2_LIB.BASEBOARD_FAB2(SCH_1):PAGE60
  EE38 M_K_DQS_DN<4> @BASEBOARD_FAB2_LIB.BASEBOARD_FAB2(SCH_1):M_K_DQS_DN(4)   I172 @BASEBOARD_FAB2_LIB.BASEBOARD_FAB2(SCH_1):PAGE60
  DV75 M_K_DQS_DN<3> @BASEBOARD_FAB2_LIB.BASEBOARD_FAB2(SCH_1):M_K_DQS_DN(3)   I172 @BASEBOARD_FAB2_LIB.BASEBOARD_FAB2(SCH_1):PAGE60
  DL82 M_K_DQS_DN<2> @BASEBOARD_FAB2_LIB.BASEBOARD_FAB2(SCH_1):M_K_DQS_DN(2)   I172 @BASEBOARD_FAB2_LIB.BASEBOARD_FAB2(SCH_1):PAGE60
  DN84 M_K_DQS_DN<1> @BASEBOARD_FAB2_LIB.BASEBOARD_FAB2(SCH_1):M_K_DQS_DN(1)   I172 @BASEBOARD_FAB2_LIB.BASEBOARD_FAB2(SCH_1):PAGE60
  CU84 M_K_DQS_DN<0> @BASEBOARD_FAB2_LIB.BASEBOARD_FAB2(SCH_1):M_K_DQS_DN(0)   I172 @BASEBOARD_FAB2_LIB.BASEBOARD_FAB2(SCH_1):PAGE60
  CY67 M_K_DQS_DP<17> @BASEBOARD_FAB2_LIB.BASEBOARD_FAB2(SCH_1):M_K_DQS_DP(17)   I172 @BASEBOARD_FAB2_LIB.BASEBOARD_FAB2(SCH_1):PAGE60
  DP23 M_K_DQS_DP<16> @BASEBOARD_FAB2_LIB.BASEBOARD_FAB2(SCH_1):M_K_DQS_DP(16)   I172 @BASEBOARD_FAB2_LIB.BASEBOARD_FAB2(SCH_1):PAGE60
  DP29 M_K_DQS_DP<15> @BASEBOARD_FAB2_LIB.BASEBOARD_FAB2(SCH_1):M_K_DQS_DP(15)   I172 @BASEBOARD_FAB2_LIB.BASEBOARD_FAB2(SCH_1):PAGE60
  DM35 M_K_DQS_DP<14> @BASEBOARD_FAB2_LIB.BASEBOARD_FAB2(SCH_1):M_K_DQS_DP(14)   I172 @BASEBOARD_FAB2_LIB.BASEBOARD_FAB2(SCH_1):PAGE60
  DW38 M_K_DQS_DP<13> @BASEBOARD_FAB2_LIB.BASEBOARD_FAB2(SCH_1):M_K_DQS_DP(13)   I172 @BASEBOARD_FAB2_LIB.BASEBOARD_FAB2(SCH_1):PAGE60
  DM75 M_K_DQS_DP<12> @BASEBOARD_FAB2_LIB.BASEBOARD_FAB2(SCH_1):M_K_DQS_DP(12)   I172 @BASEBOARD_FAB2_LIB.BASEBOARD_FAB2(SCH_1):PAGE60
  DP79 M_K_DQS_DP<11> @BASEBOARD_FAB2_LIB.BASEBOARD_FAB2(SCH_1):M_K_DQS_DP(11)   I172 @BASEBOARD_FAB2_LIB.BASEBOARD_FAB2(SCH_1):PAGE60
  DL84 M_K_DQS_DP<10> @BASEBOARD_FAB2_LIB.BASEBOARD_FAB2(SCH_1):M_K_DQS_DP(10)   I172 @BASEBOARD_FAB2_LIB.BASEBOARD_FAB2(SCH_1):PAGE60
  CP85 M_K_DQS_DP<9> @BASEBOARD_FAB2_LIB.BASEBOARD_FAB2(SCH_1):M_K_DQS_DP(9)   I172 @BASEBOARD_FAB2_LIB.BASEBOARD_FAB2(SCH_1):PAGE60
  DD67 M_K_DQS_DP<8> @BASEBOARD_FAB2_LIB.BASEBOARD_FAB2(SCH_1):M_K_DQS_DP(8)   I172 @BASEBOARD_FAB2_LIB.BASEBOARD_FAB2(SCH_1):PAGE60
  DT23 M_K_DQS_DP<7> @BASEBOARD_FAB2_LIB.BASEBOARD_FAB2(SCH_1):M_K_DQS_DP(7)   I172 @BASEBOARD_FAB2_LIB.BASEBOARD_FAB2(SCH_1):PAGE60
  DT29 M_K_DQS_DP<6> @BASEBOARD_FAB2_LIB.BASEBOARD_FAB2(SCH_1):M_K_DQS_DP(6)   I172 @BASEBOARD_FAB2_LIB.BASEBOARD_FAB2(SCH_1):PAGE60
  DT35 M_K_DQS_DP<5> @BASEBOARD_FAB2_LIB.BASEBOARD_FAB2(SCH_1):M_K_DQS_DP(5)   I172 @BASEBOARD_FAB2_LIB.BASEBOARD_FAB2(SCH_1):PAGE60
  EC38 M_K_DQS_DP<4> @BASEBOARD_FAB2_LIB.BASEBOARD_FAB2(SCH_1):M_K_DQS_DP(4)   I172 @BASEBOARD_FAB2_LIB.BASEBOARD_FAB2(SCH_1):PAGE60
  DT75 M_K_DQS_DP<3> @BASEBOARD_FAB2_LIB.BASEBOARD_FAB2(SCH_1):M_K_DQS_DP(3)   I172 @BASEBOARD_FAB2_LIB.BASEBOARD_FAB2(SCH_1):PAGE60
  DM81 M_K_DQS_DP<2> @BASEBOARD_FAB2_LIB.BASEBOARD_FAB2(SCH_1):M_K_DQS_DP(2)   I172 @BASEBOARD_FAB2_LIB.BASEBOARD_FAB2(SCH_1):PAGE60
  DP85 M_K_DQS_DP<1> @BASEBOARD_FAB2_LIB.BASEBOARD_FAB2(SCH_1):M_K_DQS_DP(1)   I172 @BASEBOARD_FAB2_LIB.BASEBOARD_FAB2(SCH_1):PAGE60
  CV85 M_K_DQS_DP<0> @BASEBOARD_FAB2_LIB.BASEBOARD_FAB2(SCH_1):M_K_DQS_DP(0)   I172 @BASEBOARD_FAB2_LIB.BASEBOARD_FAB2(SCH_1):PAGE60
  DE66 M_K_ECC<7> @BASEBOARD_FAB2_LIB.BASEBOARD_FAB2(SCH_1):M_K_ECC(7)   I172 @BASEBOARD_FAB2_LIB.BASEBOARD_FAB2(SCH_1):PAGE60
  DA66 M_K_ECC<6> @BASEBOARD_FAB2_LIB.BASEBOARD_FAB2(SCH_1):M_K_ECC(6)   I172 @BASEBOARD_FAB2_LIB.BASEBOARD_FAB2(SCH_1):PAGE60
  DD69 M_K_ECC<5> @BASEBOARD_FAB2_LIB.BASEBOARD_FAB2(SCH_1):M_K_ECC(5)   I172 @BASEBOARD_FAB2_LIB.BASEBOARD_FAB2(SCH_1):PAGE60
  DB69 M_K_ECC<4> @BASEBOARD_FAB2_LIB.BASEBOARD_FAB2(SCH_1):M_K_ECC(4)   I172 @BASEBOARD_FAB2_LIB.BASEBOARD_FAB2(SCH_1):PAGE60
  DD65 M_K_ECC<3> @BASEBOARD_FAB2_LIB.BASEBOARD_FAB2(SCH_1):M_K_ECC(3)   I172 @BASEBOARD_FAB2_LIB.BASEBOARD_FAB2(SCH_1):PAGE60
  DB65 M_K_ECC<2> @BASEBOARD_FAB2_LIB.BASEBOARD_FAB2(SCH_1):M_K_ECC(2)   I172 @BASEBOARD_FAB2_LIB.BASEBOARD_FAB2(SCH_1):PAGE60
  DE68 M_K_ECC<1> @BASEBOARD_FAB2_LIB.BASEBOARD_FAB2(SCH_1):M_K_ECC(1)   I172 @BASEBOARD_FAB2_LIB.BASEBOARD_FAB2(SCH_1):PAGE60
  DA68 M_K_ECC<0> @BASEBOARD_FAB2_LIB.BASEBOARD_FAB2(SCH_1):M_K_ECC(0)   I172 @BASEBOARD_FAB2_LIB.BASEBOARD_FAB2(SCH_1):PAGE60
  EA46 M_K_MA<17> @BASEBOARD_FAB2_LIB.BASEBOARD_FAB2(SCH_1):M_K_MA(17)   I172 @BASEBOARD_FAB2_LIB.BASEBOARD_FAB2(SCH_1):PAGE60
  EA52 M_K_MA<16> @BASEBOARD_FAB2_LIB.BASEBOARD_FAB2(SCH_1):M_K_MA(16)   I172 @BASEBOARD_FAB2_LIB.BASEBOARD_FAB2(SCH_1):PAGE60
  DV49 M_K_MA<15> @BASEBOARD_FAB2_LIB.BASEBOARD_FAB2(SCH_1):M_K_MA(15)   I172 @BASEBOARD_FAB2_LIB.BASEBOARD_FAB2(SCH_1):PAGE60
  ED51 M_K_MA<14> @BASEBOARD_FAB2_LIB.BASEBOARD_FAB2(SCH_1):M_K_MA(14)   I172 @BASEBOARD_FAB2_LIB.BASEBOARD_FAB2(SCH_1):PAGE60
  DW48 M_K_MA<13> @BASEBOARD_FAB2_LIB.BASEBOARD_FAB2(SCH_1):M_K_MA(13)   I172 @BASEBOARD_FAB2_LIB.BASEBOARD_FAB2(SCH_1):PAGE60
  DT63 M_K_MA<12> @BASEBOARD_FAB2_LIB.BASEBOARD_FAB2(SCH_1):M_K_MA(12)   I172 @BASEBOARD_FAB2_LIB.BASEBOARD_FAB2(SCH_1):PAGE60
  EB61 M_K_MA<11> @BASEBOARD_FAB2_LIB.BASEBOARD_FAB2(SCH_1):M_K_MA(11)   I172 @BASEBOARD_FAB2_LIB.BASEBOARD_FAB2(SCH_1):PAGE60
  DW54 M_K_MA<10> @BASEBOARD_FAB2_LIB.BASEBOARD_FAB2(SCH_1):M_K_MA(10)   I172 @BASEBOARD_FAB2_LIB.BASEBOARD_FAB2(SCH_1):PAGE60
  EF61 M_K_MA<9> @BASEBOARD_FAB2_LIB.BASEBOARD_FAB2(SCH_1):M_K_MA(9)   I172 @BASEBOARD_FAB2_LIB.BASEBOARD_FAB2(SCH_1):PAGE60
  EB59 M_K_MA<8> @BASEBOARD_FAB2_LIB.BASEBOARD_FAB2(SCH_1):M_K_MA(8)   I172 @BASEBOARD_FAB2_LIB.BASEBOARD_FAB2(SCH_1):PAGE60
  EA60 M_K_MA<7> @BASEBOARD_FAB2_LIB.BASEBOARD_FAB2(SCH_1):M_K_MA(7)   I172 @BASEBOARD_FAB2_LIB.BASEBOARD_FAB2(SCH_1):PAGE60
  EE60 M_K_MA<6> @BASEBOARD_FAB2_LIB.BASEBOARD_FAB2(SCH_1):M_K_MA(6)   I172 @BASEBOARD_FAB2_LIB.BASEBOARD_FAB2(SCH_1):PAGE60
  EA58 M_K_MA<5> @BASEBOARD_FAB2_LIB.BASEBOARD_FAB2(SCH_1):M_K_MA(5)   I172 @BASEBOARD_FAB2_LIB.BASEBOARD_FAB2(SCH_1):PAGE60
  ED59 M_K_MA<4> @BASEBOARD_FAB2_LIB.BASEBOARD_FAB2(SCH_1):M_K_MA(4)   I172 @BASEBOARD_FAB2_LIB.BASEBOARD_FAB2(SCH_1):PAGE60
  EB57 M_K_MA<3> @BASEBOARD_FAB2_LIB.BASEBOARD_FAB2(SCH_1):M_K_MA(3)   I172 @BASEBOARD_FAB2_LIB.BASEBOARD_FAB2(SCH_1):PAGE60
  EE58 M_K_MA<2> @BASEBOARD_FAB2_LIB.BASEBOARD_FAB2(SCH_1):M_K_MA(2)   I172 @BASEBOARD_FAB2_LIB.BASEBOARD_FAB2(SCH_1):PAGE60
  ED57 M_K_MA<1> @BASEBOARD_FAB2_LIB.BASEBOARD_FAB2(SCH_1):M_K_MA(1)   I172 @BASEBOARD_FAB2_LIB.BASEBOARD_FAB2(SCH_1):PAGE60
  EB53 M_K_MA<0> @BASEBOARD_FAB2_LIB.BASEBOARD_FAB2(SCH_1):M_K_MA(0)   I172 @BASEBOARD_FAB2_LIB.BASEBOARD_FAB2(SCH_1):PAGE60
  EA48 M_K_ODT<3> @BASEBOARD_FAB2_LIB.BASEBOARD_FAB2(SCH_1):M_K_ODT(3)   I172 @BASEBOARD_FAB2_LIB.BASEBOARD_FAB2(SCH_1):PAGE60
  EA50 M_K_ODT<2> @BASEBOARD_FAB2_LIB.BASEBOARD_FAB2(SCH_1):M_K_ODT(2)   I172 @BASEBOARD_FAB2_LIB.BASEBOARD_FAB2(SCH_1):PAGE60
  EE48 M_K_ODT<1> @BASEBOARD_FAB2_LIB.BASEBOARD_FAB2(SCH_1):M_K_ODT(1)   I172 @BASEBOARD_FAB2_LIB.BASEBOARD_FAB2(SCH_1):PAGE60
  EE50 M_K_ODT<0> @BASEBOARD_FAB2_LIB.BASEBOARD_FAB2(SCH_1):M_K_ODT(0)   I172 @BASEBOARD_FAB2_LIB.BASEBOARD_FAB2(SCH_1):PAGE60
  ED53 M_K_PAR @BASEBOARD_FAB2_LIB.BASEBOARD_FAB2(SCH_1):M_K_PAR   I172 @BASEBOARD_FAB2_LIB.BASEBOARD_FAB2(SCH_1):PAGE60
  DR62 M_L_ACT_N @BASEBOARD_FAB2_LIB.BASEBOARD_FAB2(SCH_1):M_L_ACT_N   I172 @BASEBOARD_FAB2_LIB.BASEBOARD_FAB2(SCH_1):PAGE61
  DT61 M_L_ALERT_N @BASEBOARD_FAB2_LIB.BASEBOARD_FAB2(SCH_1):M_L_ALERT_N   I172 @BASEBOARD_FAB2_LIB.BASEBOARD_FAB2(SCH_1):PAGE61
  DV55 M_L_BA<1> @BASEBOARD_FAB2_LIB.BASEBOARD_FAB2(SCH_1):M_L_BA(1)   I172 @BASEBOARD_FAB2_LIB.BASEBOARD_FAB2(SCH_1):PAGE61
  DM53 M_L_BA<0> @BASEBOARD_FAB2_LIB.BASEBOARD_FAB2(SCH_1):M_L_BA(0)   I172 @BASEBOARD_FAB2_LIB.BASEBOARD_FAB2(SCH_1):PAGE61
  DM61 M_L_BG<1> @BASEBOARD_FAB2_LIB.BASEBOARD_FAB2(SCH_1):M_L_BG(1)   I172 @BASEBOARD_FAB2_LIB.BASEBOARD_FAB2(SCH_1):PAGE61
  DJ62 M_L_BG<0> @BASEBOARD_FAB2_LIB.BASEBOARD_FAB2(SCH_1):M_L_BG(0)   I172 @BASEBOARD_FAB2_LIB.BASEBOARD_FAB2(SCH_1):PAGE61
  DT47 M_L_C<2> @BASEBOARD_FAB2_LIB.BASEBOARD_FAB2(SCH_1):M_L_C(2)   I172 @BASEBOARD_FAB2_LIB.BASEBOARD_FAB2(SCH_1):PAGE61
  DR64 M_L_CKE<3> @BASEBOARD_FAB2_LIB.BASEBOARD_FAB2(SCH_1):M_L_CKE(3)   I172 @BASEBOARD_FAB2_LIB.BASEBOARD_FAB2(SCH_1):PAGE61
  DL64 M_L_CKE<2> @BASEBOARD_FAB2_LIB.BASEBOARD_FAB2(SCH_1):M_L_CKE(2)   I172 @BASEBOARD_FAB2_LIB.BASEBOARD_FAB2(SCH_1):PAGE61
  DN64 M_L_CKE<1> @BASEBOARD_FAB2_LIB.BASEBOARD_FAB2(SCH_1):M_L_CKE(1)   I172 @BASEBOARD_FAB2_LIB.BASEBOARD_FAB2(SCH_1):PAGE61
  DM63 M_L_CKE<0> @BASEBOARD_FAB2_LIB.BASEBOARD_FAB2(SCH_1):M_L_CKE(0)   I172 @BASEBOARD_FAB2_LIB.BASEBOARD_FAB2(SCH_1):PAGE61
  DT57 M_L_CLK_DN<3> @BASEBOARD_FAB2_LIB.BASEBOARD_FAB2(SCH_1):M_L_CLK_DN(3)   I172 @BASEBOARD_FAB2_LIB.BASEBOARD_FAB2(SCH_1):PAGE61
  DM57 M_L_CLK_DN<2> @BASEBOARD_FAB2_LIB.BASEBOARD_FAB2(SCH_1):M_L_CLK_DN(2)   I172 @BASEBOARD_FAB2_LIB.BASEBOARD_FAB2(SCH_1):PAGE61
  DR54 M_L_CLK_DN<1> @BASEBOARD_FAB2_LIB.BASEBOARD_FAB2(SCH_1):M_L_CLK_DN(1)   I172 @BASEBOARD_FAB2_LIB.BASEBOARD_FAB2(SCH_1):PAGE61
  DM55 M_L_CLK_DN<0> @BASEBOARD_FAB2_LIB.BASEBOARD_FAB2(SCH_1):M_L_CLK_DN(0)   I172 @BASEBOARD_FAB2_LIB.BASEBOARD_FAB2(SCH_1):PAGE61
  DR56 M_L_CLK_DP<3> @BASEBOARD_FAB2_LIB.BASEBOARD_FAB2(SCH_1):M_L_CLK_DP(3)   I172 @BASEBOARD_FAB2_LIB.BASEBOARD_FAB2(SCH_1):PAGE61
  DN56 M_L_CLK_DP<2> @BASEBOARD_FAB2_LIB.BASEBOARD_FAB2(SCH_1):M_L_CLK_DP(2)   I172 @BASEBOARD_FAB2_LIB.BASEBOARD_FAB2(SCH_1):PAGE61
  DT53 M_L_CLK_DP<1> @BASEBOARD_FAB2_LIB.BASEBOARD_FAB2(SCH_1):M_L_CLK_DP(1)   I172 @BASEBOARD_FAB2_LIB.BASEBOARD_FAB2(SCH_1):PAGE61
  DN54 M_L_CLK_DP<0> @BASEBOARD_FAB2_LIB.BASEBOARD_FAB2(SCH_1):M_L_CLK_DP(0)   I172 @BASEBOARD_FAB2_LIB.BASEBOARD_FAB2(SCH_1):PAGE61
  DN46 M_L_CS_N<7> @BASEBOARD_FAB2_LIB.BASEBOARD_FAB2(SCH_1):M_L_CS_N(7)   I172 @BASEBOARD_FAB2_LIB.BASEBOARD_FAB2(SCH_1):PAGE61
  DT45 M_L_CS_N<6> @BASEBOARD_FAB2_LIB.BASEBOARD_FAB2(SCH_1):M_L_CS_N(6)   I172 @BASEBOARD_FAB2_LIB.BASEBOARD_FAB2(SCH_1):PAGE61
  DM49 M_L_CS_N<5> @BASEBOARD_FAB2_LIB.BASEBOARD_FAB2(SCH_1):M_L_CS_N(5)   I172 @BASEBOARD_FAB2_LIB.BASEBOARD_FAB2(SCH_1):PAGE61
  DW50 M_L_CS_N<4> @BASEBOARD_FAB2_LIB.BASEBOARD_FAB2(SCH_1):M_L_CS_N(4)   I172 @BASEBOARD_FAB2_LIB.BASEBOARD_FAB2(SCH_1):PAGE61
  DK47 M_L_CS_N<3> @BASEBOARD_FAB2_LIB.BASEBOARD_FAB2(SCH_1):M_L_CS_N(3)   I172 @BASEBOARD_FAB2_LIB.BASEBOARD_FAB2(SCH_1):PAGE61
  DR46 M_L_CS_N<2> @BASEBOARD_FAB2_LIB.BASEBOARD_FAB2(SCH_1):M_L_CS_N(2)   I172 @BASEBOARD_FAB2_LIB.BASEBOARD_FAB2(SCH_1):PAGE61
  DN50 M_L_CS_N<1> @BASEBOARD_FAB2_LIB.BASEBOARD_FAB2(SCH_1):M_L_CS_N(1)   I172 @BASEBOARD_FAB2_LIB.BASEBOARD_FAB2(SCH_1):PAGE61
  DV51 M_L_CS_N<0> @BASEBOARD_FAB2_LIB.BASEBOARD_FAB2(SCH_1):M_L_CS_N(0)   I172 @BASEBOARD_FAB2_LIB.BASEBOARD_FAB2(SCH_1):PAGE61
  DK25 M_L_DQ<63> @BASEBOARD_FAB2_LIB.BASEBOARD_FAB2(SCH_1):M_L_DQ(63)   I172 @BASEBOARD_FAB2_LIB.BASEBOARD_FAB2(SCH_1):PAGE61
  DF25 M_L_DQ<62> @BASEBOARD_FAB2_LIB.BASEBOARD_FAB2(SCH_1):M_L_DQ(62)   I172 @BASEBOARD_FAB2_LIB.BASEBOARD_FAB2(SCH_1):PAGE61
  DJ28 M_L_DQ<61> @BASEBOARD_FAB2_LIB.BASEBOARD_FAB2(SCH_1):M_L_DQ(61)   I172 @BASEBOARD_FAB2_LIB.BASEBOARD_FAB2(SCH_1):PAGE61
  DG28 M_L_DQ<60> @BASEBOARD_FAB2_LIB.BASEBOARD_FAB2(SCH_1):M_L_DQ(60)   I172 @BASEBOARD_FAB2_LIB.BASEBOARD_FAB2(SCH_1):PAGE61
  DJ24 M_L_DQ<59> @BASEBOARD_FAB2_LIB.BASEBOARD_FAB2(SCH_1):M_L_DQ(59)   I172 @BASEBOARD_FAB2_LIB.BASEBOARD_FAB2(SCH_1):PAGE61
  DD25 M_L_DQ<58> @BASEBOARD_FAB2_LIB.BASEBOARD_FAB2(SCH_1):M_L_DQ(58)   I172 @BASEBOARD_FAB2_LIB.BASEBOARD_FAB2(SCH_1):PAGE61
  DK27 M_L_DQ<57> @BASEBOARD_FAB2_LIB.BASEBOARD_FAB2(SCH_1):M_L_DQ(57)   I172 @BASEBOARD_FAB2_LIB.BASEBOARD_FAB2(SCH_1):PAGE61
  DF27 M_L_DQ<56> @BASEBOARD_FAB2_LIB.BASEBOARD_FAB2(SCH_1):M_L_DQ(56)   I172 @BASEBOARD_FAB2_LIB.BASEBOARD_FAB2(SCH_1):PAGE61
  ED25 M_L_DQ<55> @BASEBOARD_FAB2_LIB.BASEBOARD_FAB2(SCH_1):M_L_DQ(55)   I172 @BASEBOARD_FAB2_LIB.BASEBOARD_FAB2(SCH_1):PAGE61
  DY25 M_L_DQ<54> @BASEBOARD_FAB2_LIB.BASEBOARD_FAB2(SCH_1):M_L_DQ(54)   I172 @BASEBOARD_FAB2_LIB.BASEBOARD_FAB2(SCH_1):PAGE61
  EA28 M_L_DQ<53> @BASEBOARD_FAB2_LIB.BASEBOARD_FAB2(SCH_1):M_L_DQ(53)   I172 @BASEBOARD_FAB2_LIB.BASEBOARD_FAB2(SCH_1):PAGE61
  DY27 M_L_DQ<52> @BASEBOARD_FAB2_LIB.BASEBOARD_FAB2(SCH_1):M_L_DQ(52)   I172 @BASEBOARD_FAB2_LIB.BASEBOARD_FAB2(SCH_1):PAGE61
  EC24 M_L_DQ<51> @BASEBOARD_FAB2_LIB.BASEBOARD_FAB2(SCH_1):M_L_DQ(51)   I172 @BASEBOARD_FAB2_LIB.BASEBOARD_FAB2(SCH_1):PAGE61
  EA24 M_L_DQ<50> @BASEBOARD_FAB2_LIB.BASEBOARD_FAB2(SCH_1):M_L_DQ(50)   I172 @BASEBOARD_FAB2_LIB.BASEBOARD_FAB2(SCH_1):PAGE61
  ED27 M_L_DQ<49> @BASEBOARD_FAB2_LIB.BASEBOARD_FAB2(SCH_1):M_L_DQ(49)   I172 @BASEBOARD_FAB2_LIB.BASEBOARD_FAB2(SCH_1):PAGE61
  EC28 M_L_DQ<48> @BASEBOARD_FAB2_LIB.BASEBOARD_FAB2(SCH_1):M_L_DQ(48)   I172 @BASEBOARD_FAB2_LIB.BASEBOARD_FAB2(SCH_1):PAGE61
  ED31 M_L_DQ<47> @BASEBOARD_FAB2_LIB.BASEBOARD_FAB2(SCH_1):M_L_DQ(47)   I172 @BASEBOARD_FAB2_LIB.BASEBOARD_FAB2(SCH_1):PAGE61
  DY31 M_L_DQ<46> @BASEBOARD_FAB2_LIB.BASEBOARD_FAB2(SCH_1):M_L_DQ(46)   I172 @BASEBOARD_FAB2_LIB.BASEBOARD_FAB2(SCH_1):PAGE61
  EA34 M_L_DQ<45> @BASEBOARD_FAB2_LIB.BASEBOARD_FAB2(SCH_1):M_L_DQ(45)   I172 @BASEBOARD_FAB2_LIB.BASEBOARD_FAB2(SCH_1):PAGE61
  DY33 M_L_DQ<44> @BASEBOARD_FAB2_LIB.BASEBOARD_FAB2(SCH_1):M_L_DQ(44)   I172 @BASEBOARD_FAB2_LIB.BASEBOARD_FAB2(SCH_1):PAGE61
  EC30 M_L_DQ<43> @BASEBOARD_FAB2_LIB.BASEBOARD_FAB2(SCH_1):M_L_DQ(43)   I172 @BASEBOARD_FAB2_LIB.BASEBOARD_FAB2(SCH_1):PAGE61
  EA30 M_L_DQ<42> @BASEBOARD_FAB2_LIB.BASEBOARD_FAB2(SCH_1):M_L_DQ(42)   I172 @BASEBOARD_FAB2_LIB.BASEBOARD_FAB2(SCH_1):PAGE61
  ED33 M_L_DQ<41> @BASEBOARD_FAB2_LIB.BASEBOARD_FAB2(SCH_1):M_L_DQ(41)   I172 @BASEBOARD_FAB2_LIB.BASEBOARD_FAB2(SCH_1):PAGE61
  EC34 M_L_DQ<40> @BASEBOARD_FAB2_LIB.BASEBOARD_FAB2(SCH_1):M_L_DQ(40)   I172 @BASEBOARD_FAB2_LIB.BASEBOARD_FAB2(SCH_1):PAGE61
  DU40 M_L_DQ<39> @BASEBOARD_FAB2_LIB.BASEBOARD_FAB2(SCH_1):M_L_DQ(39)   I172 @BASEBOARD_FAB2_LIB.BASEBOARD_FAB2(SCH_1):PAGE61
  DN40 M_L_DQ<38> @BASEBOARD_FAB2_LIB.BASEBOARD_FAB2(SCH_1):M_L_DQ(38)   I172 @BASEBOARD_FAB2_LIB.BASEBOARD_FAB2(SCH_1):PAGE61
  DN42 M_L_DQ<37> @BASEBOARD_FAB2_LIB.BASEBOARD_FAB2(SCH_1):M_L_DQ(37)   I172 @BASEBOARD_FAB2_LIB.BASEBOARD_FAB2(SCH_1):PAGE61
  DL42 M_L_DQ<36> @BASEBOARD_FAB2_LIB.BASEBOARD_FAB2(SCH_1):M_L_DQ(36)   I172 @BASEBOARD_FAB2_LIB.BASEBOARD_FAB2(SCH_1):PAGE61
  DT39 M_L_DQ<35> @BASEBOARD_FAB2_LIB.BASEBOARD_FAB2(SCH_1):M_L_DQ(35)   I172 @BASEBOARD_FAB2_LIB.BASEBOARD_FAB2(SCH_1):PAGE61
  DP39 M_L_DQ<34> @BASEBOARD_FAB2_LIB.BASEBOARD_FAB2(SCH_1):M_L_DQ(34)   I172 @BASEBOARD_FAB2_LIB.BASEBOARD_FAB2(SCH_1):PAGE61
  DW42 M_L_DQ<33> @BASEBOARD_FAB2_LIB.BASEBOARD_FAB2(SCH_1):M_L_DQ(33)   I172 @BASEBOARD_FAB2_LIB.BASEBOARD_FAB2(SCH_1):PAGE61
  DU42 M_L_DQ<32> @BASEBOARD_FAB2_LIB.BASEBOARD_FAB2(SCH_1):M_L_DQ(32)   I172 @BASEBOARD_FAB2_LIB.BASEBOARD_FAB2(SCH_1):PAGE61
  EE72 M_L_DQ<31> @BASEBOARD_FAB2_LIB.BASEBOARD_FAB2(SCH_1):M_L_DQ(31)   I172 @BASEBOARD_FAB2_LIB.BASEBOARD_FAB2(SCH_1):PAGE61
  EA72 M_L_DQ<30> @BASEBOARD_FAB2_LIB.BASEBOARD_FAB2(SCH_1):M_L_DQ(30)   I172 @BASEBOARD_FAB2_LIB.BASEBOARD_FAB2(SCH_1):PAGE61
  EB75 M_L_DQ<29> @BASEBOARD_FAB2_LIB.BASEBOARD_FAB2(SCH_1):M_L_DQ(29)   I172 @BASEBOARD_FAB2_LIB.BASEBOARD_FAB2(SCH_1):PAGE61
  EA74 M_L_DQ<28> @BASEBOARD_FAB2_LIB.BASEBOARD_FAB2(SCH_1):M_L_DQ(28)   I172 @BASEBOARD_FAB2_LIB.BASEBOARD_FAB2(SCH_1):PAGE61
  ED71 M_L_DQ<27> @BASEBOARD_FAB2_LIB.BASEBOARD_FAB2(SCH_1):M_L_DQ(27)   I172 @BASEBOARD_FAB2_LIB.BASEBOARD_FAB2(SCH_1):PAGE61
  EB71 M_L_DQ<26> @BASEBOARD_FAB2_LIB.BASEBOARD_FAB2(SCH_1):M_L_DQ(26)   I172 @BASEBOARD_FAB2_LIB.BASEBOARD_FAB2(SCH_1):PAGE61
  EE74 M_L_DQ<25> @BASEBOARD_FAB2_LIB.BASEBOARD_FAB2(SCH_1):M_L_DQ(25)   I172 @BASEBOARD_FAB2_LIB.BASEBOARD_FAB2(SCH_1):PAGE61
  ED75 M_L_DQ<24> @BASEBOARD_FAB2_LIB.BASEBOARD_FAB2(SCH_1):M_L_DQ(24)   I172 @BASEBOARD_FAB2_LIB.BASEBOARD_FAB2(SCH_1):PAGE61
  EC78 M_L_DQ<23> @BASEBOARD_FAB2_LIB.BASEBOARD_FAB2(SCH_1):M_L_DQ(23)   I172 @BASEBOARD_FAB2_LIB.BASEBOARD_FAB2(SCH_1):PAGE61
  DW78 M_L_DQ<22> @BASEBOARD_FAB2_LIB.BASEBOARD_FAB2(SCH_1):M_L_DQ(22)   I172 @BASEBOARD_FAB2_LIB.BASEBOARD_FAB2(SCH_1):PAGE61
  EB81 M_L_DQ<21> @BASEBOARD_FAB2_LIB.BASEBOARD_FAB2(SCH_1):M_L_DQ(21)   I172 @BASEBOARD_FAB2_LIB.BASEBOARD_FAB2(SCH_1):PAGE61
  DY81 M_L_DQ<20> @BASEBOARD_FAB2_LIB.BASEBOARD_FAB2(SCH_1):M_L_DQ(20)   I172 @BASEBOARD_FAB2_LIB.BASEBOARD_FAB2(SCH_1):PAGE61
  EB77 M_L_DQ<19> @BASEBOARD_FAB2_LIB.BASEBOARD_FAB2(SCH_1):M_L_DQ(19)   I172 @BASEBOARD_FAB2_LIB.BASEBOARD_FAB2(SCH_1):PAGE61
  DY77 M_L_DQ<18> @BASEBOARD_FAB2_LIB.BASEBOARD_FAB2(SCH_1):M_L_DQ(18)   I172 @BASEBOARD_FAB2_LIB.BASEBOARD_FAB2(SCH_1):PAGE61
  EC80 M_L_DQ<17> @BASEBOARD_FAB2_LIB.BASEBOARD_FAB2(SCH_1):M_L_DQ(17)   I172 @BASEBOARD_FAB2_LIB.BASEBOARD_FAB2(SCH_1):PAGE61
  DW80 M_L_DQ<16> @BASEBOARD_FAB2_LIB.BASEBOARD_FAB2(SCH_1):M_L_DQ(16)   I172 @BASEBOARD_FAB2_LIB.BASEBOARD_FAB2(SCH_1):PAGE61
  DE82 M_L_DQ<15> @BASEBOARD_FAB2_LIB.BASEBOARD_FAB2(SCH_1):M_L_DQ(15)   I172 @BASEBOARD_FAB2_LIB.BASEBOARD_FAB2(SCH_1):PAGE61
  DC82 M_L_DQ<14> @BASEBOARD_FAB2_LIB.BASEBOARD_FAB2(SCH_1):M_L_DQ(14)   I172 @BASEBOARD_FAB2_LIB.BASEBOARD_FAB2(SCH_1):PAGE61
  CW80 M_L_DQ<13> @BASEBOARD_FAB2_LIB.BASEBOARD_FAB2(SCH_1):M_L_DQ(13)   I172 @BASEBOARD_FAB2_LIB.BASEBOARD_FAB2(SCH_1):PAGE61
  CY79 M_L_DQ<12> @BASEBOARD_FAB2_LIB.BASEBOARD_FAB2(SCH_1):M_L_DQ(12)   I172 @BASEBOARD_FAB2_LIB.BASEBOARD_FAB2(SCH_1):PAGE61
  DF81 M_L_DQ<11> @BASEBOARD_FAB2_LIB.BASEBOARD_FAB2(SCH_1):M_L_DQ(11)   I172 @BASEBOARD_FAB2_LIB.BASEBOARD_FAB2(SCH_1):PAGE61
  DE80 M_L_DQ<10> @BASEBOARD_FAB2_LIB.BASEBOARD_FAB2(SCH_1):M_L_DQ(10)   I172 @BASEBOARD_FAB2_LIB.BASEBOARD_FAB2(SCH_1):PAGE61
  CY81 M_L_DQ<9> @BASEBOARD_FAB2_LIB.BASEBOARD_FAB2(SCH_1):M_L_DQ(9)   I172 @BASEBOARD_FAB2_LIB.BASEBOARD_FAB2(SCH_1):PAGE61
  DB79 M_L_DQ<8> @BASEBOARD_FAB2_LIB.BASEBOARD_FAB2(SCH_1):M_L_DQ(8)   I172 @BASEBOARD_FAB2_LIB.BASEBOARD_FAB2(SCH_1):PAGE61
  CN82 M_L_DQ<7> @BASEBOARD_FAB2_LIB.BASEBOARD_FAB2(SCH_1):M_L_DQ(7)   I172 @BASEBOARD_FAB2_LIB.BASEBOARD_FAB2(SCH_1):PAGE61
  CR80 M_L_DQ<6> @BASEBOARD_FAB2_LIB.BASEBOARD_FAB2(SCH_1):M_L_DQ(6)   I172 @BASEBOARD_FAB2_LIB.BASEBOARD_FAB2(SCH_1):PAGE61
  CJ80 M_L_DQ<5> @BASEBOARD_FAB2_LIB.BASEBOARD_FAB2(SCH_1):M_L_DQ(5)   I172 @BASEBOARD_FAB2_LIB.BASEBOARD_FAB2(SCH_1):PAGE61
  CK79 M_L_DQ<4> @BASEBOARD_FAB2_LIB.BASEBOARD_FAB2(SCH_1):M_L_DQ(4)   I172 @BASEBOARD_FAB2_LIB.BASEBOARD_FAB2(SCH_1):PAGE61
  CR82 M_L_DQ<3> @BASEBOARD_FAB2_LIB.BASEBOARD_FAB2(SCH_1):M_L_DQ(3)   I172 @BASEBOARD_FAB2_LIB.BASEBOARD_FAB2(SCH_1):PAGE61
  CT81 M_L_DQ<2> @BASEBOARD_FAB2_LIB.BASEBOARD_FAB2(SCH_1):M_L_DQ(2)   I172 @BASEBOARD_FAB2_LIB.BASEBOARD_FAB2(SCH_1):PAGE61
  CK81 M_L_DQ<1> @BASEBOARD_FAB2_LIB.BASEBOARD_FAB2(SCH_1):M_L_DQ(1)   I172 @BASEBOARD_FAB2_LIB.BASEBOARD_FAB2(SCH_1):PAGE61
  CM79 M_L_DQ<0> @BASEBOARD_FAB2_LIB.BASEBOARD_FAB2(SCH_1):M_L_DQ(0)   I172 @BASEBOARD_FAB2_LIB.BASEBOARD_FAB2(SCH_1):PAGE61
  DV67 M_L_DQS_DN<17> @BASEBOARD_FAB2_LIB.BASEBOARD_FAB2(SCH_1):M_L_DQS_DN(17)   I172 @BASEBOARD_FAB2_LIB.BASEBOARD_FAB2(SCH_1):PAGE61
  DG26 M_L_DQS_DN<16> @BASEBOARD_FAB2_LIB.BASEBOARD_FAB2(SCH_1):M_L_DQS_DN(16)   I172 @BASEBOARD_FAB2_LIB.BASEBOARD_FAB2(SCH_1):PAGE61
  EA26 M_L_DQS_DN<15> @BASEBOARD_FAB2_LIB.BASEBOARD_FAB2(SCH_1):M_L_DQS_DN(15)   I172 @BASEBOARD_FAB2_LIB.BASEBOARD_FAB2(SCH_1):PAGE61
  EA32 M_L_DQS_DN<14> @BASEBOARD_FAB2_LIB.BASEBOARD_FAB2(SCH_1):M_L_DQS_DN(14)   I172 @BASEBOARD_FAB2_LIB.BASEBOARD_FAB2(SCH_1):PAGE61
  DP41 M_L_DQS_DN<13> @BASEBOARD_FAB2_LIB.BASEBOARD_FAB2(SCH_1):M_L_DQS_DN(13)   I172 @BASEBOARD_FAB2_LIB.BASEBOARD_FAB2(SCH_1):PAGE61
  EB73 M_L_DQS_DN<12> @BASEBOARD_FAB2_LIB.BASEBOARD_FAB2(SCH_1):M_L_DQS_DN(12)   I172 @BASEBOARD_FAB2_LIB.BASEBOARD_FAB2(SCH_1):PAGE61
  DY79 M_L_DQS_DN<11> @BASEBOARD_FAB2_LIB.BASEBOARD_FAB2(SCH_1):M_L_DQS_DN(11)   I172 @BASEBOARD_FAB2_LIB.BASEBOARD_FAB2(SCH_1):PAGE61
  DC80 M_L_DQS_DN<10> @BASEBOARD_FAB2_LIB.BASEBOARD_FAB2(SCH_1):M_L_DQS_DN(10)   I172 @BASEBOARD_FAB2_LIB.BASEBOARD_FAB2(SCH_1):PAGE61
  CN80 M_L_DQS_DN<9> @BASEBOARD_FAB2_LIB.BASEBOARD_FAB2(SCH_1):M_L_DQS_DN(9)   I172 @BASEBOARD_FAB2_LIB.BASEBOARD_FAB2(SCH_1):PAGE61
  EB67 M_L_DQS_DN<8> @BASEBOARD_FAB2_LIB.BASEBOARD_FAB2(SCH_1):M_L_DQS_DN(8)   I172 @BASEBOARD_FAB2_LIB.BASEBOARD_FAB2(SCH_1):PAGE61
  DL26 M_L_DQS_DN<7> @BASEBOARD_FAB2_LIB.BASEBOARD_FAB2(SCH_1):M_L_DQS_DN(7)   I172 @BASEBOARD_FAB2_LIB.BASEBOARD_FAB2(SCH_1):PAGE61
  EE26 M_L_DQS_DN<6> @BASEBOARD_FAB2_LIB.BASEBOARD_FAB2(SCH_1):M_L_DQS_DN(6)   I172 @BASEBOARD_FAB2_LIB.BASEBOARD_FAB2(SCH_1):PAGE61
  EE32 M_L_DQS_DN<5> @BASEBOARD_FAB2_LIB.BASEBOARD_FAB2(SCH_1):M_L_DQS_DN(5)   I172 @BASEBOARD_FAB2_LIB.BASEBOARD_FAB2(SCH_1):PAGE61
  DV41 M_L_DQS_DN<4> @BASEBOARD_FAB2_LIB.BASEBOARD_FAB2(SCH_1):M_L_DQS_DN(4)   I172 @BASEBOARD_FAB2_LIB.BASEBOARD_FAB2(SCH_1):PAGE61
  EF73 M_L_DQS_DN<3> @BASEBOARD_FAB2_LIB.BASEBOARD_FAB2(SCH_1):M_L_DQS_DN(3)   I172 @BASEBOARD_FAB2_LIB.BASEBOARD_FAB2(SCH_1):PAGE61
  ED79 M_L_DQS_DN<2> @BASEBOARD_FAB2_LIB.BASEBOARD_FAB2(SCH_1):M_L_DQS_DN(2)   I172 @BASEBOARD_FAB2_LIB.BASEBOARD_FAB2(SCH_1):PAGE61
  DA82 M_L_DQS_DN<1> @BASEBOARD_FAB2_LIB.BASEBOARD_FAB2(SCH_1):M_L_DQS_DN(1)   I172 @BASEBOARD_FAB2_LIB.BASEBOARD_FAB2(SCH_1):PAGE61
  CL82 M_L_DQS_DN<0> @BASEBOARD_FAB2_LIB.BASEBOARD_FAB2(SCH_1):M_L_DQS_DN(0)   I172 @BASEBOARD_FAB2_LIB.BASEBOARD_FAB2(SCH_1):PAGE61
  DT67 M_L_DQS_DP<17> @BASEBOARD_FAB2_LIB.BASEBOARD_FAB2(SCH_1):M_L_DQS_DP(17)   I172 @BASEBOARD_FAB2_LIB.BASEBOARD_FAB2(SCH_1):PAGE61
  DE26 M_L_DQS_DP<16> @BASEBOARD_FAB2_LIB.BASEBOARD_FAB2(SCH_1):M_L_DQS_DP(16)   I172 @BASEBOARD_FAB2_LIB.BASEBOARD_FAB2(SCH_1):PAGE61
  DW26 M_L_DQS_DP<15> @BASEBOARD_FAB2_LIB.BASEBOARD_FAB2(SCH_1):M_L_DQS_DP(15)   I172 @BASEBOARD_FAB2_LIB.BASEBOARD_FAB2(SCH_1):PAGE61
  DW32 M_L_DQS_DP<14> @BASEBOARD_FAB2_LIB.BASEBOARD_FAB2(SCH_1):M_L_DQS_DP(14)   I172 @BASEBOARD_FAB2_LIB.BASEBOARD_FAB2(SCH_1):PAGE61
  DM41 M_L_DQS_DP<13> @BASEBOARD_FAB2_LIB.BASEBOARD_FAB2(SCH_1):M_L_DQS_DP(13)   I172 @BASEBOARD_FAB2_LIB.BASEBOARD_FAB2(SCH_1):PAGE61
  DY73 M_L_DQS_DP<12> @BASEBOARD_FAB2_LIB.BASEBOARD_FAB2(SCH_1):M_L_DQS_DP(12)   I172 @BASEBOARD_FAB2_LIB.BASEBOARD_FAB2(SCH_1):PAGE61
  DV79 M_L_DQS_DP<11> @BASEBOARD_FAB2_LIB.BASEBOARD_FAB2(SCH_1):M_L_DQS_DP(11)   I172 @BASEBOARD_FAB2_LIB.BASEBOARD_FAB2(SCH_1):PAGE61
  DD79 M_L_DQS_DP<10> @BASEBOARD_FAB2_LIB.BASEBOARD_FAB2(SCH_1):M_L_DQS_DP(10)   I172 @BASEBOARD_FAB2_LIB.BASEBOARD_FAB2(SCH_1):PAGE61
  CP79 M_L_DQS_DP<9> @BASEBOARD_FAB2_LIB.BASEBOARD_FAB2(SCH_1):M_L_DQS_DP(9)   I172 @BASEBOARD_FAB2_LIB.BASEBOARD_FAB2(SCH_1):PAGE61
  DY67 M_L_DQS_DP<8> @BASEBOARD_FAB2_LIB.BASEBOARD_FAB2(SCH_1):M_L_DQS_DP(8)   I172 @BASEBOARD_FAB2_LIB.BASEBOARD_FAB2(SCH_1):PAGE61
  DJ26 M_L_DQS_DP<7> @BASEBOARD_FAB2_LIB.BASEBOARD_FAB2(SCH_1):M_L_DQS_DP(7)   I172 @BASEBOARD_FAB2_LIB.BASEBOARD_FAB2(SCH_1):PAGE61
  EC26 M_L_DQS_DP<6> @BASEBOARD_FAB2_LIB.BASEBOARD_FAB2(SCH_1):M_L_DQS_DP(6)   I172 @BASEBOARD_FAB2_LIB.BASEBOARD_FAB2(SCH_1):PAGE61
  EC32 M_L_DQS_DP<5> @BASEBOARD_FAB2_LIB.BASEBOARD_FAB2(SCH_1):M_L_DQS_DP(5)   I172 @BASEBOARD_FAB2_LIB.BASEBOARD_FAB2(SCH_1):PAGE61
  DT41 M_L_DQS_DP<4> @BASEBOARD_FAB2_LIB.BASEBOARD_FAB2(SCH_1):M_L_DQS_DP(4)   I172 @BASEBOARD_FAB2_LIB.BASEBOARD_FAB2(SCH_1):PAGE61
  ED73 M_L_DQS_DP<3> @BASEBOARD_FAB2_LIB.BASEBOARD_FAB2(SCH_1):M_L_DQS_DP(3)   I172 @BASEBOARD_FAB2_LIB.BASEBOARD_FAB2(SCH_1):PAGE61
  EB79 M_L_DQS_DP<2> @BASEBOARD_FAB2_LIB.BASEBOARD_FAB2(SCH_1):M_L_DQS_DP(2)   I172 @BASEBOARD_FAB2_LIB.BASEBOARD_FAB2(SCH_1):PAGE61
  DB81 M_L_DQS_DP<1> @BASEBOARD_FAB2_LIB.BASEBOARD_FAB2(SCH_1):M_L_DQS_DP(1)   I172 @BASEBOARD_FAB2_LIB.BASEBOARD_FAB2(SCH_1):PAGE61
  CM81 M_L_DQS_DP<0> @BASEBOARD_FAB2_LIB.BASEBOARD_FAB2(SCH_1):M_L_DQS_DP(0)   I172 @BASEBOARD_FAB2_LIB.BASEBOARD_FAB2(SCH_1):PAGE61
  EA66 M_L_ECC<7> @BASEBOARD_FAB2_LIB.BASEBOARD_FAB2(SCH_1):M_L_ECC(7)   I172 @BASEBOARD_FAB2_LIB.BASEBOARD_FAB2(SCH_1):PAGE61
  DU66 M_L_ECC<6> @BASEBOARD_FAB2_LIB.BASEBOARD_FAB2(SCH_1):M_L_ECC(6)   I172 @BASEBOARD_FAB2_LIB.BASEBOARD_FAB2(SCH_1):PAGE61
  DV69 M_L_ECC<5> @BASEBOARD_FAB2_LIB.BASEBOARD_FAB2(SCH_1):M_L_ECC(5)   I172 @BASEBOARD_FAB2_LIB.BASEBOARD_FAB2(SCH_1):PAGE61
  DU68 M_L_ECC<4> @BASEBOARD_FAB2_LIB.BASEBOARD_FAB2(SCH_1):M_L_ECC(4)   I172 @BASEBOARD_FAB2_LIB.BASEBOARD_FAB2(SCH_1):PAGE61
  DY65 M_L_ECC<3> @BASEBOARD_FAB2_LIB.BASEBOARD_FAB2(SCH_1):M_L_ECC(3)   I172 @BASEBOARD_FAB2_LIB.BASEBOARD_FAB2(SCH_1):PAGE61
  DV65 M_L_ECC<2> @BASEBOARD_FAB2_LIB.BASEBOARD_FAB2(SCH_1):M_L_ECC(2)   I172 @BASEBOARD_FAB2_LIB.BASEBOARD_FAB2(SCH_1):PAGE61
  EA68 M_L_ECC<1> @BASEBOARD_FAB2_LIB.BASEBOARD_FAB2(SCH_1):M_L_ECC(1)   I172 @BASEBOARD_FAB2_LIB.BASEBOARD_FAB2(SCH_1):PAGE61
  DY69 M_L_ECC<0> @BASEBOARD_FAB2_LIB.BASEBOARD_FAB2(SCH_1):M_L_ECC(0)   I172 @BASEBOARD_FAB2_LIB.BASEBOARD_FAB2(SCH_1):PAGE61
  DR48 M_L_MA<17> @BASEBOARD_FAB2_LIB.BASEBOARD_FAB2(SCH_1):M_L_MA(17)   I172 @BASEBOARD_FAB2_LIB.BASEBOARD_FAB2(SCH_1):PAGE61
  DN52 M_L_MA<16> @BASEBOARD_FAB2_LIB.BASEBOARD_FAB2(SCH_1):M_L_MA(16)   I172 @BASEBOARD_FAB2_LIB.BASEBOARD_FAB2(SCH_1):PAGE61
  DR52 M_L_MA<15> @BASEBOARD_FAB2_LIB.BASEBOARD_FAB2(SCH_1):M_L_MA(15)   I172 @BASEBOARD_FAB2_LIB.BASEBOARD_FAB2(SCH_1):PAGE61
  DM51 M_L_MA<14> @BASEBOARD_FAB2_LIB.BASEBOARD_FAB2(SCH_1):M_L_MA(14)   I172 @BASEBOARD_FAB2_LIB.BASEBOARD_FAB2(SCH_1):PAGE61
  DT51 M_L_MA<13> @BASEBOARD_FAB2_LIB.BASEBOARD_FAB2(SCH_1):M_L_MA(13)   I172 @BASEBOARD_FAB2_LIB.BASEBOARD_FAB2(SCH_1):PAGE61
  DN60 M_L_MA<12> @BASEBOARD_FAB2_LIB.BASEBOARD_FAB2(SCH_1):M_L_MA(12)   I172 @BASEBOARD_FAB2_LIB.BASEBOARD_FAB2(SCH_1):PAGE61
  DR60 M_L_MA<11> @BASEBOARD_FAB2_LIB.BASEBOARD_FAB2(SCH_1):M_L_MA(11)   I172 @BASEBOARD_FAB2_LIB.BASEBOARD_FAB2(SCH_1):PAGE61
  DT55 M_L_MA<10> @BASEBOARD_FAB2_LIB.BASEBOARD_FAB2(SCH_1):M_L_MA(10)   I172 @BASEBOARD_FAB2_LIB.BASEBOARD_FAB2(SCH_1):PAGE61
  DV59 M_L_MA<9> @BASEBOARD_FAB2_LIB.BASEBOARD_FAB2(SCH_1):M_L_MA(9)   I172 @BASEBOARD_FAB2_LIB.BASEBOARD_FAB2(SCH_1):PAGE61
  DJ60 M_L_MA<8> @BASEBOARD_FAB2_LIB.BASEBOARD_FAB2(SCH_1):M_L_MA(8)   I172 @BASEBOARD_FAB2_LIB.BASEBOARD_FAB2(SCH_1):PAGE61
  DK61 M_L_MA<7> @BASEBOARD_FAB2_LIB.BASEBOARD_FAB2(SCH_1):M_L_MA(7)   I172 @BASEBOARD_FAB2_LIB.BASEBOARD_FAB2(SCH_1):PAGE61
  DM59 M_L_MA<6> @BASEBOARD_FAB2_LIB.BASEBOARD_FAB2(SCH_1):M_L_MA(6)   I172 @BASEBOARD_FAB2_LIB.BASEBOARD_FAB2(SCH_1):PAGE61
  DN58 M_L_MA<5> @BASEBOARD_FAB2_LIB.BASEBOARD_FAB2(SCH_1):M_L_MA(5)   I172 @BASEBOARD_FAB2_LIB.BASEBOARD_FAB2(SCH_1):PAGE61
  DT59 M_L_MA<4> @BASEBOARD_FAB2_LIB.BASEBOARD_FAB2(SCH_1):M_L_MA(4)   I172 @BASEBOARD_FAB2_LIB.BASEBOARD_FAB2(SCH_1):PAGE61
  DR58 M_L_MA<3> @BASEBOARD_FAB2_LIB.BASEBOARD_FAB2(SCH_1):M_L_MA(3)   I172 @BASEBOARD_FAB2_LIB.BASEBOARD_FAB2(SCH_1):PAGE61
  DV57 M_L_MA<2> @BASEBOARD_FAB2_LIB.BASEBOARD_FAB2(SCH_1):M_L_MA(2)   I172 @BASEBOARD_FAB2_LIB.BASEBOARD_FAB2(SCH_1):PAGE61
  DW58 M_L_MA<1> @BASEBOARD_FAB2_LIB.BASEBOARD_FAB2(SCH_1):M_L_MA(1)   I172 @BASEBOARD_FAB2_LIB.BASEBOARD_FAB2(SCH_1):PAGE61
  DW52 M_L_MA<0> @BASEBOARD_FAB2_LIB.BASEBOARD_FAB2(SCH_1):M_L_MA(0)   I172 @BASEBOARD_FAB2_LIB.BASEBOARD_FAB2(SCH_1):PAGE61
  DM47 M_L_ODT<3> @BASEBOARD_FAB2_LIB.BASEBOARD_FAB2(SCH_1):M_L_ODT(3)   I172 @BASEBOARD_FAB2_LIB.BASEBOARD_FAB2(SCH_1):PAGE61
  DT49 M_L_ODT<2> @BASEBOARD_FAB2_LIB.BASEBOARD_FAB2(SCH_1):M_L_ODT(2)   I172 @BASEBOARD_FAB2_LIB.BASEBOARD_FAB2(SCH_1):PAGE61
  DN48 M_L_ODT<1> @BASEBOARD_FAB2_LIB.BASEBOARD_FAB2(SCH_1):M_L_ODT(1)   I172 @BASEBOARD_FAB2_LIB.BASEBOARD_FAB2(SCH_1):PAGE61
  DR50 M_L_ODT<0> @BASEBOARD_FAB2_LIB.BASEBOARD_FAB2(SCH_1):M_L_ODT(0)   I172 @BASEBOARD_FAB2_LIB.BASEBOARD_FAB2(SCH_1):PAGE61
  DV53 M_L_PAR @BASEBOARD_FAB2_LIB.BASEBOARD_FAB2(SCH_1):M_L_PAR   I172 @BASEBOARD_FAB2_LIB.BASEBOARD_FAB2(SCH_1):PAGE61
  DC62 M_M_ACT_N @BASEBOARD_FAB2_LIB.BASEBOARD_FAB2(SCH_1):M_M_ACT_N   I172 @BASEBOARD_FAB2_LIB.BASEBOARD_FAB2(SCH_1):PAGE62
  DD61 M_M_ALERT_N @BASEBOARD_FAB2_LIB.BASEBOARD_FAB2(SCH_1):M_M_ALERT_N   I172 @BASEBOARD_FAB2_LIB.BASEBOARD_FAB2(SCH_1):PAGE62
  DC56 M_M_BA<1> @BASEBOARD_FAB2_LIB.BASEBOARD_FAB2(SCH_1):M_M_BA(1)   I172 @BASEBOARD_FAB2_LIB.BASEBOARD_FAB2(SCH_1):PAGE62
  DJ52 M_M_BA<0> @BASEBOARD_FAB2_LIB.BASEBOARD_FAB2(SCH_1):M_M_BA(0)   I172 @BASEBOARD_FAB2_LIB.BASEBOARD_FAB2(SCH_1):PAGE62
  DF61 M_M_BG<1> @BASEBOARD_FAB2_LIB.BASEBOARD_FAB2(SCH_1):M_M_BG(1)   I172 @BASEBOARD_FAB2_LIB.BASEBOARD_FAB2(SCH_1):PAGE62
  DA62 M_M_BG<0> @BASEBOARD_FAB2_LIB.BASEBOARD_FAB2(SCH_1):M_M_BG(0)   I172 @BASEBOARD_FAB2_LIB.BASEBOARD_FAB2(SCH_1):PAGE62
  DF45 M_M_C<2> @BASEBOARD_FAB2_LIB.BASEBOARD_FAB2(SCH_1):M_M_C(2)   I172 @BASEBOARD_FAB2_LIB.BASEBOARD_FAB2(SCH_1):PAGE62
  DF63 M_M_CKE<3> @BASEBOARD_FAB2_LIB.BASEBOARD_FAB2(SCH_1):M_M_CKE(3)   I172 @BASEBOARD_FAB2_LIB.BASEBOARD_FAB2(SCH_1):PAGE62
  DK63 M_M_CKE<2> @BASEBOARD_FAB2_LIB.BASEBOARD_FAB2(SCH_1):M_M_CKE(2)   I172 @BASEBOARD_FAB2_LIB.BASEBOARD_FAB2(SCH_1):PAGE62
  DD63 M_M_CKE<1> @BASEBOARD_FAB2_LIB.BASEBOARD_FAB2(SCH_1):M_M_CKE(1)   I172 @BASEBOARD_FAB2_LIB.BASEBOARD_FAB2(SCH_1):PAGE62
  DG62 M_M_CKE<0> @BASEBOARD_FAB2_LIB.BASEBOARD_FAB2(SCH_1):M_M_CKE(0)   I172 @BASEBOARD_FAB2_LIB.BASEBOARD_FAB2(SCH_1):PAGE62
  DF57 M_M_CLK_DN<3> @BASEBOARD_FAB2_LIB.BASEBOARD_FAB2(SCH_1):M_M_CLK_DN(3)   I172 @BASEBOARD_FAB2_LIB.BASEBOARD_FAB2(SCH_1):PAGE62
  DK57 M_M_CLK_DN<2> @BASEBOARD_FAB2_LIB.BASEBOARD_FAB2(SCH_1):M_M_CLK_DN(2)   I172 @BASEBOARD_FAB2_LIB.BASEBOARD_FAB2(SCH_1):PAGE62
  DF55 M_M_CLK_DN<1> @BASEBOARD_FAB2_LIB.BASEBOARD_FAB2(SCH_1):M_M_CLK_DN(1)   I172 @BASEBOARD_FAB2_LIB.BASEBOARD_FAB2(SCH_1):PAGE62
  DK55 M_M_CLK_DN<0> @BASEBOARD_FAB2_LIB.BASEBOARD_FAB2(SCH_1):M_M_CLK_DN(0)   I172 @BASEBOARD_FAB2_LIB.BASEBOARD_FAB2(SCH_1):PAGE62
  DG56 M_M_CLK_DP<3> @BASEBOARD_FAB2_LIB.BASEBOARD_FAB2(SCH_1):M_M_CLK_DP(3)   I172 @BASEBOARD_FAB2_LIB.BASEBOARD_FAB2(SCH_1):PAGE62
  DJ56 M_M_CLK_DP<2> @BASEBOARD_FAB2_LIB.BASEBOARD_FAB2(SCH_1):M_M_CLK_DP(2)   I172 @BASEBOARD_FAB2_LIB.BASEBOARD_FAB2(SCH_1):PAGE62
  DG54 M_M_CLK_DP<1> @BASEBOARD_FAB2_LIB.BASEBOARD_FAB2(SCH_1):M_M_CLK_DP(1)   I172 @BASEBOARD_FAB2_LIB.BASEBOARD_FAB2(SCH_1):PAGE62
  DJ54 M_M_CLK_DP<0> @BASEBOARD_FAB2_LIB.BASEBOARD_FAB2(SCH_1):M_M_CLK_DP(0)   I172 @BASEBOARD_FAB2_LIB.BASEBOARD_FAB2(SCH_1):PAGE62
  DK45 M_M_CS_N<7> @BASEBOARD_FAB2_LIB.BASEBOARD_FAB2(SCH_1):M_M_CS_N(7)   I172 @BASEBOARD_FAB2_LIB.BASEBOARD_FAB2(SCH_1):PAGE62
  DM45 M_M_CS_N<6> @BASEBOARD_FAB2_LIB.BASEBOARD_FAB2(SCH_1):M_M_CS_N(6)   I172 @BASEBOARD_FAB2_LIB.BASEBOARD_FAB2(SCH_1):PAGE62
  DJ48 M_M_CS_N<5> @BASEBOARD_FAB2_LIB.BASEBOARD_FAB2(SCH_1):M_M_CS_N(5)   I172 @BASEBOARD_FAB2_LIB.BASEBOARD_FAB2(SCH_1):PAGE62
  DF51 M_M_CS_N<4> @BASEBOARD_FAB2_LIB.BASEBOARD_FAB2(SCH_1):M_M_CS_N(4)   I172 @BASEBOARD_FAB2_LIB.BASEBOARD_FAB2(SCH_1):PAGE62
  DG46 M_M_CS_N<3> @BASEBOARD_FAB2_LIB.BASEBOARD_FAB2(SCH_1):M_M_CS_N(3)   I172 @BASEBOARD_FAB2_LIB.BASEBOARD_FAB2(SCH_1):PAGE62
  DJ46 M_M_CS_N<2> @BASEBOARD_FAB2_LIB.BASEBOARD_FAB2(SCH_1):M_M_CS_N(2)   I172 @BASEBOARD_FAB2_LIB.BASEBOARD_FAB2(SCH_1):PAGE62
  DF49 M_M_CS_N<1> @BASEBOARD_FAB2_LIB.BASEBOARD_FAB2(SCH_1):M_M_CS_N(1)   I172 @BASEBOARD_FAB2_LIB.BASEBOARD_FAB2(SCH_1):PAGE62
  DK51 M_M_CS_N<0> @BASEBOARD_FAB2_LIB.BASEBOARD_FAB2(SCH_1):M_M_CS_N(0)   I172 @BASEBOARD_FAB2_LIB.BASEBOARD_FAB2(SCH_1):PAGE62
  DC28 M_M_DQ<63> @BASEBOARD_FAB2_LIB.BASEBOARD_FAB2(SCH_1):M_M_DQ(63)   I172 @BASEBOARD_FAB2_LIB.BASEBOARD_FAB2(SCH_1):PAGE62
  CW28 M_M_DQ<62> @BASEBOARD_FAB2_LIB.BASEBOARD_FAB2(SCH_1):M_M_DQ(62)   I172 @BASEBOARD_FAB2_LIB.BASEBOARD_FAB2(SCH_1):PAGE62
  DB31 M_M_DQ<61> @BASEBOARD_FAB2_LIB.BASEBOARD_FAB2(SCH_1):M_M_DQ(61)   I172 @BASEBOARD_FAB2_LIB.BASEBOARD_FAB2(SCH_1):PAGE62
  CY31 M_M_DQ<60> @BASEBOARD_FAB2_LIB.BASEBOARD_FAB2(SCH_1):M_M_DQ(60)   I172 @BASEBOARD_FAB2_LIB.BASEBOARD_FAB2(SCH_1):PAGE62
  DB27 M_M_DQ<59> @BASEBOARD_FAB2_LIB.BASEBOARD_FAB2(SCH_1):M_M_DQ(59)   I172 @BASEBOARD_FAB2_LIB.BASEBOARD_FAB2(SCH_1):PAGE62
  CY27 M_M_DQ<58> @BASEBOARD_FAB2_LIB.BASEBOARD_FAB2(SCH_1):M_M_DQ(58)   I172 @BASEBOARD_FAB2_LIB.BASEBOARD_FAB2(SCH_1):PAGE62
  DC30 M_M_DQ<57> @BASEBOARD_FAB2_LIB.BASEBOARD_FAB2(SCH_1):M_M_DQ(57)   I172 @BASEBOARD_FAB2_LIB.BASEBOARD_FAB2(SCH_1):PAGE62
  CW30 M_M_DQ<56> @BASEBOARD_FAB2_LIB.BASEBOARD_FAB2(SCH_1):M_M_DQ(56)   I172 @BASEBOARD_FAB2_LIB.BASEBOARD_FAB2(SCH_1):PAGE62
  DC34 M_M_DQ<55> @BASEBOARD_FAB2_LIB.BASEBOARD_FAB2(SCH_1):M_M_DQ(55)   I172 @BASEBOARD_FAB2_LIB.BASEBOARD_FAB2(SCH_1):PAGE62
  CW34 M_M_DQ<54> @BASEBOARD_FAB2_LIB.BASEBOARD_FAB2(SCH_1):M_M_DQ(54)   I172 @BASEBOARD_FAB2_LIB.BASEBOARD_FAB2(SCH_1):PAGE62
  DB37 M_M_DQ<53> @BASEBOARD_FAB2_LIB.BASEBOARD_FAB2(SCH_1):M_M_DQ(53)   I172 @BASEBOARD_FAB2_LIB.BASEBOARD_FAB2(SCH_1):PAGE62
  CY37 M_M_DQ<52> @BASEBOARD_FAB2_LIB.BASEBOARD_FAB2(SCH_1):M_M_DQ(52)   I172 @BASEBOARD_FAB2_LIB.BASEBOARD_FAB2(SCH_1):PAGE62
  DB33 M_M_DQ<51> @BASEBOARD_FAB2_LIB.BASEBOARD_FAB2(SCH_1):M_M_DQ(51)   I172 @BASEBOARD_FAB2_LIB.BASEBOARD_FAB2(SCH_1):PAGE62
  CY33 M_M_DQ<50> @BASEBOARD_FAB2_LIB.BASEBOARD_FAB2(SCH_1):M_M_DQ(50)   I172 @BASEBOARD_FAB2_LIB.BASEBOARD_FAB2(SCH_1):PAGE62
  DC36 M_M_DQ<49> @BASEBOARD_FAB2_LIB.BASEBOARD_FAB2(SCH_1):M_M_DQ(49)   I172 @BASEBOARD_FAB2_LIB.BASEBOARD_FAB2(SCH_1):PAGE62
  CW36 M_M_DQ<48> @BASEBOARD_FAB2_LIB.BASEBOARD_FAB2(SCH_1):M_M_DQ(48)   I172 @BASEBOARD_FAB2_LIB.BASEBOARD_FAB2(SCH_1):PAGE62
  DK31 M_M_DQ<47> @BASEBOARD_FAB2_LIB.BASEBOARD_FAB2(SCH_1):M_M_DQ(47)   I172 @BASEBOARD_FAB2_LIB.BASEBOARD_FAB2(SCH_1):PAGE62
  DF31 M_M_DQ<46> @BASEBOARD_FAB2_LIB.BASEBOARD_FAB2(SCH_1):M_M_DQ(46)   I172 @BASEBOARD_FAB2_LIB.BASEBOARD_FAB2(SCH_1):PAGE62
  DJ34 M_M_DQ<45> @BASEBOARD_FAB2_LIB.BASEBOARD_FAB2(SCH_1):M_M_DQ(45)   I172 @BASEBOARD_FAB2_LIB.BASEBOARD_FAB2(SCH_1):PAGE62
  DG34 M_M_DQ<44> @BASEBOARD_FAB2_LIB.BASEBOARD_FAB2(SCH_1):M_M_DQ(44)   I172 @BASEBOARD_FAB2_LIB.BASEBOARD_FAB2(SCH_1):PAGE62
  DJ30 M_M_DQ<43> @BASEBOARD_FAB2_LIB.BASEBOARD_FAB2(SCH_1):M_M_DQ(43)   I172 @BASEBOARD_FAB2_LIB.BASEBOARD_FAB2(SCH_1):PAGE62
  DG30 M_M_DQ<42> @BASEBOARD_FAB2_LIB.BASEBOARD_FAB2(SCH_1):M_M_DQ(42)   I172 @BASEBOARD_FAB2_LIB.BASEBOARD_FAB2(SCH_1):PAGE62
  DK33 M_M_DQ<41> @BASEBOARD_FAB2_LIB.BASEBOARD_FAB2(SCH_1):M_M_DQ(41)   I172 @BASEBOARD_FAB2_LIB.BASEBOARD_FAB2(SCH_1):PAGE62
  DF33 M_M_DQ<40> @BASEBOARD_FAB2_LIB.BASEBOARD_FAB2(SCH_1):M_M_DQ(40)   I172 @BASEBOARD_FAB2_LIB.BASEBOARD_FAB2(SCH_1):PAGE62
  DH39 M_M_DQ<39> @BASEBOARD_FAB2_LIB.BASEBOARD_FAB2(SCH_1):M_M_DQ(39)   I172 @BASEBOARD_FAB2_LIB.BASEBOARD_FAB2(SCH_1):PAGE62
  DD39 M_M_DQ<38> @BASEBOARD_FAB2_LIB.BASEBOARD_FAB2(SCH_1):M_M_DQ(38)   I172 @BASEBOARD_FAB2_LIB.BASEBOARD_FAB2(SCH_1):PAGE62
  DE42 M_M_DQ<37> @BASEBOARD_FAB2_LIB.BASEBOARD_FAB2(SCH_1):M_M_DQ(37)   I172 @BASEBOARD_FAB2_LIB.BASEBOARD_FAB2(SCH_1):PAGE62
  DA42 M_M_DQ<36> @BASEBOARD_FAB2_LIB.BASEBOARD_FAB2(SCH_1):M_M_DQ(36)   I172 @BASEBOARD_FAB2_LIB.BASEBOARD_FAB2(SCH_1):PAGE62
  DG38 M_M_DQ<35> @BASEBOARD_FAB2_LIB.BASEBOARD_FAB2(SCH_1):M_M_DQ(35)   I172 @BASEBOARD_FAB2_LIB.BASEBOARD_FAB2(SCH_1):PAGE62
  DE38 M_M_DQ<34> @BASEBOARD_FAB2_LIB.BASEBOARD_FAB2(SCH_1):M_M_DQ(34)   I172 @BASEBOARD_FAB2_LIB.BASEBOARD_FAB2(SCH_1):PAGE62
  DG42 M_M_DQ<33> @BASEBOARD_FAB2_LIB.BASEBOARD_FAB2(SCH_1):M_M_DQ(33)   I172 @BASEBOARD_FAB2_LIB.BASEBOARD_FAB2(SCH_1):PAGE62
  DD41 M_M_DQ<32> @BASEBOARD_FAB2_LIB.BASEBOARD_FAB2(SCH_1):M_M_DQ(32)   I172 @BASEBOARD_FAB2_LIB.BASEBOARD_FAB2(SCH_1):PAGE62
  CU64 M_M_DQ<31> @BASEBOARD_FAB2_LIB.BASEBOARD_FAB2(SCH_1):M_M_DQ(31)   I172 @BASEBOARD_FAB2_LIB.BASEBOARD_FAB2(SCH_1):PAGE62
  CN64 M_M_DQ<30> @BASEBOARD_FAB2_LIB.BASEBOARD_FAB2(SCH_1):M_M_DQ(30)   I172 @BASEBOARD_FAB2_LIB.BASEBOARD_FAB2(SCH_1):PAGE62
  CT67 M_M_DQ<29> @BASEBOARD_FAB2_LIB.BASEBOARD_FAB2(SCH_1):M_M_DQ(29)   I172 @BASEBOARD_FAB2_LIB.BASEBOARD_FAB2(SCH_1):PAGE62
  CP67 M_M_DQ<28> @BASEBOARD_FAB2_LIB.BASEBOARD_FAB2(SCH_1):M_M_DQ(28)   I172 @BASEBOARD_FAB2_LIB.BASEBOARD_FAB2(SCH_1):PAGE62
  CT63 M_M_DQ<27> @BASEBOARD_FAB2_LIB.BASEBOARD_FAB2(SCH_1):M_M_DQ(27)   I172 @BASEBOARD_FAB2_LIB.BASEBOARD_FAB2(SCH_1):PAGE62
  CP63 M_M_DQ<26> @BASEBOARD_FAB2_LIB.BASEBOARD_FAB2(SCH_1):M_M_DQ(26)   I172 @BASEBOARD_FAB2_LIB.BASEBOARD_FAB2(SCH_1):PAGE62
  CU66 M_M_DQ<25> @BASEBOARD_FAB2_LIB.BASEBOARD_FAB2(SCH_1):M_M_DQ(25)   I172 @BASEBOARD_FAB2_LIB.BASEBOARD_FAB2(SCH_1):PAGE62
  CN66 M_M_DQ<24> @BASEBOARD_FAB2_LIB.BASEBOARD_FAB2(SCH_1):M_M_DQ(24)   I172 @BASEBOARD_FAB2_LIB.BASEBOARD_FAB2(SCH_1):PAGE62
  DM71 M_M_DQ<23> @BASEBOARD_FAB2_LIB.BASEBOARD_FAB2(SCH_1):M_M_DQ(23)   I172 @BASEBOARD_FAB2_LIB.BASEBOARD_FAB2(SCH_1):PAGE62
  DK69 M_M_DQ<22> @BASEBOARD_FAB2_LIB.BASEBOARD_FAB2(SCH_1):M_M_DQ(22)   I172 @BASEBOARD_FAB2_LIB.BASEBOARD_FAB2(SCH_1):PAGE62
  DG72 M_M_DQ<21> @BASEBOARD_FAB2_LIB.BASEBOARD_FAB2(SCH_1):M_M_DQ(21)   I172 @BASEBOARD_FAB2_LIB.BASEBOARD_FAB2(SCH_1):PAGE62
  DF71 M_M_DQ<20> @BASEBOARD_FAB2_LIB.BASEBOARD_FAB2(SCH_1):M_M_DQ(20)   I172 @BASEBOARD_FAB2_LIB.BASEBOARD_FAB2(SCH_1):PAGE62
  DN70 M_M_DQ<19> @BASEBOARD_FAB2_LIB.BASEBOARD_FAB2(SCH_1):M_M_DQ(19)   I172 @BASEBOARD_FAB2_LIB.BASEBOARD_FAB2(SCH_1):PAGE62
  DM69 M_M_DQ<18> @BASEBOARD_FAB2_LIB.BASEBOARD_FAB2(SCH_1):M_M_DQ(18)   I172 @BASEBOARD_FAB2_LIB.BASEBOARD_FAB2(SCH_1):PAGE62
  DJ72 M_M_DQ<17> @BASEBOARD_FAB2_LIB.BASEBOARD_FAB2(SCH_1):M_M_DQ(17)   I172 @BASEBOARD_FAB2_LIB.BASEBOARD_FAB2(SCH_1):PAGE62
  DG70 M_M_DQ<16> @BASEBOARD_FAB2_LIB.BASEBOARD_FAB2(SCH_1):M_M_DQ(16)   I172 @BASEBOARD_FAB2_LIB.BASEBOARD_FAB2(SCH_1):PAGE62
  DH77 M_M_DQ<15> @BASEBOARD_FAB2_LIB.BASEBOARD_FAB2(SCH_1):M_M_DQ(15)   I172 @BASEBOARD_FAB2_LIB.BASEBOARD_FAB2(SCH_1):PAGE62
  DF77 M_M_DQ<14> @BASEBOARD_FAB2_LIB.BASEBOARD_FAB2(SCH_1):M_M_DQ(14)   I172 @BASEBOARD_FAB2_LIB.BASEBOARD_FAB2(SCH_1):PAGE62
  DB75 M_M_DQ<13> @BASEBOARD_FAB2_LIB.BASEBOARD_FAB2(SCH_1):M_M_DQ(13)   I172 @BASEBOARD_FAB2_LIB.BASEBOARD_FAB2(SCH_1):PAGE62
  DC74 M_M_DQ<12> @BASEBOARD_FAB2_LIB.BASEBOARD_FAB2(SCH_1):M_M_DQ(12)   I172 @BASEBOARD_FAB2_LIB.BASEBOARD_FAB2(SCH_1):PAGE62
  DJ76 M_M_DQ<11> @BASEBOARD_FAB2_LIB.BASEBOARD_FAB2(SCH_1):M_M_DQ(11)   I172 @BASEBOARD_FAB2_LIB.BASEBOARD_FAB2(SCH_1):PAGE62
  DH75 M_M_DQ<10> @BASEBOARD_FAB2_LIB.BASEBOARD_FAB2(SCH_1):M_M_DQ(10)   I172 @BASEBOARD_FAB2_LIB.BASEBOARD_FAB2(SCH_1):PAGE62
  DC76 M_M_DQ<9> @BASEBOARD_FAB2_LIB.BASEBOARD_FAB2(SCH_1):M_M_DQ(9)   I172 @BASEBOARD_FAB2_LIB.BASEBOARD_FAB2(SCH_1):PAGE62
  DE74 M_M_DQ<8> @BASEBOARD_FAB2_LIB.BASEBOARD_FAB2(SCH_1):M_M_DQ(8)   I172 @BASEBOARD_FAB2_LIB.BASEBOARD_FAB2(SCH_1):PAGE62
  CT77 M_M_DQ<7> @BASEBOARD_FAB2_LIB.BASEBOARD_FAB2(SCH_1):M_M_DQ(7)   I172 @BASEBOARD_FAB2_LIB.BASEBOARD_FAB2(SCH_1):PAGE62
  CV75 M_M_DQ<6> @BASEBOARD_FAB2_LIB.BASEBOARD_FAB2(SCH_1):M_M_DQ(6)   I172 @BASEBOARD_FAB2_LIB.BASEBOARD_FAB2(SCH_1):PAGE62
  CM75 M_M_DQ<5> @BASEBOARD_FAB2_LIB.BASEBOARD_FAB2(SCH_1):M_M_DQ(5)   I172 @BASEBOARD_FAB2_LIB.BASEBOARD_FAB2(SCH_1):PAGE62
  CN74 M_M_DQ<4> @BASEBOARD_FAB2_LIB.BASEBOARD_FAB2(SCH_1):M_M_DQ(4)   I172 @BASEBOARD_FAB2_LIB.BASEBOARD_FAB2(SCH_1):PAGE62
  CV77 M_M_DQ<3> @BASEBOARD_FAB2_LIB.BASEBOARD_FAB2(SCH_1):M_M_DQ(3)   I172 @BASEBOARD_FAB2_LIB.BASEBOARD_FAB2(SCH_1):PAGE62
  CW76 M_M_DQ<2> @BASEBOARD_FAB2_LIB.BASEBOARD_FAB2(SCH_1):M_M_DQ(2)   I172 @BASEBOARD_FAB2_LIB.BASEBOARD_FAB2(SCH_1):PAGE62
  CN76 M_M_DQ<1> @BASEBOARD_FAB2_LIB.BASEBOARD_FAB2(SCH_1):M_M_DQ(1)   I172 @BASEBOARD_FAB2_LIB.BASEBOARD_FAB2(SCH_1):PAGE62
  CR74 M_M_DQ<0> @BASEBOARD_FAB2_LIB.BASEBOARD_FAB2(SCH_1):M_M_DQ(0)   I172 @BASEBOARD_FAB2_LIB.BASEBOARD_FAB2(SCH_1):PAGE62
  CJ70 M_M_DQS_DN<17> @BASEBOARD_FAB2_LIB.BASEBOARD_FAB2(SCH_1):M_M_DQS_DN(17)   I172 @BASEBOARD_FAB2_LIB.BASEBOARD_FAB2(SCH_1):PAGE62
  CY29 M_M_DQS_DN<16> @BASEBOARD_FAB2_LIB.BASEBOARD_FAB2(SCH_1):M_M_DQS_DN(16)   I172 @BASEBOARD_FAB2_LIB.BASEBOARD_FAB2(SCH_1):PAGE62
  CY35 M_M_DQS_DN<15> @BASEBOARD_FAB2_LIB.BASEBOARD_FAB2(SCH_1):M_M_DQS_DN(15)   I172 @BASEBOARD_FAB2_LIB.BASEBOARD_FAB2(SCH_1):PAGE62
  DG32 M_M_DQS_DN<14> @BASEBOARD_FAB2_LIB.BASEBOARD_FAB2(SCH_1):M_M_DQS_DN(14)   I172 @BASEBOARD_FAB2_LIB.BASEBOARD_FAB2(SCH_1):PAGE62
  DE40 M_M_DQS_DN<13> @BASEBOARD_FAB2_LIB.BASEBOARD_FAB2(SCH_1):M_M_DQS_DN(13)   I172 @BASEBOARD_FAB2_LIB.BASEBOARD_FAB2(SCH_1):PAGE62
  CP65 M_M_DQS_DN<12> @BASEBOARD_FAB2_LIB.BASEBOARD_FAB2(SCH_1):M_M_DQS_DN(12)   I172 @BASEBOARD_FAB2_LIB.BASEBOARD_FAB2(SCH_1):PAGE62
  DJ70 M_M_DQS_DN<11> @BASEBOARD_FAB2_LIB.BASEBOARD_FAB2(SCH_1):M_M_DQS_DN(11)   I172 @BASEBOARD_FAB2_LIB.BASEBOARD_FAB2(SCH_1):PAGE62
  DF75 M_M_DQS_DN<10> @BASEBOARD_FAB2_LIB.BASEBOARD_FAB2(SCH_1):M_M_DQS_DN(10)   I172 @BASEBOARD_FAB2_LIB.BASEBOARD_FAB2(SCH_1):PAGE62
  CT75 M_M_DQS_DN<9> @BASEBOARD_FAB2_LIB.BASEBOARD_FAB2(SCH_1):M_M_DQS_DN(9)   I172 @BASEBOARD_FAB2_LIB.BASEBOARD_FAB2(SCH_1):PAGE62
  CN70 M_M_DQS_DN<8> @BASEBOARD_FAB2_LIB.BASEBOARD_FAB2(SCH_1):M_M_DQS_DN(8)   I172 @BASEBOARD_FAB2_LIB.BASEBOARD_FAB2(SCH_1):PAGE62
  DD29 M_M_DQS_DN<7> @BASEBOARD_FAB2_LIB.BASEBOARD_FAB2(SCH_1):M_M_DQS_DN(7)   I172 @BASEBOARD_FAB2_LIB.BASEBOARD_FAB2(SCH_1):PAGE62
  DD35 M_M_DQS_DN<6> @BASEBOARD_FAB2_LIB.BASEBOARD_FAB2(SCH_1):M_M_DQS_DN(6)   I172 @BASEBOARD_FAB2_LIB.BASEBOARD_FAB2(SCH_1):PAGE62
  DL32 M_M_DQS_DN<5> @BASEBOARD_FAB2_LIB.BASEBOARD_FAB2(SCH_1):M_M_DQS_DN(5)   I172 @BASEBOARD_FAB2_LIB.BASEBOARD_FAB2(SCH_1):PAGE62
  DG40 M_M_DQS_DN<4> @BASEBOARD_FAB2_LIB.BASEBOARD_FAB2(SCH_1):M_M_DQS_DN(4)   I172 @BASEBOARD_FAB2_LIB.BASEBOARD_FAB2(SCH_1):PAGE62
  CV65 M_M_DQS_DN<3> @BASEBOARD_FAB2_LIB.BASEBOARD_FAB2(SCH_1):M_M_DQS_DN(3)   I172 @BASEBOARD_FAB2_LIB.BASEBOARD_FAB2(SCH_1):PAGE62
  DL72 M_M_DQS_DN<2> @BASEBOARD_FAB2_LIB.BASEBOARD_FAB2(SCH_1):M_M_DQS_DN(2)   I172 @BASEBOARD_FAB2_LIB.BASEBOARD_FAB2(SCH_1):PAGE62
  DD77 M_M_DQS_DN<1> @BASEBOARD_FAB2_LIB.BASEBOARD_FAB2(SCH_1):M_M_DQS_DN(1)   I172 @BASEBOARD_FAB2_LIB.BASEBOARD_FAB2(SCH_1):PAGE62
  CP77 M_M_DQS_DN<0> @BASEBOARD_FAB2_LIB.BASEBOARD_FAB2(SCH_1):M_M_DQS_DN(0)   I172 @BASEBOARD_FAB2_LIB.BASEBOARD_FAB2(SCH_1):PAGE62
  CG70 M_M_DQS_DP<17> @BASEBOARD_FAB2_LIB.BASEBOARD_FAB2(SCH_1):M_M_DQS_DP(17)   I172 @BASEBOARD_FAB2_LIB.BASEBOARD_FAB2(SCH_1):PAGE62
  CV29 M_M_DQS_DP<16> @BASEBOARD_FAB2_LIB.BASEBOARD_FAB2(SCH_1):M_M_DQS_DP(16)   I172 @BASEBOARD_FAB2_LIB.BASEBOARD_FAB2(SCH_1):PAGE62
  CV35 M_M_DQS_DP<15> @BASEBOARD_FAB2_LIB.BASEBOARD_FAB2(SCH_1):M_M_DQS_DP(15)   I172 @BASEBOARD_FAB2_LIB.BASEBOARD_FAB2(SCH_1):PAGE62
  DE32 M_M_DQS_DP<14> @BASEBOARD_FAB2_LIB.BASEBOARD_FAB2(SCH_1):M_M_DQS_DP(14)   I172 @BASEBOARD_FAB2_LIB.BASEBOARD_FAB2(SCH_1):PAGE62
  DC40 M_M_DQS_DP<13> @BASEBOARD_FAB2_LIB.BASEBOARD_FAB2(SCH_1):M_M_DQS_DP(13)   I172 @BASEBOARD_FAB2_LIB.BASEBOARD_FAB2(SCH_1):PAGE62
  CM65 M_M_DQS_DP<12> @BASEBOARD_FAB2_LIB.BASEBOARD_FAB2(SCH_1):M_M_DQS_DP(12)   I172 @BASEBOARD_FAB2_LIB.BASEBOARD_FAB2(SCH_1):PAGE62
  DH69 M_M_DQS_DP<11> @BASEBOARD_FAB2_LIB.BASEBOARD_FAB2(SCH_1):M_M_DQS_DP(11)   I172 @BASEBOARD_FAB2_LIB.BASEBOARD_FAB2(SCH_1):PAGE62
  DG74 M_M_DQS_DP<10> @BASEBOARD_FAB2_LIB.BASEBOARD_FAB2(SCH_1):M_M_DQS_DP(10)   I172 @BASEBOARD_FAB2_LIB.BASEBOARD_FAB2(SCH_1):PAGE62
  CU74 M_M_DQS_DP<9> @BASEBOARD_FAB2_LIB.BASEBOARD_FAB2(SCH_1):M_M_DQS_DP(9)   I172 @BASEBOARD_FAB2_LIB.BASEBOARD_FAB2(SCH_1):PAGE62
  CL70 M_M_DQS_DP<8> @BASEBOARD_FAB2_LIB.BASEBOARD_FAB2(SCH_1):M_M_DQS_DP(8)   I172 @BASEBOARD_FAB2_LIB.BASEBOARD_FAB2(SCH_1):PAGE62
  DB29 M_M_DQS_DP<7> @BASEBOARD_FAB2_LIB.BASEBOARD_FAB2(SCH_1):M_M_DQS_DP(7)   I172 @BASEBOARD_FAB2_LIB.BASEBOARD_FAB2(SCH_1):PAGE62
  DB35 M_M_DQS_DP<6> @BASEBOARD_FAB2_LIB.BASEBOARD_FAB2(SCH_1):M_M_DQS_DP(6)   I172 @BASEBOARD_FAB2_LIB.BASEBOARD_FAB2(SCH_1):PAGE62
  DJ32 M_M_DQS_DP<5> @BASEBOARD_FAB2_LIB.BASEBOARD_FAB2(SCH_1):M_M_DQS_DP(5)   I172 @BASEBOARD_FAB2_LIB.BASEBOARD_FAB2(SCH_1):PAGE62
  DJ40 M_M_DQS_DP<4> @BASEBOARD_FAB2_LIB.BASEBOARD_FAB2(SCH_1):M_M_DQS_DP(4)   I172 @BASEBOARD_FAB2_LIB.BASEBOARD_FAB2(SCH_1):PAGE62
  CT65 M_M_DQS_DP<3> @BASEBOARD_FAB2_LIB.BASEBOARD_FAB2(SCH_1):M_M_DQS_DP(3)   I172 @BASEBOARD_FAB2_LIB.BASEBOARD_FAB2(SCH_1):PAGE62
  DK71 M_M_DQS_DP<2> @BASEBOARD_FAB2_LIB.BASEBOARD_FAB2(SCH_1):M_M_DQS_DP(2)   I172 @BASEBOARD_FAB2_LIB.BASEBOARD_FAB2(SCH_1):PAGE62
  DE76 M_M_DQS_DP<1> @BASEBOARD_FAB2_LIB.BASEBOARD_FAB2(SCH_1):M_M_DQS_DP(1)   I172 @BASEBOARD_FAB2_LIB.BASEBOARD_FAB2(SCH_1):PAGE62
  CR76 M_M_DQS_DP<0> @BASEBOARD_FAB2_LIB.BASEBOARD_FAB2(SCH_1):M_M_DQS_DP(0)   I172 @BASEBOARD_FAB2_LIB.BASEBOARD_FAB2(SCH_1):PAGE62
  CM69 M_M_ECC<7> @BASEBOARD_FAB2_LIB.BASEBOARD_FAB2(SCH_1):M_M_ECC(7)   I172 @BASEBOARD_FAB2_LIB.BASEBOARD_FAB2(SCH_1):PAGE62
  CH69 M_M_ECC<6> @BASEBOARD_FAB2_LIB.BASEBOARD_FAB2(SCH_1):M_M_ECC(6)   I172 @BASEBOARD_FAB2_LIB.BASEBOARD_FAB2(SCH_1):PAGE62
  CL72 M_M_ECC<5> @BASEBOARD_FAB2_LIB.BASEBOARD_FAB2(SCH_1):M_M_ECC(5)   I172 @BASEBOARD_FAB2_LIB.BASEBOARD_FAB2(SCH_1):PAGE62
  CJ72 M_M_ECC<4> @BASEBOARD_FAB2_LIB.BASEBOARD_FAB2(SCH_1):M_M_ECC(4)   I172 @BASEBOARD_FAB2_LIB.BASEBOARD_FAB2(SCH_1):PAGE62
  CL68 M_M_ECC<3> @BASEBOARD_FAB2_LIB.BASEBOARD_FAB2(SCH_1):M_M_ECC(3)   I172 @BASEBOARD_FAB2_LIB.BASEBOARD_FAB2(SCH_1):PAGE62
  CJ68 M_M_ECC<2> @BASEBOARD_FAB2_LIB.BASEBOARD_FAB2(SCH_1):M_M_ECC(2)   I172 @BASEBOARD_FAB2_LIB.BASEBOARD_FAB2(SCH_1):PAGE62
  CM71 M_M_ECC<1> @BASEBOARD_FAB2_LIB.BASEBOARD_FAB2(SCH_1):M_M_ECC(1)   I172 @BASEBOARD_FAB2_LIB.BASEBOARD_FAB2(SCH_1):PAGE62
  CH71 M_M_ECC<0> @BASEBOARD_FAB2_LIB.BASEBOARD_FAB2(SCH_1):M_M_ECC(0)   I172 @BASEBOARD_FAB2_LIB.BASEBOARD_FAB2(SCH_1):PAGE62
  DE46 M_M_MA<17> @BASEBOARD_FAB2_LIB.BASEBOARD_FAB2(SCH_1):M_M_MA(17)   I172 @BASEBOARD_FAB2_LIB.BASEBOARD_FAB2(SCH_1):PAGE62
  DG52 M_M_MA<16> @BASEBOARD_FAB2_LIB.BASEBOARD_FAB2(SCH_1):M_M_MA(16)   I172 @BASEBOARD_FAB2_LIB.BASEBOARD_FAB2(SCH_1):PAGE62
  DC54 M_M_MA<15> @BASEBOARD_FAB2_LIB.BASEBOARD_FAB2(SCH_1):M_M_MA(15)   I172 @BASEBOARD_FAB2_LIB.BASEBOARD_FAB2(SCH_1):PAGE62
  DJ50 M_M_MA<14> @BASEBOARD_FAB2_LIB.BASEBOARD_FAB2(SCH_1):M_M_MA(14)   I172 @BASEBOARD_FAB2_LIB.BASEBOARD_FAB2(SCH_1):PAGE62
  DD53 M_M_MA<13> @BASEBOARD_FAB2_LIB.BASEBOARD_FAB2(SCH_1):M_M_MA(13)   I172 @BASEBOARD_FAB2_LIB.BASEBOARD_FAB2(SCH_1):PAGE62
  DG60 M_M_MA<12> @BASEBOARD_FAB2_LIB.BASEBOARD_FAB2(SCH_1):M_M_MA(12)   I172 @BASEBOARD_FAB2_LIB.BASEBOARD_FAB2(SCH_1):PAGE62
  DA60 M_M_MA<11> @BASEBOARD_FAB2_LIB.BASEBOARD_FAB2(SCH_1):M_M_MA(11)   I172 @BASEBOARD_FAB2_LIB.BASEBOARD_FAB2(SCH_1):PAGE62
  DD55 M_M_MA<10> @BASEBOARD_FAB2_LIB.BASEBOARD_FAB2(SCH_1):M_M_MA(10)   I172 @BASEBOARD_FAB2_LIB.BASEBOARD_FAB2(SCH_1):PAGE62
  DA58 M_M_MA<9> @BASEBOARD_FAB2_LIB.BASEBOARD_FAB2(SCH_1):M_M_MA(9)   I172 @BASEBOARD_FAB2_LIB.BASEBOARD_FAB2(SCH_1):PAGE62
  DD59 M_M_MA<8> @BASEBOARD_FAB2_LIB.BASEBOARD_FAB2(SCH_1):M_M_MA(8)   I172 @BASEBOARD_FAB2_LIB.BASEBOARD_FAB2(SCH_1):PAGE62
  DC60 M_M_MA<7> @BASEBOARD_FAB2_LIB.BASEBOARD_FAB2(SCH_1):M_M_MA(7)   I172 @BASEBOARD_FAB2_LIB.BASEBOARD_FAB2(SCH_1):PAGE62
  DK59 M_M_MA<6> @BASEBOARD_FAB2_LIB.BASEBOARD_FAB2(SCH_1):M_M_MA(6)   I172 @BASEBOARD_FAB2_LIB.BASEBOARD_FAB2(SCH_1):PAGE62
  DF59 M_M_MA<5> @BASEBOARD_FAB2_LIB.BASEBOARD_FAB2(SCH_1):M_M_MA(5)   I172 @BASEBOARD_FAB2_LIB.BASEBOARD_FAB2(SCH_1):PAGE62
  DJ58 M_M_MA<4> @BASEBOARD_FAB2_LIB.BASEBOARD_FAB2(SCH_1):M_M_MA(4)   I172 @BASEBOARD_FAB2_LIB.BASEBOARD_FAB2(SCH_1):PAGE62
  DG58 M_M_MA<3> @BASEBOARD_FAB2_LIB.BASEBOARD_FAB2(SCH_1):M_M_MA(3)   I172 @BASEBOARD_FAB2_LIB.BASEBOARD_FAB2(SCH_1):PAGE62
  DD57 M_M_MA<2> @BASEBOARD_FAB2_LIB.BASEBOARD_FAB2(SCH_1):M_M_MA(2)   I172 @BASEBOARD_FAB2_LIB.BASEBOARD_FAB2(SCH_1):PAGE62
  DC58 M_M_MA<1> @BASEBOARD_FAB2_LIB.BASEBOARD_FAB2(SCH_1):M_M_MA(1)   I172 @BASEBOARD_FAB2_LIB.BASEBOARD_FAB2(SCH_1):PAGE62
  DF53 M_M_MA<0> @BASEBOARD_FAB2_LIB.BASEBOARD_FAB2(SCH_1):M_M_MA(0)   I172 @BASEBOARD_FAB2_LIB.BASEBOARD_FAB2(SCH_1):PAGE62
  DF47 M_M_ODT<3> @BASEBOARD_FAB2_LIB.BASEBOARD_FAB2(SCH_1):M_M_ODT(3)   I172 @BASEBOARD_FAB2_LIB.BASEBOARD_FAB2(SCH_1):PAGE62
  DK49 M_M_ODT<2> @BASEBOARD_FAB2_LIB.BASEBOARD_FAB2(SCH_1):M_M_ODT(2)   I172 @BASEBOARD_FAB2_LIB.BASEBOARD_FAB2(SCH_1):PAGE62
  DG48 M_M_ODT<1> @BASEBOARD_FAB2_LIB.BASEBOARD_FAB2(SCH_1):M_M_ODT(1)   I172 @BASEBOARD_FAB2_LIB.BASEBOARD_FAB2(SCH_1):PAGE62
  DG50 M_M_ODT<0> @BASEBOARD_FAB2_LIB.BASEBOARD_FAB2(SCH_1):M_M_ODT(0)   I172 @BASEBOARD_FAB2_LIB.BASEBOARD_FAB2(SCH_1):PAGE62
  DK53 M_M_PAR @BASEBOARD_FAB2_LIB.BASEBOARD_FAB2(SCH_1):M_M_PAR   I172 @BASEBOARD_FAB2_LIB.BASEBOARD_FAB2(SCH_1):PAGE62
  BN22 TP_SMB_CPU1_CD_HFI0_I2CCLK @BASEBOARD_FAB2_LIB.BASEBOARD_FAB2(SCH_1):TP_SMB_CPU1_CD_HFI0_I2CCLK    I23 @BASEBOARD_FAB2_LIB.BASEBOARD_FAB2(SCH_1):PAGE63
  BP23 TP_SMB_CPU1_CD_HFI0_I2CDAT @BASEBOARD_FAB2_LIB.BASEBOARD_FAB2(SCH_1):TP_SMB_CPU1_CD_HFI0_I2CDAT    I23 @BASEBOARD_FAB2_LIB.BASEBOARD_FAB2(SCH_1):PAGE63
  BP19 TP_IRQ_CPU1_CD_HFI0_N @BASEBOARD_FAB2_LIB.BASEBOARD_FAB2(SCH_1):TP_IRQ_CPU1_CD_HFI0_N    I23 @BASEBOARD_FAB2_LIB.BASEBOARD_FAB2(SCH_1):PAGE63
  BK21 TP_LED_CPU1_CD_HFI0_N @BASEBOARD_FAB2_LIB.BASEBOARD_FAB2(SCH_1):TP_LED_CPU1_CD_HFI0_N    I23 @BASEBOARD_FAB2_LIB.BASEBOARD_FAB2(SCH_1):PAGE63
  BR20 TP_FM_CPU1_CD_HFI0_MODPRST_N @BASEBOARD_FAB2_LIB.BASEBOARD_FAB2(SCH_1):TP_FM_CPU1_CD_HFI0_MODPRST_N    I23 @BASEBOARD_FAB2_LIB.BASEBOARD_FAB2(SCH_1):PAGE63
  BN24 TP_RST_CPU1_CD_HFI0_N @BASEBOARD_FAB2_LIB.BASEBOARD_FAB2(SCH_1):TP_RST_CPU1_CD_HFI0_N    I23 @BASEBOARD_FAB2_LIB.BASEBOARD_FAB2(SCH_1):PAGE63
  BJ22 TP_CD_HFI1_CPU1_I2CLK @BASEBOARD_FAB2_LIB.BASEBOARD_FAB2(SCH_1):TP_CD_HFI1_CPU1_I2CLK    I23 @BASEBOARD_FAB2_LIB.BASEBOARD_FAB2(SCH_1):PAGE63
  BH23 TP_CD_HFI1_CPU1_I2CDAT @BASEBOARD_FAB2_LIB.BASEBOARD_FAB2(SCH_1):TP_CD_HFI1_CPU1_I2CDAT    I23 @BASEBOARD_FAB2_LIB.BASEBOARD_FAB2(SCH_1):PAGE63
  BM21 TP_CD_HFI1_CPU1_INT_N @BASEBOARD_FAB2_LIB.BASEBOARD_FAB2(SCH_1):TP_CD_HFI1_CPU1_INT_N    I23 @BASEBOARD_FAB2_LIB.BASEBOARD_FAB2(SCH_1):PAGE63
  BM23 TP_CD_HFI1_CPU1_LED_N @BASEBOARD_FAB2_LIB.BASEBOARD_FAB2(SCH_1):TP_CD_HFI1_CPU1_LED_N    I23 @BASEBOARD_FAB2_LIB.BASEBOARD_FAB2(SCH_1):PAGE63
  BT19 TP_CD_HFI1_CPU1_MODPRST_N @BASEBOARD_FAB2_LIB.BASEBOARD_FAB2(SCH_1):TP_CD_HFI1_CPU1_MODPRST_N    I23 @BASEBOARD_FAB2_LIB.BASEBOARD_FAB2(SCH_1):PAGE63
  BK23 TP_CD_HFI1_CPU1_RESET_N @BASEBOARD_FAB2_LIB.BASEBOARD_FAB2(SCH_1):TP_CD_HFI1_CPU1_RESET_N    I23 @BASEBOARD_FAB2_LIB.BASEBOARD_FAB2(SCH_1):PAGE63
  BE16 CLK_156M_OSC_CPU1_HFI_DN @BASEBOARD_FAB2_LIB.BASEBOARD_FAB2(SCH_1):CLK_156M_OSC_CPU1_HFI_DN    I23 @BASEBOARD_FAB2_LIB.BASEBOARD_FAB2(SCH_1):PAGE63
  BG16 CLK_156M_OSC_CPU1_HFI_DP @BASEBOARD_FAB2_LIB.BASEBOARD_FAB2(SCH_1):CLK_156M_OSC_CPU1_HFI_DP    I23 @BASEBOARD_FAB2_LIB.BASEBOARD_FAB2(SCH_1):PAGE63
  BU24 CLK_100M_CPU1_PE_REFCLK_DN @BASEBOARD_FAB2_LIB.BASEBOARD_FAB2(SCH_1):CLK_100M_CPU1_PE_REFCLK_DN    I23 @BASEBOARD_FAB2_LIB.BASEBOARD_FAB2(SCH_1):PAGE63
  BW24 CLK_100M_CPU1_PE_REFCLK_DP @BASEBOARD_FAB2_LIB.BASEBOARD_FAB2(SCH_1):CLK_100M_CPU1_PE_REFCLK_DP    I23 @BASEBOARD_FAB2_LIB.BASEBOARD_FAB2(SCH_1):PAGE63
  CF25 RST_CD_CPU1_POR_N @BASEBOARD_FAB2_LIB.BASEBOARD_FAB2(SCH_1):RST_CD_CPU1_POR_N    I23 @BASEBOARD_FAB2_LIB.BASEBOARD_FAB2(SCH_1):PAGE63
  CB23 JTAG_MCP_TCK @BASEBOARD_FAB2_LIB.BASEBOARD_FAB2(SCH_1):JTAG_MCP_TCK    I23 @BASEBOARD_FAB2_LIB.BASEBOARD_FAB2(SCH_1):PAGE63
  BY21 JTAG_MCP_CPU1_TDI @BASEBOARD_FAB2_LIB.BASEBOARD_FAB2(SCH_1):JTAG_MCP_CPU1_TDI    I23 @BASEBOARD_FAB2_LIB.BASEBOARD_FAB2(SCH_1):PAGE63
  CC22 JTAG_MCP_CPU1_TDO @BASEBOARD_FAB2_LIB.BASEBOARD_FAB2(SCH_1):JTAG_MCP_CPU1_TDO    I23 @BASEBOARD_FAB2_LIB.BASEBOARD_FAB2(SCH_1):PAGE63
  CE24 JTAG_MCP_TMS @BASEBOARD_FAB2_LIB.BASEBOARD_FAB2(SCH_1):JTAG_MCP_TMS    I23 @BASEBOARD_FAB2_LIB.BASEBOARD_FAB2(SCH_1):PAGE63
  CD23 JTAG_MCP_TRST_N @BASEBOARD_FAB2_LIB.BASEBOARD_FAB2(SCH_1):JTAG_MCP_TRST_N    I23 @BASEBOARD_FAB2_LIB.BASEBOARD_FAB2(SCH_1):PAGE63
  CT11 TP_CPU1_DMI_RX_DN3 @BASEBOARD_FAB2_LIB.BASEBOARD_FAB2(SCH_1):TP_CPU1_DMI_RX_DN3    I23 @BASEBOARD_FAB2_LIB.BASEBOARD_FAB2(SCH_1):PAGE63
  CR12 TP_CPU1_DMI_RX_DN2 @BASEBOARD_FAB2_LIB.BASEBOARD_FAB2(SCH_1):TP_CPU1_DMI_RX_DN2    I23 @BASEBOARD_FAB2_LIB.BASEBOARD_FAB2(SCH_1):PAGE63
  CM11 TP_CPU1_DMI_RX_DN1 @BASEBOARD_FAB2_LIB.BASEBOARD_FAB2(SCH_1):TP_CPU1_DMI_RX_DN1    I23 @BASEBOARD_FAB2_LIB.BASEBOARD_FAB2(SCH_1):PAGE63
   CK9 TP_CPU1_DMI_RX_DN0 @BASEBOARD_FAB2_LIB.BASEBOARD_FAB2(SCH_1):TP_CPU1_DMI_RX_DN0    I23 @BASEBOARD_FAB2_LIB.BASEBOARD_FAB2(SCH_1):PAGE63
  CV11 TP_CPU1_DMI_RX_DP3 @BASEBOARD_FAB2_LIB.BASEBOARD_FAB2(SCH_1):TP_CPU1_DMI_RX_DP3    I23 @BASEBOARD_FAB2_LIB.BASEBOARD_FAB2(SCH_1):PAGE63
  CP11 TP_CPU1_DMI_RX_DP2 @BASEBOARD_FAB2_LIB.BASEBOARD_FAB2(SCH_1):TP_CPU1_DMI_RX_DP2    I23 @BASEBOARD_FAB2_LIB.BASEBOARD_FAB2(SCH_1):PAGE63
  CN10 TP_CPU1_DMI_RX_DP1 @BASEBOARD_FAB2_LIB.BASEBOARD_FAB2(SCH_1):TP_CPU1_DMI_RX_DP1    I23 @BASEBOARD_FAB2_LIB.BASEBOARD_FAB2(SCH_1):PAGE63
  CL10 TP_CPU1_DMI_RX_DP0 @BASEBOARD_FAB2_LIB.BASEBOARD_FAB2(SCH_1):TP_CPU1_DMI_RX_DP0    I23 @BASEBOARD_FAB2_LIB.BASEBOARD_FAB2(SCH_1):PAGE63
   CP5 TP_CPU1_DMI_TX_DN3 @BASEBOARD_FAB2_LIB.BASEBOARD_FAB2(SCH_1):TP_CPU1_DMI_TX_DN3    I23 @BASEBOARD_FAB2_LIB.BASEBOARD_FAB2(SCH_1):PAGE63
   CN4 TP_CPU1_DMI_TX_DN2 @BASEBOARD_FAB2_LIB.BASEBOARD_FAB2(SCH_1):TP_CPU1_DMI_TX_DN2    I23 @BASEBOARD_FAB2_LIB.BASEBOARD_FAB2(SCH_1):PAGE63
   CJ4 TP_CPU1_DMI_TX_DN1 @BASEBOARD_FAB2_LIB.BASEBOARD_FAB2(SCH_1):TP_CPU1_DMI_TX_DN1    I23 @BASEBOARD_FAB2_LIB.BASEBOARD_FAB2(SCH_1):PAGE63
   CG4 TP_CPU1_DMI_TX_DN0 @BASEBOARD_FAB2_LIB.BASEBOARD_FAB2(SCH_1):TP_CPU1_DMI_TX_DN0    I23 @BASEBOARD_FAB2_LIB.BASEBOARD_FAB2(SCH_1):PAGE63
   CR4 TP_CPU1_DMI_TX_DP3 @BASEBOARD_FAB2_LIB.BASEBOARD_FAB2(SCH_1):TP_CPU1_DMI_TX_DP3    I23 @BASEBOARD_FAB2_LIB.BASEBOARD_FAB2(SCH_1):PAGE63
   CM3 TP_CPU1_DMI_TX_DP2 @BASEBOARD_FAB2_LIB.BASEBOARD_FAB2(SCH_1):TP_CPU1_DMI_TX_DP2    I23 @BASEBOARD_FAB2_LIB.BASEBOARD_FAB2(SCH_1):PAGE63
   CL4 TP_CPU1_DMI_TX_DP1 @BASEBOARD_FAB2_LIB.BASEBOARD_FAB2(SCH_1):TP_CPU1_DMI_TX_DP1    I23 @BASEBOARD_FAB2_LIB.BASEBOARD_FAB2(SCH_1):PAGE63
   CH5 TP_CPU1_DMI_TX_DP0 @BASEBOARD_FAB2_LIB.BASEBOARD_FAB2(SCH_1):TP_CPU1_DMI_TX_DP0    I23 @BASEBOARD_FAB2_LIB.BASEBOARD_FAB2(SCH_1):PAGE63
  AR20 PVCCMCP_CPU1 @BASEBOARD_FAB2_LIB.BASEBOARD_FAB2(SCH_1):PVCCMCP_CPU1    I23 @BASEBOARD_FAB2_LIB.BASEBOARD_FAB2(SCH_1):PAGE63
  AR22 PVCCMCP_CPU1 @BASEBOARD_FAB2_LIB.BASEBOARD_FAB2(SCH_1):PVCCMCP_CPU1    I23 @BASEBOARD_FAB2_LIB.BASEBOARD_FAB2(SCH_1):PAGE63
  AR26 PVCCMCP_CPU1 @BASEBOARD_FAB2_LIB.BASEBOARD_FAB2(SCH_1):PVCCMCP_CPU1    I23 @BASEBOARD_FAB2_LIB.BASEBOARD_FAB2(SCH_1):PAGE63
  AR62 TP_CPU1_RSVD_190 @BASEBOARD_FAB2_LIB.BASEBOARD_FAB2(SCH_1):TP_CPU1_RSVD_190    I23 @BASEBOARD_FAB2_LIB.BASEBOARD_FAB2(SCH_1):PAGE63
  AT13 TP_CPU1_RSVD_189 @BASEBOARD_FAB2_LIB.BASEBOARD_FAB2(SCH_1):TP_CPU1_RSVD_189    I23 @BASEBOARD_FAB2_LIB.BASEBOARD_FAB2(SCH_1):PAGE63
  AT23 PVCCMCP_CPU1 @BASEBOARD_FAB2_LIB.BASEBOARD_FAB2(SCH_1):PVCCMCP_CPU1    I23 @BASEBOARD_FAB2_LIB.BASEBOARD_FAB2(SCH_1):PAGE63
  AT25 PVCCMCP_CPU1 @BASEBOARD_FAB2_LIB.BASEBOARD_FAB2(SCH_1):PVCCMCP_CPU1    I23 @BASEBOARD_FAB2_LIB.BASEBOARD_FAB2(SCH_1):PAGE63
  AV77 TP_CPU1_RSVD_186 @BASEBOARD_FAB2_LIB.BASEBOARD_FAB2(SCH_1):TP_CPU1_RSVD_186    I23 @BASEBOARD_FAB2_LIB.BASEBOARD_FAB2(SCH_1):PAGE63
  AW64 TP_CPU1_RSVD_184 @BASEBOARD_FAB2_LIB.BASEBOARD_FAB2(SCH_1):TP_CPU1_RSVD_184    I23 @BASEBOARD_FAB2_LIB.BASEBOARD_FAB2(SCH_1):PAGE63
  AW76 TP_CPU1_RSVD_183 @BASEBOARD_FAB2_LIB.BASEBOARD_FAB2(SCH_1):TP_CPU1_RSVD_183    I23 @BASEBOARD_FAB2_LIB.BASEBOARD_FAB2(SCH_1):PAGE63
  AY65 TP_CPU1_RSVD_182 @BASEBOARD_FAB2_LIB.BASEBOARD_FAB2(SCH_1):TP_CPU1_RSVD_182    I23 @BASEBOARD_FAB2_LIB.BASEBOARD_FAB2(SCH_1):PAGE63
  AY67 TP_CPU1_RSVD_181 @BASEBOARD_FAB2_LIB.BASEBOARD_FAB2(SCH_1):TP_CPU1_RSVD_181    I23 @BASEBOARD_FAB2_LIB.BASEBOARD_FAB2(SCH_1):PAGE63
  AY75 TP_CPU1_RSVD_180 @BASEBOARD_FAB2_LIB.BASEBOARD_FAB2(SCH_1):TP_CPU1_RSVD_180    I23 @BASEBOARD_FAB2_LIB.BASEBOARD_FAB2(SCH_1):PAGE63
  AY77 TP_CPU1_RSVD_179 @BASEBOARD_FAB2_LIB.BASEBOARD_FAB2(SCH_1):TP_CPU1_RSVD_179    I23 @BASEBOARD_FAB2_LIB.BASEBOARD_FAB2(SCH_1):PAGE63
  BA14 TP_CPU1_RSVD_178 @BASEBOARD_FAB2_LIB.BASEBOARD_FAB2(SCH_1):TP_CPU1_RSVD_178    I23 @BASEBOARD_FAB2_LIB.BASEBOARD_FAB2(SCH_1):PAGE63
  BA16 TP_CPU1_RSVD_177 @BASEBOARD_FAB2_LIB.BASEBOARD_FAB2(SCH_1):TP_CPU1_RSVD_177    I23 @BASEBOARD_FAB2_LIB.BASEBOARD_FAB2(SCH_1):PAGE63
  BA18 TP_CPU1_RSVD_176 @BASEBOARD_FAB2_LIB.BASEBOARD_FAB2(SCH_1):TP_CPU1_RSVD_176    I23 @BASEBOARD_FAB2_LIB.BASEBOARD_FAB2(SCH_1):PAGE63
  BA22 TP_CPU1_RSVD_175 @BASEBOARD_FAB2_LIB.BASEBOARD_FAB2(SCH_1):TP_CPU1_RSVD_175    I23 @BASEBOARD_FAB2_LIB.BASEBOARD_FAB2(SCH_1):PAGE63
  BA64 TP_CPU1_RSVD_174 @BASEBOARD_FAB2_LIB.BASEBOARD_FAB2(SCH_1):TP_CPU1_RSVD_174    I23 @BASEBOARD_FAB2_LIB.BASEBOARD_FAB2(SCH_1):PAGE63
  BA66 TP_CPU1_RSVD_173 @BASEBOARD_FAB2_LIB.BASEBOARD_FAB2(SCH_1):TP_CPU1_RSVD_173    I23 @BASEBOARD_FAB2_LIB.BASEBOARD_FAB2(SCH_1):PAGE63
  BA76 TP_CPU1_RSVD_172 @BASEBOARD_FAB2_LIB.BASEBOARD_FAB2(SCH_1):TP_CPU1_RSVD_172    I23 @BASEBOARD_FAB2_LIB.BASEBOARD_FAB2(SCH_1):PAGE63
  DU16 TP_P3E_CPU1_PE1_RSR3_RXN<15> @BASEBOARD_FAB2_LIB.BASEBOARD_FAB2(SCH_1):TP_P3E_CPU1_PE1_RSR3_RXN(15)    I68 @BASEBOARD_FAB2_LIB.BASEBOARD_FAB2(SCH_1):PAGE64
  DY15 TP_P3E_CPU1_PE1_RSR3_RXN<14> @BASEBOARD_FAB2_LIB.BASEBOARD_FAB2(SCH_1):TP_P3E_CPU1_PE1_RSR3_RXN(14)    I68 @BASEBOARD_FAB2_LIB.BASEBOARD_FAB2(SCH_1):PAGE64
  DW14 TP_P3E_CPU1_PE1_RSR3_RXN<13> @BASEBOARD_FAB2_LIB.BASEBOARD_FAB2(SCH_1):TP_P3E_CPU1_PE1_RSR3_RXN(13)    I68 @BASEBOARD_FAB2_LIB.BASEBOARD_FAB2(SCH_1):PAGE64
  DV13 TP_P3E_CPU1_PE1_RSR3_RXN<12> @BASEBOARD_FAB2_LIB.BASEBOARD_FAB2(SCH_1):TP_P3E_CPU1_PE1_RSR3_RXN(12)    I68 @BASEBOARD_FAB2_LIB.BASEBOARD_FAB2(SCH_1):PAGE64
  DT13 TP_P3E_CPU1_PE1_RSR3_RXN<11> @BASEBOARD_FAB2_LIB.BASEBOARD_FAB2(SCH_1):TP_P3E_CPU1_PE1_RSR3_RXN(11)    I68 @BASEBOARD_FAB2_LIB.BASEBOARD_FAB2(SCH_1):PAGE64
  DT11 TP_P3E_CPU1_PE1_RSR3_RXN<10> @BASEBOARD_FAB2_LIB.BASEBOARD_FAB2(SCH_1):TP_P3E_CPU1_PE1_RSR3_RXN(10)    I68 @BASEBOARD_FAB2_LIB.BASEBOARD_FAB2(SCH_1):PAGE64
  DP11 TP_P3E_CPU1_PE1_RSR3_RXN<9> @BASEBOARD_FAB2_LIB.BASEBOARD_FAB2(SCH_1):TP_P3E_CPU1_PE1_RSR3_RXN(9)    I68 @BASEBOARD_FAB2_LIB.BASEBOARD_FAB2(SCH_1):PAGE64
  DM11 TP_P3E_CPU1_PE1_RSR3_RXN<8> @BASEBOARD_FAB2_LIB.BASEBOARD_FAB2(SCH_1):TP_P3E_CPU1_PE1_RSR3_RXN(8)    I68 @BASEBOARD_FAB2_LIB.BASEBOARD_FAB2(SCH_1):PAGE64
   DM9 TP_P3E_CPU1_PE1_MP_RXN<7> @BASEBOARD_FAB2_LIB.BASEBOARD_FAB2(SCH_1):TP_P3E_CPU1_PE1_MP_RXN(7)    I68 @BASEBOARD_FAB2_LIB.BASEBOARD_FAB2(SCH_1):PAGE64
   DK9 TP_P3E_CPU1_PE1_MP_RXN<6> @BASEBOARD_FAB2_LIB.BASEBOARD_FAB2(SCH_1):TP_P3E_CPU1_PE1_MP_RXN(6)    I68 @BASEBOARD_FAB2_LIB.BASEBOARD_FAB2(SCH_1):PAGE64
   DH9 TP_P3E_CPU1_PE1_MP_RXN<5> @BASEBOARD_FAB2_LIB.BASEBOARD_FAB2(SCH_1):TP_P3E_CPU1_PE1_MP_RXN(5)    I68 @BASEBOARD_FAB2_LIB.BASEBOARD_FAB2(SCH_1):PAGE64
  DE10 TP_P3E_CPU1_PE1_MP_RXN<4> @BASEBOARD_FAB2_LIB.BASEBOARD_FAB2(SCH_1):TP_P3E_CPU1_PE1_MP_RXN(4)    I68 @BASEBOARD_FAB2_LIB.BASEBOARD_FAB2(SCH_1):PAGE64
  DC10 TP_P3E_CPU1_PE1_MP_RXN<3> @BASEBOARD_FAB2_LIB.BASEBOARD_FAB2(SCH_1):TP_P3E_CPU1_PE1_MP_RXN(3)    I68 @BASEBOARD_FAB2_LIB.BASEBOARD_FAB2(SCH_1):PAGE64
   DC8 TP_P3E_CPU1_PE1_MP_RXN<2> @BASEBOARD_FAB2_LIB.BASEBOARD_FAB2(SCH_1):TP_P3E_CPU1_PE1_MP_RXN(2)    I68 @BASEBOARD_FAB2_LIB.BASEBOARD_FAB2(SCH_1):PAGE64
   DA8 TP_P3E_CPU1_PE1_MP_RXN<1> @BASEBOARD_FAB2_LIB.BASEBOARD_FAB2(SCH_1):TP_P3E_CPU1_PE1_MP_RXN(1)    I68 @BASEBOARD_FAB2_LIB.BASEBOARD_FAB2(SCH_1):PAGE64
   CW8 TP_P3E_CPU1_PE1_MP_RXN<0> @BASEBOARD_FAB2_LIB.BASEBOARD_FAB2(SCH_1):TP_P3E_CPU1_PE1_MP_RXN(0)    I68 @BASEBOARD_FAB2_LIB.BASEBOARD_FAB2(SCH_1):PAGE64
  DT15 TP_P3E_CPU1_PE1_RSR3_RXP<15> @BASEBOARD_FAB2_LIB.BASEBOARD_FAB2(SCH_1):TP_P3E_CPU1_PE1_RSR3_RXP(15)    I68 @BASEBOARD_FAB2_LIB.BASEBOARD_FAB2(SCH_1):PAGE64
  DV15 TP_P3E_CPU1_PE1_RSR3_RXP<14> @BASEBOARD_FAB2_LIB.BASEBOARD_FAB2(SCH_1):TP_P3E_CPU1_PE1_RSR3_RXP(14)    I68 @BASEBOARD_FAB2_LIB.BASEBOARD_FAB2(SCH_1):PAGE64
  DY13 TP_P3E_CPU1_PE1_RSR3_RXP<13> @BASEBOARD_FAB2_LIB.BASEBOARD_FAB2(SCH_1):TP_P3E_CPU1_PE1_RSR3_RXP(13)    I68 @BASEBOARD_FAB2_LIB.BASEBOARD_FAB2(SCH_1):PAGE64
  DU12 TP_P3E_CPU1_PE1_RSR3_RXP<12> @BASEBOARD_FAB2_LIB.BASEBOARD_FAB2(SCH_1):TP_P3E_CPU1_PE1_RSR3_RXP(12)    I68 @BASEBOARD_FAB2_LIB.BASEBOARD_FAB2(SCH_1):PAGE64
  DP13 TP_P3E_CPU1_PE1_RSR3_RXP<11> @BASEBOARD_FAB2_LIB.BASEBOARD_FAB2(SCH_1):TP_P3E_CPU1_PE1_RSR3_RXP(11)    I68 @BASEBOARD_FAB2_LIB.BASEBOARD_FAB2(SCH_1):PAGE64
  DR12 TP_P3E_CPU1_PE1_RSR3_RXP<10> @BASEBOARD_FAB2_LIB.BASEBOARD_FAB2(SCH_1):TP_P3E_CPU1_PE1_RSR3_RXP(10)    I68 @BASEBOARD_FAB2_LIB.BASEBOARD_FAB2(SCH_1):PAGE64
  DN10 TP_P3E_CPU1_PE1_RSR3_RXP<9> @BASEBOARD_FAB2_LIB.BASEBOARD_FAB2(SCH_1):TP_P3E_CPU1_PE1_RSR3_RXP(9)    I68 @BASEBOARD_FAB2_LIB.BASEBOARD_FAB2(SCH_1):PAGE64
  DK11 TP_P3E_CPU1_PE1_RSR3_RXP<8> @BASEBOARD_FAB2_LIB.BASEBOARD_FAB2(SCH_1):TP_P3E_CPU1_PE1_RSR3_RXP(8)    I68 @BASEBOARD_FAB2_LIB.BASEBOARD_FAB2(SCH_1):PAGE64
  DL10 TP_P3E_CPU1_PE1_MP_RXP<7> @BASEBOARD_FAB2_LIB.BASEBOARD_FAB2(SCH_1):TP_P3E_CPU1_PE1_MP_RXP(7)    I68 @BASEBOARD_FAB2_LIB.BASEBOARD_FAB2(SCH_1):PAGE64
   DJ8 TP_P3E_CPU1_PE1_MP_RXP<6> @BASEBOARD_FAB2_LIB.BASEBOARD_FAB2(SCH_1):TP_P3E_CPU1_PE1_MP_RXP(6)    I68 @BASEBOARD_FAB2_LIB.BASEBOARD_FAB2(SCH_1):PAGE64
   DF9 TP_P3E_CPU1_PE1_MP_RXP<5> @BASEBOARD_FAB2_LIB.BASEBOARD_FAB2(SCH_1):TP_P3E_CPU1_PE1_MP_RXP(5)    I68 @BASEBOARD_FAB2_LIB.BASEBOARD_FAB2(SCH_1):PAGE64
   DD9 TP_P3E_CPU1_PE1_MP_RXP<4> @BASEBOARD_FAB2_LIB.BASEBOARD_FAB2(SCH_1):TP_P3E_CPU1_PE1_MP_RXP(4)    I68 @BASEBOARD_FAB2_LIB.BASEBOARD_FAB2(SCH_1):PAGE64
  DA10 TP_P3E_CPU1_PE1_MP_RXP<3> @BASEBOARD_FAB2_LIB.BASEBOARD_FAB2(SCH_1):TP_P3E_CPU1_PE1_MP_RXP(3)    I68 @BASEBOARD_FAB2_LIB.BASEBOARD_FAB2(SCH_1):PAGE64
   DB9 TP_P3E_CPU1_PE1_MP_RXP<2> @BASEBOARD_FAB2_LIB.BASEBOARD_FAB2(SCH_1):TP_P3E_CPU1_PE1_MP_RXP(2)    I68 @BASEBOARD_FAB2_LIB.BASEBOARD_FAB2(SCH_1):PAGE64
   CY7 TP_P3E_CPU1_PE1_MP_RXP<1> @BASEBOARD_FAB2_LIB.BASEBOARD_FAB2(SCH_1):TP_P3E_CPU1_PE1_MP_RXP(1)    I68 @BASEBOARD_FAB2_LIB.BASEBOARD_FAB2(SCH_1):PAGE64
   CU8 TP_P3E_CPU1_PE1_MP_RXP<0> @BASEBOARD_FAB2_LIB.BASEBOARD_FAB2(SCH_1):TP_P3E_CPU1_PE1_MP_RXP(0)    I68 @BASEBOARD_FAB2_LIB.BASEBOARD_FAB2(SCH_1):PAGE64
   ED9 TP_P3E_CPU1_PE1_RSR3_TXN<15> @BASEBOARD_FAB2_LIB.BASEBOARD_FAB2(SCH_1):TP_P3E_CPU1_PE1_RSR3_TXN(15)    I68 @BASEBOARD_FAB2_LIB.BASEBOARD_FAB2(SCH_1):PAGE64
   EA8 TP_P3E_CPU1_PE1_RSR3_TXN<14> @BASEBOARD_FAB2_LIB.BASEBOARD_FAB2(SCH_1):TP_P3E_CPU1_PE1_RSR3_TXN(14)    I68 @BASEBOARD_FAB2_LIB.BASEBOARD_FAB2(SCH_1):PAGE64
   DY7 TP_P3E_CPU1_PE1_RSR3_TXN<13> @BASEBOARD_FAB2_LIB.BASEBOARD_FAB2(SCH_1):TP_P3E_CPU1_PE1_RSR3_TXN(13)    I68 @BASEBOARD_FAB2_LIB.BASEBOARD_FAB2(SCH_1):PAGE64
   DV7 TP_P3E_CPU1_PE1_RSR3_TXN<12> @BASEBOARD_FAB2_LIB.BASEBOARD_FAB2(SCH_1):TP_P3E_CPU1_PE1_RSR3_TXN(12)    I68 @BASEBOARD_FAB2_LIB.BASEBOARD_FAB2(SCH_1):PAGE64
   DU6 TP_P3E_CPU1_PE1_RSR3_TXN<11> @BASEBOARD_FAB2_LIB.BASEBOARD_FAB2(SCH_1):TP_P3E_CPU1_PE1_RSR3_TXN(11)    I68 @BASEBOARD_FAB2_LIB.BASEBOARD_FAB2(SCH_1):PAGE64
   DW4 TP_P3E_CPU1_PE1_RSR3_TXN<10> @BASEBOARD_FAB2_LIB.BASEBOARD_FAB2(SCH_1):TP_P3E_CPU1_PE1_RSR3_TXN(10)    I68 @BASEBOARD_FAB2_LIB.BASEBOARD_FAB2(SCH_1):PAGE64
   DV3 TP_P3E_CPU1_PE1_RSR3_TXN<9> @BASEBOARD_FAB2_LIB.BASEBOARD_FAB2(SCH_1):TP_P3E_CPU1_PE1_RSR3_TXN(9)    I68 @BASEBOARD_FAB2_LIB.BASEBOARD_FAB2(SCH_1):PAGE64
   DT5 TP_P3E_CPU1_PE1_RSR3_TXN<8> @BASEBOARD_FAB2_LIB.BASEBOARD_FAB2(SCH_1):TP_P3E_CPU1_PE1_RSR3_TXN(8)    I68 @BASEBOARD_FAB2_LIB.BASEBOARD_FAB2(SCH_1):PAGE64
   DN4 TP_P3E_CPU1_PE1_MP_TXN<7> @BASEBOARD_FAB2_LIB.BASEBOARD_FAB2(SCH_1):TP_P3E_CPU1_PE1_MP_TXN(7)    I68 @BASEBOARD_FAB2_LIB.BASEBOARD_FAB2(SCH_1):PAGE64
   DM3 TP_P3E_CPU1_PE1_MP_TXN<6> @BASEBOARD_FAB2_LIB.BASEBOARD_FAB2(SCH_1):TP_P3E_CPU1_PE1_MP_TXN(6)    I68 @BASEBOARD_FAB2_LIB.BASEBOARD_FAB2(SCH_1):PAGE64
   DK3 TP_P3E_CPU1_PE1_MP_TXN<5> @BASEBOARD_FAB2_LIB.BASEBOARD_FAB2(SCH_1):TP_P3E_CPU1_PE1_MP_TXN(5)    I68 @BASEBOARD_FAB2_LIB.BASEBOARD_FAB2(SCH_1):PAGE64
   DG4 TP_P3E_CPU1_PE1_MP_TXN<4> @BASEBOARD_FAB2_LIB.BASEBOARD_FAB2(SCH_1):TP_P3E_CPU1_PE1_MP_TXN(4)    I68 @BASEBOARD_FAB2_LIB.BASEBOARD_FAB2(SCH_1):PAGE64
   DE4 TP_P3E_CPU1_PE1_MP_TXN<3> @BASEBOARD_FAB2_LIB.BASEBOARD_FAB2(SCH_1):TP_P3E_CPU1_PE1_MP_TXN(3)    I68 @BASEBOARD_FAB2_LIB.BASEBOARD_FAB2(SCH_1):PAGE64
   DE2 TP_P3E_CPU1_PE1_MP_TXN<2> @BASEBOARD_FAB2_LIB.BASEBOARD_FAB2(SCH_1):TP_P3E_CPU1_PE1_MP_TXN(2)    I68 @BASEBOARD_FAB2_LIB.BASEBOARD_FAB2(SCH_1):PAGE64
   DC2 TP_P3E_CPU1_PE1_MP_TXN<1> @BASEBOARD_FAB2_LIB.BASEBOARD_FAB2(SCH_1):TP_P3E_CPU1_PE1_MP_TXN(1)    I68 @BASEBOARD_FAB2_LIB.BASEBOARD_FAB2(SCH_1):PAGE64
   DA2 TP_P3E_CPU1_PE1_MP_TXN<0> @BASEBOARD_FAB2_LIB.BASEBOARD_FAB2(SCH_1):TP_P3E_CPU1_PE1_MP_TXN(0)    I68 @BASEBOARD_FAB2_LIB.BASEBOARD_FAB2(SCH_1):PAGE64
   EC8 TP_P3E_CPU1_PE1_RSR3_TXP<15> @BASEBOARD_FAB2_LIB.BASEBOARD_FAB2(SCH_1):TP_P3E_CPU1_PE1_RSR3_TXP(15)    I68 @BASEBOARD_FAB2_LIB.BASEBOARD_FAB2(SCH_1):PAGE64
   EB7 TP_P3E_CPU1_PE1_RSR3_TXP<14> @BASEBOARD_FAB2_LIB.BASEBOARD_FAB2(SCH_1):TP_P3E_CPU1_PE1_RSR3_TXP(14)    I68 @BASEBOARD_FAB2_LIB.BASEBOARD_FAB2(SCH_1):PAGE64
   DW6 TP_P3E_CPU1_PE1_RSR3_TXP<13> @BASEBOARD_FAB2_LIB.BASEBOARD_FAB2(SCH_1):TP_P3E_CPU1_PE1_RSR3_TXP(13)    I68 @BASEBOARD_FAB2_LIB.BASEBOARD_FAB2(SCH_1):PAGE64
   DT7 TP_P3E_CPU1_PE1_RSR3_TXP<12> @BASEBOARD_FAB2_LIB.BASEBOARD_FAB2(SCH_1):TP_P3E_CPU1_PE1_RSR3_TXP(12)    I68 @BASEBOARD_FAB2_LIB.BASEBOARD_FAB2(SCH_1):PAGE64
   DV5 TP_P3E_CPU1_PE1_RSR3_TXP<11> @BASEBOARD_FAB2_LIB.BASEBOARD_FAB2(SCH_1):TP_P3E_CPU1_PE1_RSR3_TXP(11)    I68 @BASEBOARD_FAB2_LIB.BASEBOARD_FAB2(SCH_1):PAGE64
   DU4 TP_P3E_CPU1_PE1_RSR3_TXP<10> @BASEBOARD_FAB2_LIB.BASEBOARD_FAB2(SCH_1):TP_P3E_CPU1_PE1_RSR3_TXP(10)    I68 @BASEBOARD_FAB2_LIB.BASEBOARD_FAB2(SCH_1):PAGE64
   DU2 TP_P3E_CPU1_PE1_RSR3_TXP<9> @BASEBOARD_FAB2_LIB.BASEBOARD_FAB2(SCH_1):TP_P3E_CPU1_PE1_RSR3_TXP(9)    I68 @BASEBOARD_FAB2_LIB.BASEBOARD_FAB2(SCH_1):PAGE64
   DR4 TP_P3E_CPU1_PE1_RSR3_TXP<8> @BASEBOARD_FAB2_LIB.BASEBOARD_FAB2(SCH_1):TP_P3E_CPU1_PE1_RSR3_TXP(8)    I68 @BASEBOARD_FAB2_LIB.BASEBOARD_FAB2(SCH_1):PAGE64
   DP3 TP_P3E_CPU1_PE1_MP_TXP<7> @BASEBOARD_FAB2_LIB.BASEBOARD_FAB2(SCH_1):TP_P3E_CPU1_PE1_MP_TXP(7)    I68 @BASEBOARD_FAB2_LIB.BASEBOARD_FAB2(SCH_1):PAGE64
   DL2 TP_P3E_CPU1_PE1_MP_TXP<6> @BASEBOARD_FAB2_LIB.BASEBOARD_FAB2(SCH_1):TP_P3E_CPU1_PE1_MP_TXP(6)    I68 @BASEBOARD_FAB2_LIB.BASEBOARD_FAB2(SCH_1):PAGE64
   DH3 TP_P3E_CPU1_PE1_MP_TXP<5> @BASEBOARD_FAB2_LIB.BASEBOARD_FAB2(SCH_1):TP_P3E_CPU1_PE1_MP_TXP(5)    I68 @BASEBOARD_FAB2_LIB.BASEBOARD_FAB2(SCH_1):PAGE64
   DF3 TP_P3E_CPU1_PE1_MP_TXP<4> @BASEBOARD_FAB2_LIB.BASEBOARD_FAB2(SCH_1):TP_P3E_CPU1_PE1_MP_TXP(4)    I68 @BASEBOARD_FAB2_LIB.BASEBOARD_FAB2(SCH_1):PAGE64
   DC4 TP_P3E_CPU1_PE1_MP_TXP<3> @BASEBOARD_FAB2_LIB.BASEBOARD_FAB2(SCH_1):TP_P3E_CPU1_PE1_MP_TXP(3)    I68 @BASEBOARD_FAB2_LIB.BASEBOARD_FAB2(SCH_1):PAGE64
   DD3 TP_P3E_CPU1_PE1_MP_TXP<2> @BASEBOARD_FAB2_LIB.BASEBOARD_FAB2(SCH_1):TP_P3E_CPU1_PE1_MP_TXP(2)    I68 @BASEBOARD_FAB2_LIB.BASEBOARD_FAB2(SCH_1):PAGE64
   DB1 TP_P3E_CPU1_PE1_MP_TXP<1> @BASEBOARD_FAB2_LIB.BASEBOARD_FAB2(SCH_1):TP_P3E_CPU1_PE1_MP_TXP(1)    I68 @BASEBOARD_FAB2_LIB.BASEBOARD_FAB2(SCH_1):PAGE64
   CW2 TP_P3E_CPU1_PE1_MP_TXP<0> @BASEBOARD_FAB2_LIB.BASEBOARD_FAB2(SCH_1):TP_P3E_CPU1_PE1_MP_TXP(0)    I68 @BASEBOARD_FAB2_LIB.BASEBOARD_FAB2(SCH_1):PAGE64
   BK9 TP_P3E_CPU1_PE2_RSR_RXN<15> @BASEBOARD_FAB2_LIB.BASEBOARD_FAB2(SCH_1):TP_P3E_CPU1_PE2_RSR_RXN(15)    I68 @BASEBOARD_FAB2_LIB.BASEBOARD_FAB2(SCH_1):PAGE65
   BL8 TP_P3E_CPU1_PE2_RSR_RXN<14> @BASEBOARD_FAB2_LIB.BASEBOARD_FAB2(SCH_1):TP_P3E_CPU1_PE2_RSR_RXN(14)    I68 @BASEBOARD_FAB2_LIB.BASEBOARD_FAB2(SCH_1):PAGE65
   BN8 TP_P3E_CPU1_PE2_RSR_RXN<13> @BASEBOARD_FAB2_LIB.BASEBOARD_FAB2(SCH_1):TP_P3E_CPU1_PE2_RSR_RXN(13)    I68 @BASEBOARD_FAB2_LIB.BASEBOARD_FAB2(SCH_1):PAGE65
   BR8 TP_P3E_CPU1_PE2_RSR_RXN<12> @BASEBOARD_FAB2_LIB.BASEBOARD_FAB2(SCH_1):TP_P3E_CPU1_PE2_RSR_RXN(12)    I68 @BASEBOARD_FAB2_LIB.BASEBOARD_FAB2(SCH_1):PAGE65
   BT7 TP_P3E_CPU1_PE2_RSR_RXN<11> @BASEBOARD_FAB2_LIB.BASEBOARD_FAB2(SCH_1):TP_P3E_CPU1_PE2_RSR_RXN(11)    I68 @BASEBOARD_FAB2_LIB.BASEBOARD_FAB2(SCH_1):PAGE65
   BV7 TP_P3E_CPU1_PE2_RSR_RXN<10> @BASEBOARD_FAB2_LIB.BASEBOARD_FAB2(SCH_1):TP_P3E_CPU1_PE2_RSR_RXN(10)    I68 @BASEBOARD_FAB2_LIB.BASEBOARD_FAB2(SCH_1):PAGE65
   BY7 TP_P3E_CPU1_PE2_RSR_RXN<9> @BASEBOARD_FAB2_LIB.BASEBOARD_FAB2(SCH_1):TP_P3E_CPU1_PE2_RSR_RXN(9)    I68 @BASEBOARD_FAB2_LIB.BASEBOARD_FAB2(SCH_1):PAGE65
   BY9 TP_P3E_CPU1_PE2_RSR_RXN<8> @BASEBOARD_FAB2_LIB.BASEBOARD_FAB2(SCH_1):TP_P3E_CPU1_PE2_RSR_RXN(8)    I68 @BASEBOARD_FAB2_LIB.BASEBOARD_FAB2(SCH_1):PAGE65
   CE8 TP_P3E_CPU1_PE2_RSR_RXN<7> @BASEBOARD_FAB2_LIB.BASEBOARD_FAB2(SCH_1):TP_P3E_CPU1_PE2_RSR_RXN(7)    I68 @BASEBOARD_FAB2_LIB.BASEBOARD_FAB2(SCH_1):PAGE65
   CE6 TP_P3E_CPU1_PE2_RSR_RXN<6> @BASEBOARD_FAB2_LIB.BASEBOARD_FAB2(SCH_1):TP_P3E_CPU1_PE2_RSR_RXN(6)    I68 @BASEBOARD_FAB2_LIB.BASEBOARD_FAB2(SCH_1):PAGE65
   CG8 TP_P3E_CPU1_PE2_RSR_RXN<5> @BASEBOARD_FAB2_LIB.BASEBOARD_FAB2(SCH_1):TP_P3E_CPU1_PE2_RSR_RXN(5)    I68 @BASEBOARD_FAB2_LIB.BASEBOARD_FAB2(SCH_1):PAGE65
   CK7 TP_P3E_CPU1_PE2_RSR_RXN<4> @BASEBOARD_FAB2_LIB.BASEBOARD_FAB2(SCH_1):TP_P3E_CPU1_PE2_RSR_RXN(4)    I68 @BASEBOARD_FAB2_LIB.BASEBOARD_FAB2(SCH_1):PAGE65
   CM7 TP_P3E_CPU1_PE2_RSR_RXN<3> @BASEBOARD_FAB2_LIB.BASEBOARD_FAB2(SCH_1):TP_P3E_CPU1_PE2_RSR_RXN(3)    I68 @BASEBOARD_FAB2_LIB.BASEBOARD_FAB2(SCH_1):PAGE65
   CP7 TP_P3E_CPU1_PE2_RSR_RXN<2> @BASEBOARD_FAB2_LIB.BASEBOARD_FAB2(SCH_1):TP_P3E_CPU1_PE2_RSR_RXN(2)    I68 @BASEBOARD_FAB2_LIB.BASEBOARD_FAB2(SCH_1):PAGE65
   CP9 TP_P3E_CPU1_PE2_RSR_RXN<1> @BASEBOARD_FAB2_LIB.BASEBOARD_FAB2(SCH_1):TP_P3E_CPU1_PE2_RSR_RXN(1)    I68 @BASEBOARD_FAB2_LIB.BASEBOARD_FAB2(SCH_1):PAGE65
   CT9 TP_P3E_CPU1_PE2_RSR_RXN<0> @BASEBOARD_FAB2_LIB.BASEBOARD_FAB2(SCH_1):TP_P3E_CPU1_PE2_RSR_RXN(0)    I68 @BASEBOARD_FAB2_LIB.BASEBOARD_FAB2(SCH_1):PAGE65
  BJ10 TP_P3E_CPU1_PE2_RSR_RXP<15> @BASEBOARD_FAB2_LIB.BASEBOARD_FAB2(SCH_1):TP_P3E_CPU1_PE2_RSR_RXP(15)    I68 @BASEBOARD_FAB2_LIB.BASEBOARD_FAB2(SCH_1):PAGE65
   BJ8 TP_P3E_CPU1_PE2_RSR_RXP<14> @BASEBOARD_FAB2_LIB.BASEBOARD_FAB2(SCH_1):TP_P3E_CPU1_PE2_RSR_RXP(14)    I68 @BASEBOARD_FAB2_LIB.BASEBOARD_FAB2(SCH_1):PAGE65
   BM7 TP_P3E_CPU1_PE2_RSR_RXP<13> @BASEBOARD_FAB2_LIB.BASEBOARD_FAB2(SCH_1):TP_P3E_CPU1_PE2_RSR_RXP(13)    I68 @BASEBOARD_FAB2_LIB.BASEBOARD_FAB2(SCH_1):PAGE65
   BP9 TP_P3E_CPU1_PE2_RSR_RXP<12> @BASEBOARD_FAB2_LIB.BASEBOARD_FAB2(SCH_1):TP_P3E_CPU1_PE2_RSR_RXP(12)    I68 @BASEBOARD_FAB2_LIB.BASEBOARD_FAB2(SCH_1):PAGE65
   BP7 TP_P3E_CPU1_PE2_RSR_RXP<11> @BASEBOARD_FAB2_LIB.BASEBOARD_FAB2(SCH_1):TP_P3E_CPU1_PE2_RSR_RXP(11)    I68 @BASEBOARD_FAB2_LIB.BASEBOARD_FAB2(SCH_1):PAGE65
   BU6 TP_P3E_CPU1_PE2_RSR_RXP<10> @BASEBOARD_FAB2_LIB.BASEBOARD_FAB2(SCH_1):TP_P3E_CPU1_PE2_RSR_RXP(10)    I68 @BASEBOARD_FAB2_LIB.BASEBOARD_FAB2(SCH_1):PAGE65
   BW8 TP_P3E_CPU1_PE2_RSR_RXP<9> @BASEBOARD_FAB2_LIB.BASEBOARD_FAB2(SCH_1):TP_P3E_CPU1_PE2_RSR_RXP(9)    I68 @BASEBOARD_FAB2_LIB.BASEBOARD_FAB2(SCH_1):PAGE65
   BV9 TP_P3E_CPU1_PE2_RSR_RXP<8> @BASEBOARD_FAB2_LIB.BASEBOARD_FAB2(SCH_1):TP_P3E_CPU1_PE2_RSR_RXP(8)    I68 @BASEBOARD_FAB2_LIB.BASEBOARD_FAB2(SCH_1):PAGE65
   CC8 TP_P3E_CPU1_PE2_RSR_RXP<7> @BASEBOARD_FAB2_LIB.BASEBOARD_FAB2(SCH_1):TP_P3E_CPU1_PE2_RSR_RXP(7)    I68 @BASEBOARD_FAB2_LIB.BASEBOARD_FAB2(SCH_1):PAGE65
   CD7 TP_P3E_CPU1_PE2_RSR_RXP<6> @BASEBOARD_FAB2_LIB.BASEBOARD_FAB2(SCH_1):TP_P3E_CPU1_PE2_RSR_RXP(6)    I68 @BASEBOARD_FAB2_LIB.BASEBOARD_FAB2(SCH_1):PAGE65
   CF7 TP_P3E_CPU1_PE2_RSR_RXP<5> @BASEBOARD_FAB2_LIB.BASEBOARD_FAB2(SCH_1):TP_P3E_CPU1_PE2_RSR_RXP(5)    I68 @BASEBOARD_FAB2_LIB.BASEBOARD_FAB2(SCH_1):PAGE65
   CH7 TP_P3E_CPU1_PE2_RSR_RXP<4> @BASEBOARD_FAB2_LIB.BASEBOARD_FAB2(SCH_1):TP_P3E_CPU1_PE2_RSR_RXP(4)    I68 @BASEBOARD_FAB2_LIB.BASEBOARD_FAB2(SCH_1):PAGE65
   CL6 TP_P3E_CPU1_PE2_RSR_RXP<3> @BASEBOARD_FAB2_LIB.BASEBOARD_FAB2(SCH_1):TP_P3E_CPU1_PE2_RSR_RXP(3)    I68 @BASEBOARD_FAB2_LIB.BASEBOARD_FAB2(SCH_1):PAGE65
   CN8 TP_P3E_CPU1_PE2_RSR_RXP<2> @BASEBOARD_FAB2_LIB.BASEBOARD_FAB2(SCH_1):TP_P3E_CPU1_PE2_RSR_RXP(2)    I68 @BASEBOARD_FAB2_LIB.BASEBOARD_FAB2(SCH_1):PAGE65
   CM9 TP_P3E_CPU1_PE2_RSR_RXP<1> @BASEBOARD_FAB2_LIB.BASEBOARD_FAB2(SCH_1):TP_P3E_CPU1_PE2_RSR_RXP(1)    I68 @BASEBOARD_FAB2_LIB.BASEBOARD_FAB2(SCH_1):PAGE65
   CR8 TP_P3E_CPU1_PE2_RSR_RXP<0> @BASEBOARD_FAB2_LIB.BASEBOARD_FAB2(SCH_1):TP_P3E_CPU1_PE2_RSR_RXP(0)    I68 @BASEBOARD_FAB2_LIB.BASEBOARD_FAB2(SCH_1):PAGE65
   BM5 TP_P3E_CPU1_PE2_RSR_TXN<15> @BASEBOARD_FAB2_LIB.BASEBOARD_FAB2(SCH_1):TP_P3E_CPU1_PE2_RSR_TXN(15)    I68 @BASEBOARD_FAB2_LIB.BASEBOARD_FAB2(SCH_1):PAGE65
   BL4 TP_P3E_CPU1_PE2_RSR_TXN<14> @BASEBOARD_FAB2_LIB.BASEBOARD_FAB2(SCH_1):TP_P3E_CPU1_PE2_RSR_TXN(14)    I68 @BASEBOARD_FAB2_LIB.BASEBOARD_FAB2(SCH_1):PAGE65
   BP5 TP_P3E_CPU1_PE2_RSR_TXN<13> @BASEBOARD_FAB2_LIB.BASEBOARD_FAB2(SCH_1):TP_P3E_CPU1_PE2_RSR_TXN(13)    I68 @BASEBOARD_FAB2_LIB.BASEBOARD_FAB2(SCH_1):PAGE65
   BU4 TP_P3E_CPU1_PE2_RSR_TXN<12> @BASEBOARD_FAB2_LIB.BASEBOARD_FAB2(SCH_1):TP_P3E_CPU1_PE2_RSR_TXN(12)    I68 @BASEBOARD_FAB2_LIB.BASEBOARD_FAB2(SCH_1):PAGE65
   BW4 TP_P3E_CPU1_PE2_RSR_TXN<11> @BASEBOARD_FAB2_LIB.BASEBOARD_FAB2(SCH_1):TP_P3E_CPU1_PE2_RSR_TXN(11)    I68 @BASEBOARD_FAB2_LIB.BASEBOARD_FAB2(SCH_1):PAGE65
   CA4 TP_P3E_CPU1_PE2_RSR_TXN<10> @BASEBOARD_FAB2_LIB.BASEBOARD_FAB2(SCH_1):TP_P3E_CPU1_PE2_RSR_TXN(10)    I68 @BASEBOARD_FAB2_LIB.BASEBOARD_FAB2(SCH_1):PAGE65
   CB3 TP_P3E_CPU1_PE2_RSR_TXN<9> @BASEBOARD_FAB2_LIB.BASEBOARD_FAB2(SCH_1):TP_P3E_CPU1_PE2_RSR_TXN(9)    I68 @BASEBOARD_FAB2_LIB.BASEBOARD_FAB2(SCH_1):PAGE65
   CC2 TP_P3E_CPU1_PE2_RSR_TXN<8> @BASEBOARD_FAB2_LIB.BASEBOARD_FAB2(SCH_1):TP_P3E_CPU1_PE2_RSR_TXN(8)    I68 @BASEBOARD_FAB2_LIB.BASEBOARD_FAB2(SCH_1):PAGE65
   CF3 TP_P3E_CPU1_PE2_RSR_TXN<7> @BASEBOARD_FAB2_LIB.BASEBOARD_FAB2(SCH_1):TP_P3E_CPU1_PE2_RSR_TXN(7)    I68 @BASEBOARD_FAB2_LIB.BASEBOARD_FAB2(SCH_1):PAGE65
   CG2 TP_P3E_CPU1_PE2_RSR_TXN<6> @BASEBOARD_FAB2_LIB.BASEBOARD_FAB2(SCH_1):TP_P3E_CPU1_PE2_RSR_TXN(6)    I68 @BASEBOARD_FAB2_LIB.BASEBOARD_FAB2(SCH_1):PAGE65
   CL2 TP_P3E_CPU1_PE2_RSR_TXN<5> @BASEBOARD_FAB2_LIB.BASEBOARD_FAB2(SCH_1):TP_P3E_CPU1_PE2_RSR_TXN(5)    I68 @BASEBOARD_FAB2_LIB.BASEBOARD_FAB2(SCH_1):PAGE65
   CM1 TP_P3E_CPU1_PE2_RSR_TXN<4> @BASEBOARD_FAB2_LIB.BASEBOARD_FAB2(SCH_1):TP_P3E_CPU1_PE2_RSR_TXN(4)    I68 @BASEBOARD_FAB2_LIB.BASEBOARD_FAB2(SCH_1):PAGE65
   CT3 TP_P3E_CPU1_PE2_RSR_TXN<3> @BASEBOARD_FAB2_LIB.BASEBOARD_FAB2(SCH_1):TP_P3E_CPU1_PE2_RSR_TXN(3)    I68 @BASEBOARD_FAB2_LIB.BASEBOARD_FAB2(SCH_1):PAGE65
   CT1 TP_P3E_CPU1_PE2_RSR_TXN<2> @BASEBOARD_FAB2_LIB.BASEBOARD_FAB2(SCH_1):TP_P3E_CPU1_PE2_RSR_TXN(2)    I68 @BASEBOARD_FAB2_LIB.BASEBOARD_FAB2(SCH_1):PAGE65
   CV3 TP_P3E_CPU1_PE2_RSR_TXN<1> @BASEBOARD_FAB2_LIB.BASEBOARD_FAB2(SCH_1):TP_P3E_CPU1_PE2_RSR_TXN(1)    I68 @BASEBOARD_FAB2_LIB.BASEBOARD_FAB2(SCH_1):PAGE65
   CY3 TP_P3E_CPU1_PE2_RSR_TXN<0> @BASEBOARD_FAB2_LIB.BASEBOARD_FAB2(SCH_1):TP_P3E_CPU1_PE2_RSR_TXN(0)    I68 @BASEBOARD_FAB2_LIB.BASEBOARD_FAB2(SCH_1):PAGE65
   BK5 TP_P3E_CPU1_PE2_RSR_TXP<15> @BASEBOARD_FAB2_LIB.BASEBOARD_FAB2(SCH_1):TP_P3E_CPU1_PE2_RSR_TXP(15)    I68 @BASEBOARD_FAB2_LIB.BASEBOARD_FAB2(SCH_1):PAGE65
   BM3 TP_P3E_CPU1_PE2_RSR_TXP<14> @BASEBOARD_FAB2_LIB.BASEBOARD_FAB2(SCH_1):TP_P3E_CPU1_PE2_RSR_TXP(14)    I68 @BASEBOARD_FAB2_LIB.BASEBOARD_FAB2(SCH_1):PAGE65
   BN4 TP_P3E_CPU1_PE2_RSR_TXP<13> @BASEBOARD_FAB2_LIB.BASEBOARD_FAB2(SCH_1):TP_P3E_CPU1_PE2_RSR_TXP(13)    I68 @BASEBOARD_FAB2_LIB.BASEBOARD_FAB2(SCH_1):PAGE65
   BR4 TP_P3E_CPU1_PE2_RSR_TXP<12> @BASEBOARD_FAB2_LIB.BASEBOARD_FAB2(SCH_1):TP_P3E_CPU1_PE2_RSR_TXP(12)    I68 @BASEBOARD_FAB2_LIB.BASEBOARD_FAB2(SCH_1):PAGE65
   BV3 TP_P3E_CPU1_PE2_RSR_TXP<11> @BASEBOARD_FAB2_LIB.BASEBOARD_FAB2(SCH_1):TP_P3E_CPU1_PE2_RSR_TXP(11)    I68 @BASEBOARD_FAB2_LIB.BASEBOARD_FAB2(SCH_1):PAGE65
   BY5 TP_P3E_CPU1_PE2_RSR_TXP<10> @BASEBOARD_FAB2_LIB.BASEBOARD_FAB2(SCH_1):TP_P3E_CPU1_PE2_RSR_TXP(10)    I68 @BASEBOARD_FAB2_LIB.BASEBOARD_FAB2(SCH_1):PAGE65
   BY3 TP_P3E_CPU1_PE2_RSR_TXP<9> @BASEBOARD_FAB2_LIB.BASEBOARD_FAB2(SCH_1):TP_P3E_CPU1_PE2_RSR_TXP(9)    I68 @BASEBOARD_FAB2_LIB.BASEBOARD_FAB2(SCH_1):PAGE65
   CD3 TP_P3E_CPU1_PE2_RSR_TXP<8> @BASEBOARD_FAB2_LIB.BASEBOARD_FAB2(SCH_1):TP_P3E_CPU1_PE2_RSR_TXP(8)    I68 @BASEBOARD_FAB2_LIB.BASEBOARD_FAB2(SCH_1):PAGE65
   CE4 TP_P3E_CPU1_PE2_RSR_TXP<7> @BASEBOARD_FAB2_LIB.BASEBOARD_FAB2(SCH_1):TP_P3E_CPU1_PE2_RSR_TXP(7)    I68 @BASEBOARD_FAB2_LIB.BASEBOARD_FAB2(SCH_1):PAGE65
   CE2 TP_P3E_CPU1_PE2_RSR_TXP<6> @BASEBOARD_FAB2_LIB.BASEBOARD_FAB2(SCH_1):TP_P3E_CPU1_PE2_RSR_TXP(6)    I68 @BASEBOARD_FAB2_LIB.BASEBOARD_FAB2(SCH_1):PAGE65
   CK3 TP_P3E_CPU1_PE2_RSR_TXP<5> @BASEBOARD_FAB2_LIB.BASEBOARD_FAB2(SCH_1):TP_P3E_CPU1_PE2_RSR_TXP(5)    I68 @BASEBOARD_FAB2_LIB.BASEBOARD_FAB2(SCH_1):PAGE65
   CK1 TP_P3E_CPU1_PE2_RSR_TXP<4> @BASEBOARD_FAB2_LIB.BASEBOARD_FAB2(SCH_1):TP_P3E_CPU1_PE2_RSR_TXP(4)    I68 @BASEBOARD_FAB2_LIB.BASEBOARD_FAB2(SCH_1):PAGE65
   CP3 TP_P3E_CPU1_PE2_RSR_TXP<3> @BASEBOARD_FAB2_LIB.BASEBOARD_FAB2(SCH_1):TP_P3E_CPU1_PE2_RSR_TXP(3)    I68 @BASEBOARD_FAB2_LIB.BASEBOARD_FAB2(SCH_1):PAGE65
   CR2 TP_P3E_CPU1_PE2_RSR_TXP<2> @BASEBOARD_FAB2_LIB.BASEBOARD_FAB2(SCH_1):TP_P3E_CPU1_PE2_RSR_TXP(2)    I68 @BASEBOARD_FAB2_LIB.BASEBOARD_FAB2(SCH_1):PAGE65
   CU2 TP_P3E_CPU1_PE2_RSR_TXP<1> @BASEBOARD_FAB2_LIB.BASEBOARD_FAB2(SCH_1):TP_P3E_CPU1_PE2_RSR_TXP(1)    I68 @BASEBOARD_FAB2_LIB.BASEBOARD_FAB2(SCH_1):PAGE65
   CW4 TP_P3E_CPU1_PE2_RSR_TXP<0> @BASEBOARD_FAB2_LIB.BASEBOARD_FAB2(SCH_1):TP_P3E_CPU1_PE2_RSR_TXP(0)    I68 @BASEBOARD_FAB2_LIB.BASEBOARD_FAB2(SCH_1):PAGE65
   CV9 P3E_CPU1_PE3_MP_RXN<15> @BASEBOARD_FAB2_LIB.BASEBOARD_FAB2(SCH_1):P3E_CPU1_PE3_MP_RXN(15)    I84 @BASEBOARD_FAB2_LIB.BASEBOARD_FAB2(SCH_1):PAGE66
  CY11 P3E_CPU1_PE3_MP_RXN<14> @BASEBOARD_FAB2_LIB.BASEBOARD_FAB2(SCH_1):P3E_CPU1_PE3_MP_RXN(14)    I84 @BASEBOARD_FAB2_LIB.BASEBOARD_FAB2(SCH_1):PAGE66
  DB11 P3E_CPU1_PE3_MP_RXN<13> @BASEBOARD_FAB2_LIB.BASEBOARD_FAB2(SCH_1):P3E_CPU1_PE3_MP_RXN(13)    I84 @BASEBOARD_FAB2_LIB.BASEBOARD_FAB2(SCH_1):PAGE66
  DD13 P3E_CPU1_PE3_MP_RXP<12> @BASEBOARD_FAB2_LIB.BASEBOARD_FAB2(SCH_1):P3E_CPU1_PE3_MP_RXP(12)    I84 @BASEBOARD_FAB2_LIB.BASEBOARD_FAB2(SCH_1):PAGE66
  DG10 P3E_CPU1_PE3_MP_RXN<11> @BASEBOARD_FAB2_LIB.BASEBOARD_FAB2(SCH_1):P3E_CPU1_PE3_MP_RXN(11)    I84 @BASEBOARD_FAB2_LIB.BASEBOARD_FAB2(SCH_1):PAGE66
  DG12 P3E_CPU1_PE3_MP_RXN<10> @BASEBOARD_FAB2_LIB.BASEBOARD_FAB2(SCH_1):P3E_CPU1_PE3_MP_RXN(10)    I84 @BASEBOARD_FAB2_LIB.BASEBOARD_FAB2(SCH_1):PAGE66
  DJ12 P3E_CPU1_PE3_MP_RXN<9> @BASEBOARD_FAB2_LIB.BASEBOARD_FAB2(SCH_1):P3E_CPU1_PE3_MP_RXN(9)    I84 @BASEBOARD_FAB2_LIB.BASEBOARD_FAB2(SCH_1):PAGE66
  DL12 P3E_CPU1_PE3_MP_RXN<8> @BASEBOARD_FAB2_LIB.BASEBOARD_FAB2(SCH_1):P3E_CPU1_PE3_MP_RXN(8)    I84 @BASEBOARD_FAB2_LIB.BASEBOARD_FAB2(SCH_1):PAGE66
  DL14 P3E_CPU1_PE3_MP_RXN<7> @BASEBOARD_FAB2_LIB.BASEBOARD_FAB2(SCH_1):P3E_CPU1_PE3_MP_RXN(7)    I84 @BASEBOARD_FAB2_LIB.BASEBOARD_FAB2(SCH_1):PAGE66
  DN14 P3E_CPU1_PE3_MP_RXN<6> @BASEBOARD_FAB2_LIB.BASEBOARD_FAB2(SCH_1):P3E_CPU1_PE3_MP_RXN(6)    I84 @BASEBOARD_FAB2_LIB.BASEBOARD_FAB2(SCH_1):PAGE66
  DR14 P3E_CPU1_PE3_MP_RXN<5> @BASEBOARD_FAB2_LIB.BASEBOARD_FAB2(SCH_1):P3E_CPU1_PE3_MP_RXN(5)    I84 @BASEBOARD_FAB2_LIB.BASEBOARD_FAB2(SCH_1):PAGE66
  DR16 P3E_CPU1_PE3_MP_RXN<4> @BASEBOARD_FAB2_LIB.BASEBOARD_FAB2(SCH_1):P3E_CPU1_PE3_MP_RXN(4)    I84 @BASEBOARD_FAB2_LIB.BASEBOARD_FAB2(SCH_1):PAGE66
  DT19 P3E_CPU1_PE3_MP_RXN<3> @BASEBOARD_FAB2_LIB.BASEBOARD_FAB2(SCH_1):P3E_CPU1_PE3_MP_RXN(3)    I84 @BASEBOARD_FAB2_LIB.BASEBOARD_FAB2(SCH_1):PAGE66
  DW16 P3E_CPU1_PE3_MP_RXN<2> @BASEBOARD_FAB2_LIB.BASEBOARD_FAB2(SCH_1):P3E_CPU1_PE3_MP_RXN(2)    I84 @BASEBOARD_FAB2_LIB.BASEBOARD_FAB2(SCH_1):PAGE66
  DW18 P3E_CPU1_PE3_MP_RXN<1> @BASEBOARD_FAB2_LIB.BASEBOARD_FAB2(SCH_1):P3E_CPU1_PE3_MP_RXN(1)    I84 @BASEBOARD_FAB2_LIB.BASEBOARD_FAB2(SCH_1):PAGE66
  EA18 P3E_CPU1_PE3_MP_RXN<0> @BASEBOARD_FAB2_LIB.BASEBOARD_FAB2(SCH_1):P3E_CPU1_PE3_MP_RXN(0)    I84 @BASEBOARD_FAB2_LIB.BASEBOARD_FAB2(SCH_1):PAGE66
  CU10 P3E_CPU1_PE3_MP_RXP<15> @BASEBOARD_FAB2_LIB.BASEBOARD_FAB2(SCH_1):P3E_CPU1_PE3_MP_RXP(15)    I84 @BASEBOARD_FAB2_LIB.BASEBOARD_FAB2(SCH_1):PAGE66
  CW10 P3E_CPU1_PE3_MP_RXP<14> @BASEBOARD_FAB2_LIB.BASEBOARD_FAB2(SCH_1):P3E_CPU1_PE3_MP_RXP(14)    I84 @BASEBOARD_FAB2_LIB.BASEBOARD_FAB2(SCH_1):PAGE66
  DA12 P3E_CPU1_PE3_MP_RXP<13> @BASEBOARD_FAB2_LIB.BASEBOARD_FAB2(SCH_1):P3E_CPU1_PE3_MP_RXP(13)    I84 @BASEBOARD_FAB2_LIB.BASEBOARD_FAB2(SCH_1):PAGE66
  DC12 P3E_CPU1_PE3_MP_RXN<12> @BASEBOARD_FAB2_LIB.BASEBOARD_FAB2(SCH_1):P3E_CPU1_PE3_MP_RXN(12)    I84 @BASEBOARD_FAB2_LIB.BASEBOARD_FAB2(SCH_1):PAGE66
  DF11 P3E_CPU1_PE3_MP_RXP<11> @BASEBOARD_FAB2_LIB.BASEBOARD_FAB2(SCH_1):P3E_CPU1_PE3_MP_RXP(11)    I84 @BASEBOARD_FAB2_LIB.BASEBOARD_FAB2(SCH_1):PAGE66
  DE12 P3E_CPU1_PE3_MP_RXP<10> @BASEBOARD_FAB2_LIB.BASEBOARD_FAB2(SCH_1):P3E_CPU1_PE3_MP_RXP(10)    I84 @BASEBOARD_FAB2_LIB.BASEBOARD_FAB2(SCH_1):PAGE66
  DH11 P3E_CPU1_PE3_MP_RXP<9> @BASEBOARD_FAB2_LIB.BASEBOARD_FAB2(SCH_1):P3E_CPU1_PE3_MP_RXP(9)    I84 @BASEBOARD_FAB2_LIB.BASEBOARD_FAB2(SCH_1):PAGE66
  DK13 P3E_CPU1_PE3_MP_RXP<8> @BASEBOARD_FAB2_LIB.BASEBOARD_FAB2(SCH_1):P3E_CPU1_PE3_MP_RXP(8)    I84 @BASEBOARD_FAB2_LIB.BASEBOARD_FAB2(SCH_1):PAGE66
  DJ14 P3E_CPU1_PE3_MP_RXP<7> @BASEBOARD_FAB2_LIB.BASEBOARD_FAB2(SCH_1):P3E_CPU1_PE3_MP_RXP(7)    I84 @BASEBOARD_FAB2_LIB.BASEBOARD_FAB2(SCH_1):PAGE66
  DM13 P3E_CPU1_PE3_MP_RXP<6> @BASEBOARD_FAB2_LIB.BASEBOARD_FAB2(SCH_1):P3E_CPU1_PE3_MP_RXP(6)    I84 @BASEBOARD_FAB2_LIB.BASEBOARD_FAB2(SCH_1):PAGE66
  DP15 P3E_CPU1_PE3_MP_RXP<5> @BASEBOARD_FAB2_LIB.BASEBOARD_FAB2(SCH_1):P3E_CPU1_PE3_MP_RXP(5)    I84 @BASEBOARD_FAB2_LIB.BASEBOARD_FAB2(SCH_1):PAGE66
  DN16 P3E_CPU1_PE3_MP_RXP<4> @BASEBOARD_FAB2_LIB.BASEBOARD_FAB2(SCH_1):P3E_CPU1_PE3_MP_RXP(4)    I84 @BASEBOARD_FAB2_LIB.BASEBOARD_FAB2(SCH_1):PAGE66
  DR18 P3E_CPU1_PE3_MP_RXP<3> @BASEBOARD_FAB2_LIB.BASEBOARD_FAB2(SCH_1):P3E_CPU1_PE3_MP_RXP(3)    I84 @BASEBOARD_FAB2_LIB.BASEBOARD_FAB2(SCH_1):PAGE66
  DV17 P3E_CPU1_PE3_MP_RXP<2> @BASEBOARD_FAB2_LIB.BASEBOARD_FAB2(SCH_1):P3E_CPU1_PE3_MP_RXP(2)    I84 @BASEBOARD_FAB2_LIB.BASEBOARD_FAB2(SCH_1):PAGE66
  DU18 P3E_CPU1_PE3_MP_RXP<1> @BASEBOARD_FAB2_LIB.BASEBOARD_FAB2(SCH_1):P3E_CPU1_PE3_MP_RXP(1)    I84 @BASEBOARD_FAB2_LIB.BASEBOARD_FAB2(SCH_1):PAGE66
  DY17 P3E_CPU1_PE3_MP_RXP<0> @BASEBOARD_FAB2_LIB.BASEBOARD_FAB2(SCH_1):P3E_CPU1_PE3_MP_RXP(0)    I84 @BASEBOARD_FAB2_LIB.BASEBOARD_FAB2(SCH_1):PAGE66
   CY5 P3E_CPU1_PE3_MP_TXN<15> @BASEBOARD_FAB2_LIB.BASEBOARD_FAB2(SCH_1):P3E_CPU1_PE3_MP_TXN(15)    I84 @BASEBOARD_FAB2_LIB.BASEBOARD_FAB2(SCH_1):PAGE66
   DB5 P3E_CPU1_PE3_MP_TXN<14> @BASEBOARD_FAB2_LIB.BASEBOARD_FAB2(SCH_1):P3E_CPU1_PE3_MP_TXN(14)    I84 @BASEBOARD_FAB2_LIB.BASEBOARD_FAB2(SCH_1):PAGE66
   DD5 P3E_CPU1_PE3_MP_TXN<13> @BASEBOARD_FAB2_LIB.BASEBOARD_FAB2(SCH_1):P3E_CPU1_PE3_MP_TXN(13)    I84 @BASEBOARD_FAB2_LIB.BASEBOARD_FAB2(SCH_1):PAGE66
   DJ6 P3E_CPU1_PE3_MP_TXN<12> @BASEBOARD_FAB2_LIB.BASEBOARD_FAB2(SCH_1):P3E_CPU1_PE3_MP_TXN(12)    I84 @BASEBOARD_FAB2_LIB.BASEBOARD_FAB2(SCH_1):PAGE66
   DJ4 P3E_CPU1_PE3_MP_TXN<11> @BASEBOARD_FAB2_LIB.BASEBOARD_FAB2(SCH_1):P3E_CPU1_PE3_MP_TXN(11)    I84 @BASEBOARD_FAB2_LIB.BASEBOARD_FAB2(SCH_1):PAGE66
   DL6 P3E_CPU1_PE3_MP_TXN<10> @BASEBOARD_FAB2_LIB.BASEBOARD_FAB2(SCH_1):P3E_CPU1_PE3_MP_TXN(10)    I84 @BASEBOARD_FAB2_LIB.BASEBOARD_FAB2(SCH_1):PAGE66
   DP5 P3E_CPU1_PE3_MP_TXN<9> @BASEBOARD_FAB2_LIB.BASEBOARD_FAB2(SCH_1):P3E_CPU1_PE3_MP_TXN(9)    I84 @BASEBOARD_FAB2_LIB.BASEBOARD_FAB2(SCH_1):PAGE66
   DM7 P3E_CPU1_PE3_MP_TXN<8> @BASEBOARD_FAB2_LIB.BASEBOARD_FAB2(SCH_1):P3E_CPU1_PE3_MP_TXN(8)    I84 @BASEBOARD_FAB2_LIB.BASEBOARD_FAB2(SCH_1):PAGE66
   DR8 P3E_CPU1_PE3_MP_TXN<7> @BASEBOARD_FAB2_LIB.BASEBOARD_FAB2(SCH_1):P3E_CPU1_PE3_MP_TXN(7)    I84 @BASEBOARD_FAB2_LIB.BASEBOARD_FAB2(SCH_1):PAGE66
   DU8 P3E_CPU1_PE3_MP_TXN<6> @BASEBOARD_FAB2_LIB.BASEBOARD_FAB2(SCH_1):P3E_CPU1_PE3_MP_TXN(6)    I84 @BASEBOARD_FAB2_LIB.BASEBOARD_FAB2(SCH_1):PAGE66
  DW10 P3E_CPU1_PE3_MP_TXN<5> @BASEBOARD_FAB2_LIB.BASEBOARD_FAB2(SCH_1):P3E_CPU1_PE3_MP_TXN(5)    I84 @BASEBOARD_FAB2_LIB.BASEBOARD_FAB2(SCH_1):PAGE66
   EB9 P3E_CPU1_PE3_MP_TXN<4> @BASEBOARD_FAB2_LIB.BASEBOARD_FAB2(SCH_1):P3E_CPU1_PE3_MP_TXN(4)    I84 @BASEBOARD_FAB2_LIB.BASEBOARD_FAB2(SCH_1):PAGE66
  DY11 P3E_CPU1_PE3_MP_TXN<3> @BASEBOARD_FAB2_LIB.BASEBOARD_FAB2(SCH_1):P3E_CPU1_PE3_MP_TXN(3)    I84 @BASEBOARD_FAB2_LIB.BASEBOARD_FAB2(SCH_1):PAGE66
  EC12 P3E_CPU1_PE3_MP_TXN<2> @BASEBOARD_FAB2_LIB.BASEBOARD_FAB2(SCH_1):P3E_CPU1_PE3_MP_TXN(2)    I84 @BASEBOARD_FAB2_LIB.BASEBOARD_FAB2(SCH_1):PAGE66
  EE12 P3E_CPU1_PE3_MP_TXN<1> @BASEBOARD_FAB2_LIB.BASEBOARD_FAB2(SCH_1):P3E_CPU1_PE3_MP_TXN(1)    I84 @BASEBOARD_FAB2_LIB.BASEBOARD_FAB2(SCH_1):PAGE66
  EE14 P3E_CPU1_PE3_MP_TXN<0> @BASEBOARD_FAB2_LIB.BASEBOARD_FAB2(SCH_1):P3E_CPU1_PE3_MP_TXN(0)    I84 @BASEBOARD_FAB2_LIB.BASEBOARD_FAB2(SCH_1):PAGE66
   CV5 P3E_CPU1_PE3_MP_TXP<15> @BASEBOARD_FAB2_LIB.BASEBOARD_FAB2(SCH_1):P3E_CPU1_PE3_MP_TXP(15)    I84 @BASEBOARD_FAB2_LIB.BASEBOARD_FAB2(SCH_1):PAGE66
   DA4 P3E_CPU1_PE3_MP_TXP<14> @BASEBOARD_FAB2_LIB.BASEBOARD_FAB2(SCH_1):P3E_CPU1_PE3_MP_TXP(14)    I84 @BASEBOARD_FAB2_LIB.BASEBOARD_FAB2(SCH_1):PAGE66
   DC6 P3E_CPU1_PE3_MP_TXP<13> @BASEBOARD_FAB2_LIB.BASEBOARD_FAB2(SCH_1):P3E_CPU1_PE3_MP_TXP(13)    I84 @BASEBOARD_FAB2_LIB.BASEBOARD_FAB2(SCH_1):PAGE66
   DG6 P3E_CPU1_PE3_MP_TXP<12> @BASEBOARD_FAB2_LIB.BASEBOARD_FAB2(SCH_1):P3E_CPU1_PE3_MP_TXP(12)    I84 @BASEBOARD_FAB2_LIB.BASEBOARD_FAB2(SCH_1):PAGE66
   DH5 P3E_CPU1_PE3_MP_TXP<11> @BASEBOARD_FAB2_LIB.BASEBOARD_FAB2(SCH_1):P3E_CPU1_PE3_MP_TXP(11)    I84 @BASEBOARD_FAB2_LIB.BASEBOARD_FAB2(SCH_1):PAGE66
   DK5 P3E_CPU1_PE3_MP_TXP<10> @BASEBOARD_FAB2_LIB.BASEBOARD_FAB2(SCH_1):P3E_CPU1_PE3_MP_TXP(10)    I84 @BASEBOARD_FAB2_LIB.BASEBOARD_FAB2(SCH_1):PAGE66
   DM5 P3E_CPU1_PE3_MP_TXP<9> @BASEBOARD_FAB2_LIB.BASEBOARD_FAB2(SCH_1):P3E_CPU1_PE3_MP_TXP(9)    I84 @BASEBOARD_FAB2_LIB.BASEBOARD_FAB2(SCH_1):PAGE66
   DN6 P3E_CPU1_PE3_MP_TXP<8> @BASEBOARD_FAB2_LIB.BASEBOARD_FAB2(SCH_1):P3E_CPU1_PE3_MP_TXP(8)    I84 @BASEBOARD_FAB2_LIB.BASEBOARD_FAB2(SCH_1):PAGE66
   DP7 P3E_CPU1_PE3_MP_TXP<7> @BASEBOARD_FAB2_LIB.BASEBOARD_FAB2(SCH_1):P3E_CPU1_PE3_MP_TXP(7)    I84 @BASEBOARD_FAB2_LIB.BASEBOARD_FAB2(SCH_1):PAGE66
   DT9 P3E_CPU1_PE3_MP_TXP<6> @BASEBOARD_FAB2_LIB.BASEBOARD_FAB2(SCH_1):P3E_CPU1_PE3_MP_TXP(6)    I84 @BASEBOARD_FAB2_LIB.BASEBOARD_FAB2(SCH_1):PAGE66
   DV9 P3E_CPU1_PE3_MP_TXP<5> @BASEBOARD_FAB2_LIB.BASEBOARD_FAB2(SCH_1):P3E_CPU1_PE3_MP_TXP(5)    I84 @BASEBOARD_FAB2_LIB.BASEBOARD_FAB2(SCH_1):PAGE66
   DY9 P3E_CPU1_PE3_MP_TXP<4> @BASEBOARD_FAB2_LIB.BASEBOARD_FAB2(SCH_1):P3E_CPU1_PE3_MP_TXP(4)    I84 @BASEBOARD_FAB2_LIB.BASEBOARD_FAB2(SCH_1):PAGE66
  EA10 P3E_CPU1_PE3_MP_TXP<3> @BASEBOARD_FAB2_LIB.BASEBOARD_FAB2(SCH_1):P3E_CPU1_PE3_MP_TXP(3)    I84 @BASEBOARD_FAB2_LIB.BASEBOARD_FAB2(SCH_1):PAGE66
  EB11 P3E_CPU1_PE3_MP_TXP<2> @BASEBOARD_FAB2_LIB.BASEBOARD_FAB2(SCH_1):P3E_CPU1_PE3_MP_TXP(2)    I84 @BASEBOARD_FAB2_LIB.BASEBOARD_FAB2(SCH_1):PAGE66
  ED13 P3E_CPU1_PE3_MP_TXP<1> @BASEBOARD_FAB2_LIB.BASEBOARD_FAB2(SCH_1):P3E_CPU1_PE3_MP_TXP(1)    I84 @BASEBOARD_FAB2_LIB.BASEBOARD_FAB2(SCH_1):PAGE66
  EC14 P3E_CPU1_PE3_MP_TXP<0> @BASEBOARD_FAB2_LIB.BASEBOARD_FAB2(SCH_1):P3E_CPU1_PE3_MP_TXP(0)    I84 @BASEBOARD_FAB2_LIB.BASEBOARD_FAB2(SCH_1):PAGE66
  BB11 UPI_CPU0_CPU1_P0P0_DP<19> @BASEBOARD_FAB2_LIB.BASEBOARD_FAB2(SCH_1):UPI_CPU0_CPU1_P0P0_DP(19)   I132 @BASEBOARD_FAB2_LIB.BASEBOARD_FAB2(SCH_1):PAGE67
   BD9 UPI_CPU0_CPU1_P0P0_DP<18> @BASEBOARD_FAB2_LIB.BASEBOARD_FAB2(SCH_1):UPI_CPU0_CPU1_P0P0_DP(18)   I132 @BASEBOARD_FAB2_LIB.BASEBOARD_FAB2(SCH_1):PAGE67
   AY9 UPI_CPU0_CPU1_P0P0_DN<17> @BASEBOARD_FAB2_LIB.BASEBOARD_FAB2(SCH_1):UPI_CPU0_CPU1_P0P0_DN(17)   I132 @BASEBOARD_FAB2_LIB.BASEBOARD_FAB2(SCH_1):PAGE67
   AW8 UPI_CPU0_CPU1_P0P0_DN<16> @BASEBOARD_FAB2_LIB.BASEBOARD_FAB2(SCH_1):UPI_CPU0_CPU1_P0P0_DN(16)   I132 @BASEBOARD_FAB2_LIB.BASEBOARD_FAB2(SCH_1):PAGE67
   BD7 UPI_CPU0_CPU1_P0P0_DN<15> @BASEBOARD_FAB2_LIB.BASEBOARD_FAB2(SCH_1):UPI_CPU0_CPU1_P0P0_DN(15)   I132 @BASEBOARD_FAB2_LIB.BASEBOARD_FAB2(SCH_1):PAGE67
   BC6 UPI_CPU0_CPU1_P0P0_DP<14> @BASEBOARD_FAB2_LIB.BASEBOARD_FAB2(SCH_1):UPI_CPU0_CPU1_P0P0_DP(14)   I132 @BASEBOARD_FAB2_LIB.BASEBOARD_FAB2(SCH_1):PAGE67
   BA8 UPI_CPU0_CPU1_P0P0_DN<13> @BASEBOARD_FAB2_LIB.BASEBOARD_FAB2(SCH_1):UPI_CPU0_CPU1_P0P0_DN(13)   I132 @BASEBOARD_FAB2_LIB.BASEBOARD_FAB2(SCH_1):PAGE67
  AU10 UPI_CPU0_CPU1_P0P0_DN<12> @BASEBOARD_FAB2_LIB.BASEBOARD_FAB2(SCH_1):UPI_CPU0_CPU1_P0P0_DN(12)   I132 @BASEBOARD_FAB2_LIB.BASEBOARD_FAB2(SCH_1):PAGE67
   AR8 UPI_CPU0_CPU1_P0P0_DP<11> @BASEBOARD_FAB2_LIB.BASEBOARD_FAB2(SCH_1):UPI_CPU0_CPU1_P0P0_DP(11)   I132 @BASEBOARD_FAB2_LIB.BASEBOARD_FAB2(SCH_1):PAGE67
   AP7 UPI_CPU0_CPU1_P0P0_DN<10> @BASEBOARD_FAB2_LIB.BASEBOARD_FAB2(SCH_1):UPI_CPU0_CPU1_P0P0_DN(10)   I132 @BASEBOARD_FAB2_LIB.BASEBOARD_FAB2(SCH_1):PAGE67
   AM9 UPI_CPU0_CPU1_P0P0_DP<9> @BASEBOARD_FAB2_LIB.BASEBOARD_FAB2(SCH_1):UPI_CPU0_CPU1_P0P0_DP(9)   I132 @BASEBOARD_FAB2_LIB.BASEBOARD_FAB2(SCH_1):PAGE67
   AK7 UPI_CPU0_CPU1_P0P0_DP<8> @BASEBOARD_FAB2_LIB.BASEBOARD_FAB2(SCH_1):UPI_CPU0_CPU1_P0P0_DP(8)   I132 @BASEBOARD_FAB2_LIB.BASEBOARD_FAB2(SCH_1):PAGE67
   AL6 UPI_CPU0_CPU1_P0P0_DP<7> @BASEBOARD_FAB2_LIB.BASEBOARD_FAB2(SCH_1):UPI_CPU0_CPU1_P0P0_DP(7)   I132 @BASEBOARD_FAB2_LIB.BASEBOARD_FAB2(SCH_1):PAGE67
   AJ6 UPI_CPU0_CPU1_P0P0_DP<6> @BASEBOARD_FAB2_LIB.BASEBOARD_FAB2(SCH_1):UPI_CPU0_CPU1_P0P0_DP(6)   I132 @BASEBOARD_FAB2_LIB.BASEBOARD_FAB2(SCH_1):PAGE67
   AG8 UPI_CPU0_CPU1_P0P0_DP<5> @BASEBOARD_FAB2_LIB.BASEBOARD_FAB2(SCH_1):UPI_CPU0_CPU1_P0P0_DP(5)   I132 @BASEBOARD_FAB2_LIB.BASEBOARD_FAB2(SCH_1):PAGE67
   AE6 UPI_CPU0_CPU1_P0P0_DP<4> @BASEBOARD_FAB2_LIB.BASEBOARD_FAB2(SCH_1):UPI_CPU0_CPU1_P0P0_DP(4)   I132 @BASEBOARD_FAB2_LIB.BASEBOARD_FAB2(SCH_1):PAGE67
   AD5 UPI_CPU0_CPU1_P0P0_DP<3> @BASEBOARD_FAB2_LIB.BASEBOARD_FAB2(SCH_1):UPI_CPU0_CPU1_P0P0_DP(3)   I132 @BASEBOARD_FAB2_LIB.BASEBOARD_FAB2(SCH_1):PAGE67
   AB7 UPI_CPU0_CPU1_P0P0_DN<2> @BASEBOARD_FAB2_LIB.BASEBOARD_FAB2(SCH_1):UPI_CPU0_CPU1_P0P0_DN(2)   I132 @BASEBOARD_FAB2_LIB.BASEBOARD_FAB2(SCH_1):PAGE67
   AA8 UPI_CPU0_CPU1_P0P0_DN<1> @BASEBOARD_FAB2_LIB.BASEBOARD_FAB2(SCH_1):UPI_CPU0_CPU1_P0P0_DN(1)   I132 @BASEBOARD_FAB2_LIB.BASEBOARD_FAB2(SCH_1):PAGE67
  AC10 UPI_CPU0_CPU1_P0P0_DP<0> @BASEBOARD_FAB2_LIB.BASEBOARD_FAB2(SCH_1):UPI_CPU0_CPU1_P0P0_DP(0)   I132 @BASEBOARD_FAB2_LIB.BASEBOARD_FAB2(SCH_1):PAGE67
  BA10 UPI_CPU0_CPU1_P0P0_DN<19> @BASEBOARD_FAB2_LIB.BASEBOARD_FAB2(SCH_1):UPI_CPU0_CPU1_P0P0_DN(19)   I132 @BASEBOARD_FAB2_LIB.BASEBOARD_FAB2(SCH_1):PAGE67
  BC10 UPI_CPU0_CPU1_P0P0_DN<18> @BASEBOARD_FAB2_LIB.BASEBOARD_FAB2(SCH_1):UPI_CPU0_CPU1_P0P0_DN(18)   I132 @BASEBOARD_FAB2_LIB.BASEBOARD_FAB2(SCH_1):PAGE67
   BB9 UPI_CPU0_CPU1_P0P0_DP<17> @BASEBOARD_FAB2_LIB.BASEBOARD_FAB2(SCH_1):UPI_CPU0_CPU1_P0P0_DP(17)   I132 @BASEBOARD_FAB2_LIB.BASEBOARD_FAB2(SCH_1):PAGE67
   AV9 UPI_CPU0_CPU1_P0P0_DP<16> @BASEBOARD_FAB2_LIB.BASEBOARD_FAB2(SCH_1):UPI_CPU0_CPU1_P0P0_DP(16)   I132 @BASEBOARD_FAB2_LIB.BASEBOARD_FAB2(SCH_1):PAGE67
   BF7 UPI_CPU0_CPU1_P0P0_DP<15> @BASEBOARD_FAB2_LIB.BASEBOARD_FAB2(SCH_1):UPI_CPU0_CPU1_P0P0_DP(15)   I132 @BASEBOARD_FAB2_LIB.BASEBOARD_FAB2(SCH_1):PAGE67
   BB7 UPI_CPU0_CPU1_P0P0_DN<14> @BASEBOARD_FAB2_LIB.BASEBOARD_FAB2(SCH_1):UPI_CPU0_CPU1_P0P0_DN(14)   I132 @BASEBOARD_FAB2_LIB.BASEBOARD_FAB2(SCH_1):PAGE67
   AY7 UPI_CPU0_CPU1_P0P0_DP<13> @BASEBOARD_FAB2_LIB.BASEBOARD_FAB2(SCH_1):UPI_CPU0_CPU1_P0P0_DP(13)   I132 @BASEBOARD_FAB2_LIB.BASEBOARD_FAB2(SCH_1):PAGE67
   AT9 UPI_CPU0_CPU1_P0P0_DP<12> @BASEBOARD_FAB2_LIB.BASEBOARD_FAB2(SCH_1):UPI_CPU0_CPU1_P0P0_DP(12)   I132 @BASEBOARD_FAB2_LIB.BASEBOARD_FAB2(SCH_1):PAGE67
   AU8 UPI_CPU0_CPU1_P0P0_DN<11> @BASEBOARD_FAB2_LIB.BASEBOARD_FAB2(SCH_1):UPI_CPU0_CPU1_P0P0_DN(11)   I132 @BASEBOARD_FAB2_LIB.BASEBOARD_FAB2(SCH_1):PAGE67
   AN8 UPI_CPU0_CPU1_P0P0_DP<10> @BASEBOARD_FAB2_LIB.BASEBOARD_FAB2(SCH_1):UPI_CPU0_CPU1_P0P0_DP(10)   I132 @BASEBOARD_FAB2_LIB.BASEBOARD_FAB2(SCH_1):PAGE67
   AL8 UPI_CPU0_CPU1_P0P0_DN<9> @BASEBOARD_FAB2_LIB.BASEBOARD_FAB2(SCH_1):UPI_CPU0_CPU1_P0P0_DN(9)   I132 @BASEBOARD_FAB2_LIB.BASEBOARD_FAB2(SCH_1):PAGE67
   AM7 UPI_CPU0_CPU1_P0P0_DN<8> @BASEBOARD_FAB2_LIB.BASEBOARD_FAB2(SCH_1):UPI_CPU0_CPU1_P0P0_DN(8)   I132 @BASEBOARD_FAB2_LIB.BASEBOARD_FAB2(SCH_1):PAGE67
   AK5 UPI_CPU0_CPU1_P0P0_DN<7> @BASEBOARD_FAB2_LIB.BASEBOARD_FAB2(SCH_1):UPI_CPU0_CPU1_P0P0_DN(7)   I132 @BASEBOARD_FAB2_LIB.BASEBOARD_FAB2(SCH_1):PAGE67
   AH7 UPI_CPU0_CPU1_P0P0_DN<6> @BASEBOARD_FAB2_LIB.BASEBOARD_FAB2(SCH_1):UPI_CPU0_CPU1_P0P0_DN(6)   I132 @BASEBOARD_FAB2_LIB.BASEBOARD_FAB2(SCH_1):PAGE67
   AF7 UPI_CPU0_CPU1_P0P0_DN<5> @BASEBOARD_FAB2_LIB.BASEBOARD_FAB2(SCH_1):UPI_CPU0_CPU1_P0P0_DN(5)   I132 @BASEBOARD_FAB2_LIB.BASEBOARD_FAB2(SCH_1):PAGE67
   AG6 UPI_CPU0_CPU1_P0P0_DN<4> @BASEBOARD_FAB2_LIB.BASEBOARD_FAB2(SCH_1):UPI_CPU0_CPU1_P0P0_DN(4)   I132 @BASEBOARD_FAB2_LIB.BASEBOARD_FAB2(SCH_1):PAGE67
   AC6 UPI_CPU0_CPU1_P0P0_DN<3> @BASEBOARD_FAB2_LIB.BASEBOARD_FAB2(SCH_1):UPI_CPU0_CPU1_P0P0_DN(3)   I132 @BASEBOARD_FAB2_LIB.BASEBOARD_FAB2(SCH_1):PAGE67
   AA6 UPI_CPU0_CPU1_P0P0_DP<2> @BASEBOARD_FAB2_LIB.BASEBOARD_FAB2(SCH_1):UPI_CPU0_CPU1_P0P0_DP(2)   I132 @BASEBOARD_FAB2_LIB.BASEBOARD_FAB2(SCH_1):PAGE67
   AC8 UPI_CPU0_CPU1_P0P0_DP<1> @BASEBOARD_FAB2_LIB.BASEBOARD_FAB2(SCH_1):UPI_CPU0_CPU1_P0P0_DP(1)   I132 @BASEBOARD_FAB2_LIB.BASEBOARD_FAB2(SCH_1):PAGE67
   AB9 UPI_CPU0_CPU1_P0P0_DN<0> @BASEBOARD_FAB2_LIB.BASEBOARD_FAB2(SCH_1):UPI_CPU0_CPU1_P0P0_DN(0)   I132 @BASEBOARD_FAB2_LIB.BASEBOARD_FAB2(SCH_1):PAGE67
   BG4 UPI_CPU1_CPU0_P0P0_DP<19> @BASEBOARD_FAB2_LIB.BASEBOARD_FAB2(SCH_1):UPI_CPU1_CPU0_P0P0_DP(19)   I132 @BASEBOARD_FAB2_LIB.BASEBOARD_FAB2(SCH_1):PAGE67
   BF3 UPI_CPU1_CPU0_P0P0_DN<18> @BASEBOARD_FAB2_LIB.BASEBOARD_FAB2(SCH_1):UPI_CPU1_CPU0_P0P0_DN(18)   I132 @BASEBOARD_FAB2_LIB.BASEBOARD_FAB2(SCH_1):PAGE67
   BB3 UPI_CPU1_CPU0_P0P0_DN<17> @BASEBOARD_FAB2_LIB.BASEBOARD_FAB2(SCH_1):UPI_CPU1_CPU0_P0P0_DN(17)   I132 @BASEBOARD_FAB2_LIB.BASEBOARD_FAB2(SCH_1):PAGE67
   BA4 UPI_CPU1_CPU0_P0P0_DP<16> @BASEBOARD_FAB2_LIB.BASEBOARD_FAB2(SCH_1):UPI_CPU1_CPU0_P0P0_DP(16)   I132 @BASEBOARD_FAB2_LIB.BASEBOARD_FAB2(SCH_1):PAGE67
   AV5 UPI_CPU1_CPU0_P0P0_DP<15> @BASEBOARD_FAB2_LIB.BASEBOARD_FAB2(SCH_1):UPI_CPU1_CPU0_P0P0_DP(15)   I132 @BASEBOARD_FAB2_LIB.BASEBOARD_FAB2(SCH_1):PAGE67
   AU4 UPI_CPU1_CPU0_P0P0_DP<14> @BASEBOARD_FAB2_LIB.BASEBOARD_FAB2(SCH_1):UPI_CPU1_CPU0_P0P0_DP(14)   I132 @BASEBOARD_FAB2_LIB.BASEBOARD_FAB2(SCH_1):PAGE67
   AT3 UPI_CPU1_CPU0_P0P0_DP<13> @BASEBOARD_FAB2_LIB.BASEBOARD_FAB2(SCH_1):UPI_CPU1_CPU0_P0P0_DP(13)   I132 @BASEBOARD_FAB2_LIB.BASEBOARD_FAB2(SCH_1):PAGE67
   AT1 UPI_CPU1_CPU0_P0P0_DP<12> @BASEBOARD_FAB2_LIB.BASEBOARD_FAB2(SCH_1):UPI_CPU1_CPU0_P0P0_DP(12)   I132 @BASEBOARD_FAB2_LIB.BASEBOARD_FAB2(SCH_1):PAGE67
   AN4 UPI_CPU1_CPU0_P0P0_DP<11> @BASEBOARD_FAB2_LIB.BASEBOARD_FAB2(SCH_1):UPI_CPU1_CPU0_P0P0_DP(11)   I132 @BASEBOARD_FAB2_LIB.BASEBOARD_FAB2(SCH_1):PAGE67
   AM3 UPI_CPU1_CPU0_P0P0_DP<10> @BASEBOARD_FAB2_LIB.BASEBOARD_FAB2(SCH_1):UPI_CPU1_CPU0_P0P0_DP(10)   I132 @BASEBOARD_FAB2_LIB.BASEBOARD_FAB2(SCH_1):PAGE67
   AL2 UPI_CPU1_CPU0_P0P0_DN<9> @BASEBOARD_FAB2_LIB.BASEBOARD_FAB2(SCH_1):UPI_CPU1_CPU0_P0P0_DN(9)   I132 @BASEBOARD_FAB2_LIB.BASEBOARD_FAB2(SCH_1):PAGE67
   AH3 UPI_CPU1_CPU0_P0P0_DP<8> @BASEBOARD_FAB2_LIB.BASEBOARD_FAB2(SCH_1):UPI_CPU1_CPU0_P0P0_DP(8)   I132 @BASEBOARD_FAB2_LIB.BASEBOARD_FAB2(SCH_1):PAGE67
   AE2 UPI_CPU1_CPU0_P0P0_DN<7> @BASEBOARD_FAB2_LIB.BASEBOARD_FAB2(SCH_1):UPI_CPU1_CPU0_P0P0_DN(7)   I132 @BASEBOARD_FAB2_LIB.BASEBOARD_FAB2(SCH_1):PAGE67
   AG4 UPI_CPU1_CPU0_P0P0_DN<6> @BASEBOARD_FAB2_LIB.BASEBOARD_FAB2(SCH_1):UPI_CPU1_CPU0_P0P0_DN(6)   I132 @BASEBOARD_FAB2_LIB.BASEBOARD_FAB2(SCH_1):PAGE67
   AC2 UPI_CPU1_CPU0_P0P0_DP<5> @BASEBOARD_FAB2_LIB.BASEBOARD_FAB2(SCH_1):UPI_CPU1_CPU0_P0P0_DP(5)   I132 @BASEBOARD_FAB2_LIB.BASEBOARD_FAB2(SCH_1):PAGE67
   AB3 UPI_CPU1_CPU0_P0P0_DN<4> @BASEBOARD_FAB2_LIB.BASEBOARD_FAB2(SCH_1):UPI_CPU1_CPU0_P0P0_DN(4)   I132 @BASEBOARD_FAB2_LIB.BASEBOARD_FAB2(SCH_1):PAGE67
    Y1 UPI_CPU1_CPU0_P0P0_DN<3> @BASEBOARD_FAB2_LIB.BASEBOARD_FAB2(SCH_1):UPI_CPU1_CPU0_P0P0_DN(3)   I132 @BASEBOARD_FAB2_LIB.BASEBOARD_FAB2(SCH_1):PAGE67
    V3 UPI_CPU1_CPU0_P0P0_DN<2> @BASEBOARD_FAB2_LIB.BASEBOARD_FAB2(SCH_1):UPI_CPU1_CPU0_P0P0_DN(2)   I132 @BASEBOARD_FAB2_LIB.BASEBOARD_FAB2(SCH_1):PAGE67
    P1 UPI_CPU1_CPU0_P0P0_DP<1> @BASEBOARD_FAB2_LIB.BASEBOARD_FAB2(SCH_1):UPI_CPU1_CPU0_P0P0_DP(1)   I132 @BASEBOARD_FAB2_LIB.BASEBOARD_FAB2(SCH_1):PAGE67
    N2 UPI_CPU1_CPU0_P0P0_DP<0> @BASEBOARD_FAB2_LIB.BASEBOARD_FAB2(SCH_1):UPI_CPU1_CPU0_P0P0_DP(0)   I132 @BASEBOARD_FAB2_LIB.BASEBOARD_FAB2(SCH_1):PAGE67
   BH3 UPI_CPU1_CPU0_P0P0_DN<19> @BASEBOARD_FAB2_LIB.BASEBOARD_FAB2(SCH_1):UPI_CPU1_CPU0_P0P0_DN(19)   I132 @BASEBOARD_FAB2_LIB.BASEBOARD_FAB2(SCH_1):PAGE67
   BD3 UPI_CPU1_CPU0_P0P0_DP<18> @BASEBOARD_FAB2_LIB.BASEBOARD_FAB2(SCH_1):UPI_CPU1_CPU0_P0P0_DP(18)   I132 @BASEBOARD_FAB2_LIB.BASEBOARD_FAB2(SCH_1):PAGE67
   BC2 UPI_CPU1_CPU0_P0P0_DP<17> @BASEBOARD_FAB2_LIB.BASEBOARD_FAB2(SCH_1):UPI_CPU1_CPU0_P0P0_DP(17)   I132 @BASEBOARD_FAB2_LIB.BASEBOARD_FAB2(SCH_1):PAGE67
   AY3 UPI_CPU1_CPU0_P0P0_DN<16> @BASEBOARD_FAB2_LIB.BASEBOARD_FAB2(SCH_1):UPI_CPU1_CPU0_P0P0_DN(16)   I132 @BASEBOARD_FAB2_LIB.BASEBOARD_FAB2(SCH_1):PAGE67
   AW4 UPI_CPU1_CPU0_P0P0_DN<15> @BASEBOARD_FAB2_LIB.BASEBOARD_FAB2(SCH_1):UPI_CPU1_CPU0_P0P0_DN(15)   I132 @BASEBOARD_FAB2_LIB.BASEBOARD_FAB2(SCH_1):PAGE67
   AR4 UPI_CPU1_CPU0_P0P0_DN<14> @BASEBOARD_FAB2_LIB.BASEBOARD_FAB2(SCH_1):UPI_CPU1_CPU0_P0P0_DN(14)   I132 @BASEBOARD_FAB2_LIB.BASEBOARD_FAB2(SCH_1):PAGE67
   AR2 UPI_CPU1_CPU0_P0P0_DN<13> @BASEBOARD_FAB2_LIB.BASEBOARD_FAB2(SCH_1):UPI_CPU1_CPU0_P0P0_DN(13)   I132 @BASEBOARD_FAB2_LIB.BASEBOARD_FAB2(SCH_1):PAGE67
   AP1 UPI_CPU1_CPU0_P0P0_DN<12> @BASEBOARD_FAB2_LIB.BASEBOARD_FAB2(SCH_1):UPI_CPU1_CPU0_P0P0_DN(12)   I132 @BASEBOARD_FAB2_LIB.BASEBOARD_FAB2(SCH_1):PAGE67
   AP3 UPI_CPU1_CPU0_P0P0_DN<11> @BASEBOARD_FAB2_LIB.BASEBOARD_FAB2(SCH_1):UPI_CPU1_CPU0_P0P0_DN(11)   I132 @BASEBOARD_FAB2_LIB.BASEBOARD_FAB2(SCH_1):PAGE67
   AK3 UPI_CPU1_CPU0_P0P0_DN<10> @BASEBOARD_FAB2_LIB.BASEBOARD_FAB2(SCH_1):UPI_CPU1_CPU0_P0P0_DN(10)   I132 @BASEBOARD_FAB2_LIB.BASEBOARD_FAB2(SCH_1):PAGE67
   AK1 UPI_CPU1_CPU0_P0P0_DP<9> @BASEBOARD_FAB2_LIB.BASEBOARD_FAB2(SCH_1):UPI_CPU1_CPU0_P0P0_DP(9)   I132 @BASEBOARD_FAB2_LIB.BASEBOARD_FAB2(SCH_1):PAGE67
   AJ2 UPI_CPU1_CPU0_P0P0_DN<8> @BASEBOARD_FAB2_LIB.BASEBOARD_FAB2(SCH_1):UPI_CPU1_CPU0_P0P0_DN(8)   I132 @BASEBOARD_FAB2_LIB.BASEBOARD_FAB2(SCH_1):PAGE67
   AG2 UPI_CPU1_CPU0_P0P0_DP<7> @BASEBOARD_FAB2_LIB.BASEBOARD_FAB2(SCH_1):UPI_CPU1_CPU0_P0P0_DP(7)   I132 @BASEBOARD_FAB2_LIB.BASEBOARD_FAB2(SCH_1):PAGE67
   AF3 UPI_CPU1_CPU0_P0P0_DP<6> @BASEBOARD_FAB2_LIB.BASEBOARD_FAB2(SCH_1):UPI_CPU1_CPU0_P0P0_DP(6)   I132 @BASEBOARD_FAB2_LIB.BASEBOARD_FAB2(SCH_1):PAGE67
   AD1 UPI_CPU1_CPU0_P0P0_DN<5> @BASEBOARD_FAB2_LIB.BASEBOARD_FAB2(SCH_1):UPI_CPU1_CPU0_P0P0_DN(5)   I132 @BASEBOARD_FAB2_LIB.BASEBOARD_FAB2(SCH_1):PAGE67
   AA2 UPI_CPU1_CPU0_P0P0_DP<4> @BASEBOARD_FAB2_LIB.BASEBOARD_FAB2(SCH_1):UPI_CPU1_CPU0_P0P0_DP(4)   I132 @BASEBOARD_FAB2_LIB.BASEBOARD_FAB2(SCH_1):PAGE67
    W2 UPI_CPU1_CPU0_P0P0_DP<3> @BASEBOARD_FAB2_LIB.BASEBOARD_FAB2(SCH_1):UPI_CPU1_CPU0_P0P0_DP(3)   I132 @BASEBOARD_FAB2_LIB.BASEBOARD_FAB2(SCH_1):PAGE67
    Y3 UPI_CPU1_CPU0_P0P0_DP<2> @BASEBOARD_FAB2_LIB.BASEBOARD_FAB2(SCH_1):UPI_CPU1_CPU0_P0P0_DP(2)   I132 @BASEBOARD_FAB2_LIB.BASEBOARD_FAB2(SCH_1):PAGE67
    T1 UPI_CPU1_CPU0_P0P0_DN<1> @BASEBOARD_FAB2_LIB.BASEBOARD_FAB2(SCH_1):UPI_CPU1_CPU0_P0P0_DN(1)   I132 @BASEBOARD_FAB2_LIB.BASEBOARD_FAB2(SCH_1):PAGE67
    M1 UPI_CPU1_CPU0_P0P0_DN<0> @BASEBOARD_FAB2_LIB.BASEBOARD_FAB2(SCH_1):UPI_CPU1_CPU0_P0P0_DN(0)   I132 @BASEBOARD_FAB2_LIB.BASEBOARD_FAB2(SCH_1):PAGE67
  AB19 UPI_CPU0_CPU1_P1P1_DP<19> @BASEBOARD_FAB2_LIB.BASEBOARD_FAB2(SCH_1):UPI_CPU0_CPU1_P1P1_DP(19)   I125 @BASEBOARD_FAB2_LIB.BASEBOARD_FAB2(SCH_1):PAGE68
   Y21 UPI_CPU0_CPU1_P1P1_DP<18> @BASEBOARD_FAB2_LIB.BASEBOARD_FAB2(SCH_1):UPI_CPU0_CPU1_P1P1_DP(18)   I125 @BASEBOARD_FAB2_LIB.BASEBOARD_FAB2(SCH_1):PAGE68
   V19 UPI_CPU0_CPU1_P1P1_DN<17> @BASEBOARD_FAB2_LIB.BASEBOARD_FAB2(SCH_1):UPI_CPU0_CPU1_P1P1_DN(17)   I125 @BASEBOARD_FAB2_LIB.BASEBOARD_FAB2(SCH_1):PAGE68
   P21 UPI_CPU0_CPU1_P1P1_DN<16> @BASEBOARD_FAB2_LIB.BASEBOARD_FAB2(SCH_1):UPI_CPU0_CPU1_P1P1_DN(16)   I125 @BASEBOARD_FAB2_LIB.BASEBOARD_FAB2(SCH_1):PAGE68
   U18 UPI_CPU0_CPU1_P1P1_DN<15> @BASEBOARD_FAB2_LIB.BASEBOARD_FAB2(SCH_1):UPI_CPU0_CPU1_P1P1_DN(15)   I125 @BASEBOARD_FAB2_LIB.BASEBOARD_FAB2(SCH_1):PAGE68
   R20 UPI_CPU0_CPU1_P1P1_DN<14> @BASEBOARD_FAB2_LIB.BASEBOARD_FAB2(SCH_1):UPI_CPU0_CPU1_P1P1_DN(14)   I125 @BASEBOARD_FAB2_LIB.BASEBOARD_FAB2(SCH_1):PAGE68
   W18 UPI_CPU0_CPU1_P1P1_DP<13> @BASEBOARD_FAB2_LIB.BASEBOARD_FAB2(SCH_1):UPI_CPU0_CPU1_P1P1_DP(13)   I125 @BASEBOARD_FAB2_LIB.BASEBOARD_FAB2(SCH_1):PAGE68
   U16 UPI_CPU0_CPU1_P1P1_DP<12> @BASEBOARD_FAB2_LIB.BASEBOARD_FAB2(SCH_1):UPI_CPU0_CPU1_P1P1_DP(12)   I125 @BASEBOARD_FAB2_LIB.BASEBOARD_FAB2(SCH_1):PAGE68
   P17 UPI_CPU0_CPU1_P1P1_DP<11> @BASEBOARD_FAB2_LIB.BASEBOARD_FAB2(SCH_1):UPI_CPU0_CPU1_P1P1_DP(11)   I125 @BASEBOARD_FAB2_LIB.BASEBOARD_FAB2(SCH_1):PAGE68
   R16 UPI_CPU0_CPU1_P1P1_DN<10> @BASEBOARD_FAB2_LIB.BASEBOARD_FAB2(SCH_1):UPI_CPU0_CPU1_P1P1_DN(10)   I125 @BASEBOARD_FAB2_LIB.BASEBOARD_FAB2(SCH_1):PAGE68
   R12 UPI_CPU0_CPU1_P1P1_DN<9> @BASEBOARD_FAB2_LIB.BASEBOARD_FAB2(SCH_1):UPI_CPU0_CPU1_P1P1_DN(9)   I125 @BASEBOARD_FAB2_LIB.BASEBOARD_FAB2(SCH_1):PAGE68
   N14 UPI_CPU0_CPU1_P1P1_DP<8> @BASEBOARD_FAB2_LIB.BASEBOARD_FAB2(SCH_1):UPI_CPU0_CPU1_P1P1_DP(8)   I125 @BASEBOARD_FAB2_LIB.BASEBOARD_FAB2(SCH_1):PAGE68
   L12 UPI_CPU0_CPU1_P1P1_DN<7> @BASEBOARD_FAB2_LIB.BASEBOARD_FAB2(SCH_1):UPI_CPU0_CPU1_P1P1_DN(7)   I125 @BASEBOARD_FAB2_LIB.BASEBOARD_FAB2(SCH_1):PAGE68
   U12 UPI_CPU0_CPU1_P1P1_DN<6> @BASEBOARD_FAB2_LIB.BASEBOARD_FAB2(SCH_1):UPI_CPU0_CPU1_P1P1_DN(6)   I125 @BASEBOARD_FAB2_LIB.BASEBOARD_FAB2(SCH_1):PAGE68
   R10 UPI_CPU0_CPU1_P1P1_DN<5> @BASEBOARD_FAB2_LIB.BASEBOARD_FAB2(SCH_1):UPI_CPU0_CPU1_P1P1_DN(5)   I125 @BASEBOARD_FAB2_LIB.BASEBOARD_FAB2(SCH_1):PAGE68
    P9 UPI_CPU0_CPU1_P1P1_DN<4> @BASEBOARD_FAB2_LIB.BASEBOARD_FAB2(SCH_1):UPI_CPU0_CPU1_P1P1_DN(4)   I125 @BASEBOARD_FAB2_LIB.BASEBOARD_FAB2(SCH_1):PAGE68
    T9 UPI_CPU0_CPU1_P1P1_DN<3> @BASEBOARD_FAB2_LIB.BASEBOARD_FAB2(SCH_1):UPI_CPU0_CPU1_P1P1_DN(3)   I125 @BASEBOARD_FAB2_LIB.BASEBOARD_FAB2(SCH_1):PAGE68
    V7 UPI_CPU0_CPU1_P1P1_DN<2> @BASEBOARD_FAB2_LIB.BASEBOARD_FAB2(SCH_1):UPI_CPU0_CPU1_P1P1_DN(2)   I125 @BASEBOARD_FAB2_LIB.BASEBOARD_FAB2(SCH_1):PAGE68
    P7 UPI_CPU0_CPU1_P1P1_DN<1> @BASEBOARD_FAB2_LIB.BASEBOARD_FAB2(SCH_1):UPI_CPU0_CPU1_P1P1_DN(1)   I125 @BASEBOARD_FAB2_LIB.BASEBOARD_FAB2(SCH_1):PAGE68
    T5 UPI_CPU0_CPU1_P1P1_DP<0> @BASEBOARD_FAB2_LIB.BASEBOARD_FAB2(SCH_1):UPI_CPU0_CPU1_P1P1_DP(0)   I125 @BASEBOARD_FAB2_LIB.BASEBOARD_FAB2(SCH_1):PAGE68
  AA20 UPI_CPU0_CPU1_P1P1_DN<19> @BASEBOARD_FAB2_LIB.BASEBOARD_FAB2(SCH_1):UPI_CPU0_CPU1_P1P1_DN(19)   I125 @BASEBOARD_FAB2_LIB.BASEBOARD_FAB2(SCH_1):PAGE68
   W20 UPI_CPU0_CPU1_P1P1_DN<18> @BASEBOARD_FAB2_LIB.BASEBOARD_FAB2(SCH_1):UPI_CPU0_CPU1_P1P1_DN(18)   I125 @BASEBOARD_FAB2_LIB.BASEBOARD_FAB2(SCH_1):PAGE68
   Y19 UPI_CPU0_CPU1_P1P1_DP<17> @BASEBOARD_FAB2_LIB.BASEBOARD_FAB2(SCH_1):UPI_CPU0_CPU1_P1P1_DP(17)   I125 @BASEBOARD_FAB2_LIB.BASEBOARD_FAB2(SCH_1):PAGE68
   T21 UPI_CPU0_CPU1_P1P1_DP<16> @BASEBOARD_FAB2_LIB.BASEBOARD_FAB2(SCH_1):UPI_CPU0_CPU1_P1P1_DP(16)   I125 @BASEBOARD_FAB2_LIB.BASEBOARD_FAB2(SCH_1):PAGE68
   T19 UPI_CPU0_CPU1_P1P1_DP<15> @BASEBOARD_FAB2_LIB.BASEBOARD_FAB2(SCH_1):UPI_CPU0_CPU1_P1P1_DP(15)   I125 @BASEBOARD_FAB2_LIB.BASEBOARD_FAB2(SCH_1):PAGE68
   P19 UPI_CPU0_CPU1_P1P1_DP<14> @BASEBOARD_FAB2_LIB.BASEBOARD_FAB2(SCH_1):UPI_CPU0_CPU1_P1P1_DP(14)   I125 @BASEBOARD_FAB2_LIB.BASEBOARD_FAB2(SCH_1):PAGE68
   V17 UPI_CPU0_CPU1_P1P1_DN<13> @BASEBOARD_FAB2_LIB.BASEBOARD_FAB2(SCH_1):UPI_CPU0_CPU1_P1P1_DN(13)   I125 @BASEBOARD_FAB2_LIB.BASEBOARD_FAB2(SCH_1):PAGE68
   W16 UPI_CPU0_CPU1_P1P1_DN<12> @BASEBOARD_FAB2_LIB.BASEBOARD_FAB2(SCH_1):UPI_CPU0_CPU1_P1P1_DN(12)   I125 @BASEBOARD_FAB2_LIB.BASEBOARD_FAB2(SCH_1):PAGE68
   N16 UPI_CPU0_CPU1_P1P1_DN<11> @BASEBOARD_FAB2_LIB.BASEBOARD_FAB2(SCH_1):UPI_CPU0_CPU1_P1P1_DN(11)   I125 @BASEBOARD_FAB2_LIB.BASEBOARD_FAB2(SCH_1):PAGE68
   T15 UPI_CPU0_CPU1_P1P1_DP<10> @BASEBOARD_FAB2_LIB.BASEBOARD_FAB2(SCH_1):UPI_CPU0_CPU1_P1P1_DP(10)   I125 @BASEBOARD_FAB2_LIB.BASEBOARD_FAB2(SCH_1):PAGE68
   P13 UPI_CPU0_CPU1_P1P1_DP<9> @BASEBOARD_FAB2_LIB.BASEBOARD_FAB2(SCH_1):UPI_CPU0_CPU1_P1P1_DP(9)   I125 @BASEBOARD_FAB2_LIB.BASEBOARD_FAB2(SCH_1):PAGE68
   M13 UPI_CPU0_CPU1_P1P1_DN<8> @BASEBOARD_FAB2_LIB.BASEBOARD_FAB2(SCH_1):UPI_CPU0_CPU1_P1P1_DN(8)   I125 @BASEBOARD_FAB2_LIB.BASEBOARD_FAB2(SCH_1):PAGE68
   N12 UPI_CPU0_CPU1_P1P1_DP<7> @BASEBOARD_FAB2_LIB.BASEBOARD_FAB2(SCH_1):UPI_CPU0_CPU1_P1P1_DP(7)   I125 @BASEBOARD_FAB2_LIB.BASEBOARD_FAB2(SCH_1):PAGE68
   T11 UPI_CPU0_CPU1_P1P1_DP<6> @BASEBOARD_FAB2_LIB.BASEBOARD_FAB2(SCH_1):UPI_CPU0_CPU1_P1P1_DP(6)   I125 @BASEBOARD_FAB2_LIB.BASEBOARD_FAB2(SCH_1):PAGE68
   U10 UPI_CPU0_CPU1_P1P1_DP<5> @BASEBOARD_FAB2_LIB.BASEBOARD_FAB2(SCH_1):UPI_CPU0_CPU1_P1P1_DP(5)   I125 @BASEBOARD_FAB2_LIB.BASEBOARD_FAB2(SCH_1):PAGE68
   N10 UPI_CPU0_CPU1_P1P1_DP<4> @BASEBOARD_FAB2_LIB.BASEBOARD_FAB2(SCH_1):UPI_CPU0_CPU1_P1P1_DP(4)   I125 @BASEBOARD_FAB2_LIB.BASEBOARD_FAB2(SCH_1):PAGE68
    R8 UPI_CPU0_CPU1_P1P1_DP<3> @BASEBOARD_FAB2_LIB.BASEBOARD_FAB2(SCH_1):UPI_CPU0_CPU1_P1P1_DP(3)   I125 @BASEBOARD_FAB2_LIB.BASEBOARD_FAB2(SCH_1):PAGE68
    U8 UPI_CPU0_CPU1_P1P1_DP<2> @BASEBOARD_FAB2_LIB.BASEBOARD_FAB2(SCH_1):UPI_CPU0_CPU1_P1P1_DP(2)   I125 @BASEBOARD_FAB2_LIB.BASEBOARD_FAB2(SCH_1):PAGE68
    T7 UPI_CPU0_CPU1_P1P1_DP<1> @BASEBOARD_FAB2_LIB.BASEBOARD_FAB2(SCH_1):UPI_CPU0_CPU1_P1P1_DP(1)   I125 @BASEBOARD_FAB2_LIB.BASEBOARD_FAB2(SCH_1):PAGE68
    R6 UPI_CPU0_CPU1_P1P1_DN<0> @BASEBOARD_FAB2_LIB.BASEBOARD_FAB2(SCH_1):UPI_CPU0_CPU1_P1P1_DN(0)   I125 @BASEBOARD_FAB2_LIB.BASEBOARD_FAB2(SCH_1):PAGE68
   H21 UPI_CPU1_CPU0_P1P1_DP<19> @BASEBOARD_FAB2_LIB.BASEBOARD_FAB2(SCH_1):UPI_CPU1_CPU0_P1P1_DP(19)   I125 @BASEBOARD_FAB2_LIB.BASEBOARD_FAB2(SCH_1):PAGE68
   F21 UPI_CPU1_CPU0_P1P1_DP<18> @BASEBOARD_FAB2_LIB.BASEBOARD_FAB2(SCH_1):UPI_CPU1_CPU0_P1P1_DP(18)   I125 @BASEBOARD_FAB2_LIB.BASEBOARD_FAB2(SCH_1):PAGE68
   J20 UPI_CPU1_CPU0_P1P1_DN<17> @BASEBOARD_FAB2_LIB.BASEBOARD_FAB2(SCH_1):UPI_CPU1_CPU0_P1P1_DN(17)   I125 @BASEBOARD_FAB2_LIB.BASEBOARD_FAB2(SCH_1):PAGE68
   G18 UPI_CPU1_CPU0_P1P1_DN<16> @BASEBOARD_FAB2_LIB.BASEBOARD_FAB2(SCH_1):UPI_CPU1_CPU0_P1P1_DN(16)   I125 @BASEBOARD_FAB2_LIB.BASEBOARD_FAB2(SCH_1):PAGE68
   K19 UPI_CPU1_CPU0_P1P1_DN<15> @BASEBOARD_FAB2_LIB.BASEBOARD_FAB2(SCH_1):UPI_CPU1_CPU0_P1P1_DN(15)   I125 @BASEBOARD_FAB2_LIB.BASEBOARD_FAB2(SCH_1):PAGE68
   H17 UPI_CPU1_CPU0_P1P1_DN<14> @BASEBOARD_FAB2_LIB.BASEBOARD_FAB2(SCH_1):UPI_CPU1_CPU0_P1P1_DN(14)   I125 @BASEBOARD_FAB2_LIB.BASEBOARD_FAB2(SCH_1):PAGE68
   F15 UPI_CPU1_CPU0_P1P1_DN<13> @BASEBOARD_FAB2_LIB.BASEBOARD_FAB2(SCH_1):UPI_CPU1_CPU0_P1P1_DN(13)   I125 @BASEBOARD_FAB2_LIB.BASEBOARD_FAB2(SCH_1):PAGE68
   D15 UPI_CPU1_CPU0_P1P1_DN<12> @BASEBOARD_FAB2_LIB.BASEBOARD_FAB2(SCH_1):UPI_CPU1_CPU0_P1P1_DN(12)   I125 @BASEBOARD_FAB2_LIB.BASEBOARD_FAB2(SCH_1):PAGE68
   G14 UPI_CPU1_CPU0_P1P1_DP<11> @BASEBOARD_FAB2_LIB.BASEBOARD_FAB2(SCH_1):UPI_CPU1_CPU0_P1P1_DP(11)   I125 @BASEBOARD_FAB2_LIB.BASEBOARD_FAB2(SCH_1):PAGE68
   E12 UPI_CPU1_CPU0_P1P1_DN<10> @BASEBOARD_FAB2_LIB.BASEBOARD_FAB2(SCH_1):UPI_CPU1_CPU0_P1P1_DN(10)   I125 @BASEBOARD_FAB2_LIB.BASEBOARD_FAB2(SCH_1):PAGE68
   G10 UPI_CPU1_CPU0_P1P1_DN<9> @BASEBOARD_FAB2_LIB.BASEBOARD_FAB2(SCH_1):UPI_CPU1_CPU0_P1P1_DN(9)   I125 @BASEBOARD_FAB2_LIB.BASEBOARD_FAB2(SCH_1):PAGE68
   F11 UPI_CPU1_CPU0_P1P1_DP<8> @BASEBOARD_FAB2_LIB.BASEBOARD_FAB2(SCH_1):UPI_CPU1_CPU0_P1P1_DP(8)   I125 @BASEBOARD_FAB2_LIB.BASEBOARD_FAB2(SCH_1):PAGE68
    D9 UPI_CPU1_CPU0_P1P1_DP<7> @BASEBOARD_FAB2_LIB.BASEBOARD_FAB2(SCH_1):UPI_CPU1_CPU0_P1P1_DP(7)   I125 @BASEBOARD_FAB2_LIB.BASEBOARD_FAB2(SCH_1):PAGE68
    K9 UPI_CPU1_CPU0_P1P1_DP<6> @BASEBOARD_FAB2_LIB.BASEBOARD_FAB2(SCH_1):UPI_CPU1_CPU0_P1P1_DP(6)   I125 @BASEBOARD_FAB2_LIB.BASEBOARD_FAB2(SCH_1):PAGE68
    H7 UPI_CPU1_CPU0_P1P1_DN<5> @BASEBOARD_FAB2_LIB.BASEBOARD_FAB2(SCH_1):UPI_CPU1_CPU0_P1P1_DN(5)   I125 @BASEBOARD_FAB2_LIB.BASEBOARD_FAB2(SCH_1):PAGE68
    G6 UPI_CPU1_CPU0_P1P1_DN<4> @BASEBOARD_FAB2_LIB.BASEBOARD_FAB2(SCH_1):UPI_CPU1_CPU0_P1P1_DN(4)   I125 @BASEBOARD_FAB2_LIB.BASEBOARD_FAB2(SCH_1):PAGE68
    J6 UPI_CPU1_CPU0_P1P1_DN<3> @BASEBOARD_FAB2_LIB.BASEBOARD_FAB2(SCH_1):UPI_CPU1_CPU0_P1P1_DN(3)   I125 @BASEBOARD_FAB2_LIB.BASEBOARD_FAB2(SCH_1):PAGE68
    K5 UPI_CPU1_CPU0_P1P1_DN<2> @BASEBOARD_FAB2_LIB.BASEBOARD_FAB2(SCH_1):UPI_CPU1_CPU0_P1P1_DN(2)   I125 @BASEBOARD_FAB2_LIB.BASEBOARD_FAB2(SCH_1):PAGE68
    L4 UPI_CPU1_CPU0_P1P1_DP<1> @BASEBOARD_FAB2_LIB.BASEBOARD_FAB2(SCH_1):UPI_CPU1_CPU0_P1P1_DP(1)   I125 @BASEBOARD_FAB2_LIB.BASEBOARD_FAB2(SCH_1):PAGE68
    M3 UPI_CPU1_CPU0_P1P1_DP<0> @BASEBOARD_FAB2_LIB.BASEBOARD_FAB2(SCH_1):UPI_CPU1_CPU0_P1P1_DP(0)   I125 @BASEBOARD_FAB2_LIB.BASEBOARD_FAB2(SCH_1):PAGE68
   K21 UPI_CPU1_CPU0_P1P1_DN<19> @BASEBOARD_FAB2_LIB.BASEBOARD_FAB2(SCH_1):UPI_CPU1_CPU0_P1P1_DN(19)   I125 @BASEBOARD_FAB2_LIB.BASEBOARD_FAB2(SCH_1):PAGE68
   G20 UPI_CPU1_CPU0_P1P1_DN<18> @BASEBOARD_FAB2_LIB.BASEBOARD_FAB2(SCH_1):UPI_CPU1_CPU0_P1P1_DN(18)   I125 @BASEBOARD_FAB2_LIB.BASEBOARD_FAB2(SCH_1):PAGE68
   H19 UPI_CPU1_CPU0_P1P1_DP<17> @BASEBOARD_FAB2_LIB.BASEBOARD_FAB2(SCH_1):UPI_CPU1_CPU0_P1P1_DP(17)   I125 @BASEBOARD_FAB2_LIB.BASEBOARD_FAB2(SCH_1):PAGE68
   J18 UPI_CPU1_CPU0_P1P1_DP<16> @BASEBOARD_FAB2_LIB.BASEBOARD_FAB2(SCH_1):UPI_CPU1_CPU0_P1P1_DP(16)   I125 @BASEBOARD_FAB2_LIB.BASEBOARD_FAB2(SCH_1):PAGE68
   L18 UPI_CPU1_CPU0_P1P1_DP<15> @BASEBOARD_FAB2_LIB.BASEBOARD_FAB2(SCH_1):UPI_CPU1_CPU0_P1P1_DP(15)   I125 @BASEBOARD_FAB2_LIB.BASEBOARD_FAB2(SCH_1):PAGE68
   G16 UPI_CPU1_CPU0_P1P1_DP<14> @BASEBOARD_FAB2_LIB.BASEBOARD_FAB2(SCH_1):UPI_CPU1_CPU0_P1P1_DP(14)   I125 @BASEBOARD_FAB2_LIB.BASEBOARD_FAB2(SCH_1):PAGE68
   H15 UPI_CPU1_CPU0_P1P1_DP<13> @BASEBOARD_FAB2_LIB.BASEBOARD_FAB2(SCH_1):UPI_CPU1_CPU0_P1P1_DP(13)   I125 @BASEBOARD_FAB2_LIB.BASEBOARD_FAB2(SCH_1):PAGE68
   E14 UPI_CPU1_CPU0_P1P1_DP<12> @BASEBOARD_FAB2_LIB.BASEBOARD_FAB2(SCH_1):UPI_CPU1_CPU0_P1P1_DP(12)   I125 @BASEBOARD_FAB2_LIB.BASEBOARD_FAB2(SCH_1):PAGE68
   F13 UPI_CPU1_CPU0_P1P1_DN<11> @BASEBOARD_FAB2_LIB.BASEBOARD_FAB2(SCH_1):UPI_CPU1_CPU0_P1P1_DN(11)   I125 @BASEBOARD_FAB2_LIB.BASEBOARD_FAB2(SCH_1):PAGE68
   G12 UPI_CPU1_CPU0_P1P1_DP<10> @BASEBOARD_FAB2_LIB.BASEBOARD_FAB2(SCH_1):UPI_CPU1_CPU0_P1P1_DP(10)   I125 @BASEBOARD_FAB2_LIB.BASEBOARD_FAB2(SCH_1):PAGE68
    H9 UPI_CPU1_CPU0_P1P1_DP<9> @BASEBOARD_FAB2_LIB.BASEBOARD_FAB2(SCH_1):UPI_CPU1_CPU0_P1P1_DP(9)   I125 @BASEBOARD_FAB2_LIB.BASEBOARD_FAB2(SCH_1):PAGE68
   E10 UPI_CPU1_CPU0_P1P1_DN<8> @BASEBOARD_FAB2_LIB.BASEBOARD_FAB2(SCH_1):UPI_CPU1_CPU0_P1P1_DN(8)   I125 @BASEBOARD_FAB2_LIB.BASEBOARD_FAB2(SCH_1):PAGE68
    F9 UPI_CPU1_CPU0_P1P1_DN<7> @BASEBOARD_FAB2_LIB.BASEBOARD_FAB2(SCH_1):UPI_CPU1_CPU0_P1P1_DN(7)   I125 @BASEBOARD_FAB2_LIB.BASEBOARD_FAB2(SCH_1):PAGE68
    J8 UPI_CPU1_CPU0_P1P1_DN<6> @BASEBOARD_FAB2_LIB.BASEBOARD_FAB2(SCH_1):UPI_CPU1_CPU0_P1P1_DN(6)   I125 @BASEBOARD_FAB2_LIB.BASEBOARD_FAB2(SCH_1):PAGE68
    K7 UPI_CPU1_CPU0_P1P1_DP<5> @BASEBOARD_FAB2_LIB.BASEBOARD_FAB2(SCH_1):UPI_CPU1_CPU0_P1P1_DP(5)   I125 @BASEBOARD_FAB2_LIB.BASEBOARD_FAB2(SCH_1):PAGE68
    F7 UPI_CPU1_CPU0_P1P1_DP<4> @BASEBOARD_FAB2_LIB.BASEBOARD_FAB2(SCH_1):UPI_CPU1_CPU0_P1P1_DP(4)   I125 @BASEBOARD_FAB2_LIB.BASEBOARD_FAB2(SCH_1):PAGE68
    H5 UPI_CPU1_CPU0_P1P1_DP<3> @BASEBOARD_FAB2_LIB.BASEBOARD_FAB2(SCH_1):UPI_CPU1_CPU0_P1P1_DP(3)   I125 @BASEBOARD_FAB2_LIB.BASEBOARD_FAB2(SCH_1):PAGE68
    M5 UPI_CPU1_CPU0_P1P1_DP<2> @BASEBOARD_FAB2_LIB.BASEBOARD_FAB2(SCH_1):UPI_CPU1_CPU0_P1P1_DP(2)   I125 @BASEBOARD_FAB2_LIB.BASEBOARD_FAB2(SCH_1):PAGE68
    K3 UPI_CPU1_CPU0_P1P1_DN<1> @BASEBOARD_FAB2_LIB.BASEBOARD_FAB2(SCH_1):UPI_CPU1_CPU0_P1P1_DN(1)   I125 @BASEBOARD_FAB2_LIB.BASEBOARD_FAB2(SCH_1):PAGE68
    P3 UPI_CPU1_CPU0_P1P1_DN<0> @BASEBOARD_FAB2_LIB.BASEBOARD_FAB2(SCH_1):UPI_CPU1_CPU0_P1P1_DN(0)   I125 @BASEBOARD_FAB2_LIB.BASEBOARD_FAB2(SCH_1):PAGE68
  BY17    GND @BASEBOARD_FAB2_LIB.BASEBOARD_FAB2(SCH_1):GND     I1 @BASEBOARD_FAB2_LIB.BASEBOARD_FAB2(SCH_1):PAGE69
  CB15    GND @BASEBOARD_FAB2_LIB.BASEBOARD_FAB2(SCH_1):GND     I1 @BASEBOARD_FAB2_LIB.BASEBOARD_FAB2(SCH_1):PAGE69
  CF17    GND @BASEBOARD_FAB2_LIB.BASEBOARD_FAB2(SCH_1):GND     I1 @BASEBOARD_FAB2_LIB.BASEBOARD_FAB2(SCH_1):PAGE69
  CD15    GND @BASEBOARD_FAB2_LIB.BASEBOARD_FAB2(SCH_1):GND     I1 @BASEBOARD_FAB2_LIB.BASEBOARD_FAB2(SCH_1):PAGE69
  CE16    GND @BASEBOARD_FAB2_LIB.BASEBOARD_FAB2(SCH_1):GND     I1 @BASEBOARD_FAB2_LIB.BASEBOARD_FAB2(SCH_1):PAGE69
  CH17    GND @BASEBOARD_FAB2_LIB.BASEBOARD_FAB2(SCH_1):GND     I1 @BASEBOARD_FAB2_LIB.BASEBOARD_FAB2(SCH_1):PAGE69
  CJ18    GND @BASEBOARD_FAB2_LIB.BASEBOARD_FAB2(SCH_1):GND     I1 @BASEBOARD_FAB2_LIB.BASEBOARD_FAB2(SCH_1):PAGE69
  CL16    GND @BASEBOARD_FAB2_LIB.BASEBOARD_FAB2(SCH_1):GND     I1 @BASEBOARD_FAB2_LIB.BASEBOARD_FAB2(SCH_1):PAGE69
  CP21    GND @BASEBOARD_FAB2_LIB.BASEBOARD_FAB2(SCH_1):GND     I1 @BASEBOARD_FAB2_LIB.BASEBOARD_FAB2(SCH_1):PAGE69
  CN20    GND @BASEBOARD_FAB2_LIB.BASEBOARD_FAB2(SCH_1):GND     I1 @BASEBOARD_FAB2_LIB.BASEBOARD_FAB2(SCH_1):PAGE69
  CR18    GND @BASEBOARD_FAB2_LIB.BASEBOARD_FAB2(SCH_1):GND     I1 @BASEBOARD_FAB2_LIB.BASEBOARD_FAB2(SCH_1):PAGE69
  CT21    GND @BASEBOARD_FAB2_LIB.BASEBOARD_FAB2(SCH_1):GND     I1 @BASEBOARD_FAB2_LIB.BASEBOARD_FAB2(SCH_1):PAGE69
  CV19    GND @BASEBOARD_FAB2_LIB.BASEBOARD_FAB2(SCH_1):GND     I1 @BASEBOARD_FAB2_LIB.BASEBOARD_FAB2(SCH_1):PAGE69
  CW20    GND @BASEBOARD_FAB2_LIB.BASEBOARD_FAB2(SCH_1):GND     I1 @BASEBOARD_FAB2_LIB.BASEBOARD_FAB2(SCH_1):PAGE69
  DA20    GND @BASEBOARD_FAB2_LIB.BASEBOARD_FAB2(SCH_1):GND     I1 @BASEBOARD_FAB2_LIB.BASEBOARD_FAB2(SCH_1):PAGE69
  DD19    GND @BASEBOARD_FAB2_LIB.BASEBOARD_FAB2(SCH_1):GND     I1 @BASEBOARD_FAB2_LIB.BASEBOARD_FAB2(SCH_1):PAGE69
  DB21    GND @BASEBOARD_FAB2_LIB.BASEBOARD_FAB2(SCH_1):GND     I1 @BASEBOARD_FAB2_LIB.BASEBOARD_FAB2(SCH_1):PAGE69
  DC22    GND @BASEBOARD_FAB2_LIB.BASEBOARD_FAB2(SCH_1):GND     I1 @BASEBOARD_FAB2_LIB.BASEBOARD_FAB2(SCH_1):PAGE69
  DE22    GND @BASEBOARD_FAB2_LIB.BASEBOARD_FAB2(SCH_1):GND     I1 @BASEBOARD_FAB2_LIB.BASEBOARD_FAB2(SCH_1):PAGE69
  DF23    GND @BASEBOARD_FAB2_LIB.BASEBOARD_FAB2(SCH_1):GND     I1 @BASEBOARD_FAB2_LIB.BASEBOARD_FAB2(SCH_1):PAGE69
  CA16    GND @BASEBOARD_FAB2_LIB.BASEBOARD_FAB2(SCH_1):GND     I1 @BASEBOARD_FAB2_LIB.BASEBOARD_FAB2(SCH_1):PAGE69
  BY15    GND @BASEBOARD_FAB2_LIB.BASEBOARD_FAB2(SCH_1):GND     I1 @BASEBOARD_FAB2_LIB.BASEBOARD_FAB2(SCH_1):PAGE69
  CD17    GND @BASEBOARD_FAB2_LIB.BASEBOARD_FAB2(SCH_1):GND     I1 @BASEBOARD_FAB2_LIB.BASEBOARD_FAB2(SCH_1):PAGE69
  CC14    GND @BASEBOARD_FAB2_LIB.BASEBOARD_FAB2(SCH_1):GND     I1 @BASEBOARD_FAB2_LIB.BASEBOARD_FAB2(SCH_1):PAGE69
  CF15    GND @BASEBOARD_FAB2_LIB.BASEBOARD_FAB2(SCH_1):GND     I1 @BASEBOARD_FAB2_LIB.BASEBOARD_FAB2(SCH_1):PAGE69
  CG16    GND @BASEBOARD_FAB2_LIB.BASEBOARD_FAB2(SCH_1):GND     I1 @BASEBOARD_FAB2_LIB.BASEBOARD_FAB2(SCH_1):PAGE69
  CK17    GND @BASEBOARD_FAB2_LIB.BASEBOARD_FAB2(SCH_1):GND     I1 @BASEBOARD_FAB2_LIB.BASEBOARD_FAB2(SCH_1):PAGE69
  CJ16    GND @BASEBOARD_FAB2_LIB.BASEBOARD_FAB2(SCH_1):GND     I1 @BASEBOARD_FAB2_LIB.BASEBOARD_FAB2(SCH_1):PAGE69
  CM21    GND @BASEBOARD_FAB2_LIB.BASEBOARD_FAB2(SCH_1):GND     I1 @BASEBOARD_FAB2_LIB.BASEBOARD_FAB2(SCH_1):PAGE69
  CP19    GND @BASEBOARD_FAB2_LIB.BASEBOARD_FAB2(SCH_1):GND     I1 @BASEBOARD_FAB2_LIB.BASEBOARD_FAB2(SCH_1):PAGE69
  CN18    GND @BASEBOARD_FAB2_LIB.BASEBOARD_FAB2(SCH_1):GND     I1 @BASEBOARD_FAB2_LIB.BASEBOARD_FAB2(SCH_1):PAGE69
  CR20    GND @BASEBOARD_FAB2_LIB.BASEBOARD_FAB2(SCH_1):GND     I1 @BASEBOARD_FAB2_LIB.BASEBOARD_FAB2(SCH_1):PAGE69
  CW18    GND @BASEBOARD_FAB2_LIB.BASEBOARD_FAB2(SCH_1):GND     I1 @BASEBOARD_FAB2_LIB.BASEBOARD_FAB2(SCH_1):PAGE69
  CU20    GND @BASEBOARD_FAB2_LIB.BASEBOARD_FAB2(SCH_1):GND     I1 @BASEBOARD_FAB2_LIB.BASEBOARD_FAB2(SCH_1):PAGE69
  CY19    GND @BASEBOARD_FAB2_LIB.BASEBOARD_FAB2(SCH_1):GND     I1 @BASEBOARD_FAB2_LIB.BASEBOARD_FAB2(SCH_1):PAGE69
  DB19    GND @BASEBOARD_FAB2_LIB.BASEBOARD_FAB2(SCH_1):GND     I1 @BASEBOARD_FAB2_LIB.BASEBOARD_FAB2(SCH_1):PAGE69
  DC20    GND @BASEBOARD_FAB2_LIB.BASEBOARD_FAB2(SCH_1):GND     I1 @BASEBOARD_FAB2_LIB.BASEBOARD_FAB2(SCH_1):PAGE69
  DA22    GND @BASEBOARD_FAB2_LIB.BASEBOARD_FAB2(SCH_1):GND     I1 @BASEBOARD_FAB2_LIB.BASEBOARD_FAB2(SCH_1):PAGE69
  DD21    GND @BASEBOARD_FAB2_LIB.BASEBOARD_FAB2(SCH_1):GND     I1 @BASEBOARD_FAB2_LIB.BASEBOARD_FAB2(SCH_1):PAGE69
  DG22    GND @BASEBOARD_FAB2_LIB.BASEBOARD_FAB2(SCH_1):GND     I1 @BASEBOARD_FAB2_LIB.BASEBOARD_FAB2(SCH_1):PAGE69
  CC12 TP_CPU1_UPI2_RSVD_DT21 @BASEBOARD_FAB2_LIB.BASEBOARD_FAB2(SCH_1):TP_CPU1_UPI2_RSVD_DT21     I1 @BASEBOARD_FAB2_LIB.BASEBOARD_FAB2(SCH_1):PAGE69
  CC10 TP_CPU1_UPI2_RSVD_DM21 @BASEBOARD_FAB2_LIB.BASEBOARD_FAB2(SCH_1):TP_CPU1_UPI2_RSVD_DM21     I1 @BASEBOARD_FAB2_LIB.BASEBOARD_FAB2(SCH_1):PAGE69
  CE12 TP_CPU1_UPI2_RSVD_DL20 @BASEBOARD_FAB2_LIB.BASEBOARD_FAB2(SCH_1):TP_CPU1_UPI2_RSVD_DL20     I1 @BASEBOARD_FAB2_LIB.BASEBOARD_FAB2(SCH_1):PAGE69
  CH11 TP_CPU1_UPI2_RSVD_DG20 @BASEBOARD_FAB2_LIB.BASEBOARD_FAB2(SCH_1):TP_CPU1_UPI2_RSVD_DG20     I1 @BASEBOARD_FAB2_LIB.BASEBOARD_FAB2(SCH_1):PAGE69
  CF13 TP_CPU1_UPI2_RSVD_DH19 @BASEBOARD_FAB2_LIB.BASEBOARD_FAB2(SCH_1):TP_CPU1_UPI2_RSVD_DH19     I1 @BASEBOARD_FAB2_LIB.BASEBOARD_FAB2(SCH_1):PAGE69
  CJ14 TP_CPU1_UPI2_RSVD_DK17 @BASEBOARD_FAB2_LIB.BASEBOARD_FAB2(SCH_1):TP_CPU1_UPI2_RSVD_DK17     I1 @BASEBOARD_FAB2_LIB.BASEBOARD_FAB2(SCH_1):PAGE69
  CM13 TP_CPU1_UPI2_RSVD_DG18 @BASEBOARD_FAB2_LIB.BASEBOARD_FAB2(SCH_1):TP_CPU1_UPI2_RSVD_DG18     I1 @BASEBOARD_FAB2_LIB.BASEBOARD_FAB2(SCH_1):PAGE69
  CU14 TP_CPU1_UPI2_RSVD_DD17 @BASEBOARD_FAB2_LIB.BASEBOARD_FAB2(SCH_1):TP_CPU1_UPI2_RSVD_DD17     I1 @BASEBOARD_FAB2_LIB.BASEBOARD_FAB2(SCH_1):PAGE69
  CW14 TP_CPU1_UPI2_RSVD_DF15 @BASEBOARD_FAB2_LIB.BASEBOARD_FAB2(SCH_1):TP_CPU1_UPI2_RSVD_DF15     I1 @BASEBOARD_FAB2_LIB.BASEBOARD_FAB2(SCH_1):PAGE69
  DA16 TP_CPU1_UPI2_RSVD_DC16 @BASEBOARD_FAB2_LIB.BASEBOARD_FAB2(SCH_1):TP_CPU1_UPI2_RSVD_DC16     I1 @BASEBOARD_FAB2_LIB.BASEBOARD_FAB2(SCH_1):PAGE69
  DC16 TP_CPU1_UPI2_RSVD_DA16 @BASEBOARD_FAB2_LIB.BASEBOARD_FAB2(SCH_1):TP_CPU1_UPI2_RSVD_DA16     I1 @BASEBOARD_FAB2_LIB.BASEBOARD_FAB2(SCH_1):PAGE69
  DF15 TP_CPU1_UPI2_RSVD_CW14 @BASEBOARD_FAB2_LIB.BASEBOARD_FAB2(SCH_1):TP_CPU1_UPI2_RSVD_CW14     I1 @BASEBOARD_FAB2_LIB.BASEBOARD_FAB2(SCH_1):PAGE69
  DD17 TP_CPU1_UPI2_RSVD_CU14 @BASEBOARD_FAB2_LIB.BASEBOARD_FAB2(SCH_1):TP_CPU1_UPI2_RSVD_CU14     I1 @BASEBOARD_FAB2_LIB.BASEBOARD_FAB2(SCH_1):PAGE69
  DG18 TP_CPU1_UPI2_RSVD_CM13 @BASEBOARD_FAB2_LIB.BASEBOARD_FAB2(SCH_1):TP_CPU1_UPI2_RSVD_CM13     I1 @BASEBOARD_FAB2_LIB.BASEBOARD_FAB2(SCH_1):PAGE69
  DK17 TP_CPU1_UPI2_RSVD_CJ14 @BASEBOARD_FAB2_LIB.BASEBOARD_FAB2(SCH_1):TP_CPU1_UPI2_RSVD_CJ14     I1 @BASEBOARD_FAB2_LIB.BASEBOARD_FAB2(SCH_1):PAGE69
  DH19 TP_CPU1_UPI2_RSVD_CF13 @BASEBOARD_FAB2_LIB.BASEBOARD_FAB2(SCH_1):TP_CPU1_UPI2_RSVD_CF13     I1 @BASEBOARD_FAB2_LIB.BASEBOARD_FAB2(SCH_1):PAGE69
  DG20 TP_CPU1_UPI2_RSVD_CH11 @BASEBOARD_FAB2_LIB.BASEBOARD_FAB2(SCH_1):TP_CPU1_UPI2_RSVD_CH11     I1 @BASEBOARD_FAB2_LIB.BASEBOARD_FAB2(SCH_1):PAGE69
  DL20 TP_CPU1_UPI2_RSVD_CE12 @BASEBOARD_FAB2_LIB.BASEBOARD_FAB2(SCH_1):TP_CPU1_UPI2_RSVD_CE12     I1 @BASEBOARD_FAB2_LIB.BASEBOARD_FAB2(SCH_1):PAGE69
  DM21 TP_CPU1_UPI2_RSVD_CC10 @BASEBOARD_FAB2_LIB.BASEBOARD_FAB2(SCH_1):TP_CPU1_UPI2_RSVD_CC10     I1 @BASEBOARD_FAB2_LIB.BASEBOARD_FAB2(SCH_1):PAGE69
  DT21 TP_CPU1_UPI2_RSVD_CC12 @BASEBOARD_FAB2_LIB.BASEBOARD_FAB2(SCH_1):TP_CPU1_UPI2_RSVD_CC12     I1 @BASEBOARD_FAB2_LIB.BASEBOARD_FAB2(SCH_1):PAGE69
  CA12 TP_CPU1_UPI2_RSVD_DP21 @BASEBOARD_FAB2_LIB.BASEBOARD_FAB2(SCH_1):TP_CPU1_UPI2_RSVD_DP21     I1 @BASEBOARD_FAB2_LIB.BASEBOARD_FAB2(SCH_1):PAGE69
  CB11 TP_CPU1_UPI2_RSVD_DN20 @BASEBOARD_FAB2_LIB.BASEBOARD_FAB2(SCH_1):TP_CPU1_UPI2_RSVD_DN20     I1 @BASEBOARD_FAB2_LIB.BASEBOARD_FAB2(SCH_1):PAGE69
  CD11 TP_CPU1_UPI2_RSVD_DK19 @BASEBOARD_FAB2_LIB.BASEBOARD_FAB2(SCH_1):TP_CPU1_UPI2_RSVD_DK19     I1 @BASEBOARD_FAB2_LIB.BASEBOARD_FAB2(SCH_1):PAGE69
  CF11 TP_CPU1_UPI2_RSVD_DJ20 @BASEBOARD_FAB2_LIB.BASEBOARD_FAB2(SCH_1):TP_CPU1_UPI2_RSVD_DJ20     I1 @BASEBOARD_FAB2_LIB.BASEBOARD_FAB2(SCH_1):PAGE69
  CG12 TP_CPU1_UPI2_RSVD_DJ18 @BASEBOARD_FAB2_LIB.BASEBOARD_FAB2(SCH_1):TP_CPU1_UPI2_RSVD_DJ18     I1 @BASEBOARD_FAB2_LIB.BASEBOARD_FAB2(SCH_1):PAGE69
  CH13 TP_CPU1_UPI2_RSVD_DH17 @BASEBOARD_FAB2_LIB.BASEBOARD_FAB2(SCH_1):TP_CPU1_UPI2_RSVD_DH17     I1 @BASEBOARD_FAB2_LIB.BASEBOARD_FAB2(SCH_1):PAGE69
  CK13 TP_CPU1_UPI2_RSVD_DF17 @BASEBOARD_FAB2_LIB.BASEBOARD_FAB2(SCH_1):TP_CPU1_UPI2_RSVD_DF17     I1 @BASEBOARD_FAB2_LIB.BASEBOARD_FAB2(SCH_1):PAGE69
  CR14 TP_CPU1_UPI2_RSVD_DE16 @BASEBOARD_FAB2_LIB.BASEBOARD_FAB2(SCH_1):TP_CPU1_UPI2_RSVD_DE16     I1 @BASEBOARD_FAB2_LIB.BASEBOARD_FAB2(SCH_1):PAGE69
  CV13 TP_CPU1_UPI2_RSVD_DD15 @BASEBOARD_FAB2_LIB.BASEBOARD_FAB2(SCH_1):TP_CPU1_UPI2_RSVD_DD15     I1 @BASEBOARD_FAB2_LIB.BASEBOARD_FAB2(SCH_1):PAGE69
  CW16 TP_CPU1_UPI2_RSVD_DB15 @BASEBOARD_FAB2_LIB.BASEBOARD_FAB2(SCH_1):TP_CPU1_UPI2_RSVD_DB15     I1 @BASEBOARD_FAB2_LIB.BASEBOARD_FAB2(SCH_1):PAGE69
  DB15 TP_CPU1_UPI2_RSVD_CW16 @BASEBOARD_FAB2_LIB.BASEBOARD_FAB2(SCH_1):TP_CPU1_UPI2_RSVD_CW16     I1 @BASEBOARD_FAB2_LIB.BASEBOARD_FAB2(SCH_1):PAGE69
  DD15 TP_CPU1_UPI2_RSVD_CV13 @BASEBOARD_FAB2_LIB.BASEBOARD_FAB2(SCH_1):TP_CPU1_UPI2_RSVD_CV13     I1 @BASEBOARD_FAB2_LIB.BASEBOARD_FAB2(SCH_1):PAGE69
  DE16 TP_CPU1_UPI2_RSVD_CR14 @BASEBOARD_FAB2_LIB.BASEBOARD_FAB2(SCH_1):TP_CPU1_UPI2_RSVD_CR14     I1 @BASEBOARD_FAB2_LIB.BASEBOARD_FAB2(SCH_1):PAGE69
  DF17 TP_CPU1_UPI2_RSVD_CK13 @BASEBOARD_FAB2_LIB.BASEBOARD_FAB2(SCH_1):TP_CPU1_UPI2_RSVD_CK13     I1 @BASEBOARD_FAB2_LIB.BASEBOARD_FAB2(SCH_1):PAGE69
  DH17 TP_CPU1_UPI2_RSVD_CH13 @BASEBOARD_FAB2_LIB.BASEBOARD_FAB2(SCH_1):TP_CPU1_UPI2_RSVD_CH13     I1 @BASEBOARD_FAB2_LIB.BASEBOARD_FAB2(SCH_1):PAGE69
  DJ18 TP_CPU1_UPI2_RSVD_CG12 @BASEBOARD_FAB2_LIB.BASEBOARD_FAB2(SCH_1):TP_CPU1_UPI2_RSVD_CG12     I1 @BASEBOARD_FAB2_LIB.BASEBOARD_FAB2(SCH_1):PAGE69
  DJ20 TP_CPU1_UPI2_RSVD_CF11 @BASEBOARD_FAB2_LIB.BASEBOARD_FAB2(SCH_1):TP_CPU1_UPI2_RSVD_CF11     I1 @BASEBOARD_FAB2_LIB.BASEBOARD_FAB2(SCH_1):PAGE69
  DK19 TP_CPU1_UPI2_RSVD_CD11 @BASEBOARD_FAB2_LIB.BASEBOARD_FAB2(SCH_1):TP_CPU1_UPI2_RSVD_CD11     I1 @BASEBOARD_FAB2_LIB.BASEBOARD_FAB2(SCH_1):PAGE69
  DN20 TP_CPU1_UPI2_RSVD_CB11 @BASEBOARD_FAB2_LIB.BASEBOARD_FAB2(SCH_1):TP_CPU1_UPI2_RSVD_CB11     I1 @BASEBOARD_FAB2_LIB.BASEBOARD_FAB2(SCH_1):PAGE69
  DP21 TP_CPU1_UPI2_RSVD_CA12 @BASEBOARD_FAB2_LIB.BASEBOARD_FAB2(SCH_1):TP_CPU1_UPI2_RSVD_CA12     I1 @BASEBOARD_FAB2_LIB.BASEBOARD_FAB2(SCH_1):PAGE69
  AY83 TP_CPU1_RSVD_255 @BASEBOARD_FAB2_LIB.BASEBOARD_FAB2(SCH_1):TP_CPU1_RSVD_255     I9 @BASEBOARD_FAB2_LIB.BASEBOARD_FAB2(SCH_1):PAGE70
  BA78 TP_CPU1_RSVD_171 @BASEBOARD_FAB2_LIB.BASEBOARD_FAB2(SCH_1):TP_CPU1_RSVD_171     I9 @BASEBOARD_FAB2_LIB.BASEBOARD_FAB2(SCH_1):PAGE70
  BA82 TP_CPU1_RSVD_170 @BASEBOARD_FAB2_LIB.BASEBOARD_FAB2(SCH_1):TP_CPU1_RSVD_170     I9 @BASEBOARD_FAB2_LIB.BASEBOARD_FAB2(SCH_1):PAGE70
  BB13 TP_CPU1_RSVD_169 @BASEBOARD_FAB2_LIB.BASEBOARD_FAB2(SCH_1):TP_CPU1_RSVD_169     I9 @BASEBOARD_FAB2_LIB.BASEBOARD_FAB2(SCH_1):PAGE70
  BB15 TP_CPU1_RSVD_168 @BASEBOARD_FAB2_LIB.BASEBOARD_FAB2(SCH_1):TP_CPU1_RSVD_168     I9 @BASEBOARD_FAB2_LIB.BASEBOARD_FAB2(SCH_1):PAGE70
  BB17 TP_CPU1_RSVD_167 @BASEBOARD_FAB2_LIB.BASEBOARD_FAB2(SCH_1):TP_CPU1_RSVD_167     I9 @BASEBOARD_FAB2_LIB.BASEBOARD_FAB2(SCH_1):PAGE70
  BB21 TP_CPU1_RSVD_166 @BASEBOARD_FAB2_LIB.BASEBOARD_FAB2(SCH_1):TP_CPU1_RSVD_166     I9 @BASEBOARD_FAB2_LIB.BASEBOARD_FAB2(SCH_1):PAGE70
  BB25 CLK_100M_CPU1_RC_REFCLK1_DN @BASEBOARD_FAB2_LIB.BASEBOARD_FAB2(SCH_1):CLK_100M_CPU1_RC_REFCLK1_DN     I9 @BASEBOARD_FAB2_LIB.BASEBOARD_FAB2(SCH_1):PAGE70
  BB65 TP_CPU1_RSVD_164 @BASEBOARD_FAB2_LIB.BASEBOARD_FAB2(SCH_1):TP_CPU1_RSVD_164     I9 @BASEBOARD_FAB2_LIB.BASEBOARD_FAB2(SCH_1):PAGE70
  BB67 TP_CPU1_RSVD_163 @BASEBOARD_FAB2_LIB.BASEBOARD_FAB2(SCH_1):TP_CPU1_RSVD_163     I9 @BASEBOARD_FAB2_LIB.BASEBOARD_FAB2(SCH_1):PAGE70
  BC14 TP_CPU1_RSVD_162 @BASEBOARD_FAB2_LIB.BASEBOARD_FAB2(SCH_1):TP_CPU1_RSVD_162     I9 @BASEBOARD_FAB2_LIB.BASEBOARD_FAB2(SCH_1):PAGE70
  BC18 TP_CPU1_RSVD_161 @BASEBOARD_FAB2_LIB.BASEBOARD_FAB2(SCH_1):TP_CPU1_RSVD_161     I9 @BASEBOARD_FAB2_LIB.BASEBOARD_FAB2(SCH_1):PAGE70
  BC20 TP_CPU1_RSVD_160 @BASEBOARD_FAB2_LIB.BASEBOARD_FAB2(SCH_1):TP_CPU1_RSVD_160     I9 @BASEBOARD_FAB2_LIB.BASEBOARD_FAB2(SCH_1):PAGE70
  BC22 TP_CPU1_RSVD_159 @BASEBOARD_FAB2_LIB.BASEBOARD_FAB2(SCH_1):TP_CPU1_RSVD_159     I9 @BASEBOARD_FAB2_LIB.BASEBOARD_FAB2(SCH_1):PAGE70
  BC64 TP_CPU1_RSVD_158 @BASEBOARD_FAB2_LIB.BASEBOARD_FAB2(SCH_1):TP_CPU1_RSVD_158     I9 @BASEBOARD_FAB2_LIB.BASEBOARD_FAB2(SCH_1):PAGE70
  BC66 TP_CPU1_RSVD_157 @BASEBOARD_FAB2_LIB.BASEBOARD_FAB2(SCH_1):TP_CPU1_RSVD_157     I9 @BASEBOARD_FAB2_LIB.BASEBOARD_FAB2(SCH_1):PAGE70
  BC68 TP_CPU1_RSVD_156 @BASEBOARD_FAB2_LIB.BASEBOARD_FAB2(SCH_1):TP_CPU1_RSVD_156     I9 @BASEBOARD_FAB2_LIB.BASEBOARD_FAB2(SCH_1):PAGE70
  BD17 TP_CPU1_RSVD_155 @BASEBOARD_FAB2_LIB.BASEBOARD_FAB2(SCH_1):TP_CPU1_RSVD_155     I9 @BASEBOARD_FAB2_LIB.BASEBOARD_FAB2(SCH_1):PAGE70
  BD19 TP_CPU1_RSVD_154 @BASEBOARD_FAB2_LIB.BASEBOARD_FAB2(SCH_1):TP_CPU1_RSVD_154     I9 @BASEBOARD_FAB2_LIB.BASEBOARD_FAB2(SCH_1):PAGE70
  BD25 CLK_100M_CPU1_RC_REFCLK1_DP @BASEBOARD_FAB2_LIB.BASEBOARD_FAB2(SCH_1):CLK_100M_CPU1_RC_REFCLK1_DP     I9 @BASEBOARD_FAB2_LIB.BASEBOARD_FAB2(SCH_1):PAGE70
  BD65 TP_CPU1_RSVD_152 @BASEBOARD_FAB2_LIB.BASEBOARD_FAB2(SCH_1):TP_CPU1_RSVD_152     I9 @BASEBOARD_FAB2_LIB.BASEBOARD_FAB2(SCH_1):PAGE70
  BD67 TP_CPU1_RSVD_151 @BASEBOARD_FAB2_LIB.BASEBOARD_FAB2(SCH_1):TP_CPU1_RSVD_151     I9 @BASEBOARD_FAB2_LIB.BASEBOARD_FAB2(SCH_1):PAGE70
  BD69 TP_CPU1_RSVD_150 @BASEBOARD_FAB2_LIB.BASEBOARD_FAB2(SCH_1):TP_CPU1_RSVD_150     I9 @BASEBOARD_FAB2_LIB.BASEBOARD_FAB2(SCH_1):PAGE70
  BE18 TP_CPU1_RSVD_149 @BASEBOARD_FAB2_LIB.BASEBOARD_FAB2(SCH_1):TP_CPU1_RSVD_149     I9 @BASEBOARD_FAB2_LIB.BASEBOARD_FAB2(SCH_1):PAGE70
  BE20 TP_CPU1_RSVD_148 @BASEBOARD_FAB2_LIB.BASEBOARD_FAB2(SCH_1):TP_CPU1_RSVD_148     I9 @BASEBOARD_FAB2_LIB.BASEBOARD_FAB2(SCH_1):PAGE70
  BE22 TP_CPU1_RSVD_147 @BASEBOARD_FAB2_LIB.BASEBOARD_FAB2(SCH_1):TP_CPU1_RSVD_147     I9 @BASEBOARD_FAB2_LIB.BASEBOARD_FAB2(SCH_1):PAGE70
  BF21 TP_CPU1_RSVD_146 @BASEBOARD_FAB2_LIB.BASEBOARD_FAB2(SCH_1):TP_CPU1_RSVD_146     I9 @BASEBOARD_FAB2_LIB.BASEBOARD_FAB2(SCH_1):PAGE70
  BG18 TP_CPU1_RSVD_145 @BASEBOARD_FAB2_LIB.BASEBOARD_FAB2(SCH_1):TP_CPU1_RSVD_145     I9 @BASEBOARD_FAB2_LIB.BASEBOARD_FAB2(SCH_1):PAGE70
  BG20 TP_CPU1_RSVD_144 @BASEBOARD_FAB2_LIB.BASEBOARD_FAB2(SCH_1):TP_CPU1_RSVD_144     I9 @BASEBOARD_FAB2_LIB.BASEBOARD_FAB2(SCH_1):PAGE70
  BH19 PVCCMCP_CPU1 @BASEBOARD_FAB2_LIB.BASEBOARD_FAB2(SCH_1):PVCCMCP_CPU1     I9 @BASEBOARD_FAB2_LIB.BASEBOARD_FAB2(SCH_1):PAGE70
  BJ16 PVCCMCP_CPU1 @BASEBOARD_FAB2_LIB.BASEBOARD_FAB2(SCH_1):PVCCMCP_CPU1     I9 @BASEBOARD_FAB2_LIB.BASEBOARD_FAB2(SCH_1):PAGE70
  BJ18 PVCCMCP_CPU1 @BASEBOARD_FAB2_LIB.BASEBOARD_FAB2(SCH_1):PVCCMCP_CPU1     I9 @BASEBOARD_FAB2_LIB.BASEBOARD_FAB2(SCH_1):PAGE70
  BJ20 PVCCMCP_CPU1 @BASEBOARD_FAB2_LIB.BASEBOARD_FAB2(SCH_1):PVCCMCP_CPU1     I9 @BASEBOARD_FAB2_LIB.BASEBOARD_FAB2(SCH_1):PAGE70
  BK17 PVCCMCP_CPU1 @BASEBOARD_FAB2_LIB.BASEBOARD_FAB2(SCH_1):PVCCMCP_CPU1     I9 @BASEBOARD_FAB2_LIB.BASEBOARD_FAB2(SCH_1):PAGE70
  BL18 PVCCMCP_CPU1 @BASEBOARD_FAB2_LIB.BASEBOARD_FAB2(SCH_1):PVCCMCP_CPU1     I9 @BASEBOARD_FAB2_LIB.BASEBOARD_FAB2(SCH_1):PAGE70
  BL20 PVCCMCP_CPU1 @BASEBOARD_FAB2_LIB.BASEBOARD_FAB2(SCH_1):PVCCMCP_CPU1     I9 @BASEBOARD_FAB2_LIB.BASEBOARD_FAB2(SCH_1):PAGE70
  BM17 PVCCMCP_CPU1 @BASEBOARD_FAB2_LIB.BASEBOARD_FAB2(SCH_1):PVCCMCP_CPU1     I9 @BASEBOARD_FAB2_LIB.BASEBOARD_FAB2(SCH_1):PAGE70
  BM19 PVCCMCP_CPU1 @BASEBOARD_FAB2_LIB.BASEBOARD_FAB2(SCH_1):PVCCMCP_CPU1     I9 @BASEBOARD_FAB2_LIB.BASEBOARD_FAB2(SCH_1):PAGE70
  BN18 PVCCMCP_CPU1 @BASEBOARD_FAB2_LIB.BASEBOARD_FAB2(SCH_1):PVCCMCP_CPU1     I9 @BASEBOARD_FAB2_LIB.BASEBOARD_FAB2(SCH_1):PAGE70
  BP17 PVCCMCP_CPU1 @BASEBOARD_FAB2_LIB.BASEBOARD_FAB2(SCH_1):PVCCMCP_CPU1     I9 @BASEBOARD_FAB2_LIB.BASEBOARD_FAB2(SCH_1):PAGE70
  BP21 PVCCMCP_CPU1 @BASEBOARD_FAB2_LIB.BASEBOARD_FAB2(SCH_1):PVCCMCP_CPU1     I9 @BASEBOARD_FAB2_LIB.BASEBOARD_FAB2(SCH_1):PAGE70
  BR22 PVCCMCP_CPU1 @BASEBOARD_FAB2_LIB.BASEBOARD_FAB2(SCH_1):PVCCMCP_CPU1     I9 @BASEBOARD_FAB2_LIB.BASEBOARD_FAB2(SCH_1):PAGE70
  BR24 PVCCMCP_CPU1 @BASEBOARD_FAB2_LIB.BASEBOARD_FAB2(SCH_1):PVCCMCP_CPU1     I9 @BASEBOARD_FAB2_LIB.BASEBOARD_FAB2(SCH_1):PAGE70
  BU18 PVCCMCP_CPU1 @BASEBOARD_FAB2_LIB.BASEBOARD_FAB2(SCH_1):PVCCMCP_CPU1     I9 @BASEBOARD_FAB2_LIB.BASEBOARD_FAB2(SCH_1):PAGE70
  BU20 PVCCMCP_CPU1 @BASEBOARD_FAB2_LIB.BASEBOARD_FAB2(SCH_1):PVCCMCP_CPU1     I9 @BASEBOARD_FAB2_LIB.BASEBOARD_FAB2(SCH_1):PAGE70
  BU22 PVCCMCP_CPU1 @BASEBOARD_FAB2_LIB.BASEBOARD_FAB2(SCH_1):PVCCMCP_CPU1     I9 @BASEBOARD_FAB2_LIB.BASEBOARD_FAB2(SCH_1):PAGE70
  BV19 PVCCMCP_CPU1 @BASEBOARD_FAB2_LIB.BASEBOARD_FAB2(SCH_1):PVCCMCP_CPU1     I9 @BASEBOARD_FAB2_LIB.BASEBOARD_FAB2(SCH_1):PAGE70
  BV21 PVCCMCP_CPU1 @BASEBOARD_FAB2_LIB.BASEBOARD_FAB2(SCH_1):PVCCMCP_CPU1     I9 @BASEBOARD_FAB2_LIB.BASEBOARD_FAB2(SCH_1):PAGE70
  BV23 TP_CPU1_RSVD_124 @BASEBOARD_FAB2_LIB.BASEBOARD_FAB2(SCH_1):TP_CPU1_RSVD_124     I9 @BASEBOARD_FAB2_LIB.BASEBOARD_FAB2(SCH_1):PAGE70
  BW10 TP_CPU1_RSVD_123 @BASEBOARD_FAB2_LIB.BASEBOARD_FAB2(SCH_1):TP_CPU1_RSVD_123     I9 @BASEBOARD_FAB2_LIB.BASEBOARD_FAB2(SCH_1):PAGE70
  BW20 PVCCMCP_CPU1 @BASEBOARD_FAB2_LIB.BASEBOARD_FAB2(SCH_1):PVCCMCP_CPU1     I9 @BASEBOARD_FAB2_LIB.BASEBOARD_FAB2(SCH_1):PAGE70
  BW22 TP_CPU1_RSVD_121 @BASEBOARD_FAB2_LIB.BASEBOARD_FAB2(SCH_1):TP_CPU1_RSVD_121     I9 @BASEBOARD_FAB2_LIB.BASEBOARD_FAB2(SCH_1):PAGE70
  BY19 PVCCMCP_CPU1 @BASEBOARD_FAB2_LIB.BASEBOARD_FAB2(SCH_1):PVCCMCP_CPU1     I9 @BASEBOARD_FAB2_LIB.BASEBOARD_FAB2(SCH_1):PAGE70
  BY25 TP_CPU1_RSVD_119 @BASEBOARD_FAB2_LIB.BASEBOARD_FAB2(SCH_1):TP_CPU1_RSVD_119     I9 @BASEBOARD_FAB2_LIB.BASEBOARD_FAB2(SCH_1):PAGE70
  CA22 PVCCMCP_CPU1 @BASEBOARD_FAB2_LIB.BASEBOARD_FAB2(SCH_1):PVCCMCP_CPU1     I9 @BASEBOARD_FAB2_LIB.BASEBOARD_FAB2(SCH_1):PAGE70
  CA24 TP_CPU1_RSVD_117 @BASEBOARD_FAB2_LIB.BASEBOARD_FAB2(SCH_1):TP_CPU1_RSVD_117     I9 @BASEBOARD_FAB2_LIB.BASEBOARD_FAB2(SCH_1):PAGE70
  CB19 PVCCMCP_CPU1 @BASEBOARD_FAB2_LIB.BASEBOARD_FAB2(SCH_1):PVCCMCP_CPU1     I9 @BASEBOARD_FAB2_LIB.BASEBOARD_FAB2(SCH_1):PAGE70
  CB21 PVCCMCP_CPU1 @BASEBOARD_FAB2_LIB.BASEBOARD_FAB2(SCH_1):PVCCMCP_CPU1     I9 @BASEBOARD_FAB2_LIB.BASEBOARD_FAB2(SCH_1):PAGE70
  CB25 TP_CPU1_RSVD_114 @BASEBOARD_FAB2_LIB.BASEBOARD_FAB2(SCH_1):TP_CPU1_RSVD_114     I9 @BASEBOARD_FAB2_LIB.BASEBOARD_FAB2(SCH_1):PAGE70
   CB5 TP_CPU1_RSVD_113 @BASEBOARD_FAB2_LIB.BASEBOARD_FAB2(SCH_1):TP_CPU1_RSVD_113     I9 @BASEBOARD_FAB2_LIB.BASEBOARD_FAB2(SCH_1):PAGE70
  CC20 PVCCMCP_CPU1 @BASEBOARD_FAB2_LIB.BASEBOARD_FAB2(SCH_1):PVCCMCP_CPU1     I9 @BASEBOARD_FAB2_LIB.BASEBOARD_FAB2(SCH_1):PAGE70
   CC6 TP_CPU1_RSVD_111 @BASEBOARD_FAB2_LIB.BASEBOARD_FAB2(SCH_1):TP_CPU1_RSVD_111     I9 @BASEBOARD_FAB2_LIB.BASEBOARD_FAB2(SCH_1):PAGE70
  CD19 PVCCMCP_CPU1 @BASEBOARD_FAB2_LIB.BASEBOARD_FAB2(SCH_1):PVCCMCP_CPU1     I9 @BASEBOARD_FAB2_LIB.BASEBOARD_FAB2(SCH_1):PAGE70
  CD21 PVCCMCP_CPU1 @BASEBOARD_FAB2_LIB.BASEBOARD_FAB2(SCH_1):PVCCMCP_CPU1     I9 @BASEBOARD_FAB2_LIB.BASEBOARD_FAB2(SCH_1):PAGE70
  CD25 TP_CPU1_RSVD_108 @BASEBOARD_FAB2_LIB.BASEBOARD_FAB2(SCH_1):TP_CPU1_RSVD_108     I9 @BASEBOARD_FAB2_LIB.BASEBOARD_FAB2(SCH_1):PAGE70
  CE22 PVCCMCP_CPU1 @BASEBOARD_FAB2_LIB.BASEBOARD_FAB2(SCH_1):PVCCMCP_CPU1     I9 @BASEBOARD_FAB2_LIB.BASEBOARD_FAB2(SCH_1):PAGE70
  CE78 TP_CPU1_RSVD_106 @BASEBOARD_FAB2_LIB.BASEBOARD_FAB2(SCH_1):TP_CPU1_RSVD_106     I9 @BASEBOARD_FAB2_LIB.BASEBOARD_FAB2(SCH_1):PAGE70
  CE80 TP_CPU1_RSVD_105 @BASEBOARD_FAB2_LIB.BASEBOARD_FAB2(SCH_1):TP_CPU1_RSVD_105     I9 @BASEBOARD_FAB2_LIB.BASEBOARD_FAB2(SCH_1):PAGE70
  CF19 PVCCMCP_CPU1 @BASEBOARD_FAB2_LIB.BASEBOARD_FAB2(SCH_1):PVCCMCP_CPU1     I9 @BASEBOARD_FAB2_LIB.BASEBOARD_FAB2(SCH_1):PAGE70
  CF21 PVCCMCP_CPU1 @BASEBOARD_FAB2_LIB.BASEBOARD_FAB2(SCH_1):PVCCMCP_CPU1     I9 @BASEBOARD_FAB2_LIB.BASEBOARD_FAB2(SCH_1):PAGE70
  CF23 PVCCMCP_CPU1 @BASEBOARD_FAB2_LIB.BASEBOARD_FAB2(SCH_1):PVCCMCP_CPU1     I9 @BASEBOARD_FAB2_LIB.BASEBOARD_FAB2(SCH_1):PAGE70
  CF79 TP_CPU1_RSVD_101 @BASEBOARD_FAB2_LIB.BASEBOARD_FAB2(SCH_1):TP_CPU1_RSVD_101     I9 @BASEBOARD_FAB2_LIB.BASEBOARD_FAB2(SCH_1):PAGE70
  CF81 TP_CPU1_RSVD_100 @BASEBOARD_FAB2_LIB.BASEBOARD_FAB2(SCH_1):TP_CPU1_RSVD_100     I9 @BASEBOARD_FAB2_LIB.BASEBOARD_FAB2(SCH_1):PAGE70
  CG10 TP_CPU1_RSVD_99 @BASEBOARD_FAB2_LIB.BASEBOARD_FAB2(SCH_1):TP_CPU1_RSVD_99     I9 @BASEBOARD_FAB2_LIB.BASEBOARD_FAB2(SCH_1):PAGE70
  CG20 PVCCMCP_CPU1 @BASEBOARD_FAB2_LIB.BASEBOARD_FAB2(SCH_1):PVCCMCP_CPU1     I9 @BASEBOARD_FAB2_LIB.BASEBOARD_FAB2(SCH_1):PAGE70
  CG24 TP_CPU1_RSVD_97 @BASEBOARD_FAB2_LIB.BASEBOARD_FAB2(SCH_1):TP_CPU1_RSVD_97     I9 @BASEBOARD_FAB2_LIB.BASEBOARD_FAB2(SCH_1):PAGE70
  CG26 PVCCMCP_CPU1 @BASEBOARD_FAB2_LIB.BASEBOARD_FAB2(SCH_1):PVCCMCP_CPU1     I9 @BASEBOARD_FAB2_LIB.BASEBOARD_FAB2(SCH_1):PAGE70
  CG78 TP_CPU1_RSVD_95 @BASEBOARD_FAB2_LIB.BASEBOARD_FAB2(SCH_1):TP_CPU1_RSVD_95     I9 @BASEBOARD_FAB2_LIB.BASEBOARD_FAB2(SCH_1):PAGE70
  CG82 TP_CPU1_RSVD_94 @BASEBOARD_FAB2_LIB.BASEBOARD_FAB2(SCH_1):TP_CPU1_RSVD_94     I9 @BASEBOARD_FAB2_LIB.BASEBOARD_FAB2(SCH_1):PAGE70
  CH21 PVCCMCP_CPU1 @BASEBOARD_FAB2_LIB.BASEBOARD_FAB2(SCH_1):PVCCMCP_CPU1     I9 @BASEBOARD_FAB2_LIB.BASEBOARD_FAB2(SCH_1):PAGE70
  CH23 PVCCMCP_CPU1 @BASEBOARD_FAB2_LIB.BASEBOARD_FAB2(SCH_1):PVCCMCP_CPU1     I9 @BASEBOARD_FAB2_LIB.BASEBOARD_FAB2(SCH_1):PAGE70
  CH25 TP_CPU1_RSVD_91 @BASEBOARD_FAB2_LIB.BASEBOARD_FAB2(SCH_1):TP_CPU1_RSVD_91    I10 @BASEBOARD_FAB2_LIB.BASEBOARD_FAB2(SCH_1):PAGE70
  CH77 TP_CPU1_RSVD_90 @BASEBOARD_FAB2_LIB.BASEBOARD_FAB2(SCH_1):TP_CPU1_RSVD_90    I10 @BASEBOARD_FAB2_LIB.BASEBOARD_FAB2(SCH_1):PAGE70
  CJ20 PVCCMCP_CPU1 @BASEBOARD_FAB2_LIB.BASEBOARD_FAB2(SCH_1):PVCCMCP_CPU1    I10 @BASEBOARD_FAB2_LIB.BASEBOARD_FAB2(SCH_1):PAGE70
  CJ22 PVCCMCP_CPU1 @BASEBOARD_FAB2_LIB.BASEBOARD_FAB2(SCH_1):PVCCMCP_CPU1    I10 @BASEBOARD_FAB2_LIB.BASEBOARD_FAB2(SCH_1):PAGE70
  CJ24 PVCCMCP_CPU1 @BASEBOARD_FAB2_LIB.BASEBOARD_FAB2(SCH_1):PVCCMCP_CPU1    I10 @BASEBOARD_FAB2_LIB.BASEBOARD_FAB2(SCH_1):PAGE70
  CJ26 PVCCMCP_CPU1 @BASEBOARD_FAB2_LIB.BASEBOARD_FAB2(SCH_1):PVCCMCP_CPU1    I10 @BASEBOARD_FAB2_LIB.BASEBOARD_FAB2(SCH_1):PAGE70
  CK19 TP_CPU1_RSVD_85 @BASEBOARD_FAB2_LIB.BASEBOARD_FAB2(SCH_1):TP_CPU1_RSVD_85    I10 @BASEBOARD_FAB2_LIB.BASEBOARD_FAB2(SCH_1):PAGE70
  CK23 PVCCMCP_CPU1 @BASEBOARD_FAB2_LIB.BASEBOARD_FAB2(SCH_1):PVCCMCP_CPU1    I10 @BASEBOARD_FAB2_LIB.BASEBOARD_FAB2(SCH_1):PAGE70
  CK25 PVCCMCP_CPU1 @BASEBOARD_FAB2_LIB.BASEBOARD_FAB2(SCH_1):PVCCMCP_CPU1    I10 @BASEBOARD_FAB2_LIB.BASEBOARD_FAB2(SCH_1):PAGE70
  CK77 TP_CPU1_RSVD_82 @BASEBOARD_FAB2_LIB.BASEBOARD_FAB2(SCH_1):TP_CPU1_RSVD_82    I10 @BASEBOARD_FAB2_LIB.BASEBOARD_FAB2(SCH_1):PAGE70
  CL24 PVCCMCP_CPU1 @BASEBOARD_FAB2_LIB.BASEBOARD_FAB2(SCH_1):PVCCMCP_CPU1    I10 @BASEBOARD_FAB2_LIB.BASEBOARD_FAB2(SCH_1):PAGE70
  AW22 TP_CPU1_TEST_10 @BASEBOARD_FAB2_LIB.BASEBOARD_FAB2(SCH_1):TP_CPU1_TEST_10    I10 @BASEBOARD_FAB2_LIB.BASEBOARD_FAB2(SCH_1):PAGE70
  AR16 TP_CPU1_TEST_6 @BASEBOARD_FAB2_LIB.BASEBOARD_FAB2(SCH_1):TP_CPU1_TEST_6    I10 @BASEBOARD_FAB2_LIB.BASEBOARD_FAB2(SCH_1):PAGE70
  AU18 TP_CPU1_TEST_7 @BASEBOARD_FAB2_LIB.BASEBOARD_FAB2(SCH_1):TP_CPU1_TEST_7    I10 @BASEBOARD_FAB2_LIB.BASEBOARD_FAB2(SCH_1):PAGE70
  AW16 TP_CPU1_TEST_8 @BASEBOARD_FAB2_LIB.BASEBOARD_FAB2(SCH_1):TP_CPU1_TEST_8    I10 @BASEBOARD_FAB2_LIB.BASEBOARD_FAB2(SCH_1):PAGE70
  AW20 TP_CPU1_TEST_9 @BASEBOARD_FAB2_LIB.BASEBOARD_FAB2(SCH_1):TP_CPU1_TEST_9    I10 @BASEBOARD_FAB2_LIB.BASEBOARD_FAB2(SCH_1):PAGE70
  AF43 PVCCIN_CPU1 @BASEBOARD_FAB2_LIB.BASEBOARD_FAB2(SCH_1):PVCCIN_CPU1    I50 @BASEBOARD_FAB2_LIB.BASEBOARD_FAB2(SCH_1):PAGE71
  AG38 PVCCIN_CPU1 @BASEBOARD_FAB2_LIB.BASEBOARD_FAB2(SCH_1):PVCCIN_CPU1    I50 @BASEBOARD_FAB2_LIB.BASEBOARD_FAB2(SCH_1):PAGE71
  AG40 PVCCIN_CPU1 @BASEBOARD_FAB2_LIB.BASEBOARD_FAB2(SCH_1):PVCCIN_CPU1    I50 @BASEBOARD_FAB2_LIB.BASEBOARD_FAB2(SCH_1):PAGE71
  AG42 PVCCIN_CPU1 @BASEBOARD_FAB2_LIB.BASEBOARD_FAB2(SCH_1):PVCCIN_CPU1    I50 @BASEBOARD_FAB2_LIB.BASEBOARD_FAB2(SCH_1):PAGE71
  AH37 PVCCIN_CPU1 @BASEBOARD_FAB2_LIB.BASEBOARD_FAB2(SCH_1):PVCCIN_CPU1    I50 @BASEBOARD_FAB2_LIB.BASEBOARD_FAB2(SCH_1):PAGE71
  AH39 PVCCIN_CPU1 @BASEBOARD_FAB2_LIB.BASEBOARD_FAB2(SCH_1):PVCCIN_CPU1    I50 @BASEBOARD_FAB2_LIB.BASEBOARD_FAB2(SCH_1):PAGE71
  AH41 PVCCIN_CPU1 @BASEBOARD_FAB2_LIB.BASEBOARD_FAB2(SCH_1):PVCCIN_CPU1    I50 @BASEBOARD_FAB2_LIB.BASEBOARD_FAB2(SCH_1):PAGE71
  AJ36 PVCCIN_CPU1 @BASEBOARD_FAB2_LIB.BASEBOARD_FAB2(SCH_1):PVCCIN_CPU1    I50 @BASEBOARD_FAB2_LIB.BASEBOARD_FAB2(SCH_1):PAGE71
  AK35 PVCCIN_CPU1 @BASEBOARD_FAB2_LIB.BASEBOARD_FAB2(SCH_1):PVCCIN_CPU1    I50 @BASEBOARD_FAB2_LIB.BASEBOARD_FAB2(SCH_1):PAGE71
  AK45 PVCCIN_CPU1 @BASEBOARD_FAB2_LIB.BASEBOARD_FAB2(SCH_1):PVCCIN_CPU1    I50 @BASEBOARD_FAB2_LIB.BASEBOARD_FAB2(SCH_1):PAGE71
  AK47 PVCCIN_CPU1 @BASEBOARD_FAB2_LIB.BASEBOARD_FAB2(SCH_1):PVCCIN_CPU1    I50 @BASEBOARD_FAB2_LIB.BASEBOARD_FAB2(SCH_1):PAGE71
  AK49 PVCCIN_CPU1 @BASEBOARD_FAB2_LIB.BASEBOARD_FAB2(SCH_1):PVCCIN_CPU1    I50 @BASEBOARD_FAB2_LIB.BASEBOARD_FAB2(SCH_1):PAGE71
  AK51 PVCCIN_CPU1 @BASEBOARD_FAB2_LIB.BASEBOARD_FAB2(SCH_1):PVCCIN_CPU1    I50 @BASEBOARD_FAB2_LIB.BASEBOARD_FAB2(SCH_1):PAGE71
  AK53 PVCCIN_CPU1 @BASEBOARD_FAB2_LIB.BASEBOARD_FAB2(SCH_1):PVCCIN_CPU1    I50 @BASEBOARD_FAB2_LIB.BASEBOARD_FAB2(SCH_1):PAGE71
  AL34 PVCCIN_CPU1 @BASEBOARD_FAB2_LIB.BASEBOARD_FAB2(SCH_1):PVCCIN_CPU1    I50 @BASEBOARD_FAB2_LIB.BASEBOARD_FAB2(SCH_1):PAGE71
  AL46 PVCCIN_CPU1 @BASEBOARD_FAB2_LIB.BASEBOARD_FAB2(SCH_1):PVCCIN_CPU1    I50 @BASEBOARD_FAB2_LIB.BASEBOARD_FAB2(SCH_1):PAGE71
  AL48 PVCCIN_CPU1 @BASEBOARD_FAB2_LIB.BASEBOARD_FAB2(SCH_1):PVCCIN_CPU1    I50 @BASEBOARD_FAB2_LIB.BASEBOARD_FAB2(SCH_1):PAGE71
  AL50 PVCCIN_CPU1 @BASEBOARD_FAB2_LIB.BASEBOARD_FAB2(SCH_1):PVCCIN_CPU1    I50 @BASEBOARD_FAB2_LIB.BASEBOARD_FAB2(SCH_1):PAGE71
  AL52 PVCCIN_CPU1 @BASEBOARD_FAB2_LIB.BASEBOARD_FAB2(SCH_1):PVCCIN_CPU1    I50 @BASEBOARD_FAB2_LIB.BASEBOARD_FAB2(SCH_1):PAGE71
  AL54 PVCCIN_CPU1 @BASEBOARD_FAB2_LIB.BASEBOARD_FAB2(SCH_1):PVCCIN_CPU1    I50 @BASEBOARD_FAB2_LIB.BASEBOARD_FAB2(SCH_1):PAGE71
  AM33 PVCCIN_CPU1 @BASEBOARD_FAB2_LIB.BASEBOARD_FAB2(SCH_1):PVCCIN_CPU1    I50 @BASEBOARD_FAB2_LIB.BASEBOARD_FAB2(SCH_1):PAGE71
  AM53 PVCCIN_CPU1 @BASEBOARD_FAB2_LIB.BASEBOARD_FAB2(SCH_1):PVCCIN_CPU1    I50 @BASEBOARD_FAB2_LIB.BASEBOARD_FAB2(SCH_1):PAGE71
  AM55 PVCCIN_CPU1 @BASEBOARD_FAB2_LIB.BASEBOARD_FAB2(SCH_1):PVCCIN_CPU1    I50 @BASEBOARD_FAB2_LIB.BASEBOARD_FAB2(SCH_1):PAGE71
  AN32 PVCCIN_CPU1 @BASEBOARD_FAB2_LIB.BASEBOARD_FAB2(SCH_1):PVCCIN_CPU1    I50 @BASEBOARD_FAB2_LIB.BASEBOARD_FAB2(SCH_1):PAGE71
  AN54 PVCCIN_CPU1 @BASEBOARD_FAB2_LIB.BASEBOARD_FAB2(SCH_1):PVCCIN_CPU1    I50 @BASEBOARD_FAB2_LIB.BASEBOARD_FAB2(SCH_1):PAGE71
  AN56 PVCCIN_CPU1 @BASEBOARD_FAB2_LIB.BASEBOARD_FAB2(SCH_1):PVCCIN_CPU1    I50 @BASEBOARD_FAB2_LIB.BASEBOARD_FAB2(SCH_1):PAGE71
  AP55 PVCCIN_CPU1 @BASEBOARD_FAB2_LIB.BASEBOARD_FAB2(SCH_1):PVCCIN_CPU1    I50 @BASEBOARD_FAB2_LIB.BASEBOARD_FAB2(SCH_1):PAGE71
  AP57 PVCCIN_CPU1 @BASEBOARD_FAB2_LIB.BASEBOARD_FAB2(SCH_1):PVCCIN_CPU1    I50 @BASEBOARD_FAB2_LIB.BASEBOARD_FAB2(SCH_1):PAGE71
  AR56 PVCCIN_CPU1 @BASEBOARD_FAB2_LIB.BASEBOARD_FAB2(SCH_1):PVCCIN_CPU1    I50 @BASEBOARD_FAB2_LIB.BASEBOARD_FAB2(SCH_1):PAGE71
  AR58 PVCCIN_CPU1 @BASEBOARD_FAB2_LIB.BASEBOARD_FAB2(SCH_1):PVCCIN_CPU1    I50 @BASEBOARD_FAB2_LIB.BASEBOARD_FAB2(SCH_1):PAGE71
  AT57 PVCCIN_CPU1 @BASEBOARD_FAB2_LIB.BASEBOARD_FAB2(SCH_1):PVCCIN_CPU1    I50 @BASEBOARD_FAB2_LIB.BASEBOARD_FAB2(SCH_1):PAGE71
  AT59 PVCCIN_CPU1 @BASEBOARD_FAB2_LIB.BASEBOARD_FAB2(SCH_1):PVCCIN_CPU1    I50 @BASEBOARD_FAB2_LIB.BASEBOARD_FAB2(SCH_1):PAGE71
  AU58 PVCCIN_CPU1 @BASEBOARD_FAB2_LIB.BASEBOARD_FAB2(SCH_1):PVCCIN_CPU1    I50 @BASEBOARD_FAB2_LIB.BASEBOARD_FAB2(SCH_1):PAGE71
  AU60 PVCCIN_CPU1 @BASEBOARD_FAB2_LIB.BASEBOARD_FAB2(SCH_1):PVCCIN_CPU1    I50 @BASEBOARD_FAB2_LIB.BASEBOARD_FAB2(SCH_1):PAGE71
  AV59 PVCCIN_CPU1 @BASEBOARD_FAB2_LIB.BASEBOARD_FAB2(SCH_1):PVCCIN_CPU1    I50 @BASEBOARD_FAB2_LIB.BASEBOARD_FAB2(SCH_1):PAGE71
  AV61 PVCCIN_CPU1 @BASEBOARD_FAB2_LIB.BASEBOARD_FAB2(SCH_1):PVCCIN_CPU1    I50 @BASEBOARD_FAB2_LIB.BASEBOARD_FAB2(SCH_1):PAGE71
  AW60 PVCCIN_CPU1 @BASEBOARD_FAB2_LIB.BASEBOARD_FAB2(SCH_1):PVCCIN_CPU1    I50 @BASEBOARD_FAB2_LIB.BASEBOARD_FAB2(SCH_1):PAGE71
  AY61 PVCCIN_CPU1 @BASEBOARD_FAB2_LIB.BASEBOARD_FAB2(SCH_1):PVCCIN_CPU1    I50 @BASEBOARD_FAB2_LIB.BASEBOARD_FAB2(SCH_1):PAGE71
  BA60 PVCCIN_CPU1 @BASEBOARD_FAB2_LIB.BASEBOARD_FAB2(SCH_1):PVCCIN_CPU1    I50 @BASEBOARD_FAB2_LIB.BASEBOARD_FAB2(SCH_1):PAGE71
  BB61 PVCCIN_CPU1 @BASEBOARD_FAB2_LIB.BASEBOARD_FAB2(SCH_1):PVCCIN_CPU1    I50 @BASEBOARD_FAB2_LIB.BASEBOARD_FAB2(SCH_1):PAGE71
  BB85 PVCCIN_CPU1 @BASEBOARD_FAB2_LIB.BASEBOARD_FAB2(SCH_1):PVCCIN_CPU1    I50 @BASEBOARD_FAB2_LIB.BASEBOARD_FAB2(SCH_1):PAGE71
  BC60 PVCCIN_CPU1 @BASEBOARD_FAB2_LIB.BASEBOARD_FAB2(SCH_1):PVCCIN_CPU1    I50 @BASEBOARD_FAB2_LIB.BASEBOARD_FAB2(SCH_1):PAGE71
  BC62 PVCCIN_CPU1 @BASEBOARD_FAB2_LIB.BASEBOARD_FAB2(SCH_1):PVCCIN_CPU1    I50 @BASEBOARD_FAB2_LIB.BASEBOARD_FAB2(SCH_1):PAGE71
  BC84 PVCCIN_CPU1 @BASEBOARD_FAB2_LIB.BASEBOARD_FAB2(SCH_1):PVCCIN_CPU1    I50 @BASEBOARD_FAB2_LIB.BASEBOARD_FAB2(SCH_1):PAGE71
  BD61 PVCCIN_CPU1 @BASEBOARD_FAB2_LIB.BASEBOARD_FAB2(SCH_1):PVCCIN_CPU1    I50 @BASEBOARD_FAB2_LIB.BASEBOARD_FAB2(SCH_1):PAGE71
  BD73 PVCCIN_CPU1 @BASEBOARD_FAB2_LIB.BASEBOARD_FAB2(SCH_1):PVCCIN_CPU1    I50 @BASEBOARD_FAB2_LIB.BASEBOARD_FAB2(SCH_1):PAGE71
  BD75 PVCCIN_CPU1 @BASEBOARD_FAB2_LIB.BASEBOARD_FAB2(SCH_1):PVCCIN_CPU1    I50 @BASEBOARD_FAB2_LIB.BASEBOARD_FAB2(SCH_1):PAGE71
  BD77 PVCCIN_CPU1 @BASEBOARD_FAB2_LIB.BASEBOARD_FAB2(SCH_1):PVCCIN_CPU1    I50 @BASEBOARD_FAB2_LIB.BASEBOARD_FAB2(SCH_1):PAGE71
  BD79 PVCCIN_CPU1 @BASEBOARD_FAB2_LIB.BASEBOARD_FAB2(SCH_1):PVCCIN_CPU1    I50 @BASEBOARD_FAB2_LIB.BASEBOARD_FAB2(SCH_1):PAGE71
  BD81 PVCCIN_CPU1 @BASEBOARD_FAB2_LIB.BASEBOARD_FAB2(SCH_1):PVCCIN_CPU1    I50 @BASEBOARD_FAB2_LIB.BASEBOARD_FAB2(SCH_1):PAGE71
  BD83 PVCCIN_CPU1 @BASEBOARD_FAB2_LIB.BASEBOARD_FAB2(SCH_1):PVCCIN_CPU1    I50 @BASEBOARD_FAB2_LIB.BASEBOARD_FAB2(SCH_1):PAGE71
  BD85 PVCCIN_CPU1 @BASEBOARD_FAB2_LIB.BASEBOARD_FAB2(SCH_1):PVCCIN_CPU1    I50 @BASEBOARD_FAB2_LIB.BASEBOARD_FAB2(SCH_1):PAGE71
  BE60 PVCCIN_CPU1 @BASEBOARD_FAB2_LIB.BASEBOARD_FAB2(SCH_1):PVCCIN_CPU1    I50 @BASEBOARD_FAB2_LIB.BASEBOARD_FAB2(SCH_1):PAGE71
  BE62 PVCCIN_CPU1 @BASEBOARD_FAB2_LIB.BASEBOARD_FAB2(SCH_1):PVCCIN_CPU1    I50 @BASEBOARD_FAB2_LIB.BASEBOARD_FAB2(SCH_1):PAGE71
  BE72 PVCCIN_CPU1 @BASEBOARD_FAB2_LIB.BASEBOARD_FAB2(SCH_1):PVCCIN_CPU1    I50 @BASEBOARD_FAB2_LIB.BASEBOARD_FAB2(SCH_1):PAGE71
  BE74 PVCCIN_CPU1 @BASEBOARD_FAB2_LIB.BASEBOARD_FAB2(SCH_1):PVCCIN_CPU1    I50 @BASEBOARD_FAB2_LIB.BASEBOARD_FAB2(SCH_1):PAGE71
  BE76 PVCCIN_CPU1 @BASEBOARD_FAB2_LIB.BASEBOARD_FAB2(SCH_1):PVCCIN_CPU1    I50 @BASEBOARD_FAB2_LIB.BASEBOARD_FAB2(SCH_1):PAGE71
  BE78 PVCCIN_CPU1 @BASEBOARD_FAB2_LIB.BASEBOARD_FAB2(SCH_1):PVCCIN_CPU1    I50 @BASEBOARD_FAB2_LIB.BASEBOARD_FAB2(SCH_1):PAGE71
  BE80 PVCCIN_CPU1 @BASEBOARD_FAB2_LIB.BASEBOARD_FAB2(SCH_1):PVCCIN_CPU1    I50 @BASEBOARD_FAB2_LIB.BASEBOARD_FAB2(SCH_1):PAGE71
  BE82 PVCCIN_CPU1 @BASEBOARD_FAB2_LIB.BASEBOARD_FAB2(SCH_1):PVCCIN_CPU1    I50 @BASEBOARD_FAB2_LIB.BASEBOARD_FAB2(SCH_1):PAGE71
  BE84 PVCCIN_CPU1 @BASEBOARD_FAB2_LIB.BASEBOARD_FAB2(SCH_1):PVCCIN_CPU1    I50 @BASEBOARD_FAB2_LIB.BASEBOARD_FAB2(SCH_1):PAGE71
  BF61 PVCCIN_CPU1 @BASEBOARD_FAB2_LIB.BASEBOARD_FAB2(SCH_1):PVCCIN_CPU1    I50 @BASEBOARD_FAB2_LIB.BASEBOARD_FAB2(SCH_1):PAGE71
  BF73 PVCCIN_CPU1 @BASEBOARD_FAB2_LIB.BASEBOARD_FAB2(SCH_1):PVCCIN_CPU1    I50 @BASEBOARD_FAB2_LIB.BASEBOARD_FAB2(SCH_1):PAGE71
  BF75 PVCCIN_CPU1 @BASEBOARD_FAB2_LIB.BASEBOARD_FAB2(SCH_1):PVCCIN_CPU1    I50 @BASEBOARD_FAB2_LIB.BASEBOARD_FAB2(SCH_1):PAGE71
  BF77 PVCCIN_CPU1 @BASEBOARD_FAB2_LIB.BASEBOARD_FAB2(SCH_1):PVCCIN_CPU1    I50 @BASEBOARD_FAB2_LIB.BASEBOARD_FAB2(SCH_1):PAGE71
  BF79 PVCCIN_CPU1 @BASEBOARD_FAB2_LIB.BASEBOARD_FAB2(SCH_1):PVCCIN_CPU1    I50 @BASEBOARD_FAB2_LIB.BASEBOARD_FAB2(SCH_1):PAGE71
  BF81 PVCCIN_CPU1 @BASEBOARD_FAB2_LIB.BASEBOARD_FAB2(SCH_1):PVCCIN_CPU1    I50 @BASEBOARD_FAB2_LIB.BASEBOARD_FAB2(SCH_1):PAGE71
  BF83 PVCCIN_CPU1 @BASEBOARD_FAB2_LIB.BASEBOARD_FAB2(SCH_1):PVCCIN_CPU1    I50 @BASEBOARD_FAB2_LIB.BASEBOARD_FAB2(SCH_1):PAGE71
  BF85 PVCCIN_CPU1 @BASEBOARD_FAB2_LIB.BASEBOARD_FAB2(SCH_1):PVCCIN_CPU1    I50 @BASEBOARD_FAB2_LIB.BASEBOARD_FAB2(SCH_1):PAGE71
  BG60 PVCCIN_CPU1 @BASEBOARD_FAB2_LIB.BASEBOARD_FAB2(SCH_1):PVCCIN_CPU1    I50 @BASEBOARD_FAB2_LIB.BASEBOARD_FAB2(SCH_1):PAGE71
  BG62 PVCCIN_CPU1 @BASEBOARD_FAB2_LIB.BASEBOARD_FAB2(SCH_1):PVCCIN_CPU1    I50 @BASEBOARD_FAB2_LIB.BASEBOARD_FAB2(SCH_1):PAGE71
  BG64 PVCCIN_CPU1 @BASEBOARD_FAB2_LIB.BASEBOARD_FAB2(SCH_1):PVCCIN_CPU1    I50 @BASEBOARD_FAB2_LIB.BASEBOARD_FAB2(SCH_1):PAGE71
  BG66 PVCCIN_CPU1 @BASEBOARD_FAB2_LIB.BASEBOARD_FAB2(SCH_1):PVCCIN_CPU1    I50 @BASEBOARD_FAB2_LIB.BASEBOARD_FAB2(SCH_1):PAGE71
  BG68 PVCCIN_CPU1 @BASEBOARD_FAB2_LIB.BASEBOARD_FAB2(SCH_1):PVCCIN_CPU1    I50 @BASEBOARD_FAB2_LIB.BASEBOARD_FAB2(SCH_1):PAGE71
  BG70 PVCCIN_CPU1 @BASEBOARD_FAB2_LIB.BASEBOARD_FAB2(SCH_1):PVCCIN_CPU1    I50 @BASEBOARD_FAB2_LIB.BASEBOARD_FAB2(SCH_1):PAGE71
  BG84 PVCCIN_CPU1 @BASEBOARD_FAB2_LIB.BASEBOARD_FAB2(SCH_1):PVCCIN_CPU1    I50 @BASEBOARD_FAB2_LIB.BASEBOARD_FAB2(SCH_1):PAGE71
  BH61 PVCCIN_CPU1 @BASEBOARD_FAB2_LIB.BASEBOARD_FAB2(SCH_1):PVCCIN_CPU1    I50 @BASEBOARD_FAB2_LIB.BASEBOARD_FAB2(SCH_1):PAGE71
  BH63 PVCCIN_CPU1 @BASEBOARD_FAB2_LIB.BASEBOARD_FAB2(SCH_1):PVCCIN_CPU1    I50 @BASEBOARD_FAB2_LIB.BASEBOARD_FAB2(SCH_1):PAGE71
  BH65 PVCCIN_CPU1 @BASEBOARD_FAB2_LIB.BASEBOARD_FAB2(SCH_1):PVCCIN_CPU1    I50 @BASEBOARD_FAB2_LIB.BASEBOARD_FAB2(SCH_1):PAGE71
  BH67 PVCCIN_CPU1 @BASEBOARD_FAB2_LIB.BASEBOARD_FAB2(SCH_1):PVCCIN_CPU1    I50 @BASEBOARD_FAB2_LIB.BASEBOARD_FAB2(SCH_1):PAGE71
  BH69 PVCCIN_CPU1 @BASEBOARD_FAB2_LIB.BASEBOARD_FAB2(SCH_1):PVCCIN_CPU1    I50 @BASEBOARD_FAB2_LIB.BASEBOARD_FAB2(SCH_1):PAGE71
  BH71 PVCCIN_CPU1 @BASEBOARD_FAB2_LIB.BASEBOARD_FAB2(SCH_1):PVCCIN_CPU1    I50 @BASEBOARD_FAB2_LIB.BASEBOARD_FAB2(SCH_1):PAGE71
  BH73 PVCCIN_CPU1 @BASEBOARD_FAB2_LIB.BASEBOARD_FAB2(SCH_1):PVCCIN_CPU1    I50 @BASEBOARD_FAB2_LIB.BASEBOARD_FAB2(SCH_1):PAGE71
  BH75 PVCCIN_CPU1 @BASEBOARD_FAB2_LIB.BASEBOARD_FAB2(SCH_1):PVCCIN_CPU1    I50 @BASEBOARD_FAB2_LIB.BASEBOARD_FAB2(SCH_1):PAGE71
  BH77 PVCCIN_CPU1 @BASEBOARD_FAB2_LIB.BASEBOARD_FAB2(SCH_1):PVCCIN_CPU1    I50 @BASEBOARD_FAB2_LIB.BASEBOARD_FAB2(SCH_1):PAGE71
  BH79 PVCCIN_CPU1 @BASEBOARD_FAB2_LIB.BASEBOARD_FAB2(SCH_1):PVCCIN_CPU1    I50 @BASEBOARD_FAB2_LIB.BASEBOARD_FAB2(SCH_1):PAGE71
  BH81 PVCCIN_CPU1 @BASEBOARD_FAB2_LIB.BASEBOARD_FAB2(SCH_1):PVCCIN_CPU1    I50 @BASEBOARD_FAB2_LIB.BASEBOARD_FAB2(SCH_1):PAGE71
  BH83 PVCCIN_CPU1 @BASEBOARD_FAB2_LIB.BASEBOARD_FAB2(SCH_1):PVCCIN_CPU1    I50 @BASEBOARD_FAB2_LIB.BASEBOARD_FAB2(SCH_1):PAGE71
  BJ60 PVCCIN_CPU1 @BASEBOARD_FAB2_LIB.BASEBOARD_FAB2(SCH_1):PVCCIN_CPU1    I50 @BASEBOARD_FAB2_LIB.BASEBOARD_FAB2(SCH_1):PAGE71
  BJ62 PVCCIN_CPU1 @BASEBOARD_FAB2_LIB.BASEBOARD_FAB2(SCH_1):PVCCIN_CPU1    I50 @BASEBOARD_FAB2_LIB.BASEBOARD_FAB2(SCH_1):PAGE71
  BJ64 PVCCIN_CPU1 @BASEBOARD_FAB2_LIB.BASEBOARD_FAB2(SCH_1):PVCCIN_CPU1    I50 @BASEBOARD_FAB2_LIB.BASEBOARD_FAB2(SCH_1):PAGE71
  BJ66 PVCCIN_CPU1 @BASEBOARD_FAB2_LIB.BASEBOARD_FAB2(SCH_1):PVCCIN_CPU1    I50 @BASEBOARD_FAB2_LIB.BASEBOARD_FAB2(SCH_1):PAGE71
  BJ68 PVCCIN_CPU1 @BASEBOARD_FAB2_LIB.BASEBOARD_FAB2(SCH_1):PVCCIN_CPU1    I50 @BASEBOARD_FAB2_LIB.BASEBOARD_FAB2(SCH_1):PAGE71
  BJ70 PVCCIN_CPU1 @BASEBOARD_FAB2_LIB.BASEBOARD_FAB2(SCH_1):PVCCIN_CPU1    I50 @BASEBOARD_FAB2_LIB.BASEBOARD_FAB2(SCH_1):PAGE71
  BJ72 PVCCIN_CPU1 @BASEBOARD_FAB2_LIB.BASEBOARD_FAB2(SCH_1):PVCCIN_CPU1    I50 @BASEBOARD_FAB2_LIB.BASEBOARD_FAB2(SCH_1):PAGE71
  BJ74 PVCCIN_CPU1 @BASEBOARD_FAB2_LIB.BASEBOARD_FAB2(SCH_1):PVCCIN_CPU1    I50 @BASEBOARD_FAB2_LIB.BASEBOARD_FAB2(SCH_1):PAGE71
  BJ76 PVCCIN_CPU1 @BASEBOARD_FAB2_LIB.BASEBOARD_FAB2(SCH_1):PVCCIN_CPU1    I50 @BASEBOARD_FAB2_LIB.BASEBOARD_FAB2(SCH_1):PAGE71
  BJ78 PVCCIN_CPU1 @BASEBOARD_FAB2_LIB.BASEBOARD_FAB2(SCH_1):PVCCIN_CPU1    I50 @BASEBOARD_FAB2_LIB.BASEBOARD_FAB2(SCH_1):PAGE71
  BJ80 PVCCIN_CPU1 @BASEBOARD_FAB2_LIB.BASEBOARD_FAB2(SCH_1):PVCCIN_CPU1    I50 @BASEBOARD_FAB2_LIB.BASEBOARD_FAB2(SCH_1):PAGE71
  BJ82 PVCCIN_CPU1 @BASEBOARD_FAB2_LIB.BASEBOARD_FAB2(SCH_1):PVCCIN_CPU1    I50 @BASEBOARD_FAB2_LIB.BASEBOARD_FAB2(SCH_1):PAGE71
  BJ84 PVCCIN_CPU1 @BASEBOARD_FAB2_LIB.BASEBOARD_FAB2(SCH_1):PVCCIN_CPU1    I50 @BASEBOARD_FAB2_LIB.BASEBOARD_FAB2(SCH_1):PAGE71
  BK61 PVCCIN_CPU1 @BASEBOARD_FAB2_LIB.BASEBOARD_FAB2(SCH_1):PVCCIN_CPU1    I50 @BASEBOARD_FAB2_LIB.BASEBOARD_FAB2(SCH_1):PAGE71
  BK63 PVCCIN_CPU1 @BASEBOARD_FAB2_LIB.BASEBOARD_FAB2(SCH_1):PVCCIN_CPU1    I50 @BASEBOARD_FAB2_LIB.BASEBOARD_FAB2(SCH_1):PAGE71
  BK65 PVCCIN_CPU1 @BASEBOARD_FAB2_LIB.BASEBOARD_FAB2(SCH_1):PVCCIN_CPU1    I50 @BASEBOARD_FAB2_LIB.BASEBOARD_FAB2(SCH_1):PAGE71
  BK67 PVCCIN_CPU1 @BASEBOARD_FAB2_LIB.BASEBOARD_FAB2(SCH_1):PVCCIN_CPU1    I50 @BASEBOARD_FAB2_LIB.BASEBOARD_FAB2(SCH_1):PAGE71
  BK69 PVCCIN_CPU1 @BASEBOARD_FAB2_LIB.BASEBOARD_FAB2(SCH_1):PVCCIN_CPU1    I50 @BASEBOARD_FAB2_LIB.BASEBOARD_FAB2(SCH_1):PAGE71
  BK71 PVCCIN_CPU1 @BASEBOARD_FAB2_LIB.BASEBOARD_FAB2(SCH_1):PVCCIN_CPU1    I50 @BASEBOARD_FAB2_LIB.BASEBOARD_FAB2(SCH_1):PAGE71
  BK73 PVCCIN_CPU1 @BASEBOARD_FAB2_LIB.BASEBOARD_FAB2(SCH_1):PVCCIN_CPU1    I50 @BASEBOARD_FAB2_LIB.BASEBOARD_FAB2(SCH_1):PAGE71
  BK75 PVCCIN_CPU1 @BASEBOARD_FAB2_LIB.BASEBOARD_FAB2(SCH_1):PVCCIN_CPU1    I50 @BASEBOARD_FAB2_LIB.BASEBOARD_FAB2(SCH_1):PAGE71
  BK77 PVCCIN_CPU1 @BASEBOARD_FAB2_LIB.BASEBOARD_FAB2(SCH_1):PVCCIN_CPU1    I50 @BASEBOARD_FAB2_LIB.BASEBOARD_FAB2(SCH_1):PAGE71
  BK79 PVCCIN_CPU1 @BASEBOARD_FAB2_LIB.BASEBOARD_FAB2(SCH_1):PVCCIN_CPU1    I50 @BASEBOARD_FAB2_LIB.BASEBOARD_FAB2(SCH_1):PAGE71
  BK81 PVCCIN_CPU1 @BASEBOARD_FAB2_LIB.BASEBOARD_FAB2(SCH_1):PVCCIN_CPU1    I50 @BASEBOARD_FAB2_LIB.BASEBOARD_FAB2(SCH_1):PAGE71
  BK83 PVCCIN_CPU1 @BASEBOARD_FAB2_LIB.BASEBOARD_FAB2(SCH_1):PVCCIN_CPU1    I50 @BASEBOARD_FAB2_LIB.BASEBOARD_FAB2(SCH_1):PAGE71
  BL60 PVCCIN_CPU1 @BASEBOARD_FAB2_LIB.BASEBOARD_FAB2(SCH_1):PVCCIN_CPU1    I50 @BASEBOARD_FAB2_LIB.BASEBOARD_FAB2(SCH_1):PAGE71
  BL62 PVCCIN_CPU1 @BASEBOARD_FAB2_LIB.BASEBOARD_FAB2(SCH_1):PVCCIN_CPU1    I50 @BASEBOARD_FAB2_LIB.BASEBOARD_FAB2(SCH_1):PAGE71
  BL84 PVCCIN_CPU1 @BASEBOARD_FAB2_LIB.BASEBOARD_FAB2(SCH_1):PVCCIN_CPU1    I50 @BASEBOARD_FAB2_LIB.BASEBOARD_FAB2(SCH_1):PAGE71
  BM61 PVCCIN_CPU1 @BASEBOARD_FAB2_LIB.BASEBOARD_FAB2(SCH_1):PVCCIN_CPU1    I50 @BASEBOARD_FAB2_LIB.BASEBOARD_FAB2(SCH_1):PAGE71
  BM63 PVCCIN_CPU1 @BASEBOARD_FAB2_LIB.BASEBOARD_FAB2(SCH_1):PVCCIN_CPU1    I50 @BASEBOARD_FAB2_LIB.BASEBOARD_FAB2(SCH_1):PAGE71
  BM65 PVCCIN_CPU1 @BASEBOARD_FAB2_LIB.BASEBOARD_FAB2(SCH_1):PVCCIN_CPU1    I50 @BASEBOARD_FAB2_LIB.BASEBOARD_FAB2(SCH_1):PAGE71
  BM67 PVCCIN_CPU1 @BASEBOARD_FAB2_LIB.BASEBOARD_FAB2(SCH_1):PVCCIN_CPU1    I50 @BASEBOARD_FAB2_LIB.BASEBOARD_FAB2(SCH_1):PAGE71
  BM69 PVCCIN_CPU1 @BASEBOARD_FAB2_LIB.BASEBOARD_FAB2(SCH_1):PVCCIN_CPU1    I50 @BASEBOARD_FAB2_LIB.BASEBOARD_FAB2(SCH_1):PAGE71
  BM71 PVCCIN_CPU1 @BASEBOARD_FAB2_LIB.BASEBOARD_FAB2(SCH_1):PVCCIN_CPU1    I50 @BASEBOARD_FAB2_LIB.BASEBOARD_FAB2(SCH_1):PAGE71
  BM73 PVCCIN_CPU1 @BASEBOARD_FAB2_LIB.BASEBOARD_FAB2(SCH_1):PVCCIN_CPU1    I50 @BASEBOARD_FAB2_LIB.BASEBOARD_FAB2(SCH_1):PAGE71
  BM75 PVCCIN_CPU1 @BASEBOARD_FAB2_LIB.BASEBOARD_FAB2(SCH_1):PVCCIN_CPU1    I50 @BASEBOARD_FAB2_LIB.BASEBOARD_FAB2(SCH_1):PAGE71
  BM77 PVCCIN_CPU1 @BASEBOARD_FAB2_LIB.BASEBOARD_FAB2(SCH_1):PVCCIN_CPU1    I50 @BASEBOARD_FAB2_LIB.BASEBOARD_FAB2(SCH_1):PAGE71
  BM79 PVCCIN_CPU1 @BASEBOARD_FAB2_LIB.BASEBOARD_FAB2(SCH_1):PVCCIN_CPU1    I50 @BASEBOARD_FAB2_LIB.BASEBOARD_FAB2(SCH_1):PAGE71
  BM81 PVCCIN_CPU1 @BASEBOARD_FAB2_LIB.BASEBOARD_FAB2(SCH_1):PVCCIN_CPU1    I50 @BASEBOARD_FAB2_LIB.BASEBOARD_FAB2(SCH_1):PAGE71
  BM83 PVCCIN_CPU1 @BASEBOARD_FAB2_LIB.BASEBOARD_FAB2(SCH_1):PVCCIN_CPU1    I50 @BASEBOARD_FAB2_LIB.BASEBOARD_FAB2(SCH_1):PAGE71
  BN60 PVCCIN_CPU1 @BASEBOARD_FAB2_LIB.BASEBOARD_FAB2(SCH_1):PVCCIN_CPU1    I50 @BASEBOARD_FAB2_LIB.BASEBOARD_FAB2(SCH_1):PAGE71
  BN62 PVCCIN_CPU1 @BASEBOARD_FAB2_LIB.BASEBOARD_FAB2(SCH_1):PVCCIN_CPU1    I50 @BASEBOARD_FAB2_LIB.BASEBOARD_FAB2(SCH_1):PAGE71
  BN64 PVCCIN_CPU1 @BASEBOARD_FAB2_LIB.BASEBOARD_FAB2(SCH_1):PVCCIN_CPU1    I50 @BASEBOARD_FAB2_LIB.BASEBOARD_FAB2(SCH_1):PAGE71
  BN66 PVCCIN_CPU1 @BASEBOARD_FAB2_LIB.BASEBOARD_FAB2(SCH_1):PVCCIN_CPU1    I50 @BASEBOARD_FAB2_LIB.BASEBOARD_FAB2(SCH_1):PAGE71
  BN68 PVCCIN_CPU1 @BASEBOARD_FAB2_LIB.BASEBOARD_FAB2(SCH_1):PVCCIN_CPU1    I50 @BASEBOARD_FAB2_LIB.BASEBOARD_FAB2(SCH_1):PAGE71
  BN70 PVCCIN_CPU1 @BASEBOARD_FAB2_LIB.BASEBOARD_FAB2(SCH_1):PVCCIN_CPU1    I50 @BASEBOARD_FAB2_LIB.BASEBOARD_FAB2(SCH_1):PAGE71
  BN72 PVCCIN_CPU1 @BASEBOARD_FAB2_LIB.BASEBOARD_FAB2(SCH_1):PVCCIN_CPU1    I50 @BASEBOARD_FAB2_LIB.BASEBOARD_FAB2(SCH_1):PAGE71
  BN74 PVCCIN_CPU1 @BASEBOARD_FAB2_LIB.BASEBOARD_FAB2(SCH_1):PVCCIN_CPU1    I50 @BASEBOARD_FAB2_LIB.BASEBOARD_FAB2(SCH_1):PAGE71
  BN76 PVCCIN_CPU1 @BASEBOARD_FAB2_LIB.BASEBOARD_FAB2(SCH_1):PVCCIN_CPU1    I50 @BASEBOARD_FAB2_LIB.BASEBOARD_FAB2(SCH_1):PAGE71
  BN78 PVCCIN_CPU1 @BASEBOARD_FAB2_LIB.BASEBOARD_FAB2(SCH_1):PVCCIN_CPU1    I50 @BASEBOARD_FAB2_LIB.BASEBOARD_FAB2(SCH_1):PAGE71
  BN80 PVCCIN_CPU1 @BASEBOARD_FAB2_LIB.BASEBOARD_FAB2(SCH_1):PVCCIN_CPU1    I51 @BASEBOARD_FAB2_LIB.BASEBOARD_FAB2(SCH_1):PAGE71
  BN82 PVCCIN_CPU1 @BASEBOARD_FAB2_LIB.BASEBOARD_FAB2(SCH_1):PVCCIN_CPU1    I51 @BASEBOARD_FAB2_LIB.BASEBOARD_FAB2(SCH_1):PAGE71
  BN84 PVCCIN_CPU1 @BASEBOARD_FAB2_LIB.BASEBOARD_FAB2(SCH_1):PVCCIN_CPU1    I51 @BASEBOARD_FAB2_LIB.BASEBOARD_FAB2(SCH_1):PAGE71
  BP61 PVCCIN_CPU1 @BASEBOARD_FAB2_LIB.BASEBOARD_FAB2(SCH_1):PVCCIN_CPU1    I51 @BASEBOARD_FAB2_LIB.BASEBOARD_FAB2(SCH_1):PAGE71
  BP63 PVCCIN_CPU1 @BASEBOARD_FAB2_LIB.BASEBOARD_FAB2(SCH_1):PVCCIN_CPU1    I51 @BASEBOARD_FAB2_LIB.BASEBOARD_FAB2(SCH_1):PAGE71
  BP65 PVCCIN_CPU1 @BASEBOARD_FAB2_LIB.BASEBOARD_FAB2(SCH_1):PVCCIN_CPU1    I51 @BASEBOARD_FAB2_LIB.BASEBOARD_FAB2(SCH_1):PAGE71
  BP67 PVCCIN_CPU1 @BASEBOARD_FAB2_LIB.BASEBOARD_FAB2(SCH_1):PVCCIN_CPU1    I51 @BASEBOARD_FAB2_LIB.BASEBOARD_FAB2(SCH_1):PAGE71
  BP69 PVCCIN_CPU1 @BASEBOARD_FAB2_LIB.BASEBOARD_FAB2(SCH_1):PVCCIN_CPU1    I51 @BASEBOARD_FAB2_LIB.BASEBOARD_FAB2(SCH_1):PAGE71
  BP71 PVCCIN_CPU1 @BASEBOARD_FAB2_LIB.BASEBOARD_FAB2(SCH_1):PVCCIN_CPU1    I51 @BASEBOARD_FAB2_LIB.BASEBOARD_FAB2(SCH_1):PAGE71
  BP73 PVCCIN_CPU1 @BASEBOARD_FAB2_LIB.BASEBOARD_FAB2(SCH_1):PVCCIN_CPU1    I51 @BASEBOARD_FAB2_LIB.BASEBOARD_FAB2(SCH_1):PAGE71
  BP75 PVCCIN_CPU1 @BASEBOARD_FAB2_LIB.BASEBOARD_FAB2(SCH_1):PVCCIN_CPU1    I51 @BASEBOARD_FAB2_LIB.BASEBOARD_FAB2(SCH_1):PAGE71
  BP77 PVCCIN_CPU1 @BASEBOARD_FAB2_LIB.BASEBOARD_FAB2(SCH_1):PVCCIN_CPU1    I51 @BASEBOARD_FAB2_LIB.BASEBOARD_FAB2(SCH_1):PAGE71
  BP79 PVCCIN_CPU1 @BASEBOARD_FAB2_LIB.BASEBOARD_FAB2(SCH_1):PVCCIN_CPU1    I51 @BASEBOARD_FAB2_LIB.BASEBOARD_FAB2(SCH_1):PAGE71
  BP81 PVCCIN_CPU1 @BASEBOARD_FAB2_LIB.BASEBOARD_FAB2(SCH_1):PVCCIN_CPU1    I51 @BASEBOARD_FAB2_LIB.BASEBOARD_FAB2(SCH_1):PAGE71
  BP83 PVCCIN_CPU1 @BASEBOARD_FAB2_LIB.BASEBOARD_FAB2(SCH_1):PVCCIN_CPU1    I51 @BASEBOARD_FAB2_LIB.BASEBOARD_FAB2(SCH_1):PAGE71
  BR60 PVCCIN_CPU1 @BASEBOARD_FAB2_LIB.BASEBOARD_FAB2(SCH_1):PVCCIN_CPU1    I51 @BASEBOARD_FAB2_LIB.BASEBOARD_FAB2(SCH_1):PAGE71
  BR62 PVCCIN_CPU1 @BASEBOARD_FAB2_LIB.BASEBOARD_FAB2(SCH_1):PVCCIN_CPU1    I51 @BASEBOARD_FAB2_LIB.BASEBOARD_FAB2(SCH_1):PAGE71
  BR84 PVCCIN_CPU1 @BASEBOARD_FAB2_LIB.BASEBOARD_FAB2(SCH_1):PVCCIN_CPU1    I51 @BASEBOARD_FAB2_LIB.BASEBOARD_FAB2(SCH_1):PAGE71
  BT61 PVCCIN_CPU1 @BASEBOARD_FAB2_LIB.BASEBOARD_FAB2(SCH_1):PVCCIN_CPU1    I51 @BASEBOARD_FAB2_LIB.BASEBOARD_FAB2(SCH_1):PAGE71
  BT63 PVCCIN_CPU1 @BASEBOARD_FAB2_LIB.BASEBOARD_FAB2(SCH_1):PVCCIN_CPU1    I51 @BASEBOARD_FAB2_LIB.BASEBOARD_FAB2(SCH_1):PAGE71
  BT65 PVCCIN_CPU1 @BASEBOARD_FAB2_LIB.BASEBOARD_FAB2(SCH_1):PVCCIN_CPU1    I51 @BASEBOARD_FAB2_LIB.BASEBOARD_FAB2(SCH_1):PAGE71
  BT67 PVCCIN_CPU1 @BASEBOARD_FAB2_LIB.BASEBOARD_FAB2(SCH_1):PVCCIN_CPU1    I51 @BASEBOARD_FAB2_LIB.BASEBOARD_FAB2(SCH_1):PAGE71
  BT69 PVCCIN_CPU1 @BASEBOARD_FAB2_LIB.BASEBOARD_FAB2(SCH_1):PVCCIN_CPU1    I51 @BASEBOARD_FAB2_LIB.BASEBOARD_FAB2(SCH_1):PAGE71
  BT71 PVCCIN_CPU1 @BASEBOARD_FAB2_LIB.BASEBOARD_FAB2(SCH_1):PVCCIN_CPU1    I51 @BASEBOARD_FAB2_LIB.BASEBOARD_FAB2(SCH_1):PAGE71
  BT73 PVCCIN_CPU1 @BASEBOARD_FAB2_LIB.BASEBOARD_FAB2(SCH_1):PVCCIN_CPU1    I51 @BASEBOARD_FAB2_LIB.BASEBOARD_FAB2(SCH_1):PAGE71
  BT75 PVCCIN_CPU1 @BASEBOARD_FAB2_LIB.BASEBOARD_FAB2(SCH_1):PVCCIN_CPU1    I51 @BASEBOARD_FAB2_LIB.BASEBOARD_FAB2(SCH_1):PAGE71
  BT77 PVCCIN_CPU1 @BASEBOARD_FAB2_LIB.BASEBOARD_FAB2(SCH_1):PVCCIN_CPU1    I51 @BASEBOARD_FAB2_LIB.BASEBOARD_FAB2(SCH_1):PAGE71
  BT79 PVCCIN_CPU1 @BASEBOARD_FAB2_LIB.BASEBOARD_FAB2(SCH_1):PVCCIN_CPU1    I51 @BASEBOARD_FAB2_LIB.BASEBOARD_FAB2(SCH_1):PAGE71
  BT81 PVCCIN_CPU1 @BASEBOARD_FAB2_LIB.BASEBOARD_FAB2(SCH_1):PVCCIN_CPU1    I51 @BASEBOARD_FAB2_LIB.BASEBOARD_FAB2(SCH_1):PAGE71
  BT83 PVCCIN_CPU1 @BASEBOARD_FAB2_LIB.BASEBOARD_FAB2(SCH_1):PVCCIN_CPU1    I51 @BASEBOARD_FAB2_LIB.BASEBOARD_FAB2(SCH_1):PAGE71
  BU60 PVCCIN_CPU1 @BASEBOARD_FAB2_LIB.BASEBOARD_FAB2(SCH_1):PVCCIN_CPU1    I51 @BASEBOARD_FAB2_LIB.BASEBOARD_FAB2(SCH_1):PAGE71
  BU62 PVCCIN_CPU1 @BASEBOARD_FAB2_LIB.BASEBOARD_FAB2(SCH_1):PVCCIN_CPU1    I51 @BASEBOARD_FAB2_LIB.BASEBOARD_FAB2(SCH_1):PAGE71
  BU64 PVCCIN_CPU1 @BASEBOARD_FAB2_LIB.BASEBOARD_FAB2(SCH_1):PVCCIN_CPU1    I51 @BASEBOARD_FAB2_LIB.BASEBOARD_FAB2(SCH_1):PAGE71
  BU66 PVCCIN_CPU1 @BASEBOARD_FAB2_LIB.BASEBOARD_FAB2(SCH_1):PVCCIN_CPU1    I51 @BASEBOARD_FAB2_LIB.BASEBOARD_FAB2(SCH_1):PAGE71
  BU68 PVCCIN_CPU1 @BASEBOARD_FAB2_LIB.BASEBOARD_FAB2(SCH_1):PVCCIN_CPU1    I51 @BASEBOARD_FAB2_LIB.BASEBOARD_FAB2(SCH_1):PAGE71
  BU70 PVCCIN_CPU1 @BASEBOARD_FAB2_LIB.BASEBOARD_FAB2(SCH_1):PVCCIN_CPU1    I51 @BASEBOARD_FAB2_LIB.BASEBOARD_FAB2(SCH_1):PAGE71
  BU72 PVCCIN_CPU1 @BASEBOARD_FAB2_LIB.BASEBOARD_FAB2(SCH_1):PVCCIN_CPU1    I51 @BASEBOARD_FAB2_LIB.BASEBOARD_FAB2(SCH_1):PAGE71
  BU74 PVCCIN_CPU1 @BASEBOARD_FAB2_LIB.BASEBOARD_FAB2(SCH_1):PVCCIN_CPU1    I51 @BASEBOARD_FAB2_LIB.BASEBOARD_FAB2(SCH_1):PAGE71
  BU76 PVCCIN_CPU1 @BASEBOARD_FAB2_LIB.BASEBOARD_FAB2(SCH_1):PVCCIN_CPU1    I51 @BASEBOARD_FAB2_LIB.BASEBOARD_FAB2(SCH_1):PAGE71
  BU78 PVCCIN_CPU1 @BASEBOARD_FAB2_LIB.BASEBOARD_FAB2(SCH_1):PVCCIN_CPU1    I51 @BASEBOARD_FAB2_LIB.BASEBOARD_FAB2(SCH_1):PAGE71
  BU80 PVCCIN_CPU1 @BASEBOARD_FAB2_LIB.BASEBOARD_FAB2(SCH_1):PVCCIN_CPU1    I51 @BASEBOARD_FAB2_LIB.BASEBOARD_FAB2(SCH_1):PAGE71
  BU82 PVCCIN_CPU1 @BASEBOARD_FAB2_LIB.BASEBOARD_FAB2(SCH_1):PVCCIN_CPU1    I51 @BASEBOARD_FAB2_LIB.BASEBOARD_FAB2(SCH_1):PAGE71
  BU84 PVCCIN_CPU1 @BASEBOARD_FAB2_LIB.BASEBOARD_FAB2(SCH_1):PVCCIN_CPU1    I51 @BASEBOARD_FAB2_LIB.BASEBOARD_FAB2(SCH_1):PAGE71
  BV61 PVCCIN_CPU1 @BASEBOARD_FAB2_LIB.BASEBOARD_FAB2(SCH_1):PVCCIN_CPU1    I51 @BASEBOARD_FAB2_LIB.BASEBOARD_FAB2(SCH_1):PAGE71
  BV63 PVCCIN_CPU1 @BASEBOARD_FAB2_LIB.BASEBOARD_FAB2(SCH_1):PVCCIN_CPU1    I51 @BASEBOARD_FAB2_LIB.BASEBOARD_FAB2(SCH_1):PAGE71
  BV65 PVCCIN_CPU1 @BASEBOARD_FAB2_LIB.BASEBOARD_FAB2(SCH_1):PVCCIN_CPU1    I51 @BASEBOARD_FAB2_LIB.BASEBOARD_FAB2(SCH_1):PAGE71
  BV67 PVCCIN_CPU1 @BASEBOARD_FAB2_LIB.BASEBOARD_FAB2(SCH_1):PVCCIN_CPU1    I51 @BASEBOARD_FAB2_LIB.BASEBOARD_FAB2(SCH_1):PAGE71
  BV69 PVCCIN_CPU1 @BASEBOARD_FAB2_LIB.BASEBOARD_FAB2(SCH_1):PVCCIN_CPU1    I51 @BASEBOARD_FAB2_LIB.BASEBOARD_FAB2(SCH_1):PAGE71
  BV71 PVCCIN_CPU1 @BASEBOARD_FAB2_LIB.BASEBOARD_FAB2(SCH_1):PVCCIN_CPU1    I51 @BASEBOARD_FAB2_LIB.BASEBOARD_FAB2(SCH_1):PAGE71
  BV73 PVCCIN_CPU1 @BASEBOARD_FAB2_LIB.BASEBOARD_FAB2(SCH_1):PVCCIN_CPU1    I51 @BASEBOARD_FAB2_LIB.BASEBOARD_FAB2(SCH_1):PAGE71
  BV75 PVCCIN_CPU1 @BASEBOARD_FAB2_LIB.BASEBOARD_FAB2(SCH_1):PVCCIN_CPU1    I51 @BASEBOARD_FAB2_LIB.BASEBOARD_FAB2(SCH_1):PAGE71
  BV77 PVCCIN_CPU1 @BASEBOARD_FAB2_LIB.BASEBOARD_FAB2(SCH_1):PVCCIN_CPU1    I51 @BASEBOARD_FAB2_LIB.BASEBOARD_FAB2(SCH_1):PAGE71
  BV79 PVCCIN_CPU1 @BASEBOARD_FAB2_LIB.BASEBOARD_FAB2(SCH_1):PVCCIN_CPU1    I51 @BASEBOARD_FAB2_LIB.BASEBOARD_FAB2(SCH_1):PAGE71
  BV81 PVCCIN_CPU1 @BASEBOARD_FAB2_LIB.BASEBOARD_FAB2(SCH_1):PVCCIN_CPU1    I51 @BASEBOARD_FAB2_LIB.BASEBOARD_FAB2(SCH_1):PAGE71
  BV83 PVCCIN_CPU1 @BASEBOARD_FAB2_LIB.BASEBOARD_FAB2(SCH_1):PVCCIN_CPU1    I51 @BASEBOARD_FAB2_LIB.BASEBOARD_FAB2(SCH_1):PAGE71
  BW60 PVCCIN_CPU1 @BASEBOARD_FAB2_LIB.BASEBOARD_FAB2(SCH_1):PVCCIN_CPU1    I51 @BASEBOARD_FAB2_LIB.BASEBOARD_FAB2(SCH_1):PAGE71
  BW62 PVCCIN_CPU1 @BASEBOARD_FAB2_LIB.BASEBOARD_FAB2(SCH_1):PVCCIN_CPU1    I51 @BASEBOARD_FAB2_LIB.BASEBOARD_FAB2(SCH_1):PAGE71
  BW64 PVCCIN_CPU1 @BASEBOARD_FAB2_LIB.BASEBOARD_FAB2(SCH_1):PVCCIN_CPU1    I51 @BASEBOARD_FAB2_LIB.BASEBOARD_FAB2(SCH_1):PAGE71
  BW66 PVCCIN_CPU1 @BASEBOARD_FAB2_LIB.BASEBOARD_FAB2(SCH_1):PVCCIN_CPU1    I51 @BASEBOARD_FAB2_LIB.BASEBOARD_FAB2(SCH_1):PAGE71
  BW68 PVCCIN_CPU1 @BASEBOARD_FAB2_LIB.BASEBOARD_FAB2(SCH_1):PVCCIN_CPU1    I51 @BASEBOARD_FAB2_LIB.BASEBOARD_FAB2(SCH_1):PAGE71
  BW70 PVCCIN_CPU1 @BASEBOARD_FAB2_LIB.BASEBOARD_FAB2(SCH_1):PVCCIN_CPU1    I51 @BASEBOARD_FAB2_LIB.BASEBOARD_FAB2(SCH_1):PAGE71
  BW84 PVCCIN_CPU1 @BASEBOARD_FAB2_LIB.BASEBOARD_FAB2(SCH_1):PVCCIN_CPU1    I51 @BASEBOARD_FAB2_LIB.BASEBOARD_FAB2(SCH_1):PAGE71
  BY61 PVCCIN_CPU1 @BASEBOARD_FAB2_LIB.BASEBOARD_FAB2(SCH_1):PVCCIN_CPU1    I51 @BASEBOARD_FAB2_LIB.BASEBOARD_FAB2(SCH_1):PAGE71
  BY73 PVCCIN_CPU1 @BASEBOARD_FAB2_LIB.BASEBOARD_FAB2(SCH_1):PVCCIN_CPU1    I51 @BASEBOARD_FAB2_LIB.BASEBOARD_FAB2(SCH_1):PAGE71
  BY75 PVCCIN_CPU1 @BASEBOARD_FAB2_LIB.BASEBOARD_FAB2(SCH_1):PVCCIN_CPU1    I51 @BASEBOARD_FAB2_LIB.BASEBOARD_FAB2(SCH_1):PAGE71
  BY77 PVCCIN_CPU1 @BASEBOARD_FAB2_LIB.BASEBOARD_FAB2(SCH_1):PVCCIN_CPU1    I51 @BASEBOARD_FAB2_LIB.BASEBOARD_FAB2(SCH_1):PAGE71
  BY79 PVCCIN_CPU1 @BASEBOARD_FAB2_LIB.BASEBOARD_FAB2(SCH_1):PVCCIN_CPU1    I51 @BASEBOARD_FAB2_LIB.BASEBOARD_FAB2(SCH_1):PAGE71
  BY81 PVCCIN_CPU1 @BASEBOARD_FAB2_LIB.BASEBOARD_FAB2(SCH_1):PVCCIN_CPU1    I51 @BASEBOARD_FAB2_LIB.BASEBOARD_FAB2(SCH_1):PAGE71
  BY83 PVCCIN_CPU1 @BASEBOARD_FAB2_LIB.BASEBOARD_FAB2(SCH_1):PVCCIN_CPU1    I51 @BASEBOARD_FAB2_LIB.BASEBOARD_FAB2(SCH_1):PAGE71
  CA60 PVCCIN_CPU1 @BASEBOARD_FAB2_LIB.BASEBOARD_FAB2(SCH_1):PVCCIN_CPU1    I51 @BASEBOARD_FAB2_LIB.BASEBOARD_FAB2(SCH_1):PAGE71
  CA62 PVCCIN_CPU1 @BASEBOARD_FAB2_LIB.BASEBOARD_FAB2(SCH_1):PVCCIN_CPU1    I51 @BASEBOARD_FAB2_LIB.BASEBOARD_FAB2(SCH_1):PAGE71
  CA72 PVCCIN_CPU1 @BASEBOARD_FAB2_LIB.BASEBOARD_FAB2(SCH_1):PVCCIN_CPU1    I51 @BASEBOARD_FAB2_LIB.BASEBOARD_FAB2(SCH_1):PAGE71
  CA74 PVCCIN_CPU1 @BASEBOARD_FAB2_LIB.BASEBOARD_FAB2(SCH_1):PVCCIN_CPU1    I51 @BASEBOARD_FAB2_LIB.BASEBOARD_FAB2(SCH_1):PAGE71
  CA76 PVCCIN_CPU1 @BASEBOARD_FAB2_LIB.BASEBOARD_FAB2(SCH_1):PVCCIN_CPU1    I51 @BASEBOARD_FAB2_LIB.BASEBOARD_FAB2(SCH_1):PAGE71
  CA78 PVCCIN_CPU1 @BASEBOARD_FAB2_LIB.BASEBOARD_FAB2(SCH_1):PVCCIN_CPU1    I51 @BASEBOARD_FAB2_LIB.BASEBOARD_FAB2(SCH_1):PAGE71
  CA80 PVCCIN_CPU1 @BASEBOARD_FAB2_LIB.BASEBOARD_FAB2(SCH_1):PVCCIN_CPU1    I51 @BASEBOARD_FAB2_LIB.BASEBOARD_FAB2(SCH_1):PAGE71
  CA82 PVCCIN_CPU1 @BASEBOARD_FAB2_LIB.BASEBOARD_FAB2(SCH_1):PVCCIN_CPU1    I51 @BASEBOARD_FAB2_LIB.BASEBOARD_FAB2(SCH_1):PAGE71
  CA84 PVCCIN_CPU1 @BASEBOARD_FAB2_LIB.BASEBOARD_FAB2(SCH_1):PVCCIN_CPU1    I51 @BASEBOARD_FAB2_LIB.BASEBOARD_FAB2(SCH_1):PAGE71
  CB61 PVCCIN_CPU1 @BASEBOARD_FAB2_LIB.BASEBOARD_FAB2(SCH_1):PVCCIN_CPU1    I51 @BASEBOARD_FAB2_LIB.BASEBOARD_FAB2(SCH_1):PAGE71
  CB73 PVCCIN_CPU1 @BASEBOARD_FAB2_LIB.BASEBOARD_FAB2(SCH_1):PVCCIN_CPU1    I51 @BASEBOARD_FAB2_LIB.BASEBOARD_FAB2(SCH_1):PAGE71
  CB75 PVCCIN_CPU1 @BASEBOARD_FAB2_LIB.BASEBOARD_FAB2(SCH_1):PVCCIN_CPU1    I51 @BASEBOARD_FAB2_LIB.BASEBOARD_FAB2(SCH_1):PAGE71
  CB77 PVCCIN_CPU1 @BASEBOARD_FAB2_LIB.BASEBOARD_FAB2(SCH_1):PVCCIN_CPU1    I51 @BASEBOARD_FAB2_LIB.BASEBOARD_FAB2(SCH_1):PAGE71
  CB79 PVCCIN_CPU1 @BASEBOARD_FAB2_LIB.BASEBOARD_FAB2(SCH_1):PVCCIN_CPU1    I51 @BASEBOARD_FAB2_LIB.BASEBOARD_FAB2(SCH_1):PAGE71
  CB81 PVCCIN_CPU1 @BASEBOARD_FAB2_LIB.BASEBOARD_FAB2(SCH_1):PVCCIN_CPU1    I51 @BASEBOARD_FAB2_LIB.BASEBOARD_FAB2(SCH_1):PAGE71
  CB83 PVCCIN_CPU1 @BASEBOARD_FAB2_LIB.BASEBOARD_FAB2(SCH_1):PVCCIN_CPU1    I51 @BASEBOARD_FAB2_LIB.BASEBOARD_FAB2(SCH_1):PAGE71
  CC60 PVCCIN_CPU1 @BASEBOARD_FAB2_LIB.BASEBOARD_FAB2(SCH_1):PVCCIN_CPU1    I51 @BASEBOARD_FAB2_LIB.BASEBOARD_FAB2(SCH_1):PAGE71
  CC62 PVCCIN_CPU1 @BASEBOARD_FAB2_LIB.BASEBOARD_FAB2(SCH_1):PVCCIN_CPU1    I51 @BASEBOARD_FAB2_LIB.BASEBOARD_FAB2(SCH_1):PAGE71
  CC84 PVCCIN_CPU1 @BASEBOARD_FAB2_LIB.BASEBOARD_FAB2(SCH_1):PVCCIN_CPU1    I51 @BASEBOARD_FAB2_LIB.BASEBOARD_FAB2(SCH_1):PAGE71
  CD61 PVCCIN_CPU1 @BASEBOARD_FAB2_LIB.BASEBOARD_FAB2(SCH_1):PVCCIN_CPU1    I51 @BASEBOARD_FAB2_LIB.BASEBOARD_FAB2(SCH_1):PAGE71
  CD83 PVCCIN_CPU1 @BASEBOARD_FAB2_LIB.BASEBOARD_FAB2(SCH_1):PVCCIN_CPU1    I51 @BASEBOARD_FAB2_LIB.BASEBOARD_FAB2(SCH_1):PAGE71
  CD85 PVCCIN_CPU1 @BASEBOARD_FAB2_LIB.BASEBOARD_FAB2(SCH_1):PVCCIN_CPU1    I51 @BASEBOARD_FAB2_LIB.BASEBOARD_FAB2(SCH_1):PAGE71
  CE60 PVCCIN_CPU1 @BASEBOARD_FAB2_LIB.BASEBOARD_FAB2(SCH_1):PVCCIN_CPU1    I51 @BASEBOARD_FAB2_LIB.BASEBOARD_FAB2(SCH_1):PAGE71
  CE84 PVCCIN_CPU1 @BASEBOARD_FAB2_LIB.BASEBOARD_FAB2(SCH_1):PVCCIN_CPU1    I51 @BASEBOARD_FAB2_LIB.BASEBOARD_FAB2(SCH_1):PAGE71
  CF61 PVCCIN_CPU1 @BASEBOARD_FAB2_LIB.BASEBOARD_FAB2(SCH_1):PVCCIN_CPU1    I51 @BASEBOARD_FAB2_LIB.BASEBOARD_FAB2(SCH_1):PAGE71
  CF85 PVCCIN_CPU1 @BASEBOARD_FAB2_LIB.BASEBOARD_FAB2(SCH_1):PVCCIN_CPU1    I51 @BASEBOARD_FAB2_LIB.BASEBOARD_FAB2(SCH_1):PAGE71
  CG60 PVCCIN_CPU1 @BASEBOARD_FAB2_LIB.BASEBOARD_FAB2(SCH_1):PVCCIN_CPU1    I51 @BASEBOARD_FAB2_LIB.BASEBOARD_FAB2(SCH_1):PAGE71
  CG84 PVCCIN_CPU1 @BASEBOARD_FAB2_LIB.BASEBOARD_FAB2(SCH_1):PVCCIN_CPU1    I51 @BASEBOARD_FAB2_LIB.BASEBOARD_FAB2(SCH_1):PAGE71
  CH61 PVCCIN_CPU1 @BASEBOARD_FAB2_LIB.BASEBOARD_FAB2(SCH_1):PVCCIN_CPU1    I51 @BASEBOARD_FAB2_LIB.BASEBOARD_FAB2(SCH_1):PAGE71
  CH85 PVCCIN_CPU1 @BASEBOARD_FAB2_LIB.BASEBOARD_FAB2(SCH_1):PVCCIN_CPU1    I51 @BASEBOARD_FAB2_LIB.BASEBOARD_FAB2(SCH_1):PAGE71
  CJ60 PVCCIN_CPU1 @BASEBOARD_FAB2_LIB.BASEBOARD_FAB2(SCH_1):PVCCIN_CPU1    I51 @BASEBOARD_FAB2_LIB.BASEBOARD_FAB2(SCH_1):PAGE71
  CK59 PVCCIN_CPU1 @BASEBOARD_FAB2_LIB.BASEBOARD_FAB2(SCH_1):PVCCIN_CPU1    I51 @BASEBOARD_FAB2_LIB.BASEBOARD_FAB2(SCH_1):PAGE71
  CK61 PVCCIN_CPU1 @BASEBOARD_FAB2_LIB.BASEBOARD_FAB2(SCH_1):PVCCIN_CPU1    I51 @BASEBOARD_FAB2_LIB.BASEBOARD_FAB2(SCH_1):PAGE71
  CL58 PVCCIN_CPU1 @BASEBOARD_FAB2_LIB.BASEBOARD_FAB2(SCH_1):PVCCIN_CPU1    I51 @BASEBOARD_FAB2_LIB.BASEBOARD_FAB2(SCH_1):PAGE71
  CL60 PVCCIN_CPU1 @BASEBOARD_FAB2_LIB.BASEBOARD_FAB2(SCH_1):PVCCIN_CPU1    I51 @BASEBOARD_FAB2_LIB.BASEBOARD_FAB2(SCH_1):PAGE71
  CM57 PVCCIN_CPU1 @BASEBOARD_FAB2_LIB.BASEBOARD_FAB2(SCH_1):PVCCIN_CPU1    I51 @BASEBOARD_FAB2_LIB.BASEBOARD_FAB2(SCH_1):PAGE71
  CM59 PVCCIN_CPU1 @BASEBOARD_FAB2_LIB.BASEBOARD_FAB2(SCH_1):PVCCIN_CPU1    I51 @BASEBOARD_FAB2_LIB.BASEBOARD_FAB2(SCH_1):PAGE71
  CN56 PVCCIN_CPU1 @BASEBOARD_FAB2_LIB.BASEBOARD_FAB2(SCH_1):PVCCIN_CPU1    I51 @BASEBOARD_FAB2_LIB.BASEBOARD_FAB2(SCH_1):PAGE71
  CN58 PVCCIN_CPU1 @BASEBOARD_FAB2_LIB.BASEBOARD_FAB2(SCH_1):PVCCIN_CPU1    I51 @BASEBOARD_FAB2_LIB.BASEBOARD_FAB2(SCH_1):PAGE71
  CP33 PVCCIN_CPU1 @BASEBOARD_FAB2_LIB.BASEBOARD_FAB2(SCH_1):PVCCIN_CPU1    I51 @BASEBOARD_FAB2_LIB.BASEBOARD_FAB2(SCH_1):PAGE71
  CP55 PVCCIN_CPU1 @BASEBOARD_FAB2_LIB.BASEBOARD_FAB2(SCH_1):PVCCIN_CPU1    I51 @BASEBOARD_FAB2_LIB.BASEBOARD_FAB2(SCH_1):PAGE71
  CP57 PVCCIN_CPU1 @BASEBOARD_FAB2_LIB.BASEBOARD_FAB2(SCH_1):PVCCIN_CPU1    I51 @BASEBOARD_FAB2_LIB.BASEBOARD_FAB2(SCH_1):PAGE71
  CR34 PVCCIN_CPU1 @BASEBOARD_FAB2_LIB.BASEBOARD_FAB2(SCH_1):PVCCIN_CPU1    I51 @BASEBOARD_FAB2_LIB.BASEBOARD_FAB2(SCH_1):PAGE71
  CR54 PVCCIN_CPU1 @BASEBOARD_FAB2_LIB.BASEBOARD_FAB2(SCH_1):PVCCIN_CPU1    I51 @BASEBOARD_FAB2_LIB.BASEBOARD_FAB2(SCH_1):PAGE71
  CR56 PVCCIN_CPU1 @BASEBOARD_FAB2_LIB.BASEBOARD_FAB2(SCH_1):PVCCIN_CPU1    I51 @BASEBOARD_FAB2_LIB.BASEBOARD_FAB2(SCH_1):PAGE71
  CT37 PVCCIN_CPU1 @BASEBOARD_FAB2_LIB.BASEBOARD_FAB2(SCH_1):PVCCIN_CPU1    I51 @BASEBOARD_FAB2_LIB.BASEBOARD_FAB2(SCH_1):PAGE71
  CT39 PVCCIN_CPU1 @BASEBOARD_FAB2_LIB.BASEBOARD_FAB2(SCH_1):PVCCIN_CPU1    I51 @BASEBOARD_FAB2_LIB.BASEBOARD_FAB2(SCH_1):PAGE71
  CT41 PVCCIN_CPU1 @BASEBOARD_FAB2_LIB.BASEBOARD_FAB2(SCH_1):PVCCIN_CPU1    I51 @BASEBOARD_FAB2_LIB.BASEBOARD_FAB2(SCH_1):PAGE71
  CT53 PVCCIN_CPU1 @BASEBOARD_FAB2_LIB.BASEBOARD_FAB2(SCH_1):PVCCIN_CPU1    I51 @BASEBOARD_FAB2_LIB.BASEBOARD_FAB2(SCH_1):PAGE71
  CT55 PVCCIN_CPU1 @BASEBOARD_FAB2_LIB.BASEBOARD_FAB2(SCH_1):PVCCIN_CPU1    I51 @BASEBOARD_FAB2_LIB.BASEBOARD_FAB2(SCH_1):PAGE71
  CU38 PVCCIN_CPU1 @BASEBOARD_FAB2_LIB.BASEBOARD_FAB2(SCH_1):PVCCIN_CPU1    I51 @BASEBOARD_FAB2_LIB.BASEBOARD_FAB2(SCH_1):PAGE71
  CU40 PVCCIN_CPU1 @BASEBOARD_FAB2_LIB.BASEBOARD_FAB2(SCH_1):PVCCIN_CPU1    I51 @BASEBOARD_FAB2_LIB.BASEBOARD_FAB2(SCH_1):PAGE71
  CU42 PVCCIN_CPU1 @BASEBOARD_FAB2_LIB.BASEBOARD_FAB2(SCH_1):PVCCIN_CPU1    I51 @BASEBOARD_FAB2_LIB.BASEBOARD_FAB2(SCH_1):PAGE71
  CU52 PVCCIN_CPU1 @BASEBOARD_FAB2_LIB.BASEBOARD_FAB2(SCH_1):PVCCIN_CPU1    I51 @BASEBOARD_FAB2_LIB.BASEBOARD_FAB2(SCH_1):PAGE71
  CU54 PVCCIN_CPU1 @BASEBOARD_FAB2_LIB.BASEBOARD_FAB2(SCH_1):PVCCIN_CPU1    I51 @BASEBOARD_FAB2_LIB.BASEBOARD_FAB2(SCH_1):PAGE71
  CV51 PVCCIN_CPU1 @BASEBOARD_FAB2_LIB.BASEBOARD_FAB2(SCH_1):PVCCIN_CPU1    I51 @BASEBOARD_FAB2_LIB.BASEBOARD_FAB2(SCH_1):PAGE71
  CW46 PVCCIN_CPU1 @BASEBOARD_FAB2_LIB.BASEBOARD_FAB2(SCH_1):PVCCIN_CPU1    I51 @BASEBOARD_FAB2_LIB.BASEBOARD_FAB2(SCH_1):PAGE71
  CW48 PVCCIN_CPU1 @BASEBOARD_FAB2_LIB.BASEBOARD_FAB2(SCH_1):PVCCIN_CPU1    I51 @BASEBOARD_FAB2_LIB.BASEBOARD_FAB2(SCH_1):PAGE71
  CW50 PVCCIN_CPU1 @BASEBOARD_FAB2_LIB.BASEBOARD_FAB2(SCH_1):PVCCIN_CPU1    I51 @BASEBOARD_FAB2_LIB.BASEBOARD_FAB2(SCH_1):PAGE71
  CY47 PVCCIN_CPU1 @BASEBOARD_FAB2_LIB.BASEBOARD_FAB2(SCH_1):PVCCIN_CPU1    I51 @BASEBOARD_FAB2_LIB.BASEBOARD_FAB2(SCH_1):PAGE71
  CY49 PVCCIN_CPU1 @BASEBOARD_FAB2_LIB.BASEBOARD_FAB2(SCH_1):PVCCIN_CPU1    I51 @BASEBOARD_FAB2_LIB.BASEBOARD_FAB2(SCH_1):PAGE71
  AV85 VSENSE_VCCINR2PMAX_CPU1 @BASEBOARD_FAB2_LIB.BASEBOARD_FAB2(SCH_1):VSENSE_VCCINR2PMAX_CPU1    I51 @BASEBOARD_FAB2_LIB.BASEBOARD_FAB2(SCH_1):PAGE71
  AW86 VSENSE_VCCINR2PMAX_CPU1 @BASEBOARD_FAB2_LIB.BASEBOARD_FAB2(SCH_1):VSENSE_VCCINR2PMAX_CPU1    I51 @BASEBOARD_FAB2_LIB.BASEBOARD_FAB2(SCH_1):PAGE71
  BA86 VSENSE_PVCCIN_CPU1_SKT_VSEN @BASEBOARD_FAB2_LIB.BASEBOARD_FAB2(SCH_1):VSENSE_PVCCIN_CPU1_SKT_VSEN    I51 @BASEBOARD_FAB2_LIB.BASEBOARD_FAB2(SCH_1):PAGE71
  AD41 VSENSE_PMAX_CPU1 @BASEBOARD_FAB2_LIB.BASEBOARD_FAB2(SCH_1):VSENSE_PMAX_CPU1    I51 @BASEBOARD_FAB2_LIB.BASEBOARD_FAB2(SCH_1):PAGE71
  AY85 VSENSE_PVCCIN_CPU1_SKT_VRTN @BASEBOARD_FAB2_LIB.BASEBOARD_FAB2(SCH_1):VSENSE_PVCCIN_CPU1_SKT_VRTN    I51 @BASEBOARD_FAB2_LIB.BASEBOARD_FAB2(SCH_1):PAGE71
   B47 PVDDQ_GHJ @BASEBOARD_FAB2_LIB.BASEBOARD_FAB2(SCH_1):PVDDQ_GHJ    I32 @BASEBOARD_FAB2_LIB.BASEBOARD_FAB2(SCH_1):PAGE72
   C46 PVDDQ_GHJ @BASEBOARD_FAB2_LIB.BASEBOARD_FAB2(SCH_1):PVDDQ_GHJ    I32 @BASEBOARD_FAB2_LIB.BASEBOARD_FAB2(SCH_1):PAGE72
   D45 PVDDQ_GHJ @BASEBOARD_FAB2_LIB.BASEBOARD_FAB2(SCH_1):PVDDQ_GHJ    I32 @BASEBOARD_FAB2_LIB.BASEBOARD_FAB2(SCH_1):PAGE72
  AF63 PVDDQ_GHJ @BASEBOARD_FAB2_LIB.BASEBOARD_FAB2(SCH_1):PVDDQ_GHJ    I32 @BASEBOARD_FAB2_LIB.BASEBOARD_FAB2(SCH_1):PAGE72
  AF61 PVDDQ_GHJ @BASEBOARD_FAB2_LIB.BASEBOARD_FAB2(SCH_1):PVDDQ_GHJ    I32 @BASEBOARD_FAB2_LIB.BASEBOARD_FAB2(SCH_1):PAGE72
  AF59 PVDDQ_GHJ @BASEBOARD_FAB2_LIB.BASEBOARD_FAB2(SCH_1):PVDDQ_GHJ    I32 @BASEBOARD_FAB2_LIB.BASEBOARD_FAB2(SCH_1):PAGE72
  AF57 PVDDQ_GHJ @BASEBOARD_FAB2_LIB.BASEBOARD_FAB2(SCH_1):PVDDQ_GHJ    I32 @BASEBOARD_FAB2_LIB.BASEBOARD_FAB2(SCH_1):PAGE72
  AF55 PVDDQ_GHJ @BASEBOARD_FAB2_LIB.BASEBOARD_FAB2(SCH_1):PVDDQ_GHJ    I32 @BASEBOARD_FAB2_LIB.BASEBOARD_FAB2(SCH_1):PAGE72
  AD45 PVDDQ_GHJ @BASEBOARD_FAB2_LIB.BASEBOARD_FAB2(SCH_1):PVDDQ_GHJ    I32 @BASEBOARD_FAB2_LIB.BASEBOARD_FAB2(SCH_1):PAGE72
   Y63 PVDDQ_GHJ @BASEBOARD_FAB2_LIB.BASEBOARD_FAB2(SCH_1):PVDDQ_GHJ    I32 @BASEBOARD_FAB2_LIB.BASEBOARD_FAB2(SCH_1):PAGE72
   Y61 PVDDQ_GHJ @BASEBOARD_FAB2_LIB.BASEBOARD_FAB2(SCH_1):PVDDQ_GHJ    I32 @BASEBOARD_FAB2_LIB.BASEBOARD_FAB2(SCH_1):PAGE72
   Y59 PVDDQ_GHJ @BASEBOARD_FAB2_LIB.BASEBOARD_FAB2(SCH_1):PVDDQ_GHJ    I32 @BASEBOARD_FAB2_LIB.BASEBOARD_FAB2(SCH_1):PAGE72
   Y57 PVDDQ_GHJ @BASEBOARD_FAB2_LIB.BASEBOARD_FAB2(SCH_1):PVDDQ_GHJ    I32 @BASEBOARD_FAB2_LIB.BASEBOARD_FAB2(SCH_1):PAGE72
   Y55 PVDDQ_GHJ @BASEBOARD_FAB2_LIB.BASEBOARD_FAB2(SCH_1):PVDDQ_GHJ    I32 @BASEBOARD_FAB2_LIB.BASEBOARD_FAB2(SCH_1):PAGE72
   Y53 PVDDQ_GHJ @BASEBOARD_FAB2_LIB.BASEBOARD_FAB2(SCH_1):PVDDQ_GHJ    I32 @BASEBOARD_FAB2_LIB.BASEBOARD_FAB2(SCH_1):PAGE72
   Y51 PVDDQ_GHJ @BASEBOARD_FAB2_LIB.BASEBOARD_FAB2(SCH_1):PVDDQ_GHJ    I32 @BASEBOARD_FAB2_LIB.BASEBOARD_FAB2(SCH_1):PAGE72
   Y49 PVDDQ_GHJ @BASEBOARD_FAB2_LIB.BASEBOARD_FAB2(SCH_1):PVDDQ_GHJ    I32 @BASEBOARD_FAB2_LIB.BASEBOARD_FAB2(SCH_1):PAGE72
   Y47 PVDDQ_GHJ @BASEBOARD_FAB2_LIB.BASEBOARD_FAB2(SCH_1):PVDDQ_GHJ    I32 @BASEBOARD_FAB2_LIB.BASEBOARD_FAB2(SCH_1):PAGE72
   Y45 PVDDQ_GHJ @BASEBOARD_FAB2_LIB.BASEBOARD_FAB2(SCH_1):PVDDQ_GHJ    I32 @BASEBOARD_FAB2_LIB.BASEBOARD_FAB2(SCH_1):PAGE72
   W64 PVDDQ_GHJ @BASEBOARD_FAB2_LIB.BASEBOARD_FAB2(SCH_1):PVDDQ_GHJ    I32 @BASEBOARD_FAB2_LIB.BASEBOARD_FAB2(SCH_1):PAGE72
   U62 PVDDQ_GHJ @BASEBOARD_FAB2_LIB.BASEBOARD_FAB2(SCH_1):PVDDQ_GHJ    I32 @BASEBOARD_FAB2_LIB.BASEBOARD_FAB2(SCH_1):PAGE72
   U60 PVDDQ_GHJ @BASEBOARD_FAB2_LIB.BASEBOARD_FAB2(SCH_1):PVDDQ_GHJ    I32 @BASEBOARD_FAB2_LIB.BASEBOARD_FAB2(SCH_1):PAGE72
   U58 PVDDQ_GHJ @BASEBOARD_FAB2_LIB.BASEBOARD_FAB2(SCH_1):PVDDQ_GHJ    I32 @BASEBOARD_FAB2_LIB.BASEBOARD_FAB2(SCH_1):PAGE72
   U56 PVDDQ_GHJ @BASEBOARD_FAB2_LIB.BASEBOARD_FAB2(SCH_1):PVDDQ_GHJ    I32 @BASEBOARD_FAB2_LIB.BASEBOARD_FAB2(SCH_1):PAGE72
   U54 PVDDQ_GHJ @BASEBOARD_FAB2_LIB.BASEBOARD_FAB2(SCH_1):PVDDQ_GHJ    I32 @BASEBOARD_FAB2_LIB.BASEBOARD_FAB2(SCH_1):PAGE72
   U52 PVDDQ_GHJ @BASEBOARD_FAB2_LIB.BASEBOARD_FAB2(SCH_1):PVDDQ_GHJ    I32 @BASEBOARD_FAB2_LIB.BASEBOARD_FAB2(SCH_1):PAGE72
   U50 PVDDQ_GHJ @BASEBOARD_FAB2_LIB.BASEBOARD_FAB2(SCH_1):PVDDQ_GHJ    I32 @BASEBOARD_FAB2_LIB.BASEBOARD_FAB2(SCH_1):PAGE72
   U48 PVDDQ_GHJ @BASEBOARD_FAB2_LIB.BASEBOARD_FAB2(SCH_1):PVDDQ_GHJ    I32 @BASEBOARD_FAB2_LIB.BASEBOARD_FAB2(SCH_1):PAGE72
   U46 PVDDQ_GHJ @BASEBOARD_FAB2_LIB.BASEBOARD_FAB2(SCH_1):PVDDQ_GHJ    I32 @BASEBOARD_FAB2_LIB.BASEBOARD_FAB2(SCH_1):PAGE72
   N64 PVDDQ_GHJ @BASEBOARD_FAB2_LIB.BASEBOARD_FAB2(SCH_1):PVDDQ_GHJ    I32 @BASEBOARD_FAB2_LIB.BASEBOARD_FAB2(SCH_1):PAGE72
   L62 PVDDQ_GHJ @BASEBOARD_FAB2_LIB.BASEBOARD_FAB2(SCH_1):PVDDQ_GHJ    I32 @BASEBOARD_FAB2_LIB.BASEBOARD_FAB2(SCH_1):PAGE72
   L60 PVDDQ_GHJ @BASEBOARD_FAB2_LIB.BASEBOARD_FAB2(SCH_1):PVDDQ_GHJ    I32 @BASEBOARD_FAB2_LIB.BASEBOARD_FAB2(SCH_1):PAGE72
   L58 PVDDQ_GHJ @BASEBOARD_FAB2_LIB.BASEBOARD_FAB2(SCH_1):PVDDQ_GHJ    I32 @BASEBOARD_FAB2_LIB.BASEBOARD_FAB2(SCH_1):PAGE72
   L56 PVDDQ_GHJ @BASEBOARD_FAB2_LIB.BASEBOARD_FAB2(SCH_1):PVDDQ_GHJ    I32 @BASEBOARD_FAB2_LIB.BASEBOARD_FAB2(SCH_1):PAGE72
   L54 PVDDQ_GHJ @BASEBOARD_FAB2_LIB.BASEBOARD_FAB2(SCH_1):PVDDQ_GHJ    I32 @BASEBOARD_FAB2_LIB.BASEBOARD_FAB2(SCH_1):PAGE72
   L52 PVDDQ_GHJ @BASEBOARD_FAB2_LIB.BASEBOARD_FAB2(SCH_1):PVDDQ_GHJ    I32 @BASEBOARD_FAB2_LIB.BASEBOARD_FAB2(SCH_1):PAGE72
   L50 PVDDQ_GHJ @BASEBOARD_FAB2_LIB.BASEBOARD_FAB2(SCH_1):PVDDQ_GHJ    I32 @BASEBOARD_FAB2_LIB.BASEBOARD_FAB2(SCH_1):PAGE72
   L48 PVDDQ_GHJ @BASEBOARD_FAB2_LIB.BASEBOARD_FAB2(SCH_1):PVDDQ_GHJ    I32 @BASEBOARD_FAB2_LIB.BASEBOARD_FAB2(SCH_1):PAGE72
   L46 PVDDQ_GHJ @BASEBOARD_FAB2_LIB.BASEBOARD_FAB2(SCH_1):PVDDQ_GHJ    I32 @BASEBOARD_FAB2_LIB.BASEBOARD_FAB2(SCH_1):PAGE72
   E64 PVDDQ_GHJ @BASEBOARD_FAB2_LIB.BASEBOARD_FAB2(SCH_1):PVDDQ_GHJ    I32 @BASEBOARD_FAB2_LIB.BASEBOARD_FAB2(SCH_1):PAGE72
   E62 PVDDQ_GHJ @BASEBOARD_FAB2_LIB.BASEBOARD_FAB2(SCH_1):PVDDQ_GHJ    I32 @BASEBOARD_FAB2_LIB.BASEBOARD_FAB2(SCH_1):PAGE72
   E60 PVDDQ_GHJ @BASEBOARD_FAB2_LIB.BASEBOARD_FAB2(SCH_1):PVDDQ_GHJ    I32 @BASEBOARD_FAB2_LIB.BASEBOARD_FAB2(SCH_1):PAGE72
   E58 PVDDQ_GHJ @BASEBOARD_FAB2_LIB.BASEBOARD_FAB2(SCH_1):PVDDQ_GHJ    I32 @BASEBOARD_FAB2_LIB.BASEBOARD_FAB2(SCH_1):PAGE72
   E56 PVDDQ_GHJ @BASEBOARD_FAB2_LIB.BASEBOARD_FAB2(SCH_1):PVDDQ_GHJ    I32 @BASEBOARD_FAB2_LIB.BASEBOARD_FAB2(SCH_1):PAGE72
   E54 PVDDQ_GHJ @BASEBOARD_FAB2_LIB.BASEBOARD_FAB2(SCH_1):PVDDQ_GHJ    I32 @BASEBOARD_FAB2_LIB.BASEBOARD_FAB2(SCH_1):PAGE72
   E52 PVDDQ_GHJ @BASEBOARD_FAB2_LIB.BASEBOARD_FAB2(SCH_1):PVDDQ_GHJ    I32 @BASEBOARD_FAB2_LIB.BASEBOARD_FAB2(SCH_1):PAGE72
   E50 PVDDQ_GHJ @BASEBOARD_FAB2_LIB.BASEBOARD_FAB2(SCH_1):PVDDQ_GHJ    I32 @BASEBOARD_FAB2_LIB.BASEBOARD_FAB2(SCH_1):PAGE72
   E48 PVDDQ_GHJ @BASEBOARD_FAB2_LIB.BASEBOARD_FAB2(SCH_1):PVDDQ_GHJ    I32 @BASEBOARD_FAB2_LIB.BASEBOARD_FAB2(SCH_1):PAGE72
   E46 PVDDQ_GHJ @BASEBOARD_FAB2_LIB.BASEBOARD_FAB2(SCH_1):PVDDQ_GHJ    I32 @BASEBOARD_FAB2_LIB.BASEBOARD_FAB2(SCH_1):PAGE72
   B59 PVDDQ_GHJ @BASEBOARD_FAB2_LIB.BASEBOARD_FAB2(SCH_1):PVDDQ_GHJ    I32 @BASEBOARD_FAB2_LIB.BASEBOARD_FAB2(SCH_1):PAGE72
   B53 PVDDQ_GHJ @BASEBOARD_FAB2_LIB.BASEBOARD_FAB2(SCH_1):PVDDQ_GHJ    I32 @BASEBOARD_FAB2_LIB.BASEBOARD_FAB2(SCH_1):PAGE72
   B49 PVDDQ_GHJ @BASEBOARD_FAB2_LIB.BASEBOARD_FAB2(SCH_1):PVDDQ_GHJ    I32 @BASEBOARD_FAB2_LIB.BASEBOARD_FAB2(SCH_1):PAGE72
  EE44 PVDDQ_KLM @BASEBOARD_FAB2_LIB.BASEBOARD_FAB2(SCH_1):PVDDQ_KLM    I32 @BASEBOARD_FAB2_LIB.BASEBOARD_FAB2(SCH_1):PAGE72
  EF45 PVDDQ_KLM @BASEBOARD_FAB2_LIB.BASEBOARD_FAB2(SCH_1):PVDDQ_KLM    I32 @BASEBOARD_FAB2_LIB.BASEBOARD_FAB2(SCH_1):PAGE72
  DB53 PVDDQ_KLM @BASEBOARD_FAB2_LIB.BASEBOARD_FAB2(SCH_1):PVDDQ_KLM    I32 @BASEBOARD_FAB2_LIB.BASEBOARD_FAB2(SCH_1):PAGE72
  DB55 PVDDQ_KLM @BASEBOARD_FAB2_LIB.BASEBOARD_FAB2(SCH_1):PVDDQ_KLM    I32 @BASEBOARD_FAB2_LIB.BASEBOARD_FAB2(SCH_1):PAGE72
  DB57 PVDDQ_KLM @BASEBOARD_FAB2_LIB.BASEBOARD_FAB2(SCH_1):PVDDQ_KLM    I32 @BASEBOARD_FAB2_LIB.BASEBOARD_FAB2(SCH_1):PAGE72
  DB59 PVDDQ_KLM @BASEBOARD_FAB2_LIB.BASEBOARD_FAB2(SCH_1):PVDDQ_KLM    I32 @BASEBOARD_FAB2_LIB.BASEBOARD_FAB2(SCH_1):PAGE72
  DB61 PVDDQ_KLM @BASEBOARD_FAB2_LIB.BASEBOARD_FAB2(SCH_1):PVDDQ_KLM    I32 @BASEBOARD_FAB2_LIB.BASEBOARD_FAB2(SCH_1):PAGE72
  DB63 PVDDQ_KLM @BASEBOARD_FAB2_LIB.BASEBOARD_FAB2(SCH_1):PVDDQ_KLM    I32 @BASEBOARD_FAB2_LIB.BASEBOARD_FAB2(SCH_1):PAGE72
  DD45 PVDDQ_KLM @BASEBOARD_FAB2_LIB.BASEBOARD_FAB2(SCH_1):PVDDQ_KLM    I32 @BASEBOARD_FAB2_LIB.BASEBOARD_FAB2(SCH_1):PAGE72
  DH45 PVDDQ_KLM @BASEBOARD_FAB2_LIB.BASEBOARD_FAB2(SCH_1):PVDDQ_KLM    I32 @BASEBOARD_FAB2_LIB.BASEBOARD_FAB2(SCH_1):PAGE72
  DH47 PVDDQ_KLM @BASEBOARD_FAB2_LIB.BASEBOARD_FAB2(SCH_1):PVDDQ_KLM    I32 @BASEBOARD_FAB2_LIB.BASEBOARD_FAB2(SCH_1):PAGE72
  DH49 PVDDQ_KLM @BASEBOARD_FAB2_LIB.BASEBOARD_FAB2(SCH_1):PVDDQ_KLM    I32 @BASEBOARD_FAB2_LIB.BASEBOARD_FAB2(SCH_1):PAGE72
  DH51 PVDDQ_KLM @BASEBOARD_FAB2_LIB.BASEBOARD_FAB2(SCH_1):PVDDQ_KLM    I32 @BASEBOARD_FAB2_LIB.BASEBOARD_FAB2(SCH_1):PAGE72
  DH53 PVDDQ_KLM @BASEBOARD_FAB2_LIB.BASEBOARD_FAB2(SCH_1):PVDDQ_KLM    I32 @BASEBOARD_FAB2_LIB.BASEBOARD_FAB2(SCH_1):PAGE72
  DH55 PVDDQ_KLM @BASEBOARD_FAB2_LIB.BASEBOARD_FAB2(SCH_1):PVDDQ_KLM    I32 @BASEBOARD_FAB2_LIB.BASEBOARD_FAB2(SCH_1):PAGE72
  DH57 PVDDQ_KLM @BASEBOARD_FAB2_LIB.BASEBOARD_FAB2(SCH_1):PVDDQ_KLM    I32 @BASEBOARD_FAB2_LIB.BASEBOARD_FAB2(SCH_1):PAGE72
  DH59 PVDDQ_KLM @BASEBOARD_FAB2_LIB.BASEBOARD_FAB2(SCH_1):PVDDQ_KLM    I32 @BASEBOARD_FAB2_LIB.BASEBOARD_FAB2(SCH_1):PAGE72
  DH61 PVDDQ_KLM @BASEBOARD_FAB2_LIB.BASEBOARD_FAB2(SCH_1):PVDDQ_KLM    I32 @BASEBOARD_FAB2_LIB.BASEBOARD_FAB2(SCH_1):PAGE72
  DH63 PVDDQ_KLM @BASEBOARD_FAB2_LIB.BASEBOARD_FAB2(SCH_1):PVDDQ_KLM    I32 @BASEBOARD_FAB2_LIB.BASEBOARD_FAB2(SCH_1):PAGE72
  DJ64 PVDDQ_KLM @BASEBOARD_FAB2_LIB.BASEBOARD_FAB2(SCH_1):PVDDQ_KLM    I32 @BASEBOARD_FAB2_LIB.BASEBOARD_FAB2(SCH_1):PAGE72
  DL46 PVDDQ_KLM @BASEBOARD_FAB2_LIB.BASEBOARD_FAB2(SCH_1):PVDDQ_KLM    I32 @BASEBOARD_FAB2_LIB.BASEBOARD_FAB2(SCH_1):PAGE72
  DL48 PVDDQ_KLM @BASEBOARD_FAB2_LIB.BASEBOARD_FAB2(SCH_1):PVDDQ_KLM    I32 @BASEBOARD_FAB2_LIB.BASEBOARD_FAB2(SCH_1):PAGE72
  DL50 PVDDQ_KLM @BASEBOARD_FAB2_LIB.BASEBOARD_FAB2(SCH_1):PVDDQ_KLM    I32 @BASEBOARD_FAB2_LIB.BASEBOARD_FAB2(SCH_1):PAGE72
  DL52 PVDDQ_KLM @BASEBOARD_FAB2_LIB.BASEBOARD_FAB2(SCH_1):PVDDQ_KLM    I32 @BASEBOARD_FAB2_LIB.BASEBOARD_FAB2(SCH_1):PAGE72
  DL54 PVDDQ_KLM @BASEBOARD_FAB2_LIB.BASEBOARD_FAB2(SCH_1):PVDDQ_KLM    I32 @BASEBOARD_FAB2_LIB.BASEBOARD_FAB2(SCH_1):PAGE72
  DL56 PVDDQ_KLM @BASEBOARD_FAB2_LIB.BASEBOARD_FAB2(SCH_1):PVDDQ_KLM    I32 @BASEBOARD_FAB2_LIB.BASEBOARD_FAB2(SCH_1):PAGE72
  DL58 PVDDQ_KLM @BASEBOARD_FAB2_LIB.BASEBOARD_FAB2(SCH_1):PVDDQ_KLM    I32 @BASEBOARD_FAB2_LIB.BASEBOARD_FAB2(SCH_1):PAGE72
  DL60 PVDDQ_KLM @BASEBOARD_FAB2_LIB.BASEBOARD_FAB2(SCH_1):PVDDQ_KLM    I32 @BASEBOARD_FAB2_LIB.BASEBOARD_FAB2(SCH_1):PAGE72
  DL62 PVDDQ_KLM @BASEBOARD_FAB2_LIB.BASEBOARD_FAB2(SCH_1):PVDDQ_KLM    I32 @BASEBOARD_FAB2_LIB.BASEBOARD_FAB2(SCH_1):PAGE72
  DU46 PVDDQ_KLM @BASEBOARD_FAB2_LIB.BASEBOARD_FAB2(SCH_1):PVDDQ_KLM    I32 @BASEBOARD_FAB2_LIB.BASEBOARD_FAB2(SCH_1):PAGE72
  DU48 PVDDQ_KLM @BASEBOARD_FAB2_LIB.BASEBOARD_FAB2(SCH_1):PVDDQ_KLM    I32 @BASEBOARD_FAB2_LIB.BASEBOARD_FAB2(SCH_1):PAGE72
  DU50 PVDDQ_KLM @BASEBOARD_FAB2_LIB.BASEBOARD_FAB2(SCH_1):PVDDQ_KLM    I32 @BASEBOARD_FAB2_LIB.BASEBOARD_FAB2(SCH_1):PAGE72
  DU52 PVDDQ_KLM @BASEBOARD_FAB2_LIB.BASEBOARD_FAB2(SCH_1):PVDDQ_KLM    I32 @BASEBOARD_FAB2_LIB.BASEBOARD_FAB2(SCH_1):PAGE72
  DU54 PVDDQ_KLM @BASEBOARD_FAB2_LIB.BASEBOARD_FAB2(SCH_1):PVDDQ_KLM    I32 @BASEBOARD_FAB2_LIB.BASEBOARD_FAB2(SCH_1):PAGE72
  DU56 PVDDQ_KLM @BASEBOARD_FAB2_LIB.BASEBOARD_FAB2(SCH_1):PVDDQ_KLM    I32 @BASEBOARD_FAB2_LIB.BASEBOARD_FAB2(SCH_1):PAGE72
  DU58 PVDDQ_KLM @BASEBOARD_FAB2_LIB.BASEBOARD_FAB2(SCH_1):PVDDQ_KLM    I32 @BASEBOARD_FAB2_LIB.BASEBOARD_FAB2(SCH_1):PAGE72
  DU60 PVDDQ_KLM @BASEBOARD_FAB2_LIB.BASEBOARD_FAB2(SCH_1):PVDDQ_KLM    I32 @BASEBOARD_FAB2_LIB.BASEBOARD_FAB2(SCH_1):PAGE72
  DU62 PVDDQ_KLM @BASEBOARD_FAB2_LIB.BASEBOARD_FAB2(SCH_1):PVDDQ_KLM    I32 @BASEBOARD_FAB2_LIB.BASEBOARD_FAB2(SCH_1):PAGE72
  DU64 PVDDQ_KLM @BASEBOARD_FAB2_LIB.BASEBOARD_FAB2(SCH_1):PVDDQ_KLM    I32 @BASEBOARD_FAB2_LIB.BASEBOARD_FAB2(SCH_1):PAGE72
  EC46 PVDDQ_KLM @BASEBOARD_FAB2_LIB.BASEBOARD_FAB2(SCH_1):PVDDQ_KLM    I32 @BASEBOARD_FAB2_LIB.BASEBOARD_FAB2(SCH_1):PAGE72
  EC48 PVDDQ_KLM @BASEBOARD_FAB2_LIB.BASEBOARD_FAB2(SCH_1):PVDDQ_KLM    I32 @BASEBOARD_FAB2_LIB.BASEBOARD_FAB2(SCH_1):PAGE72
  EC50 PVDDQ_KLM @BASEBOARD_FAB2_LIB.BASEBOARD_FAB2(SCH_1):PVDDQ_KLM    I32 @BASEBOARD_FAB2_LIB.BASEBOARD_FAB2(SCH_1):PAGE72
  EC52 PVDDQ_KLM @BASEBOARD_FAB2_LIB.BASEBOARD_FAB2(SCH_1):PVDDQ_KLM    I32 @BASEBOARD_FAB2_LIB.BASEBOARD_FAB2(SCH_1):PAGE72
  EC54 PVDDQ_KLM @BASEBOARD_FAB2_LIB.BASEBOARD_FAB2(SCH_1):PVDDQ_KLM    I32 @BASEBOARD_FAB2_LIB.BASEBOARD_FAB2(SCH_1):PAGE72
  EC56 PVDDQ_KLM @BASEBOARD_FAB2_LIB.BASEBOARD_FAB2(SCH_1):PVDDQ_KLM    I32 @BASEBOARD_FAB2_LIB.BASEBOARD_FAB2(SCH_1):PAGE72
  EC58 PVDDQ_KLM @BASEBOARD_FAB2_LIB.BASEBOARD_FAB2(SCH_1):PVDDQ_KLM    I32 @BASEBOARD_FAB2_LIB.BASEBOARD_FAB2(SCH_1):PAGE72
  EC60 PVDDQ_KLM @BASEBOARD_FAB2_LIB.BASEBOARD_FAB2(SCH_1):PVDDQ_KLM    I32 @BASEBOARD_FAB2_LIB.BASEBOARD_FAB2(SCH_1):PAGE72
  EC62 PVDDQ_KLM @BASEBOARD_FAB2_LIB.BASEBOARD_FAB2(SCH_1):PVDDQ_KLM    I32 @BASEBOARD_FAB2_LIB.BASEBOARD_FAB2(SCH_1):PAGE72
  EF49 PVDDQ_KLM @BASEBOARD_FAB2_LIB.BASEBOARD_FAB2(SCH_1):PVDDQ_KLM    I32 @BASEBOARD_FAB2_LIB.BASEBOARD_FAB2(SCH_1):PAGE72
  EF53 PVDDQ_KLM @BASEBOARD_FAB2_LIB.BASEBOARD_FAB2(SCH_1):PVDDQ_KLM    I32 @BASEBOARD_FAB2_LIB.BASEBOARD_FAB2(SCH_1):PAGE72
  EF59 PVDDQ_KLM @BASEBOARD_FAB2_LIB.BASEBOARD_FAB2(SCH_1):PVDDQ_KLM    I32 @BASEBOARD_FAB2_LIB.BASEBOARD_FAB2(SCH_1):PAGE72
  BY27 P1V8_MCP_CPU1 @BASEBOARD_FAB2_LIB.BASEBOARD_FAB2(SCH_1):P1V8_MCP_CPU1    I33 @BASEBOARD_FAB2_LIB.BASEBOARD_FAB2(SCH_1):PAGE72
  BV27 P1V8_MCP_CPU1 @BASEBOARD_FAB2_LIB.BASEBOARD_FAB2(SCH_1):P1V8_MCP_CPU1    I33 @BASEBOARD_FAB2_LIB.BASEBOARD_FAB2(SCH_1):PAGE72
  BU26 P1V8_MCP_CPU1 @BASEBOARD_FAB2_LIB.BASEBOARD_FAB2(SCH_1):P1V8_MCP_CPU1    I33 @BASEBOARD_FAB2_LIB.BASEBOARD_FAB2(SCH_1):PAGE72
  BT27 P1V8_MCP_CPU1 @BASEBOARD_FAB2_LIB.BASEBOARD_FAB2(SCH_1):P1V8_MCP_CPU1    I33 @BASEBOARD_FAB2_LIB.BASEBOARD_FAB2(SCH_1):PAGE72
  BM11 PVCCIOMCP_CPU1 @BASEBOARD_FAB2_LIB.BASEBOARD_FAB2(SCH_1):PVCCIOMCP_CPU1    I33 @BASEBOARD_FAB2_LIB.BASEBOARD_FAB2(SCH_1):PAGE72
  BN12 PVCCIOMCP_CPU1 @BASEBOARD_FAB2_LIB.BASEBOARD_FAB2(SCH_1):PVCCIOMCP_CPU1    I33 @BASEBOARD_FAB2_LIB.BASEBOARD_FAB2(SCH_1):PAGE72
  BN14 PVCCIOMCP_CPU1 @BASEBOARD_FAB2_LIB.BASEBOARD_FAB2(SCH_1):PVCCIOMCP_CPU1    I33 @BASEBOARD_FAB2_LIB.BASEBOARD_FAB2(SCH_1):PAGE72
  BP11 PVCCIOMCP_CPU1 @BASEBOARD_FAB2_LIB.BASEBOARD_FAB2(SCH_1):PVCCIOMCP_CPU1    I33 @BASEBOARD_FAB2_LIB.BASEBOARD_FAB2(SCH_1):PAGE72
  BP13 PVCCIOMCP_CPU1 @BASEBOARD_FAB2_LIB.BASEBOARD_FAB2(SCH_1):PVCCIOMCP_CPU1    I33 @BASEBOARD_FAB2_LIB.BASEBOARD_FAB2(SCH_1):PAGE72
  BP15 PVCCIOMCP_CPU1 @BASEBOARD_FAB2_LIB.BASEBOARD_FAB2(SCH_1):PVCCIOMCP_CPU1    I33 @BASEBOARD_FAB2_LIB.BASEBOARD_FAB2(SCH_1):PAGE72
  BR12 PVCCIOMCP_CPU1 @BASEBOARD_FAB2_LIB.BASEBOARD_FAB2(SCH_1):PVCCIOMCP_CPU1    I33 @BASEBOARD_FAB2_LIB.BASEBOARD_FAB2(SCH_1):PAGE72
  BR14 PVCCIOMCP_CPU1 @BASEBOARD_FAB2_LIB.BASEBOARD_FAB2(SCH_1):PVCCIOMCP_CPU1    I33 @BASEBOARD_FAB2_LIB.BASEBOARD_FAB2(SCH_1):PAGE72
  BT11 PVCCIOMCP_CPU1 @BASEBOARD_FAB2_LIB.BASEBOARD_FAB2(SCH_1):PVCCIOMCP_CPU1    I33 @BASEBOARD_FAB2_LIB.BASEBOARD_FAB2(SCH_1):PAGE72
  BT13 PVCCIOMCP_CPU1 @BASEBOARD_FAB2_LIB.BASEBOARD_FAB2(SCH_1):PVCCIOMCP_CPU1    I33 @BASEBOARD_FAB2_LIB.BASEBOARD_FAB2(SCH_1):PAGE72
  BT15 PVCCIOMCP_CPU1 @BASEBOARD_FAB2_LIB.BASEBOARD_FAB2(SCH_1):PVCCIOMCP_CPU1    I33 @BASEBOARD_FAB2_LIB.BASEBOARD_FAB2(SCH_1):PAGE72
  BU12 PVCCIOMCP_CPU1 @BASEBOARD_FAB2_LIB.BASEBOARD_FAB2(SCH_1):PVCCIOMCP_CPU1    I33 @BASEBOARD_FAB2_LIB.BASEBOARD_FAB2(SCH_1):PAGE72
  BU14 PVCCIOMCP_CPU1 @BASEBOARD_FAB2_LIB.BASEBOARD_FAB2(SCH_1):PVCCIOMCP_CPU1    I33 @BASEBOARD_FAB2_LIB.BASEBOARD_FAB2(SCH_1):PAGE72
  BV11 PVCCIOMCP_CPU1 @BASEBOARD_FAB2_LIB.BASEBOARD_FAB2(SCH_1):PVCCIOMCP_CPU1    I33 @BASEBOARD_FAB2_LIB.BASEBOARD_FAB2(SCH_1):PAGE72
  BV13 PVCCIOMCP_CPU1 @BASEBOARD_FAB2_LIB.BASEBOARD_FAB2(SCH_1):PVCCIOMCP_CPU1    I33 @BASEBOARD_FAB2_LIB.BASEBOARD_FAB2(SCH_1):PAGE72
  BV15 PVCCIOMCP_CPU1 @BASEBOARD_FAB2_LIB.BASEBOARD_FAB2(SCH_1):PVCCIOMCP_CPU1    I33 @BASEBOARD_FAB2_LIB.BASEBOARD_FAB2(SCH_1):PAGE72
  BD13 PVCCMCP_CPU1 @BASEBOARD_FAB2_LIB.BASEBOARD_FAB2(SCH_1):PVCCMCP_CPU1    I33 @BASEBOARD_FAB2_LIB.BASEBOARD_FAB2(SCH_1):PAGE72
  BE12 PVCCMCP_CPU1 @BASEBOARD_FAB2_LIB.BASEBOARD_FAB2(SCH_1):PVCCMCP_CPU1    I33 @BASEBOARD_FAB2_LIB.BASEBOARD_FAB2(SCH_1):PAGE72
  BE14 PVCCMCP_CPU1 @BASEBOARD_FAB2_LIB.BASEBOARD_FAB2(SCH_1):PVCCMCP_CPU1    I33 @BASEBOARD_FAB2_LIB.BASEBOARD_FAB2(SCH_1):PAGE72
  BF11 PVCCMCP_CPU1 @BASEBOARD_FAB2_LIB.BASEBOARD_FAB2(SCH_1):PVCCMCP_CPU1    I33 @BASEBOARD_FAB2_LIB.BASEBOARD_FAB2(SCH_1):PAGE72
  BF13 PVCCMCP_CPU1 @BASEBOARD_FAB2_LIB.BASEBOARD_FAB2(SCH_1):PVCCMCP_CPU1    I33 @BASEBOARD_FAB2_LIB.BASEBOARD_FAB2(SCH_1):PAGE72
  BG12 PVCCMCP_CPU1 @BASEBOARD_FAB2_LIB.BASEBOARD_FAB2(SCH_1):PVCCMCP_CPU1    I33 @BASEBOARD_FAB2_LIB.BASEBOARD_FAB2(SCH_1):PAGE72
  BG14 PVCCMCP_CPU1 @BASEBOARD_FAB2_LIB.BASEBOARD_FAB2(SCH_1):PVCCMCP_CPU1    I33 @BASEBOARD_FAB2_LIB.BASEBOARD_FAB2(SCH_1):PAGE72
  BH13 PVCCMCP_CPU1 @BASEBOARD_FAB2_LIB.BASEBOARD_FAB2(SCH_1):PVCCMCP_CPU1    I33 @BASEBOARD_FAB2_LIB.BASEBOARD_FAB2(SCH_1):PAGE72
  BJ12 PVCCMCP_CPU1 @BASEBOARD_FAB2_LIB.BASEBOARD_FAB2(SCH_1):PVCCMCP_CPU1    I33 @BASEBOARD_FAB2_LIB.BASEBOARD_FAB2(SCH_1):PAGE72
  BJ14 PVCCMCP_CPU1 @BASEBOARD_FAB2_LIB.BASEBOARD_FAB2(SCH_1):PVCCMCP_CPU1    I33 @BASEBOARD_FAB2_LIB.BASEBOARD_FAB2(SCH_1):PAGE72
  BK13 PVCCMCP_CPU1 @BASEBOARD_FAB2_LIB.BASEBOARD_FAB2(SCH_1):PVCCMCP_CPU1    I33 @BASEBOARD_FAB2_LIB.BASEBOARD_FAB2(SCH_1):PAGE72
  BK15 PVCCMCP_CPU1 @BASEBOARD_FAB2_LIB.BASEBOARD_FAB2(SCH_1):PVCCMCP_CPU1    I33 @BASEBOARD_FAB2_LIB.BASEBOARD_FAB2(SCH_1):PAGE72
  BL14 PVCCMCP_CPU1 @BASEBOARD_FAB2_LIB.BASEBOARD_FAB2(SCH_1):PVCCMCP_CPU1    I33 @BASEBOARD_FAB2_LIB.BASEBOARD_FAB2(SCH_1):PAGE72
    A8 PVPP_GHJ @BASEBOARD_FAB2_LIB.BASEBOARD_FAB2(SCH_1):PVPP_GHJ    I33 @BASEBOARD_FAB2_LIB.BASEBOARD_FAB2(SCH_1):PAGE72
   A10 PVPP_GHJ @BASEBOARD_FAB2_LIB.BASEBOARD_FAB2(SCH_1):PVPP_GHJ    I33 @BASEBOARD_FAB2_LIB.BASEBOARD_FAB2(SCH_1):PAGE72
   A12 PVPP_GHJ @BASEBOARD_FAB2_LIB.BASEBOARD_FAB2(SCH_1):PVPP_GHJ    I33 @BASEBOARD_FAB2_LIB.BASEBOARD_FAB2(SCH_1):PAGE72
   B11 PVPP_GHJ @BASEBOARD_FAB2_LIB.BASEBOARD_FAB2(SCH_1):PVPP_GHJ    I33 @BASEBOARD_FAB2_LIB.BASEBOARD_FAB2(SCH_1):PAGE72
  CY55 P3V3_STBY @BASEBOARD_FAB2_LIB.BASEBOARD_FAB2(SCH_1):P3V3_STBY    I33 @BASEBOARD_FAB2_LIB.BASEBOARD_FAB2(SCH_1):PAGE72
  AR28 PVCCIO_CPU1 @BASEBOARD_FAB2_LIB.BASEBOARD_FAB2(SCH_1):PVCCIO_CPU1    I33 @BASEBOARD_FAB2_LIB.BASEBOARD_FAB2(SCH_1):PAGE72
  AL28 PVCCIO_CPU1 @BASEBOARD_FAB2_LIB.BASEBOARD_FAB2(SCH_1):PVCCIO_CPU1    I33 @BASEBOARD_FAB2_LIB.BASEBOARD_FAB2(SCH_1):PAGE72
  AM29 PVCCIO_CPU1 @BASEBOARD_FAB2_LIB.BASEBOARD_FAB2(SCH_1):PVCCIO_CPU1    I33 @BASEBOARD_FAB2_LIB.BASEBOARD_FAB2(SCH_1):PAGE72
  AG34 PVCCIO_CPU1 @BASEBOARD_FAB2_LIB.BASEBOARD_FAB2(SCH_1):PVCCIO_CPU1    I33 @BASEBOARD_FAB2_LIB.BASEBOARD_FAB2(SCH_1):PAGE72
  AE34 PVCCIO_CPU1 @BASEBOARD_FAB2_LIB.BASEBOARD_FAB2(SCH_1):PVCCIO_CPU1    I33 @BASEBOARD_FAB2_LIB.BASEBOARD_FAB2(SCH_1):PAGE72
  AD35 PVCCIO_CPU1 @BASEBOARD_FAB2_LIB.BASEBOARD_FAB2(SCH_1):PVCCIO_CPU1    I33 @BASEBOARD_FAB2_LIB.BASEBOARD_FAB2(SCH_1):PAGE72
  AF35 PVCCIO_CPU1 @BASEBOARD_FAB2_LIB.BASEBOARD_FAB2(SCH_1):PVCCIO_CPU1    I33 @BASEBOARD_FAB2_LIB.BASEBOARD_FAB2(SCH_1):PAGE72
  AC36 PVCCIO_CPU1 @BASEBOARD_FAB2_LIB.BASEBOARD_FAB2(SCH_1):PVCCIO_CPU1    I33 @BASEBOARD_FAB2_LIB.BASEBOARD_FAB2(SCH_1):PAGE72
  AD37 PVCCIO_CPU1 @BASEBOARD_FAB2_LIB.BASEBOARD_FAB2(SCH_1):PVCCIO_CPU1    I33 @BASEBOARD_FAB2_LIB.BASEBOARD_FAB2(SCH_1):PAGE72
  AE36 PVCCIO_CPU1 @BASEBOARD_FAB2_LIB.BASEBOARD_FAB2(SCH_1):PVCCIO_CPU1    I33 @BASEBOARD_FAB2_LIB.BASEBOARD_FAB2(SCH_1):PAGE72
  BF27 PVCCIO_CPU1 @BASEBOARD_FAB2_LIB.BASEBOARD_FAB2(SCH_1):PVCCIO_CPU1    I33 @BASEBOARD_FAB2_LIB.BASEBOARD_FAB2(SCH_1):PAGE72
  BG26 PVCCIO_CPU1 @BASEBOARD_FAB2_LIB.BASEBOARD_FAB2(SCH_1):PVCCIO_CPU1    I33 @BASEBOARD_FAB2_LIB.BASEBOARD_FAB2(SCH_1):PAGE72
  BH25 PVCCIO_CPU1 @BASEBOARD_FAB2_LIB.BASEBOARD_FAB2(SCH_1):PVCCIO_CPU1    I33 @BASEBOARD_FAB2_LIB.BASEBOARD_FAB2(SCH_1):PAGE72
  BH27 PVCCIO_CPU1 @BASEBOARD_FAB2_LIB.BASEBOARD_FAB2(SCH_1):PVCCIO_CPU1    I33 @BASEBOARD_FAB2_LIB.BASEBOARD_FAB2(SCH_1):PAGE72
  BJ26 PVCCIO_CPU1 @BASEBOARD_FAB2_LIB.BASEBOARD_FAB2(SCH_1):PVCCIO_CPU1    I33 @BASEBOARD_FAB2_LIB.BASEBOARD_FAB2(SCH_1):PAGE72
  BK25 PVCCIO_CPU1 @BASEBOARD_FAB2_LIB.BASEBOARD_FAB2(SCH_1):PVCCIO_CPU1    I33 @BASEBOARD_FAB2_LIB.BASEBOARD_FAB2(SCH_1):PAGE72
  BK27 PVCCIO_CPU1 @BASEBOARD_FAB2_LIB.BASEBOARD_FAB2(SCH_1):PVCCIO_CPU1    I33 @BASEBOARD_FAB2_LIB.BASEBOARD_FAB2(SCH_1):PAGE72
  BL26 PVCCIO_CPU1 @BASEBOARD_FAB2_LIB.BASEBOARD_FAB2(SCH_1):PVCCIO_CPU1    I33 @BASEBOARD_FAB2_LIB.BASEBOARD_FAB2(SCH_1):PAGE72
  BM27 PVCCIO_CPU1 @BASEBOARD_FAB2_LIB.BASEBOARD_FAB2(SCH_1):PVCCIO_CPU1    I33 @BASEBOARD_FAB2_LIB.BASEBOARD_FAB2(SCH_1):PAGE72
  CH27 PVCCIO_CPU1 @BASEBOARD_FAB2_LIB.BASEBOARD_FAB2(SCH_1):PVCCIO_CPU1    I33 @BASEBOARD_FAB2_LIB.BASEBOARD_FAB2(SCH_1):PAGE72
  CJ28 PVCCIO_CPU1 @BASEBOARD_FAB2_LIB.BASEBOARD_FAB2(SCH_1):PVCCIO_CPU1    I33 @BASEBOARD_FAB2_LIB.BASEBOARD_FAB2(SCH_1):PAGE72
  CC26 PVCCIO_CPU1 @BASEBOARD_FAB2_LIB.BASEBOARD_FAB2(SCH_1):PVCCIO_CPU1    I33 @BASEBOARD_FAB2_LIB.BASEBOARD_FAB2(SCH_1):PAGE72
  CD27 PVCCIO_CPU1 @BASEBOARD_FAB2_LIB.BASEBOARD_FAB2(SCH_1):PVCCIO_CPU1    I33 @BASEBOARD_FAB2_LIB.BASEBOARD_FAB2(SCH_1):PAGE72
  CF27 PVCCIO_CPU1 @BASEBOARD_FAB2_LIB.BASEBOARD_FAB2(SCH_1):PVCCIO_CPU1    I33 @BASEBOARD_FAB2_LIB.BASEBOARD_FAB2(SCH_1):PAGE72
  AV27 PVCCIO_CPU1 @BASEBOARD_FAB2_LIB.BASEBOARD_FAB2(SCH_1):PVCCIO_CPU1    I33 @BASEBOARD_FAB2_LIB.BASEBOARD_FAB2(SCH_1):PAGE72
  AW26 PVCCIO_CPU1 @BASEBOARD_FAB2_LIB.BASEBOARD_FAB2(SCH_1):PVCCIO_CPU1    I33 @BASEBOARD_FAB2_LIB.BASEBOARD_FAB2(SCH_1):PAGE72
  AY27 PVCCIO_CPU1 @BASEBOARD_FAB2_LIB.BASEBOARD_FAB2(SCH_1):PVCCIO_CPU1    I33 @BASEBOARD_FAB2_LIB.BASEBOARD_FAB2(SCH_1):PAGE72
  BA26 PVCCIO_CPU1 @BASEBOARD_FAB2_LIB.BASEBOARD_FAB2(SCH_1):PVCCIO_CPU1    I33 @BASEBOARD_FAB2_LIB.BASEBOARD_FAB2(SCH_1):PAGE72
  BB27 PVCCIO_CPU1 @BASEBOARD_FAB2_LIB.BASEBOARD_FAB2(SCH_1):PVCCIO_CPU1    I33 @BASEBOARD_FAB2_LIB.BASEBOARD_FAB2(SCH_1):PAGE72
  BC26 PVCCIO_CPU1 @BASEBOARD_FAB2_LIB.BASEBOARD_FAB2(SCH_1):PVCCIO_CPU1    I33 @BASEBOARD_FAB2_LIB.BASEBOARD_FAB2(SCH_1):PAGE72
   W10 PVCCIO_CPU1 @BASEBOARD_FAB2_LIB.BASEBOARD_FAB2(SCH_1):PVCCIO_CPU1    I33 @BASEBOARD_FAB2_LIB.BASEBOARD_FAB2(SCH_1):PAGE72
   N18 PVCCIO_CPU1 @BASEBOARD_FAB2_LIB.BASEBOARD_FAB2(SCH_1):PVCCIO_CPU1    I33 @BASEBOARD_FAB2_LIB.BASEBOARD_FAB2(SCH_1):PAGE72
    M9 PVCCIO_CPU1 @BASEBOARD_FAB2_LIB.BASEBOARD_FAB2(SCH_1):PVCCIO_CPU1    I33 @BASEBOARD_FAB2_LIB.BASEBOARD_FAB2(SCH_1):PAGE72
    M7 PVCCIO_CPU1 @BASEBOARD_FAB2_LIB.BASEBOARD_FAB2(SCH_1):PVCCIO_CPU1    I33 @BASEBOARD_FAB2_LIB.BASEBOARD_FAB2(SCH_1):PAGE72
   K15 PVCCIO_CPU1 @BASEBOARD_FAB2_LIB.BASEBOARD_FAB2(SCH_1):PVCCIO_CPU1    I33 @BASEBOARD_FAB2_LIB.BASEBOARD_FAB2(SCH_1):PAGE72
    J2 PVCCIO_CPU1 @BASEBOARD_FAB2_LIB.BASEBOARD_FAB2(SCH_1):PVCCIO_CPU1    I33 @BASEBOARD_FAB2_LIB.BASEBOARD_FAB2(SCH_1):PAGE72
  EB15 PVCCIO_CPU1 @BASEBOARD_FAB2_LIB.BASEBOARD_FAB2(SCH_1):PVCCIO_CPU1    I33 @BASEBOARD_FAB2_LIB.BASEBOARD_FAB2(SCH_1):PAGE72
  EA12 PVCCIO_CPU1 @BASEBOARD_FAB2_LIB.BASEBOARD_FAB2(SCH_1):PVCCIO_CPU1    I33 @BASEBOARD_FAB2_LIB.BASEBOARD_FAB2(SCH_1):PAGE72
  DU20 PVCCIO_CPU1 @BASEBOARD_FAB2_LIB.BASEBOARD_FAB2(SCH_1):PVCCIO_CPU1    I33 @BASEBOARD_FAB2_LIB.BASEBOARD_FAB2(SCH_1):PAGE72
   DR2 PVCCIO_CPU1 @BASEBOARD_FAB2_LIB.BASEBOARD_FAB2(SCH_1):PVCCIO_CPU1    I33 @BASEBOARD_FAB2_LIB.BASEBOARD_FAB2(SCH_1):PAGE72
  DR10 PVCCIO_CPU1 @BASEBOARD_FAB2_LIB.BASEBOARD_FAB2(SCH_1):PVCCIO_CPU1    I33 @BASEBOARD_FAB2_LIB.BASEBOARD_FAB2(SCH_1):PAGE72
  DP19 PVCCIO_CPU1 @BASEBOARD_FAB2_LIB.BASEBOARD_FAB2(SCH_1):PVCCIO_CPU1    I33 @BASEBOARD_FAB2_LIB.BASEBOARD_FAB2(SCH_1):PAGE72
   DN8 PVCCIO_CPU1 @BASEBOARD_FAB2_LIB.BASEBOARD_FAB2(SCH_1):PVCCIO_CPU1    I33 @BASEBOARD_FAB2_LIB.BASEBOARD_FAB2(SCH_1):PAGE72
  DM17 PVCCIO_CPU1 @BASEBOARD_FAB2_LIB.BASEBOARD_FAB2(SCH_1):PVCCIO_CPU1    I33 @BASEBOARD_FAB2_LIB.BASEBOARD_FAB2(SCH_1):PAGE72
  DJ16 PVCCIO_CPU1 @BASEBOARD_FAB2_LIB.BASEBOARD_FAB2(SCH_1):PVCCIO_CPU1    I33 @BASEBOARD_FAB2_LIB.BASEBOARD_FAB2(SCH_1):PAGE72
   H13 PVCCIO_CPU1 @BASEBOARD_FAB2_LIB.BASEBOARD_FAB2(SCH_1):PVCCIO_CPU1    I33 @BASEBOARD_FAB2_LIB.BASEBOARD_FAB2(SCH_1):PAGE72
   J10 PVCCIO_CPU1 @BASEBOARD_FAB2_LIB.BASEBOARD_FAB2(SCH_1):PVCCIO_CPU1    I33 @BASEBOARD_FAB2_LIB.BASEBOARD_FAB2(SCH_1):PAGE72
   L14 PVCCIO_CPU1 @BASEBOARD_FAB2_LIB.BASEBOARD_FAB2(SCH_1):PVCCIO_CPU1    I33 @BASEBOARD_FAB2_LIB.BASEBOARD_FAB2(SCH_1):PAGE72
   L16 PVCCIO_CPU1 @BASEBOARD_FAB2_LIB.BASEBOARD_FAB2(SCH_1):PVCCIO_CPU1    I33 @BASEBOARD_FAB2_LIB.BASEBOARD_FAB2(SCH_1):PAGE72
   DH7 PVCCIO_CPU1 @BASEBOARD_FAB2_LIB.BASEBOARD_FAB2(SCH_1):PVCCIO_CPU1    I33 @BASEBOARD_FAB2_LIB.BASEBOARD_FAB2(SCH_1):PAGE72
   DG8 PVCCIO_CPU1 @BASEBOARD_FAB2_LIB.BASEBOARD_FAB2(SCH_1):PVCCIO_CPU1    I33 @BASEBOARD_FAB2_LIB.BASEBOARD_FAB2(SCH_1):PAGE72
   M11 PVCCIO_CPU1 @BASEBOARD_FAB2_LIB.BASEBOARD_FAB2(SCH_1):PVCCIO_CPU1    I33 @BASEBOARD_FAB2_LIB.BASEBOARD_FAB2(SCH_1):PAGE72
   M21 PVCCIO_CPU1 @BASEBOARD_FAB2_LIB.BASEBOARD_FAB2(SCH_1):PVCCIO_CPU1    I33 @BASEBOARD_FAB2_LIB.BASEBOARD_FAB2(SCH_1):PAGE72
    P5 PVCCIO_CPU1 @BASEBOARD_FAB2_LIB.BASEBOARD_FAB2(SCH_1):PVCCIO_CPU1    I33 @BASEBOARD_FAB2_LIB.BASEBOARD_FAB2(SCH_1):PAGE72
    T3 PVCCIO_CPU1 @BASEBOARD_FAB2_LIB.BASEBOARD_FAB2(SCH_1):PVCCIO_CPU1    I33 @BASEBOARD_FAB2_LIB.BASEBOARD_FAB2(SCH_1):PAGE72
   U14 PVCCIO_CPU1 @BASEBOARD_FAB2_LIB.BASEBOARD_FAB2(SCH_1):PVCCIO_CPU1    I33 @BASEBOARD_FAB2_LIB.BASEBOARD_FAB2(SCH_1):PAGE72
  DF21 PVCCIO_CPU1 @BASEBOARD_FAB2_LIB.BASEBOARD_FAB2(SCH_1):PVCCIO_CPU1    I33 @BASEBOARD_FAB2_LIB.BASEBOARD_FAB2(SCH_1):PAGE72
    W4 PVCCIO_CPU1 @BASEBOARD_FAB2_LIB.BASEBOARD_FAB2(SCH_1):PVCCIO_CPU1    I33 @BASEBOARD_FAB2_LIB.BASEBOARD_FAB2(SCH_1):PAGE72
    W6 PVCCIO_CPU1 @BASEBOARD_FAB2_LIB.BASEBOARD_FAB2(SCH_1):PVCCIO_CPU1    I33 @BASEBOARD_FAB2_LIB.BASEBOARD_FAB2(SCH_1):PAGE72
  AA10 PVCCIO_CPU1 @BASEBOARD_FAB2_LIB.BASEBOARD_FAB2(SCH_1):PVCCIO_CPU1    I33 @BASEBOARD_FAB2_LIB.BASEBOARD_FAB2(SCH_1):PAGE72
  AC20 PVCCIO_CPU1 @BASEBOARD_FAB2_LIB.BASEBOARD_FAB2(SCH_1):PVCCIO_CPU1    I33 @BASEBOARD_FAB2_LIB.BASEBOARD_FAB2(SCH_1):PAGE72
   AC4 PVCCIO_CPU1 @BASEBOARD_FAB2_LIB.BASEBOARD_FAB2(SCH_1):PVCCIO_CPU1    I33 @BASEBOARD_FAB2_LIB.BASEBOARD_FAB2(SCH_1):PAGE72
   AH9 PVCCIO_CPU1 @BASEBOARD_FAB2_LIB.BASEBOARD_FAB2(SCH_1):PVCCIO_CPU1    I33 @BASEBOARD_FAB2_LIB.BASEBOARD_FAB2(SCH_1):PAGE72
  DF13 PVCCIO_CPU1 @BASEBOARD_FAB2_LIB.BASEBOARD_FAB2(SCH_1):PVCCIO_CPU1    I33 @BASEBOARD_FAB2_LIB.BASEBOARD_FAB2(SCH_1):PAGE72
  AN10 PVCCIO_CPU1 @BASEBOARD_FAB2_LIB.BASEBOARD_FAB2(SCH_1):PVCCIO_CPU1    I33 @BASEBOARD_FAB2_LIB.BASEBOARD_FAB2(SCH_1):PAGE72
   DD7 PVCCIO_CPU1 @BASEBOARD_FAB2_LIB.BASEBOARD_FAB2(SCH_1):PVCCIO_CPU1    I33 @BASEBOARD_FAB2_LIB.BASEBOARD_FAB2(SCH_1):PAGE72
  AT11 PVCCIO_CPU1 @BASEBOARD_FAB2_LIB.BASEBOARD_FAB2(SCH_1):PVCCIO_CPU1    I33 @BASEBOARD_FAB2_LIB.BASEBOARD_FAB2(SCH_1):PAGE72
   AW6 PVCCIO_CPU1 @BASEBOARD_FAB2_LIB.BASEBOARD_FAB2(SCH_1):PVCCIO_CPU1    I33 @BASEBOARD_FAB2_LIB.BASEBOARD_FAB2(SCH_1):PAGE72
  AY11 PVCCIO_CPU1 @BASEBOARD_FAB2_LIB.BASEBOARD_FAB2(SCH_1):PVCCIO_CPU1    I33 @BASEBOARD_FAB2_LIB.BASEBOARD_FAB2(SCH_1):PAGE72
  BA24 PVCCIO_CPU1 @BASEBOARD_FAB2_LIB.BASEBOARD_FAB2(SCH_1):PVCCIO_CPU1    I33 @BASEBOARD_FAB2_LIB.BASEBOARD_FAB2(SCH_1):PAGE72
   BB5 PVCCIO_CPU1 @BASEBOARD_FAB2_LIB.BASEBOARD_FAB2(SCH_1):PVCCIO_CPU1    I33 @BASEBOARD_FAB2_LIB.BASEBOARD_FAB2(SCH_1):PAGE72
  DA14 PVCCIO_CPU1 @BASEBOARD_FAB2_LIB.BASEBOARD_FAB2(SCH_1):PVCCIO_CPU1    I33 @BASEBOARD_FAB2_LIB.BASEBOARD_FAB2(SCH_1):PAGE72
  BF23 PVCCIO_CPU1 @BASEBOARD_FAB2_LIB.BASEBOARD_FAB2(SCH_1):PVCCIO_CPU1    I33 @BASEBOARD_FAB2_LIB.BASEBOARD_FAB2(SCH_1):PAGE72
  BJ24 PVCCIO_CPU1 @BASEBOARD_FAB2_LIB.BASEBOARD_FAB2(SCH_1):PVCCIO_CPU1    I33 @BASEBOARD_FAB2_LIB.BASEBOARD_FAB2(SCH_1):PAGE72
  BP25 PVCCIO_CPU1 @BASEBOARD_FAB2_LIB.BASEBOARD_FAB2(SCH_1):PVCCIO_CPU1    I33 @BASEBOARD_FAB2_LIB.BASEBOARD_FAB2(SCH_1):PAGE72
  CB13 PVCCIO_CPU1 @BASEBOARD_FAB2_LIB.BASEBOARD_FAB2(SCH_1):PVCCIO_CPU1    I33 @BASEBOARD_FAB2_LIB.BASEBOARD_FAB2(SCH_1):PAGE72
  CB17 PVCCIO_CPU1 @BASEBOARD_FAB2_LIB.BASEBOARD_FAB2(SCH_1):PVCCIO_CPU1    I33 @BASEBOARD_FAB2_LIB.BASEBOARD_FAB2(SCH_1):PAGE72
   CD9 PVCCIO_CPU1 @BASEBOARD_FAB2_LIB.BASEBOARD_FAB2(SCH_1):PVCCIO_CPU1    I33 @BASEBOARD_FAB2_LIB.BASEBOARD_FAB2(SCH_1):PAGE72
  CE18 PVCCIO_CPU1 @BASEBOARD_FAB2_LIB.BASEBOARD_FAB2(SCH_1):PVCCIO_CPU1    I33 @BASEBOARD_FAB2_LIB.BASEBOARD_FAB2(SCH_1):PAGE72
    D7 PVCCIO_CPU1 @BASEBOARD_FAB2_LIB.BASEBOARD_FAB2(SCH_1):PVCCIO_CPU1    I33 @BASEBOARD_FAB2_LIB.BASEBOARD_FAB2(SCH_1):PAGE72
   CH9 PVCCIO_CPU1 @BASEBOARD_FAB2_LIB.BASEBOARD_FAB2(SCH_1):PVCCIO_CPU1    I33 @BASEBOARD_FAB2_LIB.BASEBOARD_FAB2(SCH_1):PAGE72
   CV7 PVCCIO_CPU1 @BASEBOARD_FAB2_LIB.BASEBOARD_FAB2(SCH_1):PVCCIO_CPU1    I33 @BASEBOARD_FAB2_LIB.BASEBOARD_FAB2(SCH_1):PAGE72
   CK5 PVCCIO_CPU1 @BASEBOARD_FAB2_LIB.BASEBOARD_FAB2(SCH_1):PVCCIO_CPU1    I33 @BASEBOARD_FAB2_LIB.BASEBOARD_FAB2(SCH_1):PAGE72
  CL12 PVCCIO_CPU1 @BASEBOARD_FAB2_LIB.BASEBOARD_FAB2(SCH_1):PVCCIO_CPU1    I33 @BASEBOARD_FAB2_LIB.BASEBOARD_FAB2(SCH_1):PAGE72
  CM15 PVCCIO_CPU1 @BASEBOARD_FAB2_LIB.BASEBOARD_FAB2(SCH_1):PVCCIO_CPU1    I33 @BASEBOARD_FAB2_LIB.BASEBOARD_FAB2(SCH_1):PAGE72
  CB65 PVSA_CPU1 @BASEBOARD_FAB2_LIB.BASEBOARD_FAB2(SCH_1):PVSA_CPU1    I33 @BASEBOARD_FAB2_LIB.BASEBOARD_FAB2(SCH_1):PAGE72
  CB67 PVSA_CPU1 @BASEBOARD_FAB2_LIB.BASEBOARD_FAB2(SCH_1):PVSA_CPU1    I33 @BASEBOARD_FAB2_LIB.BASEBOARD_FAB2(SCH_1):PAGE72
  CB69 PVSA_CPU1 @BASEBOARD_FAB2_LIB.BASEBOARD_FAB2(SCH_1):PVSA_CPU1    I33 @BASEBOARD_FAB2_LIB.BASEBOARD_FAB2(SCH_1):PAGE72
  CC66 PVSA_CPU1 @BASEBOARD_FAB2_LIB.BASEBOARD_FAB2(SCH_1):PVSA_CPU1    I33 @BASEBOARD_FAB2_LIB.BASEBOARD_FAB2(SCH_1):PAGE72
  CC68 PVSA_CPU1 @BASEBOARD_FAB2_LIB.BASEBOARD_FAB2(SCH_1):PVSA_CPU1    I33 @BASEBOARD_FAB2_LIB.BASEBOARD_FAB2(SCH_1):PAGE72
  CC70 PVSA_CPU1 @BASEBOARD_FAB2_LIB.BASEBOARD_FAB2(SCH_1):PVSA_CPU1    I33 @BASEBOARD_FAB2_LIB.BASEBOARD_FAB2(SCH_1):PAGE72
  CD65 PVSA_CPU1 @BASEBOARD_FAB2_LIB.BASEBOARD_FAB2(SCH_1):PVSA_CPU1    I33 @BASEBOARD_FAB2_LIB.BASEBOARD_FAB2(SCH_1):PAGE72
  CD67 PVSA_CPU1 @BASEBOARD_FAB2_LIB.BASEBOARD_FAB2(SCH_1):PVSA_CPU1    I33 @BASEBOARD_FAB2_LIB.BASEBOARD_FAB2(SCH_1):PAGE72
  CD69 PVSA_CPU1 @BASEBOARD_FAB2_LIB.BASEBOARD_FAB2(SCH_1):PVSA_CPU1    I33 @BASEBOARD_FAB2_LIB.BASEBOARD_FAB2(SCH_1):PAGE72
  CD71 PVSA_CPU1 @BASEBOARD_FAB2_LIB.BASEBOARD_FAB2(SCH_1):PVSA_CPU1    I33 @BASEBOARD_FAB2_LIB.BASEBOARD_FAB2(SCH_1):PAGE72
  CE64 PVSA_CPU1 @BASEBOARD_FAB2_LIB.BASEBOARD_FAB2(SCH_1):PVSA_CPU1    I33 @BASEBOARD_FAB2_LIB.BASEBOARD_FAB2(SCH_1):PAGE72
  CE66 PVSA_CPU1 @BASEBOARD_FAB2_LIB.BASEBOARD_FAB2(SCH_1):PVSA_CPU1    I33 @BASEBOARD_FAB2_LIB.BASEBOARD_FAB2(SCH_1):PAGE72
  CE68 PVSA_CPU1 @BASEBOARD_FAB2_LIB.BASEBOARD_FAB2(SCH_1):PVSA_CPU1    I33 @BASEBOARD_FAB2_LIB.BASEBOARD_FAB2(SCH_1):PAGE72
  CE72 PVSA_CPU1 @BASEBOARD_FAB2_LIB.BASEBOARD_FAB2(SCH_1):PVSA_CPU1    I33 @BASEBOARD_FAB2_LIB.BASEBOARD_FAB2(SCH_1):PAGE72
  CE74 PVSA_CPU1 @BASEBOARD_FAB2_LIB.BASEBOARD_FAB2(SCH_1):PVSA_CPU1    I33 @BASEBOARD_FAB2_LIB.BASEBOARD_FAB2(SCH_1):PAGE72
  CF65 PVSA_CPU1 @BASEBOARD_FAB2_LIB.BASEBOARD_FAB2(SCH_1):PVSA_CPU1    I33 @BASEBOARD_FAB2_LIB.BASEBOARD_FAB2(SCH_1):PAGE72
  CF67 PVSA_CPU1 @BASEBOARD_FAB2_LIB.BASEBOARD_FAB2(SCH_1):PVSA_CPU1    I33 @BASEBOARD_FAB2_LIB.BASEBOARD_FAB2(SCH_1):PAGE72
  CF73 PVSA_CPU1 @BASEBOARD_FAB2_LIB.BASEBOARD_FAB2(SCH_1):PVSA_CPU1    I33 @BASEBOARD_FAB2_LIB.BASEBOARD_FAB2(SCH_1):PAGE72
  CF75 PVSA_CPU1 @BASEBOARD_FAB2_LIB.BASEBOARD_FAB2(SCH_1):PVSA_CPU1    I33 @BASEBOARD_FAB2_LIB.BASEBOARD_FAB2(SCH_1):PAGE72
  CG64 PVSA_CPU1 @BASEBOARD_FAB2_LIB.BASEBOARD_FAB2(SCH_1):PVSA_CPU1    I33 @BASEBOARD_FAB2_LIB.BASEBOARD_FAB2(SCH_1):PAGE72
  CG66 PVSA_CPU1 @BASEBOARD_FAB2_LIB.BASEBOARD_FAB2(SCH_1):PVSA_CPU1    I33 @BASEBOARD_FAB2_LIB.BASEBOARD_FAB2(SCH_1):PAGE72
  CG74 PVSA_CPU1 @BASEBOARD_FAB2_LIB.BASEBOARD_FAB2(SCH_1):PVSA_CPU1    I33 @BASEBOARD_FAB2_LIB.BASEBOARD_FAB2(SCH_1):PAGE72
  CH65 PVSA_CPU1 @BASEBOARD_FAB2_LIB.BASEBOARD_FAB2(SCH_1):PVSA_CPU1    I33 @BASEBOARD_FAB2_LIB.BASEBOARD_FAB2(SCH_1):PAGE72
  CH75 PVSA_CPU1 @BASEBOARD_FAB2_LIB.BASEBOARD_FAB2(SCH_1):PVSA_CPU1    I33 @BASEBOARD_FAB2_LIB.BASEBOARD_FAB2(SCH_1):PAGE72
  CJ64 PVSA_CPU1 @BASEBOARD_FAB2_LIB.BASEBOARD_FAB2(SCH_1):PVSA_CPU1    I33 @BASEBOARD_FAB2_LIB.BASEBOARD_FAB2(SCH_1):PAGE72
  CJ66 PVSA_CPU1 @BASEBOARD_FAB2_LIB.BASEBOARD_FAB2(SCH_1):PVSA_CPU1    I33 @BASEBOARD_FAB2_LIB.BASEBOARD_FAB2(SCH_1):PAGE72
  BT17 VSENSE_PVCCIOMCP_CPU1_SKT_VSEN @BASEBOARD_FAB2_LIB.BASEBOARD_FAB2(SCH_1):VSENSE_PVCCIOMCP_CPU1_SKT_VSEN   I107 @BASEBOARD_FAB2_LIB.BASEBOARD_FAB2(SCH_1):PAGE73
  BU16 VSENSE_PVCCIOMCP_CPU1_SKT_VRTN @BASEBOARD_FAB2_LIB.BASEBOARD_FAB2(SCH_1):VSENSE_PVCCIOMCP_CPU1_SKT_VRTN   I107 @BASEBOARD_FAB2_LIB.BASEBOARD_FAB2(SCH_1):PAGE73
  BN16 VSENSE_PVCCMCP_CPU1_SKT_VSEN @BASEBOARD_FAB2_LIB.BASEBOARD_FAB2(SCH_1):VSENSE_PVCCMCP_CPU1_SKT_VSEN   I107 @BASEBOARD_FAB2_LIB.BASEBOARD_FAB2(SCH_1):PAGE73
  BL16 VSENSE_PVCCMCP_CPU1_SKT_VRTN @BASEBOARD_FAB2_LIB.BASEBOARD_FAB2(SCH_1):VSENSE_PVCCMCP_CPU1_SKT_VRTN   I107 @BASEBOARD_FAB2_LIB.BASEBOARD_FAB2(SCH_1):PAGE73
  CL26 PVCCMCP_CPU1 @BASEBOARD_FAB2_LIB.BASEBOARD_FAB2(SCH_1):PVCCMCP_CPU1   I107 @BASEBOARD_FAB2_LIB.BASEBOARD_FAB2(SCH_1):PAGE73
  CM23 PVCCMCP_CPU1 @BASEBOARD_FAB2_LIB.BASEBOARD_FAB2(SCH_1):PVCCMCP_CPU1   I107 @BASEBOARD_FAB2_LIB.BASEBOARD_FAB2(SCH_1):PAGE73
  CM25 PVCCMCP_CPU1 @BASEBOARD_FAB2_LIB.BASEBOARD_FAB2(SCH_1):PVCCMCP_CPU1   I107 @BASEBOARD_FAB2_LIB.BASEBOARD_FAB2(SCH_1):PAGE73
  CN22 TP_CPU1_KTI2_AMONV @BASEBOARD_FAB2_LIB.BASEBOARD_FAB2(SCH_1):TP_CPU1_KTI2_AMONV   I107 @BASEBOARD_FAB2_LIB.BASEBOARD_FAB2(SCH_1):PAGE73
  CN24 PVCCMCP_CPU1 @BASEBOARD_FAB2_LIB.BASEBOARD_FAB2(SCH_1):PVCCMCP_CPU1   I107 @BASEBOARD_FAB2_LIB.BASEBOARD_FAB2(SCH_1):PAGE73
  CN28 PD_CPU1_MCP01_DMON @BASEBOARD_FAB2_LIB.BASEBOARD_FAB2(SCH_1):PD_CPU1_MCP01_DMON   I107 @BASEBOARD_FAB2_LIB.BASEBOARD_FAB2(SCH_1):PAGE73
  CP23 PVCCMCP_CPU1 @BASEBOARD_FAB2_LIB.BASEBOARD_FAB2(SCH_1):PVCCMCP_CPU1   I107 @BASEBOARD_FAB2_LIB.BASEBOARD_FAB2(SCH_1):PAGE73
  CP31 TP_CPU1_RSVD_73 @BASEBOARD_FAB2_LIB.BASEBOARD_FAB2(SCH_1):TP_CPU1_RSVD_73   I107 @BASEBOARD_FAB2_LIB.BASEBOARD_FAB2(SCH_1):PAGE73
  CR60 TP_CPU1_RSVD_72 @BASEBOARD_FAB2_LIB.BASEBOARD_FAB2(SCH_1):TP_CPU1_RSVD_72   I107 @BASEBOARD_FAB2_LIB.BASEBOARD_FAB2(SCH_1):PAGE73
  CT23 PVCCMCP_CPU1 @BASEBOARD_FAB2_LIB.BASEBOARD_FAB2(SCH_1):PVCCMCP_CPU1   I107 @BASEBOARD_FAB2_LIB.BASEBOARD_FAB2(SCH_1):PAGE73
   CT5 TP_CPU1_RSVD_70 @BASEBOARD_FAB2_LIB.BASEBOARD_FAB2(SCH_1):TP_CPU1_RSVD_70   I107 @BASEBOARD_FAB2_LIB.BASEBOARD_FAB2(SCH_1):PAGE73
  CT69 TP_CPU1_RSVD_69 @BASEBOARD_FAB2_LIB.BASEBOARD_FAB2(SCH_1):TP_CPU1_RSVD_69   I107 @BASEBOARD_FAB2_LIB.BASEBOARD_FAB2(SCH_1):PAGE73
  CU24 PVCCMCP_CPU1 @BASEBOARD_FAB2_LIB.BASEBOARD_FAB2(SCH_1):PVCCMCP_CPU1   I107 @BASEBOARD_FAB2_LIB.BASEBOARD_FAB2(SCH_1):PAGE73
   CU6 TP_CPU1_RSVD_67 @BASEBOARD_FAB2_LIB.BASEBOARD_FAB2(SCH_1):TP_CPU1_RSVD_67   I107 @BASEBOARD_FAB2_LIB.BASEBOARD_FAB2(SCH_1):PAGE73
  CU60 TP_CPU1_RSVD_66 @BASEBOARD_FAB2_LIB.BASEBOARD_FAB2(SCH_1):TP_CPU1_RSVD_66   I107 @BASEBOARD_FAB2_LIB.BASEBOARD_FAB2(SCH_1):PAGE73
  CV23 PVCCMCP_CPU1 @BASEBOARD_FAB2_LIB.BASEBOARD_FAB2(SCH_1):PVCCMCP_CPU1   I107 @BASEBOARD_FAB2_LIB.BASEBOARD_FAB2(SCH_1):PAGE73
  CV69 TP_CPU1_RSVD_64 @BASEBOARD_FAB2_LIB.BASEBOARD_FAB2(SCH_1):TP_CPU1_RSVD_64   I107 @BASEBOARD_FAB2_LIB.BASEBOARD_FAB2(SCH_1):PAGE73
  CW22 TP_CPU1_KTI2_DFX_DN @BASEBOARD_FAB2_LIB.BASEBOARD_FAB2(SCH_1):TP_CPU1_KTI2_DFX_DN   I107 @BASEBOARD_FAB2_LIB.BASEBOARD_FAB2(SCH_1):PAGE73
  CW24 PVCCMCP_CPU1 @BASEBOARD_FAB2_LIB.BASEBOARD_FAB2(SCH_1):PVCCMCP_CPU1   I107 @BASEBOARD_FAB2_LIB.BASEBOARD_FAB2(SCH_1):PAGE73
  CW60 TP_CPU1_RSVD_61 @BASEBOARD_FAB2_LIB.BASEBOARD_FAB2(SCH_1):TP_CPU1_RSVD_61   I107 @BASEBOARD_FAB2_LIB.BASEBOARD_FAB2(SCH_1):PAGE73
  CW62 TP_CPU1_RSVD_60 @BASEBOARD_FAB2_LIB.BASEBOARD_FAB2(SCH_1):TP_CPU1_RSVD_60   I107 @BASEBOARD_FAB2_LIB.BASEBOARD_FAB2(SCH_1):PAGE73
  CY23 TP_CPU1_RSVD_59 @BASEBOARD_FAB2_LIB.BASEBOARD_FAB2(SCH_1):TP_CPU1_RSVD_59   I107 @BASEBOARD_FAB2_LIB.BASEBOARD_FAB2(SCH_1):PAGE73
  CY25 PVCCMCP_CPU1 @BASEBOARD_FAB2_LIB.BASEBOARD_FAB2(SCH_1):PVCCMCP_CPU1   I107 @BASEBOARD_FAB2_LIB.BASEBOARD_FAB2(SCH_1):PAGE73
  CY39 TP_CPU1_RSVD_57 @BASEBOARD_FAB2_LIB.BASEBOARD_FAB2(SCH_1):TP_CPU1_RSVD_57   I107 @BASEBOARD_FAB2_LIB.BASEBOARD_FAB2(SCH_1):PAGE73
  CY53 TP_CPU1_RSVD_56 @BASEBOARD_FAB2_LIB.BASEBOARD_FAB2(SCH_1):TP_CPU1_RSVD_56   I107 @BASEBOARD_FAB2_LIB.BASEBOARD_FAB2(SCH_1):PAGE73
  CY57 TP_CPU1_RSVD_55 @BASEBOARD_FAB2_LIB.BASEBOARD_FAB2(SCH_1):TP_CPU1_RSVD_55   I107 @BASEBOARD_FAB2_LIB.BASEBOARD_FAB2(SCH_1):PAGE73
  CY63 TP_CPU1_RSVD_54 @BASEBOARD_FAB2_LIB.BASEBOARD_FAB2(SCH_1):TP_CPU1_RSVD_54   I107 @BASEBOARD_FAB2_LIB.BASEBOARD_FAB2(SCH_1):PAGE73
  CY73 TP_CPU1_RSVD_53 @BASEBOARD_FAB2_LIB.BASEBOARD_FAB2(SCH_1):TP_CPU1_RSVD_53   I107 @BASEBOARD_FAB2_LIB.BASEBOARD_FAB2(SCH_1):PAGE73
  DA24 PVCCMCP_CPU1 @BASEBOARD_FAB2_LIB.BASEBOARD_FAB2(SCH_1):PVCCMCP_CPU1   I107 @BASEBOARD_FAB2_LIB.BASEBOARD_FAB2(SCH_1):PAGE73
  DA40 TP_CPU1_RSVD_51 @BASEBOARD_FAB2_LIB.BASEBOARD_FAB2(SCH_1):TP_CPU1_RSVD_51   I107 @BASEBOARD_FAB2_LIB.BASEBOARD_FAB2(SCH_1):PAGE73
  DA52 TP_CPU1_RSVD_50 @BASEBOARD_FAB2_LIB.BASEBOARD_FAB2(SCH_1):TP_CPU1_RSVD_50   I107 @BASEBOARD_FAB2_LIB.BASEBOARD_FAB2(SCH_1):PAGE73
  DA54 TP_CPU1_RSVD_49 @BASEBOARD_FAB2_LIB.BASEBOARD_FAB2(SCH_1):TP_CPU1_RSVD_49   I107 @BASEBOARD_FAB2_LIB.BASEBOARD_FAB2(SCH_1):PAGE73
  DA56 TP_CPU1_RSVD_48 @BASEBOARD_FAB2_LIB.BASEBOARD_FAB2(SCH_1):TP_CPU1_RSVD_48   I107 @BASEBOARD_FAB2_LIB.BASEBOARD_FAB2(SCH_1):PAGE73
  DC46 TP_CPU1_RSVD_47 @BASEBOARD_FAB2_LIB.BASEBOARD_FAB2(SCH_1):TP_CPU1_RSVD_47   I107 @BASEBOARD_FAB2_LIB.BASEBOARD_FAB2(SCH_1):PAGE73
  DC52 TP_CPU1_RSVD_46 @BASEBOARD_FAB2_LIB.BASEBOARD_FAB2(SCH_1):TP_CPU1_RSVD_46   I107 @BASEBOARD_FAB2_LIB.BASEBOARD_FAB2(SCH_1):PAGE73
  DD51 TP_CPU1_RSVD_45 @BASEBOARD_FAB2_LIB.BASEBOARD_FAB2(SCH_1):TP_CPU1_RSVD_45   I107 @BASEBOARD_FAB2_LIB.BASEBOARD_FAB2(SCH_1):PAGE73
  DG36 TP_CPU1_RSVD_44 @BASEBOARD_FAB2_LIB.BASEBOARD_FAB2(SCH_1):TP_CPU1_RSVD_44   I107 @BASEBOARD_FAB2_LIB.BASEBOARD_FAB2(SCH_1):PAGE73
  DG64 TP_CPU1_RSVD_43 @BASEBOARD_FAB2_LIB.BASEBOARD_FAB2(SCH_1):TP_CPU1_RSVD_43   I107 @BASEBOARD_FAB2_LIB.BASEBOARD_FAB2(SCH_1):PAGE73
  DH65 TP_CPU1_RSVD_42 @BASEBOARD_FAB2_LIB.BASEBOARD_FAB2(SCH_1):TP_CPU1_RSVD_42   I107 @BASEBOARD_FAB2_LIB.BASEBOARD_FAB2(SCH_1):PAGE73
  DJ36 TP_CPU1_RSVD_41 @BASEBOARD_FAB2_LIB.BASEBOARD_FAB2(SCH_1):TP_CPU1_RSVD_41   I107 @BASEBOARD_FAB2_LIB.BASEBOARD_FAB2(SCH_1):PAGE73
  DJ66 TP_CPU1_RSVD_40 @BASEBOARD_FAB2_LIB.BASEBOARD_FAB2(SCH_1):TP_CPU1_RSVD_40   I107 @BASEBOARD_FAB2_LIB.BASEBOARD_FAB2(SCH_1):PAGE73
  DK15 TP_CPU1_RSVD_39 @BASEBOARD_FAB2_LIB.BASEBOARD_FAB2(SCH_1):TP_CPU1_RSVD_39   I107 @BASEBOARD_FAB2_LIB.BASEBOARD_FAB2(SCH_1):PAGE73
  DK37 TP_CPU1_RSVD_38 @BASEBOARD_FAB2_LIB.BASEBOARD_FAB2(SCH_1):TP_CPU1_RSVD_38   I107 @BASEBOARD_FAB2_LIB.BASEBOARD_FAB2(SCH_1):PAGE73
  DK65 TP_CPU1_RSVD_37 @BASEBOARD_FAB2_LIB.BASEBOARD_FAB2(SCH_1):TP_CPU1_RSVD_37   I107 @BASEBOARD_FAB2_LIB.BASEBOARD_FAB2(SCH_1):PAGE73
  DK67 TP_CPU1_RSVD_36 @BASEBOARD_FAB2_LIB.BASEBOARD_FAB2(SCH_1):TP_CPU1_RSVD_36   I107 @BASEBOARD_FAB2_LIB.BASEBOARD_FAB2(SCH_1):PAGE73
  DL38 TP_CPU1_RSVD_35 @BASEBOARD_FAB2_LIB.BASEBOARD_FAB2(SCH_1):TP_CPU1_RSVD_35   I107 @BASEBOARD_FAB2_LIB.BASEBOARD_FAB2(SCH_1):PAGE73
  DL66 TP_CPU1_RSVD_34 @BASEBOARD_FAB2_LIB.BASEBOARD_FAB2(SCH_1):TP_CPU1_RSVD_34   I107 @BASEBOARD_FAB2_LIB.BASEBOARD_FAB2(SCH_1):PAGE73
  DM67 TP_CPU1_RSVD_33 @BASEBOARD_FAB2_LIB.BASEBOARD_FAB2(SCH_1):TP_CPU1_RSVD_33   I107 @BASEBOARD_FAB2_LIB.BASEBOARD_FAB2(SCH_1):PAGE73
  DN62 TP_CPU1_RSVD_32 @BASEBOARD_FAB2_LIB.BASEBOARD_FAB2(SCH_1):TP_CPU1_RSVD_32   I107 @BASEBOARD_FAB2_LIB.BASEBOARD_FAB2(SCH_1):PAGE73
  DN66 TP_CPU1_RSVD_31 @BASEBOARD_FAB2_LIB.BASEBOARD_FAB2(SCH_1):TP_CPU1_RSVD_31   I107 @BASEBOARD_FAB2_LIB.BASEBOARD_FAB2(SCH_1):PAGE73
  DP17 TP_CPU1_RSVD_30 @BASEBOARD_FAB2_LIB.BASEBOARD_FAB2(SCH_1):TP_CPU1_RSVD_30   I107 @BASEBOARD_FAB2_LIB.BASEBOARD_FAB2(SCH_1):PAGE73
  DP65 TP_CPU1_RSVD_29 @BASEBOARD_FAB2_LIB.BASEBOARD_FAB2(SCH_1):TP_CPU1_RSVD_29   I107 @BASEBOARD_FAB2_LIB.BASEBOARD_FAB2(SCH_1):PAGE73
  DR44 TP_CPU1_RSVD_28 @BASEBOARD_FAB2_LIB.BASEBOARD_FAB2(SCH_1):TP_CPU1_RSVD_28   I107 @BASEBOARD_FAB2_LIB.BASEBOARD_FAB2(SCH_1):PAGE73
  DT71 TP_CPU1_RSVD_27 @BASEBOARD_FAB2_LIB.BASEBOARD_FAB2(SCH_1):TP_CPU1_RSVD_27   I107 @BASEBOARD_FAB2_LIB.BASEBOARD_FAB2(SCH_1):PAGE73
  DU44 TP_CPU1_RSVD_26 @BASEBOARD_FAB2_LIB.BASEBOARD_FAB2(SCH_1):TP_CPU1_RSVD_26   I107 @BASEBOARD_FAB2_LIB.BASEBOARD_FAB2(SCH_1):PAGE73
  DV61 TP_CPU1_RSVD_25 @BASEBOARD_FAB2_LIB.BASEBOARD_FAB2(SCH_1):TP_CPU1_RSVD_25   I107 @BASEBOARD_FAB2_LIB.BASEBOARD_FAB2(SCH_1):PAGE73
  DV71 TP_CPU1_RSVD_24 @BASEBOARD_FAB2_LIB.BASEBOARD_FAB2(SCH_1):TP_CPU1_RSVD_24   I107 @BASEBOARD_FAB2_LIB.BASEBOARD_FAB2(SCH_1):PAGE73
  DW44 TP_CPU1_RSVD_23 @BASEBOARD_FAB2_LIB.BASEBOARD_FAB2(SCH_1):TP_CPU1_RSVD_23   I107 @BASEBOARD_FAB2_LIB.BASEBOARD_FAB2(SCH_1):PAGE73
  DW46 TP_CPU1_RSVD_22 @BASEBOARD_FAB2_LIB.BASEBOARD_FAB2(SCH_1):TP_CPU1_RSVD_22   I107 @BASEBOARD_FAB2_LIB.BASEBOARD_FAB2(SCH_1):PAGE73
   DY3 TP_CPU1_RSVD_21 @BASEBOARD_FAB2_LIB.BASEBOARD_FAB2(SCH_1):TP_CPU1_RSVD_21   I107 @BASEBOARD_FAB2_LIB.BASEBOARD_FAB2(SCH_1):PAGE73
   EA4 TP_CPU1_RSVD_20 @BASEBOARD_FAB2_LIB.BASEBOARD_FAB2(SCH_1):TP_CPU1_RSVD_20   I107 @BASEBOARD_FAB2_LIB.BASEBOARD_FAB2(SCH_1):PAGE73
  EA44 TP_CPU1_RSVD_19 @BASEBOARD_FAB2_LIB.BASEBOARD_FAB2(SCH_1):TP_CPU1_RSVD_19   I107 @BASEBOARD_FAB2_LIB.BASEBOARD_FAB2(SCH_1):PAGE73
   EB3 TP_CPU1_RSVD_18 @BASEBOARD_FAB2_LIB.BASEBOARD_FAB2(SCH_1):TP_CPU1_RSVD_18   I107 @BASEBOARD_FAB2_LIB.BASEBOARD_FAB2(SCH_1):PAGE73
   EB5 TP_CPU1_RSVD_17 @BASEBOARD_FAB2_LIB.BASEBOARD_FAB2(SCH_1):TP_CPU1_RSVD_17   I107 @BASEBOARD_FAB2_LIB.BASEBOARD_FAB2(SCH_1):PAGE73
  EB85 TP_CPU1_RSVD_16 @BASEBOARD_FAB2_LIB.BASEBOARD_FAB2(SCH_1):TP_CPU1_RSVD_16   I107 @BASEBOARD_FAB2_LIB.BASEBOARD_FAB2(SCH_1):PAGE73
  EC16 TP_CPU1_RSVD_15 @BASEBOARD_FAB2_LIB.BASEBOARD_FAB2(SCH_1):TP_CPU1_RSVD_15   I107 @BASEBOARD_FAB2_LIB.BASEBOARD_FAB2(SCH_1):PAGE73
   EC4 TP_CPU1_RSVD_14 @BASEBOARD_FAB2_LIB.BASEBOARD_FAB2(SCH_1):TP_CPU1_RSVD_14   I107 @BASEBOARD_FAB2_LIB.BASEBOARD_FAB2(SCH_1):PAGE73
  EC44 TP_CPU1_RSVD_13 @BASEBOARD_FAB2_LIB.BASEBOARD_FAB2(SCH_1):TP_CPU1_RSVD_13   I107 @BASEBOARD_FAB2_LIB.BASEBOARD_FAB2(SCH_1):PAGE73
  EC84 TP_CPU1_RSVD_12 @BASEBOARD_FAB2_LIB.BASEBOARD_FAB2(SCH_1):TP_CPU1_RSVD_12   I107 @BASEBOARD_FAB2_LIB.BASEBOARD_FAB2(SCH_1):PAGE73
  ED45 TP_CPU1_RSVD_11 @BASEBOARD_FAB2_LIB.BASEBOARD_FAB2(SCH_1):TP_CPU1_RSVD_11   I107 @BASEBOARD_FAB2_LIB.BASEBOARD_FAB2(SCH_1):PAGE73
   ED5 TP_CPU1_RSVD_10 @BASEBOARD_FAB2_LIB.BASEBOARD_FAB2(SCH_1):TP_CPU1_RSVD_10   I107 @BASEBOARD_FAB2_LIB.BASEBOARD_FAB2(SCH_1):PAGE73
  ED83 TP_CPU1_RSVD_9 @BASEBOARD_FAB2_LIB.BASEBOARD_FAB2(SCH_1):TP_CPU1_RSVD_9   I107 @BASEBOARD_FAB2_LIB.BASEBOARD_FAB2(SCH_1):PAGE73
  EE16 TP_CPU1_RSVD_8 @BASEBOARD_FAB2_LIB.BASEBOARD_FAB2(SCH_1):TP_CPU1_RSVD_8   I107 @BASEBOARD_FAB2_LIB.BASEBOARD_FAB2(SCH_1):PAGE73
  EE46 TP_CPU1_RSVD_7 @BASEBOARD_FAB2_LIB.BASEBOARD_FAB2(SCH_1):TP_CPU1_RSVD_7   I107 @BASEBOARD_FAB2_LIB.BASEBOARD_FAB2(SCH_1):PAGE73
   EE6 TP_CPU1_RSVD_6 @BASEBOARD_FAB2_LIB.BASEBOARD_FAB2(SCH_1):TP_CPU1_RSVD_6   I107 @BASEBOARD_FAB2_LIB.BASEBOARD_FAB2(SCH_1):PAGE73
  EE82 TP_CPU1_RSVD_5 @BASEBOARD_FAB2_LIB.BASEBOARD_FAB2(SCH_1):TP_CPU1_RSVD_5   I107 @BASEBOARD_FAB2_LIB.BASEBOARD_FAB2(SCH_1):PAGE73
  EE84 TP_CPU1_RSVD_4 @BASEBOARD_FAB2_LIB.BASEBOARD_FAB2(SCH_1):TP_CPU1_RSVD_4   I107 @BASEBOARD_FAB2_LIB.BASEBOARD_FAB2(SCH_1):PAGE73
  EF47 TP_CPU1_RSVD_3 @BASEBOARD_FAB2_LIB.BASEBOARD_FAB2(SCH_1):TP_CPU1_RSVD_3   I107 @BASEBOARD_FAB2_LIB.BASEBOARD_FAB2(SCH_1):PAGE73
  EF77 TP_CPU1_RSVD_2 @BASEBOARD_FAB2_LIB.BASEBOARD_FAB2(SCH_1):TP_CPU1_RSVD_2   I107 @BASEBOARD_FAB2_LIB.BASEBOARD_FAB2(SCH_1):PAGE73
  EF81 TP_CPU1_RSVD_1 @BASEBOARD_FAB2_LIB.BASEBOARD_FAB2(SCH_1):TP_CPU1_RSVD_1   I107 @BASEBOARD_FAB2_LIB.BASEBOARD_FAB2(SCH_1):PAGE73
  EF83 TP_CPU1_RSVD_0 @BASEBOARD_FAB2_LIB.BASEBOARD_FAB2(SCH_1):TP_CPU1_RSVD_0   I107 @BASEBOARD_FAB2_LIB.BASEBOARD_FAB2(SCH_1):PAGE73
   CN6 PVCCIO_CPU1 @BASEBOARD_FAB2_LIB.BASEBOARD_FAB2(SCH_1):PVCCIO_CPU1   I107 @BASEBOARD_FAB2_LIB.BASEBOARD_FAB2(SCH_1):PAGE73
  CU12 PVCCIO_CPU1 @BASEBOARD_FAB2_LIB.BASEBOARD_FAB2(SCH_1):PVCCIO_CPU1   I107 @BASEBOARD_FAB2_LIB.BASEBOARD_FAB2(SCH_1):PAGE73
  CV21 PVCCIO_CPU1 @BASEBOARD_FAB2_LIB.BASEBOARD_FAB2(SCH_1):PVCCIO_CPU1   I107 @BASEBOARD_FAB2_LIB.BASEBOARD_FAB2(SCH_1):PAGE73
  CU18 PVCCIO_CPU1 @BASEBOARD_FAB2_LIB.BASEBOARD_FAB2(SCH_1):PVCCIO_CPU1   I107 @BASEBOARD_FAB2_LIB.BASEBOARD_FAB2(SCH_1):PAGE73
  CY17 PVCCIO_CPU1 @BASEBOARD_FAB2_LIB.BASEBOARD_FAB2(SCH_1):PVCCIO_CPU1   I107 @BASEBOARD_FAB2_LIB.BASEBOARD_FAB2(SCH_1):PAGE73
  DC18 PVCCIO_CPU1 @BASEBOARD_FAB2_LIB.BASEBOARD_FAB2(SCH_1):PVCCIO_CPU1   I107 @BASEBOARD_FAB2_LIB.BASEBOARD_FAB2(SCH_1):PAGE73
  DE14 PVCCIO_CPU1 @BASEBOARD_FAB2_LIB.BASEBOARD_FAB2(SCH_1):PVCCIO_CPU1   I107 @BASEBOARD_FAB2_LIB.BASEBOARD_FAB2(SCH_1):PAGE73
  CP13 PVCCIO_CPU1 @BASEBOARD_FAB2_LIB.BASEBOARD_FAB2(SCH_1):PVCCIO_CPU1   I107 @BASEBOARD_FAB2_LIB.BASEBOARD_FAB2(SCH_1):PAGE73
  CL20 PVCCIO_CPU1 @BASEBOARD_FAB2_LIB.BASEBOARD_FAB2(SCH_1):PVCCIO_CPU1   I107 @BASEBOARD_FAB2_LIB.BASEBOARD_FAB2(SCH_1):PAGE73
  CG14 PVCCIO_CPU1 @BASEBOARD_FAB2_LIB.BASEBOARD_FAB2(SCH_1):PVCCIO_CPU1   I107 @BASEBOARD_FAB2_LIB.BASEBOARD_FAB2(SCH_1):PAGE73
   CF5 PVCCIO_CPU1 @BASEBOARD_FAB2_LIB.BASEBOARD_FAB2(SCH_1):PVCCIO_CPU1   I107 @BASEBOARD_FAB2_LIB.BASEBOARD_FAB2(SCH_1):PAGE73
  DK21 PVCCIO_CPU1 @BASEBOARD_FAB2_LIB.BASEBOARD_FAB2(SCH_1):PVCCIO_CPU1   I107 @BASEBOARD_FAB2_LIB.BASEBOARD_FAB2(SCH_1):PAGE73
  BE24 PVCCIO_CPU1 @BASEBOARD_FAB2_LIB.BASEBOARD_FAB2(SCH_1):PVCCIO_CPU1   I107 @BASEBOARD_FAB2_LIB.BASEBOARD_FAB2(SCH_1):PAGE73
   AT7 PVCCIO_CPU1 @BASEBOARD_FAB2_LIB.BASEBOARD_FAB2(SCH_1):PVCCIO_CPU1   I107 @BASEBOARD_FAB2_LIB.BASEBOARD_FAB2(SCH_1):PAGE73
   AT5 PVCCIO_CPU1 @BASEBOARD_FAB2_LIB.BASEBOARD_FAB2(SCH_1):PVCCIO_CPU1   I107 @BASEBOARD_FAB2_LIB.BASEBOARD_FAB2(SCH_1):PAGE73
   AM5 PVCCIO_CPU1 @BASEBOARD_FAB2_LIB.BASEBOARD_FAB2(SCH_1):PVCCIO_CPU1   I107 @BASEBOARD_FAB2_LIB.BASEBOARD_FAB2(SCH_1):PAGE73
  DV11 PVCCIO_CPU1 @BASEBOARD_FAB2_LIB.BASEBOARD_FAB2(SCH_1):PVCCIO_CPU1   I107 @BASEBOARD_FAB2_LIB.BASEBOARD_FAB2(SCH_1):PAGE73
   AF5 PVCCIO_CPU1 @BASEBOARD_FAB2_LIB.BASEBOARD_FAB2(SCH_1):PVCCIO_CPU1   I107 @BASEBOARD_FAB2_LIB.BASEBOARD_FAB2(SCH_1):PAGE73
  AE10 PVCCIO_CPU1 @BASEBOARD_FAB2_LIB.BASEBOARD_FAB2(SCH_1):PVCCIO_CPU1   I107 @BASEBOARD_FAB2_LIB.BASEBOARD_FAB2(SCH_1):PAGE73
  EE10 PVCCIO_CPU1 @BASEBOARD_FAB2_LIB.BASEBOARD_FAB2(SCH_1):PVCCIO_CPU1   I107 @BASEBOARD_FAB2_LIB.BASEBOARD_FAB2(SCH_1):PAGE73
   BH5 VSENSE_PVCCIO_CPU1_SKT_VSEN @BASEBOARD_FAB2_LIB.BASEBOARD_FAB2(SCH_1):VSENSE_PVCCIO_CPU1_SKT_VSEN   I107 @BASEBOARD_FAB2_LIB.BASEBOARD_FAB2(SCH_1):PAGE73
  CE76 VSENSE_PVSA_CPU1_SKT_VSEN @BASEBOARD_FAB2_LIB.BASEBOARD_FAB2(SCH_1):VSENSE_PVSA_CPU1_SKT_VSEN   I107 @BASEBOARD_FAB2_LIB.BASEBOARD_FAB2(SCH_1):PAGE73
   BF5 VSENSE_PVCCIO_CPU1_SKT_VRTN @BASEBOARD_FAB2_LIB.BASEBOARD_FAB2(SCH_1):VSENSE_PVCCIO_CPU1_SKT_VRTN   I107 @BASEBOARD_FAB2_LIB.BASEBOARD_FAB2(SCH_1):PAGE73
  CG76 VSENSE_PVSA_CPU1_SKT_VRTN @BASEBOARD_FAB2_LIB.BASEBOARD_FAB2(SCH_1):VSENSE_PVSA_CPU1_SKT_VRTN   I107 @BASEBOARD_FAB2_LIB.BASEBOARD_FAB2(SCH_1):PAGE73
    B9    GND @BASEBOARD_FAB2_LIB.BASEBOARD_FAB2(SCH_1):GND    I20 @BASEBOARD_FAB2_LIB.BASEBOARD_FAB2(SCH_1):PAGE74
   A42    GND @BASEBOARD_FAB2_LIB.BASEBOARD_FAB2(SCH_1):GND    I20 @BASEBOARD_FAB2_LIB.BASEBOARD_FAB2(SCH_1):PAGE74
   B43    GND @BASEBOARD_FAB2_LIB.BASEBOARD_FAB2(SCH_1):GND    I20 @BASEBOARD_FAB2_LIB.BASEBOARD_FAB2(SCH_1):PAGE74
    B5    GND @BASEBOARD_FAB2_LIB.BASEBOARD_FAB2(SCH_1):GND    I20 @BASEBOARD_FAB2_LIB.BASEBOARD_FAB2(SCH_1):PAGE74
   B79    GND @BASEBOARD_FAB2_LIB.BASEBOARD_FAB2(SCH_1):GND    I20 @BASEBOARD_FAB2_LIB.BASEBOARD_FAB2(SCH_1):PAGE74
    C4    GND @BASEBOARD_FAB2_LIB.BASEBOARD_FAB2(SCH_1):GND    I20 @BASEBOARD_FAB2_LIB.BASEBOARD_FAB2(SCH_1):PAGE74
   C80    GND @BASEBOARD_FAB2_LIB.BASEBOARD_FAB2(SCH_1):GND    I20 @BASEBOARD_FAB2_LIB.BASEBOARD_FAB2(SCH_1):PAGE74
    D3    GND @BASEBOARD_FAB2_LIB.BASEBOARD_FAB2(SCH_1):GND    I20 @BASEBOARD_FAB2_LIB.BASEBOARD_FAB2(SCH_1):PAGE74
   D81    GND @BASEBOARD_FAB2_LIB.BASEBOARD_FAB2(SCH_1):GND    I20 @BASEBOARD_FAB2_LIB.BASEBOARD_FAB2(SCH_1):PAGE74
   E82    GND @BASEBOARD_FAB2_LIB.BASEBOARD_FAB2(SCH_1):GND    I20 @BASEBOARD_FAB2_LIB.BASEBOARD_FAB2(SCH_1):PAGE74
   J86    GND @BASEBOARD_FAB2_LIB.BASEBOARD_FAB2(SCH_1):GND    I20 @BASEBOARD_FAB2_LIB.BASEBOARD_FAB2(SCH_1):PAGE74
  DY85    GND @BASEBOARD_FAB2_LIB.BASEBOARD_FAB2(SCH_1):GND    I20 @BASEBOARD_FAB2_LIB.BASEBOARD_FAB2(SCH_1):PAGE74
  EA84    GND @BASEBOARD_FAB2_LIB.BASEBOARD_FAB2(SCH_1):GND    I20 @BASEBOARD_FAB2_LIB.BASEBOARD_FAB2(SCH_1):PAGE74
  EB83    GND @BASEBOARD_FAB2_LIB.BASEBOARD_FAB2(SCH_1):GND    I20 @BASEBOARD_FAB2_LIB.BASEBOARD_FAB2(SCH_1):PAGE74
   DW2    GND @BASEBOARD_FAB2_LIB.BASEBOARD_FAB2(SCH_1):GND    I20 @BASEBOARD_FAB2_LIB.BASEBOARD_FAB2(SCH_1):PAGE74
  EC42    GND @BASEBOARD_FAB2_LIB.BASEBOARD_FAB2(SCH_1):GND    I20 @BASEBOARD_FAB2_LIB.BASEBOARD_FAB2(SCH_1):PAGE74
   EC6    GND @BASEBOARD_FAB2_LIB.BASEBOARD_FAB2(SCH_1):GND    I20 @BASEBOARD_FAB2_LIB.BASEBOARD_FAB2(SCH_1):PAGE74
  EC82    GND @BASEBOARD_FAB2_LIB.BASEBOARD_FAB2(SCH_1):GND    I20 @BASEBOARD_FAB2_LIB.BASEBOARD_FAB2(SCH_1):PAGE74
  ED41    GND @BASEBOARD_FAB2_LIB.BASEBOARD_FAB2(SCH_1):GND    I20 @BASEBOARD_FAB2_LIB.BASEBOARD_FAB2(SCH_1):PAGE74
   ED7    GND @BASEBOARD_FAB2_LIB.BASEBOARD_FAB2(SCH_1):GND    I20 @BASEBOARD_FAB2_LIB.BASEBOARD_FAB2(SCH_1):PAGE74
  ED81    GND @BASEBOARD_FAB2_LIB.BASEBOARD_FAB2(SCH_1):GND    I20 @BASEBOARD_FAB2_LIB.BASEBOARD_FAB2(SCH_1):PAGE74
  EE40    GND @BASEBOARD_FAB2_LIB.BASEBOARD_FAB2(SCH_1):GND    I20 @BASEBOARD_FAB2_LIB.BASEBOARD_FAB2(SCH_1):PAGE74
   EE8    GND @BASEBOARD_FAB2_LIB.BASEBOARD_FAB2(SCH_1):GND    I20 @BASEBOARD_FAB2_LIB.BASEBOARD_FAB2(SCH_1):PAGE74
  EE80    GND @BASEBOARD_FAB2_LIB.BASEBOARD_FAB2(SCH_1):GND    I20 @BASEBOARD_FAB2_LIB.BASEBOARD_FAB2(SCH_1):PAGE74
  ED69    GND @BASEBOARD_FAB2_LIB.BASEBOARD_FAB2(SCH_1):GND    I20 @BASEBOARD_FAB2_LIB.BASEBOARD_FAB2(SCH_1):PAGE74
   E66    GND @BASEBOARD_FAB2_LIB.BASEBOARD_FAB2(SCH_1):GND    I20 @BASEBOARD_FAB2_LIB.BASEBOARD_FAB2(SCH_1):PAGE74
   V11    GND @BASEBOARD_FAB2_LIB.BASEBOARD_FAB2(SCH_1):GND    I20 @BASEBOARD_FAB2_LIB.BASEBOARD_FAB2(SCH_1):PAGE74
    L8    GND @BASEBOARD_FAB2_LIB.BASEBOARD_FAB2(SCH_1):GND    I20 @BASEBOARD_FAB2_LIB.BASEBOARD_FAB2(SCH_1):PAGE74
  EA14    GND @BASEBOARD_FAB2_LIB.BASEBOARD_FAB2(SCH_1):GND    I20 @BASEBOARD_FAB2_LIB.BASEBOARD_FAB2(SCH_1):PAGE74
  DY63    GND @BASEBOARD_FAB2_LIB.BASEBOARD_FAB2(SCH_1):GND    I20 @BASEBOARD_FAB2_LIB.BASEBOARD_FAB2(SCH_1):PAGE74
  DY61    GND @BASEBOARD_FAB2_LIB.BASEBOARD_FAB2(SCH_1):GND    I20 @BASEBOARD_FAB2_LIB.BASEBOARD_FAB2(SCH_1):PAGE74
  DY59    GND @BASEBOARD_FAB2_LIB.BASEBOARD_FAB2(SCH_1):GND    I20 @BASEBOARD_FAB2_LIB.BASEBOARD_FAB2(SCH_1):PAGE74
  DY57    GND @BASEBOARD_FAB2_LIB.BASEBOARD_FAB2(SCH_1):GND    I20 @BASEBOARD_FAB2_LIB.BASEBOARD_FAB2(SCH_1):PAGE74
  DY55    GND @BASEBOARD_FAB2_LIB.BASEBOARD_FAB2(SCH_1):GND    I20 @BASEBOARD_FAB2_LIB.BASEBOARD_FAB2(SCH_1):PAGE74
  DY53    GND @BASEBOARD_FAB2_LIB.BASEBOARD_FAB2(SCH_1):GND    I20 @BASEBOARD_FAB2_LIB.BASEBOARD_FAB2(SCH_1):PAGE74
  DY51    GND @BASEBOARD_FAB2_LIB.BASEBOARD_FAB2(SCH_1):GND    I20 @BASEBOARD_FAB2_LIB.BASEBOARD_FAB2(SCH_1):PAGE74
  DY49    GND @BASEBOARD_FAB2_LIB.BASEBOARD_FAB2(SCH_1):GND    I20 @BASEBOARD_FAB2_LIB.BASEBOARD_FAB2(SCH_1):PAGE74
  DY47    GND @BASEBOARD_FAB2_LIB.BASEBOARD_FAB2(SCH_1):GND    I20 @BASEBOARD_FAB2_LIB.BASEBOARD_FAB2(SCH_1):PAGE74
  DY45    GND @BASEBOARD_FAB2_LIB.BASEBOARD_FAB2(SCH_1):GND    I20 @BASEBOARD_FAB2_LIB.BASEBOARD_FAB2(SCH_1):PAGE74
  DV19    GND @BASEBOARD_FAB2_LIB.BASEBOARD_FAB2(SCH_1):GND    I20 @BASEBOARD_FAB2_LIB.BASEBOARD_FAB2(SCH_1):PAGE74
   DP9    GND @BASEBOARD_FAB2_LIB.BASEBOARD_FAB2(SCH_1):GND    I20 @BASEBOARD_FAB2_LIB.BASEBOARD_FAB2(SCH_1):PAGE74
  DP63    GND @BASEBOARD_FAB2_LIB.BASEBOARD_FAB2(SCH_1):GND    I20 @BASEBOARD_FAB2_LIB.BASEBOARD_FAB2(SCH_1):PAGE74
  DP61    GND @BASEBOARD_FAB2_LIB.BASEBOARD_FAB2(SCH_1):GND    I20 @BASEBOARD_FAB2_LIB.BASEBOARD_FAB2(SCH_1):PAGE74
  DP59    GND @BASEBOARD_FAB2_LIB.BASEBOARD_FAB2(SCH_1):GND    I20 @BASEBOARD_FAB2_LIB.BASEBOARD_FAB2(SCH_1):PAGE74
  DP57    GND @BASEBOARD_FAB2_LIB.BASEBOARD_FAB2(SCH_1):GND    I20 @BASEBOARD_FAB2_LIB.BASEBOARD_FAB2(SCH_1):PAGE74
  DP55    GND @BASEBOARD_FAB2_LIB.BASEBOARD_FAB2(SCH_1):GND    I20 @BASEBOARD_FAB2_LIB.BASEBOARD_FAB2(SCH_1):PAGE74
  DP53    GND @BASEBOARD_FAB2_LIB.BASEBOARD_FAB2(SCH_1):GND    I20 @BASEBOARD_FAB2_LIB.BASEBOARD_FAB2(SCH_1):PAGE74
  DP51    GND @BASEBOARD_FAB2_LIB.BASEBOARD_FAB2(SCH_1):GND    I20 @BASEBOARD_FAB2_LIB.BASEBOARD_FAB2(SCH_1):PAGE74
  DP49    GND @BASEBOARD_FAB2_LIB.BASEBOARD_FAB2(SCH_1):GND    I20 @BASEBOARD_FAB2_LIB.BASEBOARD_FAB2(SCH_1):PAGE74
  DP47    GND @BASEBOARD_FAB2_LIB.BASEBOARD_FAB2(SCH_1):GND    I20 @BASEBOARD_FAB2_LIB.BASEBOARD_FAB2(SCH_1):PAGE74
  DP45    GND @BASEBOARD_FAB2_LIB.BASEBOARD_FAB2(SCH_1):GND    I20 @BASEBOARD_FAB2_LIB.BASEBOARD_FAB2(SCH_1):PAGE74
  DN18    GND @BASEBOARD_FAB2_LIB.BASEBOARD_FAB2(SCH_1):GND    I20 @BASEBOARD_FAB2_LIB.BASEBOARD_FAB2(SCH_1):PAGE74
   DL8    GND @BASEBOARD_FAB2_LIB.BASEBOARD_FAB2(SCH_1):GND    I20 @BASEBOARD_FAB2_LIB.BASEBOARD_FAB2(SCH_1):PAGE74
  DE62    GND @BASEBOARD_FAB2_LIB.BASEBOARD_FAB2(SCH_1):GND    I20 @BASEBOARD_FAB2_LIB.BASEBOARD_FAB2(SCH_1):PAGE74
  DE60    GND @BASEBOARD_FAB2_LIB.BASEBOARD_FAB2(SCH_1):GND    I20 @BASEBOARD_FAB2_LIB.BASEBOARD_FAB2(SCH_1):PAGE74
  DE58    GND @BASEBOARD_FAB2_LIB.BASEBOARD_FAB2(SCH_1):GND    I20 @BASEBOARD_FAB2_LIB.BASEBOARD_FAB2(SCH_1):PAGE74
  DE56    GND @BASEBOARD_FAB2_LIB.BASEBOARD_FAB2(SCH_1):GND    I20 @BASEBOARD_FAB2_LIB.BASEBOARD_FAB2(SCH_1):PAGE74
  DE54    GND @BASEBOARD_FAB2_LIB.BASEBOARD_FAB2(SCH_1):GND    I20 @BASEBOARD_FAB2_LIB.BASEBOARD_FAB2(SCH_1):PAGE74
  DE52    GND @BASEBOARD_FAB2_LIB.BASEBOARD_FAB2(SCH_1):GND    I20 @BASEBOARD_FAB2_LIB.BASEBOARD_FAB2(SCH_1):PAGE74
  DE50    GND @BASEBOARD_FAB2_LIB.BASEBOARD_FAB2(SCH_1):GND    I20 @BASEBOARD_FAB2_LIB.BASEBOARD_FAB2(SCH_1):PAGE74
  DE48    GND @BASEBOARD_FAB2_LIB.BASEBOARD_FAB2(SCH_1):GND    I20 @BASEBOARD_FAB2_LIB.BASEBOARD_FAB2(SCH_1):PAGE74
   CW6    GND @BASEBOARD_FAB2_LIB.BASEBOARD_FAB2(SCH_1):GND    I20 @BASEBOARD_FAB2_LIB.BASEBOARD_FAB2(SCH_1):PAGE74
   CG6    GND @BASEBOARD_FAB2_LIB.BASEBOARD_FAB2(SCH_1):GND    I20 @BASEBOARD_FAB2_LIB.BASEBOARD_FAB2(SCH_1):PAGE74
   AR6    GND @BASEBOARD_FAB2_LIB.BASEBOARD_FAB2(SCH_1):GND    I20 @BASEBOARD_FAB2_LIB.BASEBOARD_FAB2(SCH_1):PAGE74
   AJ4    GND @BASEBOARD_FAB2_LIB.BASEBOARD_FAB2(SCH_1):GND    I20 @BASEBOARD_FAB2_LIB.BASEBOARD_FAB2(SCH_1):PAGE74
  AC62    GND @BASEBOARD_FAB2_LIB.BASEBOARD_FAB2(SCH_1):GND    I20 @BASEBOARD_FAB2_LIB.BASEBOARD_FAB2(SCH_1):PAGE74
  AC60    GND @BASEBOARD_FAB2_LIB.BASEBOARD_FAB2(SCH_1):GND    I20 @BASEBOARD_FAB2_LIB.BASEBOARD_FAB2(SCH_1):PAGE74
  AC58    GND @BASEBOARD_FAB2_LIB.BASEBOARD_FAB2(SCH_1):GND    I20 @BASEBOARD_FAB2_LIB.BASEBOARD_FAB2(SCH_1):PAGE74
   A26    GND @BASEBOARD_FAB2_LIB.BASEBOARD_FAB2(SCH_1):GND    I20 @BASEBOARD_FAB2_LIB.BASEBOARD_FAB2(SCH_1):PAGE74
   A30    GND @BASEBOARD_FAB2_LIB.BASEBOARD_FAB2(SCH_1):GND    I20 @BASEBOARD_FAB2_LIB.BASEBOARD_FAB2(SCH_1):PAGE74
   A32    GND @BASEBOARD_FAB2_LIB.BASEBOARD_FAB2(SCH_1):GND    I20 @BASEBOARD_FAB2_LIB.BASEBOARD_FAB2(SCH_1):PAGE74
   A36    GND @BASEBOARD_FAB2_LIB.BASEBOARD_FAB2(SCH_1):GND    I20 @BASEBOARD_FAB2_LIB.BASEBOARD_FAB2(SCH_1):PAGE74
   A38    GND @BASEBOARD_FAB2_LIB.BASEBOARD_FAB2(SCH_1):GND    I20 @BASEBOARD_FAB2_LIB.BASEBOARD_FAB2(SCH_1):PAGE74
   B25    GND @BASEBOARD_FAB2_LIB.BASEBOARD_FAB2(SCH_1):GND    I20 @BASEBOARD_FAB2_LIB.BASEBOARD_FAB2(SCH_1):PAGE74
   B31    GND @BASEBOARD_FAB2_LIB.BASEBOARD_FAB2(SCH_1):GND    I20 @BASEBOARD_FAB2_LIB.BASEBOARD_FAB2(SCH_1):PAGE74
   B37    GND @BASEBOARD_FAB2_LIB.BASEBOARD_FAB2(SCH_1):GND    I20 @BASEBOARD_FAB2_LIB.BASEBOARD_FAB2(SCH_1):PAGE74
   B71    GND @BASEBOARD_FAB2_LIB.BASEBOARD_FAB2(SCH_1):GND    I20 @BASEBOARD_FAB2_LIB.BASEBOARD_FAB2(SCH_1):PAGE74
   B75    GND @BASEBOARD_FAB2_LIB.BASEBOARD_FAB2(SCH_1):GND    I20 @BASEBOARD_FAB2_LIB.BASEBOARD_FAB2(SCH_1):PAGE74
    C8    GND @BASEBOARD_FAB2_LIB.BASEBOARD_FAB2(SCH_1):GND    I20 @BASEBOARD_FAB2_LIB.BASEBOARD_FAB2(SCH_1):PAGE74
   C10    GND @BASEBOARD_FAB2_LIB.BASEBOARD_FAB2(SCH_1):GND    I20 @BASEBOARD_FAB2_LIB.BASEBOARD_FAB2(SCH_1):PAGE74
   C12    GND @BASEBOARD_FAB2_LIB.BASEBOARD_FAB2(SCH_1):GND    I20 @BASEBOARD_FAB2_LIB.BASEBOARD_FAB2(SCH_1):PAGE74
   C14    GND @BASEBOARD_FAB2_LIB.BASEBOARD_FAB2(SCH_1):GND    I20 @BASEBOARD_FAB2_LIB.BASEBOARD_FAB2(SCH_1):PAGE74
   C16    GND @BASEBOARD_FAB2_LIB.BASEBOARD_FAB2(SCH_1):GND    I20 @BASEBOARD_FAB2_LIB.BASEBOARD_FAB2(SCH_1):PAGE74
   C76    GND @BASEBOARD_FAB2_LIB.BASEBOARD_FAB2(SCH_1):GND    I20 @BASEBOARD_FAB2_LIB.BASEBOARD_FAB2(SCH_1):PAGE74
   C78    GND @BASEBOARD_FAB2_LIB.BASEBOARD_FAB2(SCH_1):GND    I20 @BASEBOARD_FAB2_LIB.BASEBOARD_FAB2(SCH_1):PAGE74
  CM27    GND @BASEBOARD_FAB2_LIB.BASEBOARD_FAB2(SCH_1):GND    I20 @BASEBOARD_FAB2_LIB.BASEBOARD_FAB2(SCH_1):PAGE74
   D11    GND @BASEBOARD_FAB2_LIB.BASEBOARD_FAB2(SCH_1):GND    I20 @BASEBOARD_FAB2_LIB.BASEBOARD_FAB2(SCH_1):PAGE74
   D13    GND @BASEBOARD_FAB2_LIB.BASEBOARD_FAB2(SCH_1):GND    I20 @BASEBOARD_FAB2_LIB.BASEBOARD_FAB2(SCH_1):PAGE74
   D25    GND @BASEBOARD_FAB2_LIB.BASEBOARD_FAB2(SCH_1):GND    I20 @BASEBOARD_FAB2_LIB.BASEBOARD_FAB2(SCH_1):PAGE74
   D27    GND @BASEBOARD_FAB2_LIB.BASEBOARD_FAB2(SCH_1):GND    I20 @BASEBOARD_FAB2_LIB.BASEBOARD_FAB2(SCH_1):PAGE74
   D29    GND @BASEBOARD_FAB2_LIB.BASEBOARD_FAB2(SCH_1):GND    I20 @BASEBOARD_FAB2_LIB.BASEBOARD_FAB2(SCH_1):PAGE74
   D31    GND @BASEBOARD_FAB2_LIB.BASEBOARD_FAB2(SCH_1):GND    I20 @BASEBOARD_FAB2_LIB.BASEBOARD_FAB2(SCH_1):PAGE74
   D33    GND @BASEBOARD_FAB2_LIB.BASEBOARD_FAB2(SCH_1):GND    I20 @BASEBOARD_FAB2_LIB.BASEBOARD_FAB2(SCH_1):PAGE74
   D35    GND @BASEBOARD_FAB2_LIB.BASEBOARD_FAB2(SCH_1):GND    I20 @BASEBOARD_FAB2_LIB.BASEBOARD_FAB2(SCH_1):PAGE74
   D37    GND @BASEBOARD_FAB2_LIB.BASEBOARD_FAB2(SCH_1):GND    I20 @BASEBOARD_FAB2_LIB.BASEBOARD_FAB2(SCH_1):PAGE74
   D39    GND @BASEBOARD_FAB2_LIB.BASEBOARD_FAB2(SCH_1):GND    I20 @BASEBOARD_FAB2_LIB.BASEBOARD_FAB2(SCH_1):PAGE74
   D41    GND @BASEBOARD_FAB2_LIB.BASEBOARD_FAB2(SCH_1):GND    I20 @BASEBOARD_FAB2_LIB.BASEBOARD_FAB2(SCH_1):PAGE74
   D43    GND @BASEBOARD_FAB2_LIB.BASEBOARD_FAB2(SCH_1):GND    I20 @BASEBOARD_FAB2_LIB.BASEBOARD_FAB2(SCH_1):PAGE74
   D77    GND @BASEBOARD_FAB2_LIB.BASEBOARD_FAB2(SCH_1):GND    I20 @BASEBOARD_FAB2_LIB.BASEBOARD_FAB2(SCH_1):PAGE74
    E6    GND @BASEBOARD_FAB2_LIB.BASEBOARD_FAB2(SCH_1):GND    I20 @BASEBOARD_FAB2_LIB.BASEBOARD_FAB2(SCH_1):PAGE74
    E8    GND @BASEBOARD_FAB2_LIB.BASEBOARD_FAB2(SCH_1):GND    I20 @BASEBOARD_FAB2_LIB.BASEBOARD_FAB2(SCH_1):PAGE74
   E16    GND @BASEBOARD_FAB2_LIB.BASEBOARD_FAB2(SCH_1):GND    I20 @BASEBOARD_FAB2_LIB.BASEBOARD_FAB2(SCH_1):PAGE74
   E18    GND @BASEBOARD_FAB2_LIB.BASEBOARD_FAB2(SCH_1):GND    I20 @BASEBOARD_FAB2_LIB.BASEBOARD_FAB2(SCH_1):PAGE74
   E20    GND @BASEBOARD_FAB2_LIB.BASEBOARD_FAB2(SCH_1):GND    I20 @BASEBOARD_FAB2_LIB.BASEBOARD_FAB2(SCH_1):PAGE74
   E22    GND @BASEBOARD_FAB2_LIB.BASEBOARD_FAB2(SCH_1):GND    I20 @BASEBOARD_FAB2_LIB.BASEBOARD_FAB2(SCH_1):PAGE74
   E72    GND @BASEBOARD_FAB2_LIB.BASEBOARD_FAB2(SCH_1):GND    I20 @BASEBOARD_FAB2_LIB.BASEBOARD_FAB2(SCH_1):PAGE74
   E74    GND @BASEBOARD_FAB2_LIB.BASEBOARD_FAB2(SCH_1):GND    I20 @BASEBOARD_FAB2_LIB.BASEBOARD_FAB2(SCH_1):PAGE74
   E76    GND @BASEBOARD_FAB2_LIB.BASEBOARD_FAB2(SCH_1):GND    I20 @BASEBOARD_FAB2_LIB.BASEBOARD_FAB2(SCH_1):PAGE74
    F5    GND @BASEBOARD_FAB2_LIB.BASEBOARD_FAB2(SCH_1):GND    I20 @BASEBOARD_FAB2_LIB.BASEBOARD_FAB2(SCH_1):PAGE74
   F17    GND @BASEBOARD_FAB2_LIB.BASEBOARD_FAB2(SCH_1):GND    I20 @BASEBOARD_FAB2_LIB.BASEBOARD_FAB2(SCH_1):PAGE74
   F19    GND @BASEBOARD_FAB2_LIB.BASEBOARD_FAB2(SCH_1):GND    I20 @BASEBOARD_FAB2_LIB.BASEBOARD_FAB2(SCH_1):PAGE74
   F25    GND @BASEBOARD_FAB2_LIB.BASEBOARD_FAB2(SCH_1):GND    I20 @BASEBOARD_FAB2_LIB.BASEBOARD_FAB2(SCH_1):PAGE74
   F31    GND @BASEBOARD_FAB2_LIB.BASEBOARD_FAB2(SCH_1):GND    I20 @BASEBOARD_FAB2_LIB.BASEBOARD_FAB2(SCH_1):PAGE74
   F37    GND @BASEBOARD_FAB2_LIB.BASEBOARD_FAB2(SCH_1):GND    I20 @BASEBOARD_FAB2_LIB.BASEBOARD_FAB2(SCH_1):PAGE74
   F43    GND @BASEBOARD_FAB2_LIB.BASEBOARD_FAB2(SCH_1):GND    I20 @BASEBOARD_FAB2_LIB.BASEBOARD_FAB2(SCH_1):PAGE74
   F67    GND @BASEBOARD_FAB2_LIB.BASEBOARD_FAB2(SCH_1):GND    I20 @BASEBOARD_FAB2_LIB.BASEBOARD_FAB2(SCH_1):PAGE74
   F69    GND @BASEBOARD_FAB2_LIB.BASEBOARD_FAB2(SCH_1):GND    I20 @BASEBOARD_FAB2_LIB.BASEBOARD_FAB2(SCH_1):PAGE74
    G4    GND @BASEBOARD_FAB2_LIB.BASEBOARD_FAB2(SCH_1):GND    I20 @BASEBOARD_FAB2_LIB.BASEBOARD_FAB2(SCH_1):PAGE74
    G8    GND @BASEBOARD_FAB2_LIB.BASEBOARD_FAB2(SCH_1):GND    I20 @BASEBOARD_FAB2_LIB.BASEBOARD_FAB2(SCH_1):PAGE74
   G22    GND @BASEBOARD_FAB2_LIB.BASEBOARD_FAB2(SCH_1):GND    I20 @BASEBOARD_FAB2_LIB.BASEBOARD_FAB2(SCH_1):PAGE74
   G24    GND @BASEBOARD_FAB2_LIB.BASEBOARD_FAB2(SCH_1):GND    I20 @BASEBOARD_FAB2_LIB.BASEBOARD_FAB2(SCH_1):PAGE74
   G26    GND @BASEBOARD_FAB2_LIB.BASEBOARD_FAB2(SCH_1):GND    I20 @BASEBOARD_FAB2_LIB.BASEBOARD_FAB2(SCH_1):PAGE74
   G30    GND @BASEBOARD_FAB2_LIB.BASEBOARD_FAB2(SCH_1):GND    I20 @BASEBOARD_FAB2_LIB.BASEBOARD_FAB2(SCH_1):PAGE74
   G32    GND @BASEBOARD_FAB2_LIB.BASEBOARD_FAB2(SCH_1):GND    I20 @BASEBOARD_FAB2_LIB.BASEBOARD_FAB2(SCH_1):PAGE74
   G36    GND @BASEBOARD_FAB2_LIB.BASEBOARD_FAB2(SCH_1):GND    I20 @BASEBOARD_FAB2_LIB.BASEBOARD_FAB2(SCH_1):PAGE74
   G38    GND @BASEBOARD_FAB2_LIB.BASEBOARD_FAB2(SCH_1):GND    I20 @BASEBOARD_FAB2_LIB.BASEBOARD_FAB2(SCH_1):PAGE74
   G42    GND @BASEBOARD_FAB2_LIB.BASEBOARD_FAB2(SCH_1):GND    I20 @BASEBOARD_FAB2_LIB.BASEBOARD_FAB2(SCH_1):PAGE74
   G66    GND @BASEBOARD_FAB2_LIB.BASEBOARD_FAB2(SCH_1):GND    I20 @BASEBOARD_FAB2_LIB.BASEBOARD_FAB2(SCH_1):PAGE74
   G70    GND @BASEBOARD_FAB2_LIB.BASEBOARD_FAB2(SCH_1):GND    I20 @BASEBOARD_FAB2_LIB.BASEBOARD_FAB2(SCH_1):PAGE74
   G76    GND @BASEBOARD_FAB2_LIB.BASEBOARD_FAB2(SCH_1):GND    I20 @BASEBOARD_FAB2_LIB.BASEBOARD_FAB2(SCH_1):PAGE74
   G78    GND @BASEBOARD_FAB2_LIB.BASEBOARD_FAB2(SCH_1):GND    I20 @BASEBOARD_FAB2_LIB.BASEBOARD_FAB2(SCH_1):PAGE74
   G80    GND @BASEBOARD_FAB2_LIB.BASEBOARD_FAB2(SCH_1):GND    I20 @BASEBOARD_FAB2_LIB.BASEBOARD_FAB2(SCH_1):PAGE74
   G82    GND @BASEBOARD_FAB2_LIB.BASEBOARD_FAB2(SCH_1):GND    I20 @BASEBOARD_FAB2_LIB.BASEBOARD_FAB2(SCH_1):PAGE74
    H3    GND @BASEBOARD_FAB2_LIB.BASEBOARD_FAB2(SCH_1):GND    I20 @BASEBOARD_FAB2_LIB.BASEBOARD_FAB2(SCH_1):PAGE74
   H11    GND @BASEBOARD_FAB2_LIB.BASEBOARD_FAB2(SCH_1):GND    I20 @BASEBOARD_FAB2_LIB.BASEBOARD_FAB2(SCH_1):PAGE74
   H25    GND @BASEBOARD_FAB2_LIB.BASEBOARD_FAB2(SCH_1):GND    I20 @BASEBOARD_FAB2_LIB.BASEBOARD_FAB2(SCH_1):PAGE74
   H27    GND @BASEBOARD_FAB2_LIB.BASEBOARD_FAB2(SCH_1):GND    I20 @BASEBOARD_FAB2_LIB.BASEBOARD_FAB2(SCH_1):PAGE74
   H29    GND @BASEBOARD_FAB2_LIB.BASEBOARD_FAB2(SCH_1):GND    I20 @BASEBOARD_FAB2_LIB.BASEBOARD_FAB2(SCH_1):PAGE74
   H31    GND @BASEBOARD_FAB2_LIB.BASEBOARD_FAB2(SCH_1):GND    I20 @BASEBOARD_FAB2_LIB.BASEBOARD_FAB2(SCH_1):PAGE74
   H33    GND @BASEBOARD_FAB2_LIB.BASEBOARD_FAB2(SCH_1):GND    I20 @BASEBOARD_FAB2_LIB.BASEBOARD_FAB2(SCH_1):PAGE74
   H35    GND @BASEBOARD_FAB2_LIB.BASEBOARD_FAB2(SCH_1):GND    I20 @BASEBOARD_FAB2_LIB.BASEBOARD_FAB2(SCH_1):PAGE74
   H37    GND @BASEBOARD_FAB2_LIB.BASEBOARD_FAB2(SCH_1):GND    I20 @BASEBOARD_FAB2_LIB.BASEBOARD_FAB2(SCH_1):PAGE74
   H39    GND @BASEBOARD_FAB2_LIB.BASEBOARD_FAB2(SCH_1):GND    I20 @BASEBOARD_FAB2_LIB.BASEBOARD_FAB2(SCH_1):PAGE74
   H41    GND @BASEBOARD_FAB2_LIB.BASEBOARD_FAB2(SCH_1):GND    I20 @BASEBOARD_FAB2_LIB.BASEBOARD_FAB2(SCH_1):PAGE74
   H65    GND @BASEBOARD_FAB2_LIB.BASEBOARD_FAB2(SCH_1):GND    I20 @BASEBOARD_FAB2_LIB.BASEBOARD_FAB2(SCH_1):PAGE74
   H71    GND @BASEBOARD_FAB2_LIB.BASEBOARD_FAB2(SCH_1):GND    I20 @BASEBOARD_FAB2_LIB.BASEBOARD_FAB2(SCH_1):PAGE74
   H75    GND @BASEBOARD_FAB2_LIB.BASEBOARD_FAB2(SCH_1):GND    I20 @BASEBOARD_FAB2_LIB.BASEBOARD_FAB2(SCH_1):PAGE74
  DN44    GND @BASEBOARD_FAB2_LIB.BASEBOARD_FAB2(SCH_1):GND    I20 @BASEBOARD_FAB2_LIB.BASEBOARD_FAB2(SCH_1):PAGE74
    J4    GND @BASEBOARD_FAB2_LIB.BASEBOARD_FAB2(SCH_1):GND    I20 @BASEBOARD_FAB2_LIB.BASEBOARD_FAB2(SCH_1):PAGE74
   J12    GND @BASEBOARD_FAB2_LIB.BASEBOARD_FAB2(SCH_1):GND    I20 @BASEBOARD_FAB2_LIB.BASEBOARD_FAB2(SCH_1):PAGE74
   J14    GND @BASEBOARD_FAB2_LIB.BASEBOARD_FAB2(SCH_1):GND    I20 @BASEBOARD_FAB2_LIB.BASEBOARD_FAB2(SCH_1):PAGE74
   J22    GND @BASEBOARD_FAB2_LIB.BASEBOARD_FAB2(SCH_1):GND    I20 @BASEBOARD_FAB2_LIB.BASEBOARD_FAB2(SCH_1):PAGE74
   J26    GND @BASEBOARD_FAB2_LIB.BASEBOARD_FAB2(SCH_1):GND    I20 @BASEBOARD_FAB2_LIB.BASEBOARD_FAB2(SCH_1):PAGE74
   J28    GND @BASEBOARD_FAB2_LIB.BASEBOARD_FAB2(SCH_1):GND    I20 @BASEBOARD_FAB2_LIB.BASEBOARD_FAB2(SCH_1):PAGE74
   J32    GND @BASEBOARD_FAB2_LIB.BASEBOARD_FAB2(SCH_1):GND    I20 @BASEBOARD_FAB2_LIB.BASEBOARD_FAB2(SCH_1):PAGE74
   J34    GND @BASEBOARD_FAB2_LIB.BASEBOARD_FAB2(SCH_1):GND    I20 @BASEBOARD_FAB2_LIB.BASEBOARD_FAB2(SCH_1):PAGE74
   J38    GND @BASEBOARD_FAB2_LIB.BASEBOARD_FAB2(SCH_1):GND    I20 @BASEBOARD_FAB2_LIB.BASEBOARD_FAB2(SCH_1):PAGE74
   J40    GND @BASEBOARD_FAB2_LIB.BASEBOARD_FAB2(SCH_1):GND    I20 @BASEBOARD_FAB2_LIB.BASEBOARD_FAB2(SCH_1):PAGE74
   J72    GND @BASEBOARD_FAB2_LIB.BASEBOARD_FAB2(SCH_1):GND    I20 @BASEBOARD_FAB2_LIB.BASEBOARD_FAB2(SCH_1):PAGE74
   J74    GND @BASEBOARD_FAB2_LIB.BASEBOARD_FAB2(SCH_1):GND    I20 @BASEBOARD_FAB2_LIB.BASEBOARD_FAB2(SCH_1):PAGE74
   J76    GND @BASEBOARD_FAB2_LIB.BASEBOARD_FAB2(SCH_1):GND    I21 @BASEBOARD_FAB2_LIB.BASEBOARD_FAB2(SCH_1):PAGE74
   J82    GND @BASEBOARD_FAB2_LIB.BASEBOARD_FAB2(SCH_1):GND    I21 @BASEBOARD_FAB2_LIB.BASEBOARD_FAB2(SCH_1):PAGE74
   J84    GND @BASEBOARD_FAB2_LIB.BASEBOARD_FAB2(SCH_1):GND    I21 @BASEBOARD_FAB2_LIB.BASEBOARD_FAB2(SCH_1):PAGE74
    K1    GND @BASEBOARD_FAB2_LIB.BASEBOARD_FAB2(SCH_1):GND    I21 @BASEBOARD_FAB2_LIB.BASEBOARD_FAB2(SCH_1):PAGE74
   K11    GND @BASEBOARD_FAB2_LIB.BASEBOARD_FAB2(SCH_1):GND    I21 @BASEBOARD_FAB2_LIB.BASEBOARD_FAB2(SCH_1):PAGE74
   K13    GND @BASEBOARD_FAB2_LIB.BASEBOARD_FAB2(SCH_1):GND    I21 @BASEBOARD_FAB2_LIB.BASEBOARD_FAB2(SCH_1):PAGE74
   K17    GND @BASEBOARD_FAB2_LIB.BASEBOARD_FAB2(SCH_1):GND    I21 @BASEBOARD_FAB2_LIB.BASEBOARD_FAB2(SCH_1):PAGE74
   DB7    GND @BASEBOARD_FAB2_LIB.BASEBOARD_FAB2(SCH_1):GND    I21 @BASEBOARD_FAB2_LIB.BASEBOARD_FAB2(SCH_1):PAGE74
   K27    GND @BASEBOARD_FAB2_LIB.BASEBOARD_FAB2(SCH_1):GND    I21 @BASEBOARD_FAB2_LIB.BASEBOARD_FAB2(SCH_1):PAGE74
   K33    GND @BASEBOARD_FAB2_LIB.BASEBOARD_FAB2(SCH_1):GND    I21 @BASEBOARD_FAB2_LIB.BASEBOARD_FAB2(SCH_1):PAGE74
   K39    GND @BASEBOARD_FAB2_LIB.BASEBOARD_FAB2(SCH_1):GND    I21 @BASEBOARD_FAB2_LIB.BASEBOARD_FAB2(SCH_1):PAGE74
   K65    GND @BASEBOARD_FAB2_LIB.BASEBOARD_FAB2(SCH_1):GND    I21 @BASEBOARD_FAB2_LIB.BASEBOARD_FAB2(SCH_1):PAGE74
   K67    GND @BASEBOARD_FAB2_LIB.BASEBOARD_FAB2(SCH_1):GND    I21 @BASEBOARD_FAB2_LIB.BASEBOARD_FAB2(SCH_1):PAGE74
   K69    GND @BASEBOARD_FAB2_LIB.BASEBOARD_FAB2(SCH_1):GND    I21 @BASEBOARD_FAB2_LIB.BASEBOARD_FAB2(SCH_1):PAGE74
   K71    GND @BASEBOARD_FAB2_LIB.BASEBOARD_FAB2(SCH_1):GND    I21 @BASEBOARD_FAB2_LIB.BASEBOARD_FAB2(SCH_1):PAGE74
   K73    GND @BASEBOARD_FAB2_LIB.BASEBOARD_FAB2(SCH_1):GND    I21 @BASEBOARD_FAB2_LIB.BASEBOARD_FAB2(SCH_1):PAGE74
   K77    GND @BASEBOARD_FAB2_LIB.BASEBOARD_FAB2(SCH_1):GND    I21 @BASEBOARD_FAB2_LIB.BASEBOARD_FAB2(SCH_1):PAGE74
   K81    GND @BASEBOARD_FAB2_LIB.BASEBOARD_FAB2(SCH_1):GND    I21 @BASEBOARD_FAB2_LIB.BASEBOARD_FAB2(SCH_1):PAGE74
   K83    GND @BASEBOARD_FAB2_LIB.BASEBOARD_FAB2(SCH_1):GND    I21 @BASEBOARD_FAB2_LIB.BASEBOARD_FAB2(SCH_1):PAGE74
   K85    GND @BASEBOARD_FAB2_LIB.BASEBOARD_FAB2(SCH_1):GND    I21 @BASEBOARD_FAB2_LIB.BASEBOARD_FAB2(SCH_1):PAGE74
   L10    GND @BASEBOARD_FAB2_LIB.BASEBOARD_FAB2(SCH_1):GND    I21 @BASEBOARD_FAB2_LIB.BASEBOARD_FAB2(SCH_1):PAGE74
    L2    GND @BASEBOARD_FAB2_LIB.BASEBOARD_FAB2(SCH_1):GND    I21 @BASEBOARD_FAB2_LIB.BASEBOARD_FAB2(SCH_1):PAGE74
    L6    GND @BASEBOARD_FAB2_LIB.BASEBOARD_FAB2(SCH_1):GND    I21 @BASEBOARD_FAB2_LIB.BASEBOARD_FAB2(SCH_1):PAGE74
   L20    GND @BASEBOARD_FAB2_LIB.BASEBOARD_FAB2(SCH_1):GND    I21 @BASEBOARD_FAB2_LIB.BASEBOARD_FAB2(SCH_1):PAGE74
   L22    GND @BASEBOARD_FAB2_LIB.BASEBOARD_FAB2(SCH_1):GND    I21 @BASEBOARD_FAB2_LIB.BASEBOARD_FAB2(SCH_1):PAGE74
   L72    GND @BASEBOARD_FAB2_LIB.BASEBOARD_FAB2(SCH_1):GND    I21 @BASEBOARD_FAB2_LIB.BASEBOARD_FAB2(SCH_1):PAGE74
   L78    GND @BASEBOARD_FAB2_LIB.BASEBOARD_FAB2(SCH_1):GND    I21 @BASEBOARD_FAB2_LIB.BASEBOARD_FAB2(SCH_1):PAGE74
   L80    GND @BASEBOARD_FAB2_LIB.BASEBOARD_FAB2(SCH_1):GND    I21 @BASEBOARD_FAB2_LIB.BASEBOARD_FAB2(SCH_1):PAGE74
   L82    GND @BASEBOARD_FAB2_LIB.BASEBOARD_FAB2(SCH_1):GND    I21 @BASEBOARD_FAB2_LIB.BASEBOARD_FAB2(SCH_1):PAGE74
   BT9    GND @BASEBOARD_FAB2_LIB.BASEBOARD_FAB2(SCH_1):GND    I21 @BASEBOARD_FAB2_LIB.BASEBOARD_FAB2(SCH_1):PAGE74
   CT7    GND @BASEBOARD_FAB2_LIB.BASEBOARD_FAB2(SCH_1):GND    I21 @BASEBOARD_FAB2_LIB.BASEBOARD_FAB2(SCH_1):PAGE74
   M15    GND @BASEBOARD_FAB2_LIB.BASEBOARD_FAB2(SCH_1):GND    I21 @BASEBOARD_FAB2_LIB.BASEBOARD_FAB2(SCH_1):PAGE74
   M17    GND @BASEBOARD_FAB2_LIB.BASEBOARD_FAB2(SCH_1):GND    I21 @BASEBOARD_FAB2_LIB.BASEBOARD_FAB2(SCH_1):PAGE74
   M19    GND @BASEBOARD_FAB2_LIB.BASEBOARD_FAB2(SCH_1):GND    I21 @BASEBOARD_FAB2_LIB.BASEBOARD_FAB2(SCH_1):PAGE74
   M23    GND @BASEBOARD_FAB2_LIB.BASEBOARD_FAB2(SCH_1):GND    I21 @BASEBOARD_FAB2_LIB.BASEBOARD_FAB2(SCH_1):PAGE74
   M25    GND @BASEBOARD_FAB2_LIB.BASEBOARD_FAB2(SCH_1):GND    I21 @BASEBOARD_FAB2_LIB.BASEBOARD_FAB2(SCH_1):PAGE74
   M27    GND @BASEBOARD_FAB2_LIB.BASEBOARD_FAB2(SCH_1):GND    I21 @BASEBOARD_FAB2_LIB.BASEBOARD_FAB2(SCH_1):PAGE74
   M29    GND @BASEBOARD_FAB2_LIB.BASEBOARD_FAB2(SCH_1):GND    I21 @BASEBOARD_FAB2_LIB.BASEBOARD_FAB2(SCH_1):PAGE74
   M31    GND @BASEBOARD_FAB2_LIB.BASEBOARD_FAB2(SCH_1):GND    I21 @BASEBOARD_FAB2_LIB.BASEBOARD_FAB2(SCH_1):PAGE74
   M33    GND @BASEBOARD_FAB2_LIB.BASEBOARD_FAB2(SCH_1):GND    I21 @BASEBOARD_FAB2_LIB.BASEBOARD_FAB2(SCH_1):PAGE74
   M35    GND @BASEBOARD_FAB2_LIB.BASEBOARD_FAB2(SCH_1):GND    I21 @BASEBOARD_FAB2_LIB.BASEBOARD_FAB2(SCH_1):PAGE74
   M37    GND @BASEBOARD_FAB2_LIB.BASEBOARD_FAB2(SCH_1):GND    I21 @BASEBOARD_FAB2_LIB.BASEBOARD_FAB2(SCH_1):PAGE74
   M39    GND @BASEBOARD_FAB2_LIB.BASEBOARD_FAB2(SCH_1):GND    I21 @BASEBOARD_FAB2_LIB.BASEBOARD_FAB2(SCH_1):PAGE74
   M41    GND @BASEBOARD_FAB2_LIB.BASEBOARD_FAB2(SCH_1):GND    I21 @BASEBOARD_FAB2_LIB.BASEBOARD_FAB2(SCH_1):PAGE74
   M43    GND @BASEBOARD_FAB2_LIB.BASEBOARD_FAB2(SCH_1):GND    I21 @BASEBOARD_FAB2_LIB.BASEBOARD_FAB2(SCH_1):PAGE74
   M65    GND @BASEBOARD_FAB2_LIB.BASEBOARD_FAB2(SCH_1):GND    I21 @BASEBOARD_FAB2_LIB.BASEBOARD_FAB2(SCH_1):PAGE74
   M71    GND @BASEBOARD_FAB2_LIB.BASEBOARD_FAB2(SCH_1):GND    I21 @BASEBOARD_FAB2_LIB.BASEBOARD_FAB2(SCH_1):PAGE74
   M79    GND @BASEBOARD_FAB2_LIB.BASEBOARD_FAB2(SCH_1):GND    I21 @BASEBOARD_FAB2_LIB.BASEBOARD_FAB2(SCH_1):PAGE74
   M83    GND @BASEBOARD_FAB2_LIB.BASEBOARD_FAB2(SCH_1):GND    I21 @BASEBOARD_FAB2_LIB.BASEBOARD_FAB2(SCH_1):PAGE74
   M85    GND @BASEBOARD_FAB2_LIB.BASEBOARD_FAB2(SCH_1):GND    I21 @BASEBOARD_FAB2_LIB.BASEBOARD_FAB2(SCH_1):PAGE74
  DM19    GND @BASEBOARD_FAB2_LIB.BASEBOARD_FAB2(SCH_1):GND    I21 @BASEBOARD_FAB2_LIB.BASEBOARD_FAB2(SCH_1):PAGE74
   N20    GND @BASEBOARD_FAB2_LIB.BASEBOARD_FAB2(SCH_1):GND    I21 @BASEBOARD_FAB2_LIB.BASEBOARD_FAB2(SCH_1):PAGE74
   N22    GND @BASEBOARD_FAB2_LIB.BASEBOARD_FAB2(SCH_1):GND    I21 @BASEBOARD_FAB2_LIB.BASEBOARD_FAB2(SCH_1):PAGE74
    N6    GND @BASEBOARD_FAB2_LIB.BASEBOARD_FAB2(SCH_1):GND    I21 @BASEBOARD_FAB2_LIB.BASEBOARD_FAB2(SCH_1):PAGE74
   N66    GND @BASEBOARD_FAB2_LIB.BASEBOARD_FAB2(SCH_1):GND    I21 @BASEBOARD_FAB2_LIB.BASEBOARD_FAB2(SCH_1):PAGE74
   N70    GND @BASEBOARD_FAB2_LIB.BASEBOARD_FAB2(SCH_1):GND    I21 @BASEBOARD_FAB2_LIB.BASEBOARD_FAB2(SCH_1):PAGE74
   N72    GND @BASEBOARD_FAB2_LIB.BASEBOARD_FAB2(SCH_1):GND    I21 @BASEBOARD_FAB2_LIB.BASEBOARD_FAB2(SCH_1):PAGE74
   N74    GND @BASEBOARD_FAB2_LIB.BASEBOARD_FAB2(SCH_1):GND    I21 @BASEBOARD_FAB2_LIB.BASEBOARD_FAB2(SCH_1):PAGE74
   N76    GND @BASEBOARD_FAB2_LIB.BASEBOARD_FAB2(SCH_1):GND    I21 @BASEBOARD_FAB2_LIB.BASEBOARD_FAB2(SCH_1):PAGE74
   N78    GND @BASEBOARD_FAB2_LIB.BASEBOARD_FAB2(SCH_1):GND    I21 @BASEBOARD_FAB2_LIB.BASEBOARD_FAB2(SCH_1):PAGE74
    N4    GND @BASEBOARD_FAB2_LIB.BASEBOARD_FAB2(SCH_1):GND    I21 @BASEBOARD_FAB2_LIB.BASEBOARD_FAB2(SCH_1):PAGE74
    N8    GND @BASEBOARD_FAB2_LIB.BASEBOARD_FAB2(SCH_1):GND    I21 @BASEBOARD_FAB2_LIB.BASEBOARD_FAB2(SCH_1):PAGE74
   P11    GND @BASEBOARD_FAB2_LIB.BASEBOARD_FAB2(SCH_1):GND    I21 @BASEBOARD_FAB2_LIB.BASEBOARD_FAB2(SCH_1):PAGE74
   P15    GND @BASEBOARD_FAB2_LIB.BASEBOARD_FAB2(SCH_1):GND    I21 @BASEBOARD_FAB2_LIB.BASEBOARD_FAB2(SCH_1):PAGE74
   P27    GND @BASEBOARD_FAB2_LIB.BASEBOARD_FAB2(SCH_1):GND    I21 @BASEBOARD_FAB2_LIB.BASEBOARD_FAB2(SCH_1):PAGE74
   P33    GND @BASEBOARD_FAB2_LIB.BASEBOARD_FAB2(SCH_1):GND    I21 @BASEBOARD_FAB2_LIB.BASEBOARD_FAB2(SCH_1):PAGE74
   P39    GND @BASEBOARD_FAB2_LIB.BASEBOARD_FAB2(SCH_1):GND    I21 @BASEBOARD_FAB2_LIB.BASEBOARD_FAB2(SCH_1):PAGE74
   P67    GND @BASEBOARD_FAB2_LIB.BASEBOARD_FAB2(SCH_1):GND    I21 @BASEBOARD_FAB2_LIB.BASEBOARD_FAB2(SCH_1):PAGE74
   P69    GND @BASEBOARD_FAB2_LIB.BASEBOARD_FAB2(SCH_1):GND    I21 @BASEBOARD_FAB2_LIB.BASEBOARD_FAB2(SCH_1):PAGE74
   P71    GND @BASEBOARD_FAB2_LIB.BASEBOARD_FAB2(SCH_1):GND    I21 @BASEBOARD_FAB2_LIB.BASEBOARD_FAB2(SCH_1):PAGE74
   P81    GND @BASEBOARD_FAB2_LIB.BASEBOARD_FAB2(SCH_1):GND    I21 @BASEBOARD_FAB2_LIB.BASEBOARD_FAB2(SCH_1):PAGE74
   P83    GND @BASEBOARD_FAB2_LIB.BASEBOARD_FAB2(SCH_1):GND    I21 @BASEBOARD_FAB2_LIB.BASEBOARD_FAB2(SCH_1):PAGE74
   R14    GND @BASEBOARD_FAB2_LIB.BASEBOARD_FAB2(SCH_1):GND    I21 @BASEBOARD_FAB2_LIB.BASEBOARD_FAB2(SCH_1):PAGE74
   R18    GND @BASEBOARD_FAB2_LIB.BASEBOARD_FAB2(SCH_1):GND    I21 @BASEBOARD_FAB2_LIB.BASEBOARD_FAB2(SCH_1):PAGE74
    R2    GND @BASEBOARD_FAB2_LIB.BASEBOARD_FAB2(SCH_1):GND    I21 @BASEBOARD_FAB2_LIB.BASEBOARD_FAB2(SCH_1):PAGE74
    R4    GND @BASEBOARD_FAB2_LIB.BASEBOARD_FAB2(SCH_1):GND    I21 @BASEBOARD_FAB2_LIB.BASEBOARD_FAB2(SCH_1):PAGE74
   R22    GND @BASEBOARD_FAB2_LIB.BASEBOARD_FAB2(SCH_1):GND    I21 @BASEBOARD_FAB2_LIB.BASEBOARD_FAB2(SCH_1):PAGE74
   R26    GND @BASEBOARD_FAB2_LIB.BASEBOARD_FAB2(SCH_1):GND    I21 @BASEBOARD_FAB2_LIB.BASEBOARD_FAB2(SCH_1):PAGE74
   R28    GND @BASEBOARD_FAB2_LIB.BASEBOARD_FAB2(SCH_1):GND    I21 @BASEBOARD_FAB2_LIB.BASEBOARD_FAB2(SCH_1):PAGE74
   R32    GND @BASEBOARD_FAB2_LIB.BASEBOARD_FAB2(SCH_1):GND    I21 @BASEBOARD_FAB2_LIB.BASEBOARD_FAB2(SCH_1):PAGE74
   R34    GND @BASEBOARD_FAB2_LIB.BASEBOARD_FAB2(SCH_1):GND    I21 @BASEBOARD_FAB2_LIB.BASEBOARD_FAB2(SCH_1):PAGE74
   R38    GND @BASEBOARD_FAB2_LIB.BASEBOARD_FAB2(SCH_1):GND    I21 @BASEBOARD_FAB2_LIB.BASEBOARD_FAB2(SCH_1):PAGE74
   R40    GND @BASEBOARD_FAB2_LIB.BASEBOARD_FAB2(SCH_1):GND    I21 @BASEBOARD_FAB2_LIB.BASEBOARD_FAB2(SCH_1):PAGE74
   R68    GND @BASEBOARD_FAB2_LIB.BASEBOARD_FAB2(SCH_1):GND    I21 @BASEBOARD_FAB2_LIB.BASEBOARD_FAB2(SCH_1):PAGE74
   R72    GND @BASEBOARD_FAB2_LIB.BASEBOARD_FAB2(SCH_1):GND    I21 @BASEBOARD_FAB2_LIB.BASEBOARD_FAB2(SCH_1):PAGE74
   R78    GND @BASEBOARD_FAB2_LIB.BASEBOARD_FAB2(SCH_1):GND    I21 @BASEBOARD_FAB2_LIB.BASEBOARD_FAB2(SCH_1):PAGE74
   R86    GND @BASEBOARD_FAB2_LIB.BASEBOARD_FAB2(SCH_1):GND    I21 @BASEBOARD_FAB2_LIB.BASEBOARD_FAB2(SCH_1):PAGE74
   T13    GND @BASEBOARD_FAB2_LIB.BASEBOARD_FAB2(SCH_1):GND    I21 @BASEBOARD_FAB2_LIB.BASEBOARD_FAB2(SCH_1):PAGE74
   T17    GND @BASEBOARD_FAB2_LIB.BASEBOARD_FAB2(SCH_1):GND    I21 @BASEBOARD_FAB2_LIB.BASEBOARD_FAB2(SCH_1):PAGE74
   T25    GND @BASEBOARD_FAB2_LIB.BASEBOARD_FAB2(SCH_1):GND    I21 @BASEBOARD_FAB2_LIB.BASEBOARD_FAB2(SCH_1):PAGE74
   T29    GND @BASEBOARD_FAB2_LIB.BASEBOARD_FAB2(SCH_1):GND    I21 @BASEBOARD_FAB2_LIB.BASEBOARD_FAB2(SCH_1):PAGE74
   T31    GND @BASEBOARD_FAB2_LIB.BASEBOARD_FAB2(SCH_1):GND    I21 @BASEBOARD_FAB2_LIB.BASEBOARD_FAB2(SCH_1):PAGE74
   T35    GND @BASEBOARD_FAB2_LIB.BASEBOARD_FAB2(SCH_1):GND    I21 @BASEBOARD_FAB2_LIB.BASEBOARD_FAB2(SCH_1):PAGE74
   T37    GND @BASEBOARD_FAB2_LIB.BASEBOARD_FAB2(SCH_1):GND    I21 @BASEBOARD_FAB2_LIB.BASEBOARD_FAB2(SCH_1):PAGE74
   T41    GND @BASEBOARD_FAB2_LIB.BASEBOARD_FAB2(SCH_1):GND    I21 @BASEBOARD_FAB2_LIB.BASEBOARD_FAB2(SCH_1):PAGE74
   T65    GND @BASEBOARD_FAB2_LIB.BASEBOARD_FAB2(SCH_1):GND    I21 @BASEBOARD_FAB2_LIB.BASEBOARD_FAB2(SCH_1):PAGE74
   T73    GND @BASEBOARD_FAB2_LIB.BASEBOARD_FAB2(SCH_1):GND    I21 @BASEBOARD_FAB2_LIB.BASEBOARD_FAB2(SCH_1):PAGE74
   T77    GND @BASEBOARD_FAB2_LIB.BASEBOARD_FAB2(SCH_1):GND    I21 @BASEBOARD_FAB2_LIB.BASEBOARD_FAB2(SCH_1):PAGE74
   T83    GND @BASEBOARD_FAB2_LIB.BASEBOARD_FAB2(SCH_1):GND    I21 @BASEBOARD_FAB2_LIB.BASEBOARD_FAB2(SCH_1):PAGE74
   T85    GND @BASEBOARD_FAB2_LIB.BASEBOARD_FAB2(SCH_1):GND    I21 @BASEBOARD_FAB2_LIB.BASEBOARD_FAB2(SCH_1):PAGE74
    U2    GND @BASEBOARD_FAB2_LIB.BASEBOARD_FAB2(SCH_1):GND    I21 @BASEBOARD_FAB2_LIB.BASEBOARD_FAB2(SCH_1):PAGE74
    U4    GND @BASEBOARD_FAB2_LIB.BASEBOARD_FAB2(SCH_1):GND    I21 @BASEBOARD_FAB2_LIB.BASEBOARD_FAB2(SCH_1):PAGE74
    U6    GND @BASEBOARD_FAB2_LIB.BASEBOARD_FAB2(SCH_1):GND    I21 @BASEBOARD_FAB2_LIB.BASEBOARD_FAB2(SCH_1):PAGE74
   U20    GND @BASEBOARD_FAB2_LIB.BASEBOARD_FAB2(SCH_1):GND    I21 @BASEBOARD_FAB2_LIB.BASEBOARD_FAB2(SCH_1):PAGE74
   U22    GND @BASEBOARD_FAB2_LIB.BASEBOARD_FAB2(SCH_1):GND    I21 @BASEBOARD_FAB2_LIB.BASEBOARD_FAB2(SCH_1):PAGE74
   U24    GND @BASEBOARD_FAB2_LIB.BASEBOARD_FAB2(SCH_1):GND    I21 @BASEBOARD_FAB2_LIB.BASEBOARD_FAB2(SCH_1):PAGE74
   U30    GND @BASEBOARD_FAB2_LIB.BASEBOARD_FAB2(SCH_1):GND    I21 @BASEBOARD_FAB2_LIB.BASEBOARD_FAB2(SCH_1):PAGE74
   U36    GND @BASEBOARD_FAB2_LIB.BASEBOARD_FAB2(SCH_1):GND    I21 @BASEBOARD_FAB2_LIB.BASEBOARD_FAB2(SCH_1):PAGE74
   U42    GND @BASEBOARD_FAB2_LIB.BASEBOARD_FAB2(SCH_1):GND    I21 @BASEBOARD_FAB2_LIB.BASEBOARD_FAB2(SCH_1):PAGE74
   U68    GND @BASEBOARD_FAB2_LIB.BASEBOARD_FAB2(SCH_1):GND    I21 @BASEBOARD_FAB2_LIB.BASEBOARD_FAB2(SCH_1):PAGE74
   U70    GND @BASEBOARD_FAB2_LIB.BASEBOARD_FAB2(SCH_1):GND    I21 @BASEBOARD_FAB2_LIB.BASEBOARD_FAB2(SCH_1):PAGE74
   U74    GND @BASEBOARD_FAB2_LIB.BASEBOARD_FAB2(SCH_1):GND    I21 @BASEBOARD_FAB2_LIB.BASEBOARD_FAB2(SCH_1):PAGE74
   U76    GND @BASEBOARD_FAB2_LIB.BASEBOARD_FAB2(SCH_1):GND    I21 @BASEBOARD_FAB2_LIB.BASEBOARD_FAB2(SCH_1):PAGE74
   U78    GND @BASEBOARD_FAB2_LIB.BASEBOARD_FAB2(SCH_1):GND    I21 @BASEBOARD_FAB2_LIB.BASEBOARD_FAB2(SCH_1):PAGE74
   U80    GND @BASEBOARD_FAB2_LIB.BASEBOARD_FAB2(SCH_1):GND    I21 @BASEBOARD_FAB2_LIB.BASEBOARD_FAB2(SCH_1):PAGE74
   U86    GND @BASEBOARD_FAB2_LIB.BASEBOARD_FAB2(SCH_1):GND    I21 @BASEBOARD_FAB2_LIB.BASEBOARD_FAB2(SCH_1):PAGE74
    V1    GND @BASEBOARD_FAB2_LIB.BASEBOARD_FAB2(SCH_1):GND    I21 @BASEBOARD_FAB2_LIB.BASEBOARD_FAB2(SCH_1):PAGE74
    V5    GND @BASEBOARD_FAB2_LIB.BASEBOARD_FAB2(SCH_1):GND    I21 @BASEBOARD_FAB2_LIB.BASEBOARD_FAB2(SCH_1):PAGE74
    V9    GND @BASEBOARD_FAB2_LIB.BASEBOARD_FAB2(SCH_1):GND    I21 @BASEBOARD_FAB2_LIB.BASEBOARD_FAB2(SCH_1):PAGE74
   V13    GND @BASEBOARD_FAB2_LIB.BASEBOARD_FAB2(SCH_1):GND    I21 @BASEBOARD_FAB2_LIB.BASEBOARD_FAB2(SCH_1):PAGE74
   V15    GND @BASEBOARD_FAB2_LIB.BASEBOARD_FAB2(SCH_1):GND    I21 @BASEBOARD_FAB2_LIB.BASEBOARD_FAB2(SCH_1):PAGE74
   V21    GND @BASEBOARD_FAB2_LIB.BASEBOARD_FAB2(SCH_1):GND    I21 @BASEBOARD_FAB2_LIB.BASEBOARD_FAB2(SCH_1):PAGE74
   V23    GND @BASEBOARD_FAB2_LIB.BASEBOARD_FAB2(SCH_1):GND    I21 @BASEBOARD_FAB2_LIB.BASEBOARD_FAB2(SCH_1):PAGE74
   V43    GND @BASEBOARD_FAB2_LIB.BASEBOARD_FAB2(SCH_1):GND    I21 @BASEBOARD_FAB2_LIB.BASEBOARD_FAB2(SCH_1):PAGE74
   V73    GND @BASEBOARD_FAB2_LIB.BASEBOARD_FAB2(SCH_1):GND    I21 @BASEBOARD_FAB2_LIB.BASEBOARD_FAB2(SCH_1):PAGE74
   V75    GND @BASEBOARD_FAB2_LIB.BASEBOARD_FAB2(SCH_1):GND    I21 @BASEBOARD_FAB2_LIB.BASEBOARD_FAB2(SCH_1):PAGE74
   V77    GND @BASEBOARD_FAB2_LIB.BASEBOARD_FAB2(SCH_1):GND    I21 @BASEBOARD_FAB2_LIB.BASEBOARD_FAB2(SCH_1):PAGE74
   V83    GND @BASEBOARD_FAB2_LIB.BASEBOARD_FAB2(SCH_1):GND    I21 @BASEBOARD_FAB2_LIB.BASEBOARD_FAB2(SCH_1):PAGE74
    W8    GND @BASEBOARD_FAB2_LIB.BASEBOARD_FAB2(SCH_1):GND    I21 @BASEBOARD_FAB2_LIB.BASEBOARD_FAB2(SCH_1):PAGE74
  AC56    GND @BASEBOARD_FAB2_LIB.BASEBOARD_FAB2(SCH_1):GND    I21 @BASEBOARD_FAB2_LIB.BASEBOARD_FAB2(SCH_1):PAGE74
   W12    GND @BASEBOARD_FAB2_LIB.BASEBOARD_FAB2(SCH_1):GND    I21 @BASEBOARD_FAB2_LIB.BASEBOARD_FAB2(SCH_1):PAGE74
   W22    GND @BASEBOARD_FAB2_LIB.BASEBOARD_FAB2(SCH_1):GND    I21 @BASEBOARD_FAB2_LIB.BASEBOARD_FAB2(SCH_1):PAGE74
   W24    GND @BASEBOARD_FAB2_LIB.BASEBOARD_FAB2(SCH_1):GND    I21 @BASEBOARD_FAB2_LIB.BASEBOARD_FAB2(SCH_1):PAGE74
   W26    GND @BASEBOARD_FAB2_LIB.BASEBOARD_FAB2(SCH_1):GND    I21 @BASEBOARD_FAB2_LIB.BASEBOARD_FAB2(SCH_1):PAGE74
   W28    GND @BASEBOARD_FAB2_LIB.BASEBOARD_FAB2(SCH_1):GND    I21 @BASEBOARD_FAB2_LIB.BASEBOARD_FAB2(SCH_1):PAGE74
   W30    GND @BASEBOARD_FAB2_LIB.BASEBOARD_FAB2(SCH_1):GND    I21 @BASEBOARD_FAB2_LIB.BASEBOARD_FAB2(SCH_1):PAGE74
   W32    GND @BASEBOARD_FAB2_LIB.BASEBOARD_FAB2(SCH_1):GND    I21 @BASEBOARD_FAB2_LIB.BASEBOARD_FAB2(SCH_1):PAGE74
   W34    GND @BASEBOARD_FAB2_LIB.BASEBOARD_FAB2(SCH_1):GND    I21 @BASEBOARD_FAB2_LIB.BASEBOARD_FAB2(SCH_1):PAGE74
   W36    GND @BASEBOARD_FAB2_LIB.BASEBOARD_FAB2(SCH_1):GND    I21 @BASEBOARD_FAB2_LIB.BASEBOARD_FAB2(SCH_1):PAGE74
   W38    GND @BASEBOARD_FAB2_LIB.BASEBOARD_FAB2(SCH_1):GND    I21 @BASEBOARD_FAB2_LIB.BASEBOARD_FAB2(SCH_1):PAGE74
   W40    GND @BASEBOARD_FAB2_LIB.BASEBOARD_FAB2(SCH_1):GND    I21 @BASEBOARD_FAB2_LIB.BASEBOARD_FAB2(SCH_1):PAGE74
   W42    GND @BASEBOARD_FAB2_LIB.BASEBOARD_FAB2(SCH_1):GND    I21 @BASEBOARD_FAB2_LIB.BASEBOARD_FAB2(SCH_1):PAGE74
   W68    GND @BASEBOARD_FAB2_LIB.BASEBOARD_FAB2(SCH_1):GND    I21 @BASEBOARD_FAB2_LIB.BASEBOARD_FAB2(SCH_1):PAGE74
   W74    GND @BASEBOARD_FAB2_LIB.BASEBOARD_FAB2(SCH_1):GND    I21 @BASEBOARD_FAB2_LIB.BASEBOARD_FAB2(SCH_1):PAGE74
   W78    GND @BASEBOARD_FAB2_LIB.BASEBOARD_FAB2(SCH_1):GND    I21 @BASEBOARD_FAB2_LIB.BASEBOARD_FAB2(SCH_1):PAGE74
   W82    GND @BASEBOARD_FAB2_LIB.BASEBOARD_FAB2(SCH_1):GND    I21 @BASEBOARD_FAB2_LIB.BASEBOARD_FAB2(SCH_1):PAGE74
   Y15    GND @BASEBOARD_FAB2_LIB.BASEBOARD_FAB2(SCH_1):GND    I21 @BASEBOARD_FAB2_LIB.BASEBOARD_FAB2(SCH_1):PAGE74
   Y17    GND @BASEBOARD_FAB2_LIB.BASEBOARD_FAB2(SCH_1):GND    I21 @BASEBOARD_FAB2_LIB.BASEBOARD_FAB2(SCH_1):PAGE74
    Y5    GND @BASEBOARD_FAB2_LIB.BASEBOARD_FAB2(SCH_1):GND    I21 @BASEBOARD_FAB2_LIB.BASEBOARD_FAB2(SCH_1):PAGE74
   Y67    GND @BASEBOARD_FAB2_LIB.BASEBOARD_FAB2(SCH_1):GND    I21 @BASEBOARD_FAB2_LIB.BASEBOARD_FAB2(SCH_1):PAGE74
    Y7    GND @BASEBOARD_FAB2_LIB.BASEBOARD_FAB2(SCH_1):GND    I21 @BASEBOARD_FAB2_LIB.BASEBOARD_FAB2(SCH_1):PAGE74
    Y9    GND @BASEBOARD_FAB2_LIB.BASEBOARD_FAB2(SCH_1):GND    I21 @BASEBOARD_FAB2_LIB.BASEBOARD_FAB2(SCH_1):PAGE74
   Y71    GND @BASEBOARD_FAB2_LIB.BASEBOARD_FAB2(SCH_1):GND    I21 @BASEBOARD_FAB2_LIB.BASEBOARD_FAB2(SCH_1):PAGE74
   Y73    GND @BASEBOARD_FAB2_LIB.BASEBOARD_FAB2(SCH_1):GND    I21 @BASEBOARD_FAB2_LIB.BASEBOARD_FAB2(SCH_1):PAGE74
   Y79    GND @BASEBOARD_FAB2_LIB.BASEBOARD_FAB2(SCH_1):GND    I21 @BASEBOARD_FAB2_LIB.BASEBOARD_FAB2(SCH_1):PAGE74
   Y81    GND @BASEBOARD_FAB2_LIB.BASEBOARD_FAB2(SCH_1):GND    I21 @BASEBOARD_FAB2_LIB.BASEBOARD_FAB2(SCH_1):PAGE74
   Y83    GND @BASEBOARD_FAB2_LIB.BASEBOARD_FAB2(SCH_1):GND    I21 @BASEBOARD_FAB2_LIB.BASEBOARD_FAB2(SCH_1):PAGE74
   Y85    GND @BASEBOARD_FAB2_LIB.BASEBOARD_FAB2(SCH_1):GND    I21 @BASEBOARD_FAB2_LIB.BASEBOARD_FAB2(SCH_1):PAGE74
   AA4    GND @BASEBOARD_FAB2_LIB.BASEBOARD_FAB2(SCH_1):GND    I21 @BASEBOARD_FAB2_LIB.BASEBOARD_FAB2(SCH_1):PAGE74
  AA16    GND @BASEBOARD_FAB2_LIB.BASEBOARD_FAB2(SCH_1):GND    I21 @BASEBOARD_FAB2_LIB.BASEBOARD_FAB2(SCH_1):PAGE74
  AA18    GND @BASEBOARD_FAB2_LIB.BASEBOARD_FAB2(SCH_1):GND    I22 @BASEBOARD_FAB2_LIB.BASEBOARD_FAB2(SCH_1):PAGE74
  AA22    GND @BASEBOARD_FAB2_LIB.BASEBOARD_FAB2(SCH_1):GND    I22 @BASEBOARD_FAB2_LIB.BASEBOARD_FAB2(SCH_1):PAGE74
  AA24    GND @BASEBOARD_FAB2_LIB.BASEBOARD_FAB2(SCH_1):GND    I22 @BASEBOARD_FAB2_LIB.BASEBOARD_FAB2(SCH_1):PAGE74
  AA30    GND @BASEBOARD_FAB2_LIB.BASEBOARD_FAB2(SCH_1):GND    I22 @BASEBOARD_FAB2_LIB.BASEBOARD_FAB2(SCH_1):PAGE74
  AA36    GND @BASEBOARD_FAB2_LIB.BASEBOARD_FAB2(SCH_1):GND    I22 @BASEBOARD_FAB2_LIB.BASEBOARD_FAB2(SCH_1):PAGE74
  AA42    GND @BASEBOARD_FAB2_LIB.BASEBOARD_FAB2(SCH_1):GND    I22 @BASEBOARD_FAB2_LIB.BASEBOARD_FAB2(SCH_1):PAGE74
  AA64    GND @BASEBOARD_FAB2_LIB.BASEBOARD_FAB2(SCH_1):GND    I22 @BASEBOARD_FAB2_LIB.BASEBOARD_FAB2(SCH_1):PAGE74
  AA66    GND @BASEBOARD_FAB2_LIB.BASEBOARD_FAB2(SCH_1):GND    I22 @BASEBOARD_FAB2_LIB.BASEBOARD_FAB2(SCH_1):PAGE74
  AA68    GND @BASEBOARD_FAB2_LIB.BASEBOARD_FAB2(SCH_1):GND    I22 @BASEBOARD_FAB2_LIB.BASEBOARD_FAB2(SCH_1):PAGE74
  AA76    GND @BASEBOARD_FAB2_LIB.BASEBOARD_FAB2(SCH_1):GND    I22 @BASEBOARD_FAB2_LIB.BASEBOARD_FAB2(SCH_1):PAGE74
  AA78    GND @BASEBOARD_FAB2_LIB.BASEBOARD_FAB2(SCH_1):GND    I22 @BASEBOARD_FAB2_LIB.BASEBOARD_FAB2(SCH_1):PAGE74
  AA80    GND @BASEBOARD_FAB2_LIB.BASEBOARD_FAB2(SCH_1):GND    I22 @BASEBOARD_FAB2_LIB.BASEBOARD_FAB2(SCH_1):PAGE74
  AA82    GND @BASEBOARD_FAB2_LIB.BASEBOARD_FAB2(SCH_1):GND    I22 @BASEBOARD_FAB2_LIB.BASEBOARD_FAB2(SCH_1):PAGE74
   AB1    GND @BASEBOARD_FAB2_LIB.BASEBOARD_FAB2(SCH_1):GND    I22 @BASEBOARD_FAB2_LIB.BASEBOARD_FAB2(SCH_1):PAGE74
   AB5    GND @BASEBOARD_FAB2_LIB.BASEBOARD_FAB2(SCH_1):GND    I22 @BASEBOARD_FAB2_LIB.BASEBOARD_FAB2(SCH_1):PAGE74
  AB11    GND @BASEBOARD_FAB2_LIB.BASEBOARD_FAB2(SCH_1):GND    I22 @BASEBOARD_FAB2_LIB.BASEBOARD_FAB2(SCH_1):PAGE74
  AB21    GND @BASEBOARD_FAB2_LIB.BASEBOARD_FAB2(SCH_1):GND    I22 @BASEBOARD_FAB2_LIB.BASEBOARD_FAB2(SCH_1):PAGE74
  AB23    GND @BASEBOARD_FAB2_LIB.BASEBOARD_FAB2(SCH_1):GND    I22 @BASEBOARD_FAB2_LIB.BASEBOARD_FAB2(SCH_1):PAGE74
  AB25    GND @BASEBOARD_FAB2_LIB.BASEBOARD_FAB2(SCH_1):GND    I22 @BASEBOARD_FAB2_LIB.BASEBOARD_FAB2(SCH_1):PAGE74
  AB29    GND @BASEBOARD_FAB2_LIB.BASEBOARD_FAB2(SCH_1):GND    I22 @BASEBOARD_FAB2_LIB.BASEBOARD_FAB2(SCH_1):PAGE74
  AB31    GND @BASEBOARD_FAB2_LIB.BASEBOARD_FAB2(SCH_1):GND    I22 @BASEBOARD_FAB2_LIB.BASEBOARD_FAB2(SCH_1):PAGE74
  AB35    GND @BASEBOARD_FAB2_LIB.BASEBOARD_FAB2(SCH_1):GND    I22 @BASEBOARD_FAB2_LIB.BASEBOARD_FAB2(SCH_1):PAGE74
  AB37    GND @BASEBOARD_FAB2_LIB.BASEBOARD_FAB2(SCH_1):GND    I22 @BASEBOARD_FAB2_LIB.BASEBOARD_FAB2(SCH_1):PAGE74
  AB41    GND @BASEBOARD_FAB2_LIB.BASEBOARD_FAB2(SCH_1):GND    I22 @BASEBOARD_FAB2_LIB.BASEBOARD_FAB2(SCH_1):PAGE74
  AB65    GND @BASEBOARD_FAB2_LIB.BASEBOARD_FAB2(SCH_1):GND    I22 @BASEBOARD_FAB2_LIB.BASEBOARD_FAB2(SCH_1):PAGE74
  AB69    GND @BASEBOARD_FAB2_LIB.BASEBOARD_FAB2(SCH_1):GND    I22 @BASEBOARD_FAB2_LIB.BASEBOARD_FAB2(SCH_1):PAGE74
  AB73    GND @BASEBOARD_FAB2_LIB.BASEBOARD_FAB2(SCH_1):GND    I22 @BASEBOARD_FAB2_LIB.BASEBOARD_FAB2(SCH_1):PAGE74
  AB79    GND @BASEBOARD_FAB2_LIB.BASEBOARD_FAB2(SCH_1):GND    I22 @BASEBOARD_FAB2_LIB.BASEBOARD_FAB2(SCH_1):PAGE74
  AB83    GND @BASEBOARD_FAB2_LIB.BASEBOARD_FAB2(SCH_1):GND    I22 @BASEBOARD_FAB2_LIB.BASEBOARD_FAB2(SCH_1):PAGE74
  AB85    GND @BASEBOARD_FAB2_LIB.BASEBOARD_FAB2(SCH_1):GND    I22 @BASEBOARD_FAB2_LIB.BASEBOARD_FAB2(SCH_1):PAGE74
  AC18    GND @BASEBOARD_FAB2_LIB.BASEBOARD_FAB2(SCH_1):GND    I22 @BASEBOARD_FAB2_LIB.BASEBOARD_FAB2(SCH_1):PAGE74
  AC22    GND @BASEBOARD_FAB2_LIB.BASEBOARD_FAB2(SCH_1):GND    I22 @BASEBOARD_FAB2_LIB.BASEBOARD_FAB2(SCH_1):PAGE74
  AC26    GND @BASEBOARD_FAB2_LIB.BASEBOARD_FAB2(SCH_1):GND    I22 @BASEBOARD_FAB2_LIB.BASEBOARD_FAB2(SCH_1):PAGE74
  AC28    GND @BASEBOARD_FAB2_LIB.BASEBOARD_FAB2(SCH_1):GND    I22 @BASEBOARD_FAB2_LIB.BASEBOARD_FAB2(SCH_1):PAGE74
  AC32    GND @BASEBOARD_FAB2_LIB.BASEBOARD_FAB2(SCH_1):GND    I22 @BASEBOARD_FAB2_LIB.BASEBOARD_FAB2(SCH_1):PAGE74
  AC34    GND @BASEBOARD_FAB2_LIB.BASEBOARD_FAB2(SCH_1):GND    I22 @BASEBOARD_FAB2_LIB.BASEBOARD_FAB2(SCH_1):PAGE74
  AC38    GND @BASEBOARD_FAB2_LIB.BASEBOARD_FAB2(SCH_1):GND    I22 @BASEBOARD_FAB2_LIB.BASEBOARD_FAB2(SCH_1):PAGE74
  AC40    GND @BASEBOARD_FAB2_LIB.BASEBOARD_FAB2(SCH_1):GND    I22 @BASEBOARD_FAB2_LIB.BASEBOARD_FAB2(SCH_1):PAGE74
  AC64    GND @BASEBOARD_FAB2_LIB.BASEBOARD_FAB2(SCH_1):GND    I22 @BASEBOARD_FAB2_LIB.BASEBOARD_FAB2(SCH_1):PAGE74
  AC70    GND @BASEBOARD_FAB2_LIB.BASEBOARD_FAB2(SCH_1):GND    I22 @BASEBOARD_FAB2_LIB.BASEBOARD_FAB2(SCH_1):PAGE74
  AC72    GND @BASEBOARD_FAB2_LIB.BASEBOARD_FAB2(SCH_1):GND    I22 @BASEBOARD_FAB2_LIB.BASEBOARD_FAB2(SCH_1):PAGE74
  AC78    GND @BASEBOARD_FAB2_LIB.BASEBOARD_FAB2(SCH_1):GND    I22 @BASEBOARD_FAB2_LIB.BASEBOARD_FAB2(SCH_1):PAGE74
  AC84    GND @BASEBOARD_FAB2_LIB.BASEBOARD_FAB2(SCH_1):GND    I22 @BASEBOARD_FAB2_LIB.BASEBOARD_FAB2(SCH_1):PAGE74
  AC86    GND @BASEBOARD_FAB2_LIB.BASEBOARD_FAB2(SCH_1):GND    I22 @BASEBOARD_FAB2_LIB.BASEBOARD_FAB2(SCH_1):PAGE74
   AD3    GND @BASEBOARD_FAB2_LIB.BASEBOARD_FAB2(SCH_1):GND    I22 @BASEBOARD_FAB2_LIB.BASEBOARD_FAB2(SCH_1):PAGE74
   AD7    GND @BASEBOARD_FAB2_LIB.BASEBOARD_FAB2(SCH_1):GND    I22 @BASEBOARD_FAB2_LIB.BASEBOARD_FAB2(SCH_1):PAGE74
   AD9    GND @BASEBOARD_FAB2_LIB.BASEBOARD_FAB2(SCH_1):GND    I22 @BASEBOARD_FAB2_LIB.BASEBOARD_FAB2(SCH_1):PAGE74
  AD11    GND @BASEBOARD_FAB2_LIB.BASEBOARD_FAB2(SCH_1):GND    I22 @BASEBOARD_FAB2_LIB.BASEBOARD_FAB2(SCH_1):PAGE74
  AD13    GND @BASEBOARD_FAB2_LIB.BASEBOARD_FAB2(SCH_1):GND    I22 @BASEBOARD_FAB2_LIB.BASEBOARD_FAB2(SCH_1):PAGE74
  AD15    GND @BASEBOARD_FAB2_LIB.BASEBOARD_FAB2(SCH_1):GND    I22 @BASEBOARD_FAB2_LIB.BASEBOARD_FAB2(SCH_1):PAGE74
  AD19    GND @BASEBOARD_FAB2_LIB.BASEBOARD_FAB2(SCH_1):GND    I22 @BASEBOARD_FAB2_LIB.BASEBOARD_FAB2(SCH_1):PAGE74
  AD21    GND @BASEBOARD_FAB2_LIB.BASEBOARD_FAB2(SCH_1):GND    I22 @BASEBOARD_FAB2_LIB.BASEBOARD_FAB2(SCH_1):PAGE74
  AD27    GND @BASEBOARD_FAB2_LIB.BASEBOARD_FAB2(SCH_1):GND    I22 @BASEBOARD_FAB2_LIB.BASEBOARD_FAB2(SCH_1):PAGE74
  AD33    GND @BASEBOARD_FAB2_LIB.BASEBOARD_FAB2(SCH_1):GND    I22 @BASEBOARD_FAB2_LIB.BASEBOARD_FAB2(SCH_1):PAGE74
  AD39    GND @BASEBOARD_FAB2_LIB.BASEBOARD_FAB2(SCH_1):GND    I22 @BASEBOARD_FAB2_LIB.BASEBOARD_FAB2(SCH_1):PAGE74
  AD43    GND @BASEBOARD_FAB2_LIB.BASEBOARD_FAB2(SCH_1):GND    I22 @BASEBOARD_FAB2_LIB.BASEBOARD_FAB2(SCH_1):PAGE74
  AD71    GND @BASEBOARD_FAB2_LIB.BASEBOARD_FAB2(SCH_1):GND    I22 @BASEBOARD_FAB2_LIB.BASEBOARD_FAB2(SCH_1):PAGE74
  AD73    GND @BASEBOARD_FAB2_LIB.BASEBOARD_FAB2(SCH_1):GND    I22 @BASEBOARD_FAB2_LIB.BASEBOARD_FAB2(SCH_1):PAGE74
  AD75    GND @BASEBOARD_FAB2_LIB.BASEBOARD_FAB2(SCH_1):GND    I22 @BASEBOARD_FAB2_LIB.BASEBOARD_FAB2(SCH_1):PAGE74
  AD81    GND @BASEBOARD_FAB2_LIB.BASEBOARD_FAB2(SCH_1):GND    I22 @BASEBOARD_FAB2_LIB.BASEBOARD_FAB2(SCH_1):PAGE74
  AD83    GND @BASEBOARD_FAB2_LIB.BASEBOARD_FAB2(SCH_1):GND    I22 @BASEBOARD_FAB2_LIB.BASEBOARD_FAB2(SCH_1):PAGE74
  AD85    GND @BASEBOARD_FAB2_LIB.BASEBOARD_FAB2(SCH_1):GND    I22 @BASEBOARD_FAB2_LIB.BASEBOARD_FAB2(SCH_1):PAGE74
   AE4    GND @BASEBOARD_FAB2_LIB.BASEBOARD_FAB2(SCH_1):GND    I22 @BASEBOARD_FAB2_LIB.BASEBOARD_FAB2(SCH_1):PAGE74
   AE8    GND @BASEBOARD_FAB2_LIB.BASEBOARD_FAB2(SCH_1):GND    I22 @BASEBOARD_FAB2_LIB.BASEBOARD_FAB2(SCH_1):PAGE74
  AC54    GND @BASEBOARD_FAB2_LIB.BASEBOARD_FAB2(SCH_1):GND    I22 @BASEBOARD_FAB2_LIB.BASEBOARD_FAB2(SCH_1):PAGE74
  AE16    GND @BASEBOARD_FAB2_LIB.BASEBOARD_FAB2(SCH_1):GND    I22 @BASEBOARD_FAB2_LIB.BASEBOARD_FAB2(SCH_1):PAGE74
  AE38    GND @BASEBOARD_FAB2_LIB.BASEBOARD_FAB2(SCH_1):GND    I22 @BASEBOARD_FAB2_LIB.BASEBOARD_FAB2(SCH_1):PAGE74
  AE40    GND @BASEBOARD_FAB2_LIB.BASEBOARD_FAB2(SCH_1):GND    I22 @BASEBOARD_FAB2_LIB.BASEBOARD_FAB2(SCH_1):PAGE74
  AE42    GND @BASEBOARD_FAB2_LIB.BASEBOARD_FAB2(SCH_1):GND    I22 @BASEBOARD_FAB2_LIB.BASEBOARD_FAB2(SCH_1):PAGE74
  AE64    GND @BASEBOARD_FAB2_LIB.BASEBOARD_FAB2(SCH_1):GND    I22 @BASEBOARD_FAB2_LIB.BASEBOARD_FAB2(SCH_1):PAGE74
  AE66    GND @BASEBOARD_FAB2_LIB.BASEBOARD_FAB2(SCH_1):GND    I22 @BASEBOARD_FAB2_LIB.BASEBOARD_FAB2(SCH_1):PAGE74
  AE68    GND @BASEBOARD_FAB2_LIB.BASEBOARD_FAB2(SCH_1):GND    I22 @BASEBOARD_FAB2_LIB.BASEBOARD_FAB2(SCH_1):PAGE74
  AE70    GND @BASEBOARD_FAB2_LIB.BASEBOARD_FAB2(SCH_1):GND    I22 @BASEBOARD_FAB2_LIB.BASEBOARD_FAB2(SCH_1):PAGE74
  AE78    GND @BASEBOARD_FAB2_LIB.BASEBOARD_FAB2(SCH_1):GND    I22 @BASEBOARD_FAB2_LIB.BASEBOARD_FAB2(SCH_1):PAGE74
   AF1    GND @BASEBOARD_FAB2_LIB.BASEBOARD_FAB2(SCH_1):GND    I22 @BASEBOARD_FAB2_LIB.BASEBOARD_FAB2(SCH_1):PAGE74
  AC52    GND @BASEBOARD_FAB2_LIB.BASEBOARD_FAB2(SCH_1):GND    I22 @BASEBOARD_FAB2_LIB.BASEBOARD_FAB2(SCH_1):PAGE74
   AF9    GND @BASEBOARD_FAB2_LIB.BASEBOARD_FAB2(SCH_1):GND    I22 @BASEBOARD_FAB2_LIB.BASEBOARD_FAB2(SCH_1):PAGE74
  AF21    GND @BASEBOARD_FAB2_LIB.BASEBOARD_FAB2(SCH_1):GND    I22 @BASEBOARD_FAB2_LIB.BASEBOARD_FAB2(SCH_1):PAGE74
  AF23    GND @BASEBOARD_FAB2_LIB.BASEBOARD_FAB2(SCH_1):GND    I22 @BASEBOARD_FAB2_LIB.BASEBOARD_FAB2(SCH_1):PAGE74
  AF25    GND @BASEBOARD_FAB2_LIB.BASEBOARD_FAB2(SCH_1):GND    I22 @BASEBOARD_FAB2_LIB.BASEBOARD_FAB2(SCH_1):PAGE74
  AF27    GND @BASEBOARD_FAB2_LIB.BASEBOARD_FAB2(SCH_1):GND    I22 @BASEBOARD_FAB2_LIB.BASEBOARD_FAB2(SCH_1):PAGE74
  AF29    GND @BASEBOARD_FAB2_LIB.BASEBOARD_FAB2(SCH_1):GND    I22 @BASEBOARD_FAB2_LIB.BASEBOARD_FAB2(SCH_1):PAGE74
  AF31    GND @BASEBOARD_FAB2_LIB.BASEBOARD_FAB2(SCH_1):GND    I22 @BASEBOARD_FAB2_LIB.BASEBOARD_FAB2(SCH_1):PAGE74
  AF33    GND @BASEBOARD_FAB2_LIB.BASEBOARD_FAB2(SCH_1):GND    I22 @BASEBOARD_FAB2_LIB.BASEBOARD_FAB2(SCH_1):PAGE74
  AF37    GND @BASEBOARD_FAB2_LIB.BASEBOARD_FAB2(SCH_1):GND    I22 @BASEBOARD_FAB2_LIB.BASEBOARD_FAB2(SCH_1):PAGE74
  AF39    GND @BASEBOARD_FAB2_LIB.BASEBOARD_FAB2(SCH_1):GND    I22 @BASEBOARD_FAB2_LIB.BASEBOARD_FAB2(SCH_1):PAGE74
  AF41    GND @BASEBOARD_FAB2_LIB.BASEBOARD_FAB2(SCH_1):GND    I22 @BASEBOARD_FAB2_LIB.BASEBOARD_FAB2(SCH_1):PAGE74
  AF73    GND @BASEBOARD_FAB2_LIB.BASEBOARD_FAB2(SCH_1):GND    I22 @BASEBOARD_FAB2_LIB.BASEBOARD_FAB2(SCH_1):PAGE74
  AF77    GND @BASEBOARD_FAB2_LIB.BASEBOARD_FAB2(SCH_1):GND    I22 @BASEBOARD_FAB2_LIB.BASEBOARD_FAB2(SCH_1):PAGE74
  AF83    GND @BASEBOARD_FAB2_LIB.BASEBOARD_FAB2(SCH_1):GND    I22 @BASEBOARD_FAB2_LIB.BASEBOARD_FAB2(SCH_1):PAGE74
  AF85    GND @BASEBOARD_FAB2_LIB.BASEBOARD_FAB2(SCH_1):GND    I22 @BASEBOARD_FAB2_LIB.BASEBOARD_FAB2(SCH_1):PAGE74
  AG12    GND @BASEBOARD_FAB2_LIB.BASEBOARD_FAB2(SCH_1):GND    I22 @BASEBOARD_FAB2_LIB.BASEBOARD_FAB2(SCH_1):PAGE74
  AG14    GND @BASEBOARD_FAB2_LIB.BASEBOARD_FAB2(SCH_1):GND    I22 @BASEBOARD_FAB2_LIB.BASEBOARD_FAB2(SCH_1):PAGE74
  AG18    GND @BASEBOARD_FAB2_LIB.BASEBOARD_FAB2(SCH_1):GND    I22 @BASEBOARD_FAB2_LIB.BASEBOARD_FAB2(SCH_1):PAGE74
  AG36    GND @BASEBOARD_FAB2_LIB.BASEBOARD_FAB2(SCH_1):GND    I22 @BASEBOARD_FAB2_LIB.BASEBOARD_FAB2(SCH_1):PAGE74
  AG64    GND @BASEBOARD_FAB2_LIB.BASEBOARD_FAB2(SCH_1):GND    I22 @BASEBOARD_FAB2_LIB.BASEBOARD_FAB2(SCH_1):PAGE74
  AG70    GND @BASEBOARD_FAB2_LIB.BASEBOARD_FAB2(SCH_1):GND    I22 @BASEBOARD_FAB2_LIB.BASEBOARD_FAB2(SCH_1):PAGE74
  AG74    GND @BASEBOARD_FAB2_LIB.BASEBOARD_FAB2(SCH_1):GND    I22 @BASEBOARD_FAB2_LIB.BASEBOARD_FAB2(SCH_1):PAGE74
  AG76    GND @BASEBOARD_FAB2_LIB.BASEBOARD_FAB2(SCH_1):GND    I22 @BASEBOARD_FAB2_LIB.BASEBOARD_FAB2(SCH_1):PAGE74
  AG78    GND @BASEBOARD_FAB2_LIB.BASEBOARD_FAB2(SCH_1):GND    I22 @BASEBOARD_FAB2_LIB.BASEBOARD_FAB2(SCH_1):PAGE74
  AG80    GND @BASEBOARD_FAB2_LIB.BASEBOARD_FAB2(SCH_1):GND    I22 @BASEBOARD_FAB2_LIB.BASEBOARD_FAB2(SCH_1):PAGE74
   AH1    GND @BASEBOARD_FAB2_LIB.BASEBOARD_FAB2(SCH_1):GND    I22 @BASEBOARD_FAB2_LIB.BASEBOARD_FAB2(SCH_1):PAGE74
   AH5    GND @BASEBOARD_FAB2_LIB.BASEBOARD_FAB2(SCH_1):GND    I22 @BASEBOARD_FAB2_LIB.BASEBOARD_FAB2(SCH_1):PAGE74
  AH21    GND @BASEBOARD_FAB2_LIB.BASEBOARD_FAB2(SCH_1):GND    I22 @BASEBOARD_FAB2_LIB.BASEBOARD_FAB2(SCH_1):PAGE74
  AH27    GND @BASEBOARD_FAB2_LIB.BASEBOARD_FAB2(SCH_1):GND    I22 @BASEBOARD_FAB2_LIB.BASEBOARD_FAB2(SCH_1):PAGE74
  AH33    GND @BASEBOARD_FAB2_LIB.BASEBOARD_FAB2(SCH_1):GND    I22 @BASEBOARD_FAB2_LIB.BASEBOARD_FAB2(SCH_1):PAGE74
  AH35    GND @BASEBOARD_FAB2_LIB.BASEBOARD_FAB2(SCH_1):GND    I22 @BASEBOARD_FAB2_LIB.BASEBOARD_FAB2(SCH_1):PAGE74
  AH45    GND @BASEBOARD_FAB2_LIB.BASEBOARD_FAB2(SCH_1):GND    I22 @BASEBOARD_FAB2_LIB.BASEBOARD_FAB2(SCH_1):PAGE74
  AH47    GND @BASEBOARD_FAB2_LIB.BASEBOARD_FAB2(SCH_1):GND    I22 @BASEBOARD_FAB2_LIB.BASEBOARD_FAB2(SCH_1):PAGE74
  AH49    GND @BASEBOARD_FAB2_LIB.BASEBOARD_FAB2(SCH_1):GND    I22 @BASEBOARD_FAB2_LIB.BASEBOARD_FAB2(SCH_1):PAGE74
  AH51    GND @BASEBOARD_FAB2_LIB.BASEBOARD_FAB2(SCH_1):GND    I22 @BASEBOARD_FAB2_LIB.BASEBOARD_FAB2(SCH_1):PAGE74
  AH53    GND @BASEBOARD_FAB2_LIB.BASEBOARD_FAB2(SCH_1):GND    I22 @BASEBOARD_FAB2_LIB.BASEBOARD_FAB2(SCH_1):PAGE74
  AH59    GND @BASEBOARD_FAB2_LIB.BASEBOARD_FAB2(SCH_1):GND    I22 @BASEBOARD_FAB2_LIB.BASEBOARD_FAB2(SCH_1):PAGE74
  AH61    GND @BASEBOARD_FAB2_LIB.BASEBOARD_FAB2(SCH_1):GND    I22 @BASEBOARD_FAB2_LIB.BASEBOARD_FAB2(SCH_1):PAGE74
  AH65    GND @BASEBOARD_FAB2_LIB.BASEBOARD_FAB2(SCH_1):GND    I22 @BASEBOARD_FAB2_LIB.BASEBOARD_FAB2(SCH_1):PAGE74
  AH69    GND @BASEBOARD_FAB2_LIB.BASEBOARD_FAB2(SCH_1):GND    I22 @BASEBOARD_FAB2_LIB.BASEBOARD_FAB2(SCH_1):PAGE74
  AH75    GND @BASEBOARD_FAB2_LIB.BASEBOARD_FAB2(SCH_1):GND    I22 @BASEBOARD_FAB2_LIB.BASEBOARD_FAB2(SCH_1):PAGE74
  AH77    GND @BASEBOARD_FAB2_LIB.BASEBOARD_FAB2(SCH_1):GND    I22 @BASEBOARD_FAB2_LIB.BASEBOARD_FAB2(SCH_1):PAGE74
  AH83    GND @BASEBOARD_FAB2_LIB.BASEBOARD_FAB2(SCH_1):GND    I22 @BASEBOARD_FAB2_LIB.BASEBOARD_FAB2(SCH_1):PAGE74
   AJ8    GND @BASEBOARD_FAB2_LIB.BASEBOARD_FAB2(SCH_1):GND    I22 @BASEBOARD_FAB2_LIB.BASEBOARD_FAB2(SCH_1):PAGE74
  AJ22    GND @BASEBOARD_FAB2_LIB.BASEBOARD_FAB2(SCH_1):GND    I22 @BASEBOARD_FAB2_LIB.BASEBOARD_FAB2(SCH_1):PAGE74
  AJ26    GND @BASEBOARD_FAB2_LIB.BASEBOARD_FAB2(SCH_1):GND    I22 @BASEBOARD_FAB2_LIB.BASEBOARD_FAB2(SCH_1):PAGE74
  AJ28    GND @BASEBOARD_FAB2_LIB.BASEBOARD_FAB2(SCH_1):GND    I22 @BASEBOARD_FAB2_LIB.BASEBOARD_FAB2(SCH_1):PAGE74
  AJ32    GND @BASEBOARD_FAB2_LIB.BASEBOARD_FAB2(SCH_1):GND    I22 @BASEBOARD_FAB2_LIB.BASEBOARD_FAB2(SCH_1):PAGE74
  AJ34    GND @BASEBOARD_FAB2_LIB.BASEBOARD_FAB2(SCH_1):GND    I22 @BASEBOARD_FAB2_LIB.BASEBOARD_FAB2(SCH_1):PAGE74
  AJ46    GND @BASEBOARD_FAB2_LIB.BASEBOARD_FAB2(SCH_1):GND    I22 @BASEBOARD_FAB2_LIB.BASEBOARD_FAB2(SCH_1):PAGE74
  AJ48    GND @BASEBOARD_FAB2_LIB.BASEBOARD_FAB2(SCH_1):GND    I22 @BASEBOARD_FAB2_LIB.BASEBOARD_FAB2(SCH_1):PAGE74
  AJ50    GND @BASEBOARD_FAB2_LIB.BASEBOARD_FAB2(SCH_1):GND    I22 @BASEBOARD_FAB2_LIB.BASEBOARD_FAB2(SCH_1):PAGE74
  AJ52    GND @BASEBOARD_FAB2_LIB.BASEBOARD_FAB2(SCH_1):GND    I22 @BASEBOARD_FAB2_LIB.BASEBOARD_FAB2(SCH_1):PAGE74
  AJ54    GND @BASEBOARD_FAB2_LIB.BASEBOARD_FAB2(SCH_1):GND    I22 @BASEBOARD_FAB2_LIB.BASEBOARD_FAB2(SCH_1):PAGE74
  AJ66    GND @BASEBOARD_FAB2_LIB.BASEBOARD_FAB2(SCH_1):GND    I22 @BASEBOARD_FAB2_LIB.BASEBOARD_FAB2(SCH_1):PAGE74
  AJ68    GND @BASEBOARD_FAB2_LIB.BASEBOARD_FAB2(SCH_1):GND    I22 @BASEBOARD_FAB2_LIB.BASEBOARD_FAB2(SCH_1):PAGE74
  AJ74    GND @BASEBOARD_FAB2_LIB.BASEBOARD_FAB2(SCH_1):GND    I22 @BASEBOARD_FAB2_LIB.BASEBOARD_FAB2(SCH_1):PAGE74
  AJ78    GND @BASEBOARD_FAB2_LIB.BASEBOARD_FAB2(SCH_1):GND    I22 @BASEBOARD_FAB2_LIB.BASEBOARD_FAB2(SCH_1):PAGE74
  AJ82    GND @BASEBOARD_FAB2_LIB.BASEBOARD_FAB2(SCH_1):GND    I22 @BASEBOARD_FAB2_LIB.BASEBOARD_FAB2(SCH_1):PAGE74
  AJ86    GND @BASEBOARD_FAB2_LIB.BASEBOARD_FAB2(SCH_1):GND    I22 @BASEBOARD_FAB2_LIB.BASEBOARD_FAB2(SCH_1):PAGE74
   AK9    GND @BASEBOARD_FAB2_LIB.BASEBOARD_FAB2(SCH_1):GND    I22 @BASEBOARD_FAB2_LIB.BASEBOARD_FAB2(SCH_1):PAGE74
  AK13    GND @BASEBOARD_FAB2_LIB.BASEBOARD_FAB2(SCH_1):GND    I22 @BASEBOARD_FAB2_LIB.BASEBOARD_FAB2(SCH_1):PAGE74
  AK19    GND @BASEBOARD_FAB2_LIB.BASEBOARD_FAB2(SCH_1):GND    I22 @BASEBOARD_FAB2_LIB.BASEBOARD_FAB2(SCH_1):PAGE74
  AK23    GND @BASEBOARD_FAB2_LIB.BASEBOARD_FAB2(SCH_1):GND    I22 @BASEBOARD_FAB2_LIB.BASEBOARD_FAB2(SCH_1):PAGE74
  AK25    GND @BASEBOARD_FAB2_LIB.BASEBOARD_FAB2(SCH_1):GND    I22 @BASEBOARD_FAB2_LIB.BASEBOARD_FAB2(SCH_1):PAGE74
  AK29    GND @BASEBOARD_FAB2_LIB.BASEBOARD_FAB2(SCH_1):GND    I22 @BASEBOARD_FAB2_LIB.BASEBOARD_FAB2(SCH_1):PAGE74
  AK31    GND @BASEBOARD_FAB2_LIB.BASEBOARD_FAB2(SCH_1):GND    I22 @BASEBOARD_FAB2_LIB.BASEBOARD_FAB2(SCH_1):PAGE74
  AK33    GND @BASEBOARD_FAB2_LIB.BASEBOARD_FAB2(SCH_1):GND    I22 @BASEBOARD_FAB2_LIB.BASEBOARD_FAB2(SCH_1):PAGE74
  AK55    GND @BASEBOARD_FAB2_LIB.BASEBOARD_FAB2(SCH_1):GND    I22 @BASEBOARD_FAB2_LIB.BASEBOARD_FAB2(SCH_1):PAGE74
  AK65    GND @BASEBOARD_FAB2_LIB.BASEBOARD_FAB2(SCH_1):GND    I22 @BASEBOARD_FAB2_LIB.BASEBOARD_FAB2(SCH_1):PAGE74
  AK67    GND @BASEBOARD_FAB2_LIB.BASEBOARD_FAB2(SCH_1):GND    I22 @BASEBOARD_FAB2_LIB.BASEBOARD_FAB2(SCH_1):PAGE74
  AK73    GND @BASEBOARD_FAB2_LIB.BASEBOARD_FAB2(SCH_1):GND    I22 @BASEBOARD_FAB2_LIB.BASEBOARD_FAB2(SCH_1):PAGE74
  AK79    GND @BASEBOARD_FAB2_LIB.BASEBOARD_FAB2(SCH_1):GND    I22 @BASEBOARD_FAB2_LIB.BASEBOARD_FAB2(SCH_1):PAGE74
  AK81    GND @BASEBOARD_FAB2_LIB.BASEBOARD_FAB2(SCH_1):GND    I22 @BASEBOARD_FAB2_LIB.BASEBOARD_FAB2(SCH_1):PAGE74
  AK83    GND @BASEBOARD_FAB2_LIB.BASEBOARD_FAB2(SCH_1):GND    I22 @BASEBOARD_FAB2_LIB.BASEBOARD_FAB2(SCH_1):PAGE74
  AK85    GND @BASEBOARD_FAB2_LIB.BASEBOARD_FAB2(SCH_1):GND    I22 @BASEBOARD_FAB2_LIB.BASEBOARD_FAB2(SCH_1):PAGE74
   AL4    GND @BASEBOARD_FAB2_LIB.BASEBOARD_FAB2(SCH_1):GND    I22 @BASEBOARD_FAB2_LIB.BASEBOARD_FAB2(SCH_1):PAGE74
  AL10    GND @BASEBOARD_FAB2_LIB.BASEBOARD_FAB2(SCH_1):GND    I22 @BASEBOARD_FAB2_LIB.BASEBOARD_FAB2(SCH_1):PAGE74
  AL24    GND @BASEBOARD_FAB2_LIB.BASEBOARD_FAB2(SCH_1):GND    I22 @BASEBOARD_FAB2_LIB.BASEBOARD_FAB2(SCH_1):PAGE74
  AL30    GND @BASEBOARD_FAB2_LIB.BASEBOARD_FAB2(SCH_1):GND    I22 @BASEBOARD_FAB2_LIB.BASEBOARD_FAB2(SCH_1):PAGE74
  AL32    GND @BASEBOARD_FAB2_LIB.BASEBOARD_FAB2(SCH_1):GND    I22 @BASEBOARD_FAB2_LIB.BASEBOARD_FAB2(SCH_1):PAGE74
  AL56    GND @BASEBOARD_FAB2_LIB.BASEBOARD_FAB2(SCH_1):GND    I22 @BASEBOARD_FAB2_LIB.BASEBOARD_FAB2(SCH_1):PAGE74
  AL64    GND @BASEBOARD_FAB2_LIB.BASEBOARD_FAB2(SCH_1):GND    I22 @BASEBOARD_FAB2_LIB.BASEBOARD_FAB2(SCH_1):PAGE74
  AL68    GND @BASEBOARD_FAB2_LIB.BASEBOARD_FAB2(SCH_1):GND    I22 @BASEBOARD_FAB2_LIB.BASEBOARD_FAB2(SCH_1):PAGE74
  AL76    GND @BASEBOARD_FAB2_LIB.BASEBOARD_FAB2(SCH_1):GND    I23 @BASEBOARD_FAB2_LIB.BASEBOARD_FAB2(SCH_1):PAGE74
  AL78    GND @BASEBOARD_FAB2_LIB.BASEBOARD_FAB2(SCH_1):GND    I23 @BASEBOARD_FAB2_LIB.BASEBOARD_FAB2(SCH_1):PAGE74
  AL80    GND @BASEBOARD_FAB2_LIB.BASEBOARD_FAB2(SCH_1):GND    I23 @BASEBOARD_FAB2_LIB.BASEBOARD_FAB2(SCH_1):PAGE74
  AL82    GND @BASEBOARD_FAB2_LIB.BASEBOARD_FAB2(SCH_1):GND    I23 @BASEBOARD_FAB2_LIB.BASEBOARD_FAB2(SCH_1):PAGE74
  AL86    GND @BASEBOARD_FAB2_LIB.BASEBOARD_FAB2(SCH_1):GND    I23 @BASEBOARD_FAB2_LIB.BASEBOARD_FAB2(SCH_1):PAGE74
   AM1    GND @BASEBOARD_FAB2_LIB.BASEBOARD_FAB2(SCH_1):GND    I23 @BASEBOARD_FAB2_LIB.BASEBOARD_FAB2(SCH_1):PAGE74
  AC50    GND @BASEBOARD_FAB2_LIB.BASEBOARD_FAB2(SCH_1):GND    I23 @BASEBOARD_FAB2_LIB.BASEBOARD_FAB2(SCH_1):PAGE74
  AM31    GND @BASEBOARD_FAB2_LIB.BASEBOARD_FAB2(SCH_1):GND    I23 @BASEBOARD_FAB2_LIB.BASEBOARD_FAB2(SCH_1):PAGE74
  AM57    GND @BASEBOARD_FAB2_LIB.BASEBOARD_FAB2(SCH_1):GND    I23 @BASEBOARD_FAB2_LIB.BASEBOARD_FAB2(SCH_1):PAGE74
  AM63    GND @BASEBOARD_FAB2_LIB.BASEBOARD_FAB2(SCH_1):GND    I23 @BASEBOARD_FAB2_LIB.BASEBOARD_FAB2(SCH_1):PAGE74
  AM69    GND @BASEBOARD_FAB2_LIB.BASEBOARD_FAB2(SCH_1):GND    I23 @BASEBOARD_FAB2_LIB.BASEBOARD_FAB2(SCH_1):PAGE74
  AM73    GND @BASEBOARD_FAB2_LIB.BASEBOARD_FAB2(SCH_1):GND    I23 @BASEBOARD_FAB2_LIB.BASEBOARD_FAB2(SCH_1):PAGE74
  AM79    GND @BASEBOARD_FAB2_LIB.BASEBOARD_FAB2(SCH_1):GND    I23 @BASEBOARD_FAB2_LIB.BASEBOARD_FAB2(SCH_1):PAGE74
  AM83    GND @BASEBOARD_FAB2_LIB.BASEBOARD_FAB2(SCH_1):GND    I23 @BASEBOARD_FAB2_LIB.BASEBOARD_FAB2(SCH_1):PAGE74
   AN2    GND @BASEBOARD_FAB2_LIB.BASEBOARD_FAB2(SCH_1):GND    I23 @BASEBOARD_FAB2_LIB.BASEBOARD_FAB2(SCH_1):PAGE74
   AN6    GND @BASEBOARD_FAB2_LIB.BASEBOARD_FAB2(SCH_1):GND    I23 @BASEBOARD_FAB2_LIB.BASEBOARD_FAB2(SCH_1):PAGE74
  AN28    GND @BASEBOARD_FAB2_LIB.BASEBOARD_FAB2(SCH_1):GND    I23 @BASEBOARD_FAB2_LIB.BASEBOARD_FAB2(SCH_1):PAGE74
  AN58    GND @BASEBOARD_FAB2_LIB.BASEBOARD_FAB2(SCH_1):GND    I23 @BASEBOARD_FAB2_LIB.BASEBOARD_FAB2(SCH_1):PAGE74
  AN78    GND @BASEBOARD_FAB2_LIB.BASEBOARD_FAB2(SCH_1):GND    I23 @BASEBOARD_FAB2_LIB.BASEBOARD_FAB2(SCH_1):PAGE74
   AP5    GND @BASEBOARD_FAB2_LIB.BASEBOARD_FAB2(SCH_1):GND    I23 @BASEBOARD_FAB2_LIB.BASEBOARD_FAB2(SCH_1):PAGE74
   AP9    GND @BASEBOARD_FAB2_LIB.BASEBOARD_FAB2(SCH_1):GND    I23 @BASEBOARD_FAB2_LIB.BASEBOARD_FAB2(SCH_1):PAGE74
  AP13    GND @BASEBOARD_FAB2_LIB.BASEBOARD_FAB2(SCH_1):GND    I23 @BASEBOARD_FAB2_LIB.BASEBOARD_FAB2(SCH_1):PAGE74
  AP19    GND @BASEBOARD_FAB2_LIB.BASEBOARD_FAB2(SCH_1):GND    I23 @BASEBOARD_FAB2_LIB.BASEBOARD_FAB2(SCH_1):PAGE74
  AP31    GND @BASEBOARD_FAB2_LIB.BASEBOARD_FAB2(SCH_1):GND    I23 @BASEBOARD_FAB2_LIB.BASEBOARD_FAB2(SCH_1):PAGE74
  AP59    GND @BASEBOARD_FAB2_LIB.BASEBOARD_FAB2(SCH_1):GND    I23 @BASEBOARD_FAB2_LIB.BASEBOARD_FAB2(SCH_1):PAGE74
  AP63    GND @BASEBOARD_FAB2_LIB.BASEBOARD_FAB2(SCH_1):GND    I23 @BASEBOARD_FAB2_LIB.BASEBOARD_FAB2(SCH_1):PAGE74
  AP65    GND @BASEBOARD_FAB2_LIB.BASEBOARD_FAB2(SCH_1):GND    I23 @BASEBOARD_FAB2_LIB.BASEBOARD_FAB2(SCH_1):PAGE74
  AP67    GND @BASEBOARD_FAB2_LIB.BASEBOARD_FAB2(SCH_1):GND    I23 @BASEBOARD_FAB2_LIB.BASEBOARD_FAB2(SCH_1):PAGE74
  AP69    GND @BASEBOARD_FAB2_LIB.BASEBOARD_FAB2(SCH_1):GND    I23 @BASEBOARD_FAB2_LIB.BASEBOARD_FAB2(SCH_1):PAGE74
  AP73    GND @BASEBOARD_FAB2_LIB.BASEBOARD_FAB2(SCH_1):GND    I23 @BASEBOARD_FAB2_LIB.BASEBOARD_FAB2(SCH_1):PAGE74
  AP75    GND @BASEBOARD_FAB2_LIB.BASEBOARD_FAB2(SCH_1):GND    I23 @BASEBOARD_FAB2_LIB.BASEBOARD_FAB2(SCH_1):PAGE74
  AP81    GND @BASEBOARD_FAB2_LIB.BASEBOARD_FAB2(SCH_1):GND    I23 @BASEBOARD_FAB2_LIB.BASEBOARD_FAB2(SCH_1):PAGE74
  AP83    GND @BASEBOARD_FAB2_LIB.BASEBOARD_FAB2(SCH_1):GND    I23 @BASEBOARD_FAB2_LIB.BASEBOARD_FAB2(SCH_1):PAGE74
  AP85    GND @BASEBOARD_FAB2_LIB.BASEBOARD_FAB2(SCH_1):GND    I23 @BASEBOARD_FAB2_LIB.BASEBOARD_FAB2(SCH_1):PAGE74
  AR10    GND @BASEBOARD_FAB2_LIB.BASEBOARD_FAB2(SCH_1):GND    I23 @BASEBOARD_FAB2_LIB.BASEBOARD_FAB2(SCH_1):PAGE74
  AR24    GND @BASEBOARD_FAB2_LIB.BASEBOARD_FAB2(SCH_1):GND    I23 @BASEBOARD_FAB2_LIB.BASEBOARD_FAB2(SCH_1):PAGE74
  AR30    GND @BASEBOARD_FAB2_LIB.BASEBOARD_FAB2(SCH_1):GND    I23 @BASEBOARD_FAB2_LIB.BASEBOARD_FAB2(SCH_1):PAGE74
  AR60    GND @BASEBOARD_FAB2_LIB.BASEBOARD_FAB2(SCH_1):GND    I23 @BASEBOARD_FAB2_LIB.BASEBOARD_FAB2(SCH_1):PAGE74
  AR72    GND @BASEBOARD_FAB2_LIB.BASEBOARD_FAB2(SCH_1):GND    I23 @BASEBOARD_FAB2_LIB.BASEBOARD_FAB2(SCH_1):PAGE74
  AR78    GND @BASEBOARD_FAB2_LIB.BASEBOARD_FAB2(SCH_1):GND    I23 @BASEBOARD_FAB2_LIB.BASEBOARD_FAB2(SCH_1):PAGE74
  AC48    GND @BASEBOARD_FAB2_LIB.BASEBOARD_FAB2(SCH_1):GND    I23 @BASEBOARD_FAB2_LIB.BASEBOARD_FAB2(SCH_1):PAGE74
   P63    GND @BASEBOARD_FAB2_LIB.BASEBOARD_FAB2(SCH_1):GND    I23 @BASEBOARD_FAB2_LIB.BASEBOARD_FAB2(SCH_1):PAGE74
  AT15    GND @BASEBOARD_FAB2_LIB.BASEBOARD_FAB2(SCH_1):GND    I23 @BASEBOARD_FAB2_LIB.BASEBOARD_FAB2(SCH_1):PAGE74
  AT17    GND @BASEBOARD_FAB2_LIB.BASEBOARD_FAB2(SCH_1):GND    I23 @BASEBOARD_FAB2_LIB.BASEBOARD_FAB2(SCH_1):PAGE74
  AT21    GND @BASEBOARD_FAB2_LIB.BASEBOARD_FAB2(SCH_1):GND    I23 @BASEBOARD_FAB2_LIB.BASEBOARD_FAB2(SCH_1):PAGE74
  AT27    GND @BASEBOARD_FAB2_LIB.BASEBOARD_FAB2(SCH_1):GND    I23 @BASEBOARD_FAB2_LIB.BASEBOARD_FAB2(SCH_1):PAGE74
  AT61    GND @BASEBOARD_FAB2_LIB.BASEBOARD_FAB2(SCH_1):GND    I23 @BASEBOARD_FAB2_LIB.BASEBOARD_FAB2(SCH_1):PAGE74
  AT63    GND @BASEBOARD_FAB2_LIB.BASEBOARD_FAB2(SCH_1):GND    I23 @BASEBOARD_FAB2_LIB.BASEBOARD_FAB2(SCH_1):PAGE74
  AT69    GND @BASEBOARD_FAB2_LIB.BASEBOARD_FAB2(SCH_1):GND    I23 @BASEBOARD_FAB2_LIB.BASEBOARD_FAB2(SCH_1):PAGE74
  AT73    GND @BASEBOARD_FAB2_LIB.BASEBOARD_FAB2(SCH_1):GND    I23 @BASEBOARD_FAB2_LIB.BASEBOARD_FAB2(SCH_1):PAGE74
  AT77    GND @BASEBOARD_FAB2_LIB.BASEBOARD_FAB2(SCH_1):GND    I23 @BASEBOARD_FAB2_LIB.BASEBOARD_FAB2(SCH_1):PAGE74
  AT83    GND @BASEBOARD_FAB2_LIB.BASEBOARD_FAB2(SCH_1):GND    I23 @BASEBOARD_FAB2_LIB.BASEBOARD_FAB2(SCH_1):PAGE74
  AT85    GND @BASEBOARD_FAB2_LIB.BASEBOARD_FAB2(SCH_1):GND    I23 @BASEBOARD_FAB2_LIB.BASEBOARD_FAB2(SCH_1):PAGE74
   AU2    GND @BASEBOARD_FAB2_LIB.BASEBOARD_FAB2(SCH_1):GND    I23 @BASEBOARD_FAB2_LIB.BASEBOARD_FAB2(SCH_1):PAGE74
   AU6    GND @BASEBOARD_FAB2_LIB.BASEBOARD_FAB2(SCH_1):GND    I23 @BASEBOARD_FAB2_LIB.BASEBOARD_FAB2(SCH_1):PAGE74
  AU26    GND @BASEBOARD_FAB2_LIB.BASEBOARD_FAB2(SCH_1):GND    I23 @BASEBOARD_FAB2_LIB.BASEBOARD_FAB2(SCH_1):PAGE74
  AU28    GND @BASEBOARD_FAB2_LIB.BASEBOARD_FAB2(SCH_1):GND    I23 @BASEBOARD_FAB2_LIB.BASEBOARD_FAB2(SCH_1):PAGE74
  AU62    GND @BASEBOARD_FAB2_LIB.BASEBOARD_FAB2(SCH_1):GND    I23 @BASEBOARD_FAB2_LIB.BASEBOARD_FAB2(SCH_1):PAGE74
  AU64    GND @BASEBOARD_FAB2_LIB.BASEBOARD_FAB2(SCH_1):GND    I23 @BASEBOARD_FAB2_LIB.BASEBOARD_FAB2(SCH_1):PAGE74
  AU68    GND @BASEBOARD_FAB2_LIB.BASEBOARD_FAB2(SCH_1):GND    I23 @BASEBOARD_FAB2_LIB.BASEBOARD_FAB2(SCH_1):PAGE74
  AU74    GND @BASEBOARD_FAB2_LIB.BASEBOARD_FAB2(SCH_1):GND    I23 @BASEBOARD_FAB2_LIB.BASEBOARD_FAB2(SCH_1):PAGE74
  AU76    GND @BASEBOARD_FAB2_LIB.BASEBOARD_FAB2(SCH_1):GND    I23 @BASEBOARD_FAB2_LIB.BASEBOARD_FAB2(SCH_1):PAGE74
  AU78    GND @BASEBOARD_FAB2_LIB.BASEBOARD_FAB2(SCH_1):GND    I23 @BASEBOARD_FAB2_LIB.BASEBOARD_FAB2(SCH_1):PAGE74
  AU80    GND @BASEBOARD_FAB2_LIB.BASEBOARD_FAB2(SCH_1):GND    I23 @BASEBOARD_FAB2_LIB.BASEBOARD_FAB2(SCH_1):PAGE74
  AU84    GND @BASEBOARD_FAB2_LIB.BASEBOARD_FAB2(SCH_1):GND    I23 @BASEBOARD_FAB2_LIB.BASEBOARD_FAB2(SCH_1):PAGE74
  AU86    GND @BASEBOARD_FAB2_LIB.BASEBOARD_FAB2(SCH_1):GND    I23 @BASEBOARD_FAB2_LIB.BASEBOARD_FAB2(SCH_1):PAGE74
   AV1    GND @BASEBOARD_FAB2_LIB.BASEBOARD_FAB2(SCH_1):GND    I23 @BASEBOARD_FAB2_LIB.BASEBOARD_FAB2(SCH_1):PAGE74
   AV3    GND @BASEBOARD_FAB2_LIB.BASEBOARD_FAB2(SCH_1):GND    I23 @BASEBOARD_FAB2_LIB.BASEBOARD_FAB2(SCH_1):PAGE74
   AV7    GND @BASEBOARD_FAB2_LIB.BASEBOARD_FAB2(SCH_1):GND    I23 @BASEBOARD_FAB2_LIB.BASEBOARD_FAB2(SCH_1):PAGE74
  AV11    GND @BASEBOARD_FAB2_LIB.BASEBOARD_FAB2(SCH_1):GND    I23 @BASEBOARD_FAB2_LIB.BASEBOARD_FAB2(SCH_1):PAGE74
  AV13    GND @BASEBOARD_FAB2_LIB.BASEBOARD_FAB2(SCH_1):GND    I23 @BASEBOARD_FAB2_LIB.BASEBOARD_FAB2(SCH_1):PAGE74
  AV19    GND @BASEBOARD_FAB2_LIB.BASEBOARD_FAB2(SCH_1):GND    I23 @BASEBOARD_FAB2_LIB.BASEBOARD_FAB2(SCH_1):PAGE74
  AV23    GND @BASEBOARD_FAB2_LIB.BASEBOARD_FAB2(SCH_1):GND    I23 @BASEBOARD_FAB2_LIB.BASEBOARD_FAB2(SCH_1):PAGE74
  AV25    GND @BASEBOARD_FAB2_LIB.BASEBOARD_FAB2(SCH_1):GND    I23 @BASEBOARD_FAB2_LIB.BASEBOARD_FAB2(SCH_1):PAGE74
  AV63    GND @BASEBOARD_FAB2_LIB.BASEBOARD_FAB2(SCH_1):GND    I23 @BASEBOARD_FAB2_LIB.BASEBOARD_FAB2(SCH_1):PAGE74
  AV65    GND @BASEBOARD_FAB2_LIB.BASEBOARD_FAB2(SCH_1):GND    I23 @BASEBOARD_FAB2_LIB.BASEBOARD_FAB2(SCH_1):PAGE74
  AV67    GND @BASEBOARD_FAB2_LIB.BASEBOARD_FAB2(SCH_1):GND    I23 @BASEBOARD_FAB2_LIB.BASEBOARD_FAB2(SCH_1):PAGE74
  AV75    GND @BASEBOARD_FAB2_LIB.BASEBOARD_FAB2(SCH_1):GND    I23 @BASEBOARD_FAB2_LIB.BASEBOARD_FAB2(SCH_1):PAGE74
  AV83    GND @BASEBOARD_FAB2_LIB.BASEBOARD_FAB2(SCH_1):GND    I23 @BASEBOARD_FAB2_LIB.BASEBOARD_FAB2(SCH_1):PAGE74
   AW2    GND @BASEBOARD_FAB2_LIB.BASEBOARD_FAB2(SCH_1):GND    I23 @BASEBOARD_FAB2_LIB.BASEBOARD_FAB2(SCH_1):PAGE74
  AW10    GND @BASEBOARD_FAB2_LIB.BASEBOARD_FAB2(SCH_1):GND    I23 @BASEBOARD_FAB2_LIB.BASEBOARD_FAB2(SCH_1):PAGE74
  AW62    GND @BASEBOARD_FAB2_LIB.BASEBOARD_FAB2(SCH_1):GND    I23 @BASEBOARD_FAB2_LIB.BASEBOARD_FAB2(SCH_1):PAGE74
  AW66    GND @BASEBOARD_FAB2_LIB.BASEBOARD_FAB2(SCH_1):GND    I23 @BASEBOARD_FAB2_LIB.BASEBOARD_FAB2(SCH_1):PAGE74
  AW68    GND @BASEBOARD_FAB2_LIB.BASEBOARD_FAB2(SCH_1):GND    I23 @BASEBOARD_FAB2_LIB.BASEBOARD_FAB2(SCH_1):PAGE74
  AW70    GND @BASEBOARD_FAB2_LIB.BASEBOARD_FAB2(SCH_1):GND    I23 @BASEBOARD_FAB2_LIB.BASEBOARD_FAB2(SCH_1):PAGE74
  AW72    GND @BASEBOARD_FAB2_LIB.BASEBOARD_FAB2(SCH_1):GND    I23 @BASEBOARD_FAB2_LIB.BASEBOARD_FAB2(SCH_1):PAGE74
  AW74    GND @BASEBOARD_FAB2_LIB.BASEBOARD_FAB2(SCH_1):GND    I23 @BASEBOARD_FAB2_LIB.BASEBOARD_FAB2(SCH_1):PAGE74
  AW78    GND @BASEBOARD_FAB2_LIB.BASEBOARD_FAB2(SCH_1):GND    I23 @BASEBOARD_FAB2_LIB.BASEBOARD_FAB2(SCH_1):PAGE74
  AW82    GND @BASEBOARD_FAB2_LIB.BASEBOARD_FAB2(SCH_1):GND    I23 @BASEBOARD_FAB2_LIB.BASEBOARD_FAB2(SCH_1):PAGE74
  AW84    GND @BASEBOARD_FAB2_LIB.BASEBOARD_FAB2(SCH_1):GND    I23 @BASEBOARD_FAB2_LIB.BASEBOARD_FAB2(SCH_1):PAGE74
   AY5    GND @BASEBOARD_FAB2_LIB.BASEBOARD_FAB2(SCH_1):GND    I23 @BASEBOARD_FAB2_LIB.BASEBOARD_FAB2(SCH_1):PAGE74
  AY15    GND @BASEBOARD_FAB2_LIB.BASEBOARD_FAB2(SCH_1):GND    I23 @BASEBOARD_FAB2_LIB.BASEBOARD_FAB2(SCH_1):PAGE74
  AY17    GND @BASEBOARD_FAB2_LIB.BASEBOARD_FAB2(SCH_1):GND    I23 @BASEBOARD_FAB2_LIB.BASEBOARD_FAB2(SCH_1):PAGE74
  AY21    GND @BASEBOARD_FAB2_LIB.BASEBOARD_FAB2(SCH_1):GND    I23 @BASEBOARD_FAB2_LIB.BASEBOARD_FAB2(SCH_1):PAGE74
  AY23    GND @BASEBOARD_FAB2_LIB.BASEBOARD_FAB2(SCH_1):GND    I23 @BASEBOARD_FAB2_LIB.BASEBOARD_FAB2(SCH_1):PAGE74
  AY25    GND @BASEBOARD_FAB2_LIB.BASEBOARD_FAB2(SCH_1):GND    I23 @BASEBOARD_FAB2_LIB.BASEBOARD_FAB2(SCH_1):PAGE74
  AY63    GND @BASEBOARD_FAB2_LIB.BASEBOARD_FAB2(SCH_1):GND    I23 @BASEBOARD_FAB2_LIB.BASEBOARD_FAB2(SCH_1):PAGE74
  AY79    GND @BASEBOARD_FAB2_LIB.BASEBOARD_FAB2(SCH_1):GND    I23 @BASEBOARD_FAB2_LIB.BASEBOARD_FAB2(SCH_1):PAGE74
  AY81    GND @BASEBOARD_FAB2_LIB.BASEBOARD_FAB2(SCH_1):GND    I23 @BASEBOARD_FAB2_LIB.BASEBOARD_FAB2(SCH_1):PAGE74
   BA2    GND @BASEBOARD_FAB2_LIB.BASEBOARD_FAB2(SCH_1):GND    I23 @BASEBOARD_FAB2_LIB.BASEBOARD_FAB2(SCH_1):PAGE74
   BA6    GND @BASEBOARD_FAB2_LIB.BASEBOARD_FAB2(SCH_1):GND    I23 @BASEBOARD_FAB2_LIB.BASEBOARD_FAB2(SCH_1):PAGE74
  BA12    GND @BASEBOARD_FAB2_LIB.BASEBOARD_FAB2(SCH_1):GND    I23 @BASEBOARD_FAB2_LIB.BASEBOARD_FAB2(SCH_1):PAGE74
  BA62    GND @BASEBOARD_FAB2_LIB.BASEBOARD_FAB2(SCH_1):GND    I23 @BASEBOARD_FAB2_LIB.BASEBOARD_FAB2(SCH_1):PAGE74
  BA68    GND @BASEBOARD_FAB2_LIB.BASEBOARD_FAB2(SCH_1):GND    I23 @BASEBOARD_FAB2_LIB.BASEBOARD_FAB2(SCH_1):PAGE74
  BA74    GND @BASEBOARD_FAB2_LIB.BASEBOARD_FAB2(SCH_1):GND    I23 @BASEBOARD_FAB2_LIB.BASEBOARD_FAB2(SCH_1):PAGE74
  BA80    GND @BASEBOARD_FAB2_LIB.BASEBOARD_FAB2(SCH_1):GND    I23 @BASEBOARD_FAB2_LIB.BASEBOARD_FAB2(SCH_1):PAGE74
  BA84    GND @BASEBOARD_FAB2_LIB.BASEBOARD_FAB2(SCH_1):GND    I23 @BASEBOARD_FAB2_LIB.BASEBOARD_FAB2(SCH_1):PAGE74
  BB19    GND @BASEBOARD_FAB2_LIB.BASEBOARD_FAB2(SCH_1):GND    I23 @BASEBOARD_FAB2_LIB.BASEBOARD_FAB2(SCH_1):PAGE74
  BB23    GND @BASEBOARD_FAB2_LIB.BASEBOARD_FAB2(SCH_1):GND    I23 @BASEBOARD_FAB2_LIB.BASEBOARD_FAB2(SCH_1):PAGE74
  BB63    GND @BASEBOARD_FAB2_LIB.BASEBOARD_FAB2(SCH_1):GND    I23 @BASEBOARD_FAB2_LIB.BASEBOARD_FAB2(SCH_1):PAGE74
  BB69    GND @BASEBOARD_FAB2_LIB.BASEBOARD_FAB2(SCH_1):GND    I23 @BASEBOARD_FAB2_LIB.BASEBOARD_FAB2(SCH_1):PAGE74
  BB73    GND @BASEBOARD_FAB2_LIB.BASEBOARD_FAB2(SCH_1):GND    I23 @BASEBOARD_FAB2_LIB.BASEBOARD_FAB2(SCH_1):PAGE74
  BB75    GND @BASEBOARD_FAB2_LIB.BASEBOARD_FAB2(SCH_1):GND    I23 @BASEBOARD_FAB2_LIB.BASEBOARD_FAB2(SCH_1):PAGE74
  BB77    GND @BASEBOARD_FAB2_LIB.BASEBOARD_FAB2(SCH_1):GND    I23 @BASEBOARD_FAB2_LIB.BASEBOARD_FAB2(SCH_1):PAGE74
  BB79    GND @BASEBOARD_FAB2_LIB.BASEBOARD_FAB2(SCH_1):GND    I23 @BASEBOARD_FAB2_LIB.BASEBOARD_FAB2(SCH_1):PAGE74
  BB81    GND @BASEBOARD_FAB2_LIB.BASEBOARD_FAB2(SCH_1):GND    I23 @BASEBOARD_FAB2_LIB.BASEBOARD_FAB2(SCH_1):PAGE74
  BB83    GND @BASEBOARD_FAB2_LIB.BASEBOARD_FAB2(SCH_1):GND    I23 @BASEBOARD_FAB2_LIB.BASEBOARD_FAB2(SCH_1):PAGE74
   BC4    GND @BASEBOARD_FAB2_LIB.BASEBOARD_FAB2(SCH_1):GND    I23 @BASEBOARD_FAB2_LIB.BASEBOARD_FAB2(SCH_1):PAGE74
   BC8    GND @BASEBOARD_FAB2_LIB.BASEBOARD_FAB2(SCH_1):GND    I23 @BASEBOARD_FAB2_LIB.BASEBOARD_FAB2(SCH_1):PAGE74
  BC12    GND @BASEBOARD_FAB2_LIB.BASEBOARD_FAB2(SCH_1):GND    I23 @BASEBOARD_FAB2_LIB.BASEBOARD_FAB2(SCH_1):PAGE74
  BC16    GND @BASEBOARD_FAB2_LIB.BASEBOARD_FAB2(SCH_1):GND    I23 @BASEBOARD_FAB2_LIB.BASEBOARD_FAB2(SCH_1):PAGE74
  BC70    GND @BASEBOARD_FAB2_LIB.BASEBOARD_FAB2(SCH_1):GND    I23 @BASEBOARD_FAB2_LIB.BASEBOARD_FAB2(SCH_1):PAGE74
  BC72    GND @BASEBOARD_FAB2_LIB.BASEBOARD_FAB2(SCH_1):GND    I23 @BASEBOARD_FAB2_LIB.BASEBOARD_FAB2(SCH_1):PAGE74
  BC74    GND @BASEBOARD_FAB2_LIB.BASEBOARD_FAB2(SCH_1):GND    I23 @BASEBOARD_FAB2_LIB.BASEBOARD_FAB2(SCH_1):PAGE74
  BC76    GND @BASEBOARD_FAB2_LIB.BASEBOARD_FAB2(SCH_1):GND    I23 @BASEBOARD_FAB2_LIB.BASEBOARD_FAB2(SCH_1):PAGE74
  BC78    GND @BASEBOARD_FAB2_LIB.BASEBOARD_FAB2(SCH_1):GND    I23 @BASEBOARD_FAB2_LIB.BASEBOARD_FAB2(SCH_1):PAGE74
  BC80    GND @BASEBOARD_FAB2_LIB.BASEBOARD_FAB2(SCH_1):GND    I23 @BASEBOARD_FAB2_LIB.BASEBOARD_FAB2(SCH_1):PAGE74
  BC82    GND @BASEBOARD_FAB2_LIB.BASEBOARD_FAB2(SCH_1):GND    I23 @BASEBOARD_FAB2_LIB.BASEBOARD_FAB2(SCH_1):PAGE74
   BD5    GND @BASEBOARD_FAB2_LIB.BASEBOARD_FAB2(SCH_1):GND    I23 @BASEBOARD_FAB2_LIB.BASEBOARD_FAB2(SCH_1):PAGE74
  BD11    GND @BASEBOARD_FAB2_LIB.BASEBOARD_FAB2(SCH_1):GND    I23 @BASEBOARD_FAB2_LIB.BASEBOARD_FAB2(SCH_1):PAGE74
  BD15    GND @BASEBOARD_FAB2_LIB.BASEBOARD_FAB2(SCH_1):GND    I23 @BASEBOARD_FAB2_LIB.BASEBOARD_FAB2(SCH_1):PAGE74
  BD21    GND @BASEBOARD_FAB2_LIB.BASEBOARD_FAB2(SCH_1):GND    I23 @BASEBOARD_FAB2_LIB.BASEBOARD_FAB2(SCH_1):PAGE74
  BD27    GND @BASEBOARD_FAB2_LIB.BASEBOARD_FAB2(SCH_1):GND    I23 @BASEBOARD_FAB2_LIB.BASEBOARD_FAB2(SCH_1):PAGE74
  BD63    GND @BASEBOARD_FAB2_LIB.BASEBOARD_FAB2(SCH_1):GND    I23 @BASEBOARD_FAB2_LIB.BASEBOARD_FAB2(SCH_1):PAGE74
  BD71    GND @BASEBOARD_FAB2_LIB.BASEBOARD_FAB2(SCH_1):GND    I23 @BASEBOARD_FAB2_LIB.BASEBOARD_FAB2(SCH_1):PAGE74
   BE4    GND @BASEBOARD_FAB2_LIB.BASEBOARD_FAB2(SCH_1):GND    I23 @BASEBOARD_FAB2_LIB.BASEBOARD_FAB2(SCH_1):PAGE74
   BE6    GND @BASEBOARD_FAB2_LIB.BASEBOARD_FAB2(SCH_1):GND    I23 @BASEBOARD_FAB2_LIB.BASEBOARD_FAB2(SCH_1):PAGE74
   BE8    GND @BASEBOARD_FAB2_LIB.BASEBOARD_FAB2(SCH_1):GND    I23 @BASEBOARD_FAB2_LIB.BASEBOARD_FAB2(SCH_1):PAGE74
  BE10    GND @BASEBOARD_FAB2_LIB.BASEBOARD_FAB2(SCH_1):GND    I23 @BASEBOARD_FAB2_LIB.BASEBOARD_FAB2(SCH_1):PAGE74
  BE26    GND @BASEBOARD_FAB2_LIB.BASEBOARD_FAB2(SCH_1):GND    I23 @BASEBOARD_FAB2_LIB.BASEBOARD_FAB2(SCH_1):PAGE74
  BE64    GND @BASEBOARD_FAB2_LIB.BASEBOARD_FAB2(SCH_1):GND    I23 @BASEBOARD_FAB2_LIB.BASEBOARD_FAB2(SCH_1):PAGE74
  BE66    GND @BASEBOARD_FAB2_LIB.BASEBOARD_FAB2(SCH_1):GND    I23 @BASEBOARD_FAB2_LIB.BASEBOARD_FAB2(SCH_1):PAGE74
  BE68    GND @BASEBOARD_FAB2_LIB.BASEBOARD_FAB2(SCH_1):GND    I23 @BASEBOARD_FAB2_LIB.BASEBOARD_FAB2(SCH_1):PAGE74
  BE70    GND @BASEBOARD_FAB2_LIB.BASEBOARD_FAB2(SCH_1):GND    I23 @BASEBOARD_FAB2_LIB.BASEBOARD_FAB2(SCH_1):PAGE74
   BF9    GND @BASEBOARD_FAB2_LIB.BASEBOARD_FAB2(SCH_1):GND    I23 @BASEBOARD_FAB2_LIB.BASEBOARD_FAB2(SCH_1):PAGE74
  BF15    GND @BASEBOARD_FAB2_LIB.BASEBOARD_FAB2(SCH_1):GND    I23 @BASEBOARD_FAB2_LIB.BASEBOARD_FAB2(SCH_1):PAGE74
  BF17    GND @BASEBOARD_FAB2_LIB.BASEBOARD_FAB2(SCH_1):GND    I23 @BASEBOARD_FAB2_LIB.BASEBOARD_FAB2(SCH_1):PAGE74
  BF19    GND @BASEBOARD_FAB2_LIB.BASEBOARD_FAB2(SCH_1):GND    I23 @BASEBOARD_FAB2_LIB.BASEBOARD_FAB2(SCH_1):PAGE74
  BF25    GND @BASEBOARD_FAB2_LIB.BASEBOARD_FAB2(SCH_1):GND    I23 @BASEBOARD_FAB2_LIB.BASEBOARD_FAB2(SCH_1):PAGE74
  BF63    GND @BASEBOARD_FAB2_LIB.BASEBOARD_FAB2(SCH_1):GND    I23 @BASEBOARD_FAB2_LIB.BASEBOARD_FAB2(SCH_1):PAGE74
  BF65    GND @BASEBOARD_FAB2_LIB.BASEBOARD_FAB2(SCH_1):GND    I23 @BASEBOARD_FAB2_LIB.BASEBOARD_FAB2(SCH_1):PAGE74
  BF67    GND @BASEBOARD_FAB2_LIB.BASEBOARD_FAB2(SCH_1):GND    I23 @BASEBOARD_FAB2_LIB.BASEBOARD_FAB2(SCH_1):PAGE74
  BF69    GND @BASEBOARD_FAB2_LIB.BASEBOARD_FAB2(SCH_1):GND    I23 @BASEBOARD_FAB2_LIB.BASEBOARD_FAB2(SCH_1):PAGE74
  BF71    GND @BASEBOARD_FAB2_LIB.BASEBOARD_FAB2(SCH_1):GND    I23 @BASEBOARD_FAB2_LIB.BASEBOARD_FAB2(SCH_1):PAGE74
   BG6    GND @BASEBOARD_FAB2_LIB.BASEBOARD_FAB2(SCH_1):GND    I23 @BASEBOARD_FAB2_LIB.BASEBOARD_FAB2(SCH_1):PAGE74
   BG8    GND @BASEBOARD_FAB2_LIB.BASEBOARD_FAB2(SCH_1):GND    I23 @BASEBOARD_FAB2_LIB.BASEBOARD_FAB2(SCH_1):PAGE74
  BG10    GND @BASEBOARD_FAB2_LIB.BASEBOARD_FAB2(SCH_1):GND    I23 @BASEBOARD_FAB2_LIB.BASEBOARD_FAB2(SCH_1):PAGE74
  BG22    GND @BASEBOARD_FAB2_LIB.BASEBOARD_FAB2(SCH_1):GND    I23 @BASEBOARD_FAB2_LIB.BASEBOARD_FAB2(SCH_1):PAGE74
  BG24    GND @BASEBOARD_FAB2_LIB.BASEBOARD_FAB2(SCH_1):GND    I23 @BASEBOARD_FAB2_LIB.BASEBOARD_FAB2(SCH_1):PAGE74
  BG72    GND @BASEBOARD_FAB2_LIB.BASEBOARD_FAB2(SCH_1):GND    I23 @BASEBOARD_FAB2_LIB.BASEBOARD_FAB2(SCH_1):PAGE74
  BG74    GND @BASEBOARD_FAB2_LIB.BASEBOARD_FAB2(SCH_1):GND    I17 @BASEBOARD_FAB2_LIB.BASEBOARD_FAB2(SCH_1):PAGE75
  BG76    GND @BASEBOARD_FAB2_LIB.BASEBOARD_FAB2(SCH_1):GND    I17 @BASEBOARD_FAB2_LIB.BASEBOARD_FAB2(SCH_1):PAGE75
  BG78    GND @BASEBOARD_FAB2_LIB.BASEBOARD_FAB2(SCH_1):GND    I17 @BASEBOARD_FAB2_LIB.BASEBOARD_FAB2(SCH_1):PAGE75
  BG80    GND @BASEBOARD_FAB2_LIB.BASEBOARD_FAB2(SCH_1):GND    I17 @BASEBOARD_FAB2_LIB.BASEBOARD_FAB2(SCH_1):PAGE75
  BG82    GND @BASEBOARD_FAB2_LIB.BASEBOARD_FAB2(SCH_1):GND    I17 @BASEBOARD_FAB2_LIB.BASEBOARD_FAB2(SCH_1):PAGE75
   BH7    GND @BASEBOARD_FAB2_LIB.BASEBOARD_FAB2(SCH_1):GND    I17 @BASEBOARD_FAB2_LIB.BASEBOARD_FAB2(SCH_1):PAGE75
   BH9    GND @BASEBOARD_FAB2_LIB.BASEBOARD_FAB2(SCH_1):GND    I17 @BASEBOARD_FAB2_LIB.BASEBOARD_FAB2(SCH_1):PAGE75
  BH11    GND @BASEBOARD_FAB2_LIB.BASEBOARD_FAB2(SCH_1):GND    I17 @BASEBOARD_FAB2_LIB.BASEBOARD_FAB2(SCH_1):PAGE75
  BH15    GND @BASEBOARD_FAB2_LIB.BASEBOARD_FAB2(SCH_1):GND    I17 @BASEBOARD_FAB2_LIB.BASEBOARD_FAB2(SCH_1):PAGE75
  BH21    GND @BASEBOARD_FAB2_LIB.BASEBOARD_FAB2(SCH_1):GND    I17 @BASEBOARD_FAB2_LIB.BASEBOARD_FAB2(SCH_1):PAGE75
   BJ4    GND @BASEBOARD_FAB2_LIB.BASEBOARD_FAB2(SCH_1):GND    I17 @BASEBOARD_FAB2_LIB.BASEBOARD_FAB2(SCH_1):PAGE75
   BJ6    GND @BASEBOARD_FAB2_LIB.BASEBOARD_FAB2(SCH_1):GND    I17 @BASEBOARD_FAB2_LIB.BASEBOARD_FAB2(SCH_1):PAGE75
   BK3    GND @BASEBOARD_FAB2_LIB.BASEBOARD_FAB2(SCH_1):GND    I17 @BASEBOARD_FAB2_LIB.BASEBOARD_FAB2(SCH_1):PAGE75
   BK7    GND @BASEBOARD_FAB2_LIB.BASEBOARD_FAB2(SCH_1):GND    I17 @BASEBOARD_FAB2_LIB.BASEBOARD_FAB2(SCH_1):PAGE75
  BK11    GND @BASEBOARD_FAB2_LIB.BASEBOARD_FAB2(SCH_1):GND    I17 @BASEBOARD_FAB2_LIB.BASEBOARD_FAB2(SCH_1):PAGE75
  BK19    GND @BASEBOARD_FAB2_LIB.BASEBOARD_FAB2(SCH_1):GND    I17 @BASEBOARD_FAB2_LIB.BASEBOARD_FAB2(SCH_1):PAGE75
   BL6    GND @BASEBOARD_FAB2_LIB.BASEBOARD_FAB2(SCH_1):GND    I17 @BASEBOARD_FAB2_LIB.BASEBOARD_FAB2(SCH_1):PAGE75
  BL10    GND @BASEBOARD_FAB2_LIB.BASEBOARD_FAB2(SCH_1):GND    I17 @BASEBOARD_FAB2_LIB.BASEBOARD_FAB2(SCH_1):PAGE75
  BL12    GND @BASEBOARD_FAB2_LIB.BASEBOARD_FAB2(SCH_1):GND    I17 @BASEBOARD_FAB2_LIB.BASEBOARD_FAB2(SCH_1):PAGE75
   P61    GND @BASEBOARD_FAB2_LIB.BASEBOARD_FAB2(SCH_1):GND    I17 @BASEBOARD_FAB2_LIB.BASEBOARD_FAB2(SCH_1):PAGE75
  BL22    GND @BASEBOARD_FAB2_LIB.BASEBOARD_FAB2(SCH_1):GND    I17 @BASEBOARD_FAB2_LIB.BASEBOARD_FAB2(SCH_1):PAGE75
  BL24    GND @BASEBOARD_FAB2_LIB.BASEBOARD_FAB2(SCH_1):GND    I17 @BASEBOARD_FAB2_LIB.BASEBOARD_FAB2(SCH_1):PAGE75
  BL64    GND @BASEBOARD_FAB2_LIB.BASEBOARD_FAB2(SCH_1):GND    I17 @BASEBOARD_FAB2_LIB.BASEBOARD_FAB2(SCH_1):PAGE75
  BL66    GND @BASEBOARD_FAB2_LIB.BASEBOARD_FAB2(SCH_1):GND    I17 @BASEBOARD_FAB2_LIB.BASEBOARD_FAB2(SCH_1):PAGE75
  BL68    GND @BASEBOARD_FAB2_LIB.BASEBOARD_FAB2(SCH_1):GND    I17 @BASEBOARD_FAB2_LIB.BASEBOARD_FAB2(SCH_1):PAGE75
  BL70    GND @BASEBOARD_FAB2_LIB.BASEBOARD_FAB2(SCH_1):GND    I17 @BASEBOARD_FAB2_LIB.BASEBOARD_FAB2(SCH_1):PAGE75
  BL72    GND @BASEBOARD_FAB2_LIB.BASEBOARD_FAB2(SCH_1):GND    I17 @BASEBOARD_FAB2_LIB.BASEBOARD_FAB2(SCH_1):PAGE75
  BL74    GND @BASEBOARD_FAB2_LIB.BASEBOARD_FAB2(SCH_1):GND    I17 @BASEBOARD_FAB2_LIB.BASEBOARD_FAB2(SCH_1):PAGE75
  BL76    GND @BASEBOARD_FAB2_LIB.BASEBOARD_FAB2(SCH_1):GND    I17 @BASEBOARD_FAB2_LIB.BASEBOARD_FAB2(SCH_1):PAGE75
  BL78    GND @BASEBOARD_FAB2_LIB.BASEBOARD_FAB2(SCH_1):GND    I17 @BASEBOARD_FAB2_LIB.BASEBOARD_FAB2(SCH_1):PAGE75
  BL80    GND @BASEBOARD_FAB2_LIB.BASEBOARD_FAB2(SCH_1):GND    I17 @BASEBOARD_FAB2_LIB.BASEBOARD_FAB2(SCH_1):PAGE75
  BL82    GND @BASEBOARD_FAB2_LIB.BASEBOARD_FAB2(SCH_1):GND    I17 @BASEBOARD_FAB2_LIB.BASEBOARD_FAB2(SCH_1):PAGE75
   BM9    GND @BASEBOARD_FAB2_LIB.BASEBOARD_FAB2(SCH_1):GND    I17 @BASEBOARD_FAB2_LIB.BASEBOARD_FAB2(SCH_1):PAGE75
  BM13    GND @BASEBOARD_FAB2_LIB.BASEBOARD_FAB2(SCH_1):GND    I17 @BASEBOARD_FAB2_LIB.BASEBOARD_FAB2(SCH_1):PAGE75
  BM15    GND @BASEBOARD_FAB2_LIB.BASEBOARD_FAB2(SCH_1):GND    I17 @BASEBOARD_FAB2_LIB.BASEBOARD_FAB2(SCH_1):PAGE75
   P59    GND @BASEBOARD_FAB2_LIB.BASEBOARD_FAB2(SCH_1):GND    I17 @BASEBOARD_FAB2_LIB.BASEBOARD_FAB2(SCH_1):PAGE75
  BM25    GND @BASEBOARD_FAB2_LIB.BASEBOARD_FAB2(SCH_1):GND    I17 @BASEBOARD_FAB2_LIB.BASEBOARD_FAB2(SCH_1):PAGE75
   BN6    GND @BASEBOARD_FAB2_LIB.BASEBOARD_FAB2(SCH_1):GND    I17 @BASEBOARD_FAB2_LIB.BASEBOARD_FAB2(SCH_1):PAGE75
  BN10    GND @BASEBOARD_FAB2_LIB.BASEBOARD_FAB2(SCH_1):GND    I17 @BASEBOARD_FAB2_LIB.BASEBOARD_FAB2(SCH_1):PAGE75
  BN20    GND @BASEBOARD_FAB2_LIB.BASEBOARD_FAB2(SCH_1):GND    I17 @BASEBOARD_FAB2_LIB.BASEBOARD_FAB2(SCH_1):PAGE75
  BN26    GND @BASEBOARD_FAB2_LIB.BASEBOARD_FAB2(SCH_1):GND    I17 @BASEBOARD_FAB2_LIB.BASEBOARD_FAB2(SCH_1):PAGE75
   BP3    GND @BASEBOARD_FAB2_LIB.BASEBOARD_FAB2(SCH_1):GND    I17 @BASEBOARD_FAB2_LIB.BASEBOARD_FAB2(SCH_1):PAGE75
  BP27    GND @BASEBOARD_FAB2_LIB.BASEBOARD_FAB2(SCH_1):GND    I17 @BASEBOARD_FAB2_LIB.BASEBOARD_FAB2(SCH_1):PAGE75
   BR6    GND @BASEBOARD_FAB2_LIB.BASEBOARD_FAB2(SCH_1):GND    I17 @BASEBOARD_FAB2_LIB.BASEBOARD_FAB2(SCH_1):PAGE75
  BR10    GND @BASEBOARD_FAB2_LIB.BASEBOARD_FAB2(SCH_1):GND    I17 @BASEBOARD_FAB2_LIB.BASEBOARD_FAB2(SCH_1):PAGE75
  BR16    GND @BASEBOARD_FAB2_LIB.BASEBOARD_FAB2(SCH_1):GND    I17 @BASEBOARD_FAB2_LIB.BASEBOARD_FAB2(SCH_1):PAGE75
   P57    GND @BASEBOARD_FAB2_LIB.BASEBOARD_FAB2(SCH_1):GND    I17 @BASEBOARD_FAB2_LIB.BASEBOARD_FAB2(SCH_1):PAGE75
  BR64    GND @BASEBOARD_FAB2_LIB.BASEBOARD_FAB2(SCH_1):GND    I17 @BASEBOARD_FAB2_LIB.BASEBOARD_FAB2(SCH_1):PAGE75
  BR66    GND @BASEBOARD_FAB2_LIB.BASEBOARD_FAB2(SCH_1):GND    I17 @BASEBOARD_FAB2_LIB.BASEBOARD_FAB2(SCH_1):PAGE75
  BR68    GND @BASEBOARD_FAB2_LIB.BASEBOARD_FAB2(SCH_1):GND    I17 @BASEBOARD_FAB2_LIB.BASEBOARD_FAB2(SCH_1):PAGE75
  BR70    GND @BASEBOARD_FAB2_LIB.BASEBOARD_FAB2(SCH_1):GND    I17 @BASEBOARD_FAB2_LIB.BASEBOARD_FAB2(SCH_1):PAGE75
  BR72    GND @BASEBOARD_FAB2_LIB.BASEBOARD_FAB2(SCH_1):GND    I17 @BASEBOARD_FAB2_LIB.BASEBOARD_FAB2(SCH_1):PAGE75
  BR74    GND @BASEBOARD_FAB2_LIB.BASEBOARD_FAB2(SCH_1):GND    I17 @BASEBOARD_FAB2_LIB.BASEBOARD_FAB2(SCH_1):PAGE75
  BR76    GND @BASEBOARD_FAB2_LIB.BASEBOARD_FAB2(SCH_1):GND    I17 @BASEBOARD_FAB2_LIB.BASEBOARD_FAB2(SCH_1):PAGE75
  BR78    GND @BASEBOARD_FAB2_LIB.BASEBOARD_FAB2(SCH_1):GND    I17 @BASEBOARD_FAB2_LIB.BASEBOARD_FAB2(SCH_1):PAGE75
  BR80    GND @BASEBOARD_FAB2_LIB.BASEBOARD_FAB2(SCH_1):GND    I17 @BASEBOARD_FAB2_LIB.BASEBOARD_FAB2(SCH_1):PAGE75
  BR82    GND @BASEBOARD_FAB2_LIB.BASEBOARD_FAB2(SCH_1):GND    I17 @BASEBOARD_FAB2_LIB.BASEBOARD_FAB2(SCH_1):PAGE75
   BT3    GND @BASEBOARD_FAB2_LIB.BASEBOARD_FAB2(SCH_1):GND    I17 @BASEBOARD_FAB2_LIB.BASEBOARD_FAB2(SCH_1):PAGE75
   BT5    GND @BASEBOARD_FAB2_LIB.BASEBOARD_FAB2(SCH_1):GND    I17 @BASEBOARD_FAB2_LIB.BASEBOARD_FAB2(SCH_1):PAGE75
  BT21    GND @BASEBOARD_FAB2_LIB.BASEBOARD_FAB2(SCH_1):GND    I17 @BASEBOARD_FAB2_LIB.BASEBOARD_FAB2(SCH_1):PAGE75
  BT23    GND @BASEBOARD_FAB2_LIB.BASEBOARD_FAB2(SCH_1):GND    I17 @BASEBOARD_FAB2_LIB.BASEBOARD_FAB2(SCH_1):PAGE75
  BT25    GND @BASEBOARD_FAB2_LIB.BASEBOARD_FAB2(SCH_1):GND    I17 @BASEBOARD_FAB2_LIB.BASEBOARD_FAB2(SCH_1):PAGE75
   BU8    GND @BASEBOARD_FAB2_LIB.BASEBOARD_FAB2(SCH_1):GND    I17 @BASEBOARD_FAB2_LIB.BASEBOARD_FAB2(SCH_1):PAGE75
   BV5    GND @BASEBOARD_FAB2_LIB.BASEBOARD_FAB2(SCH_1):GND    I17 @BASEBOARD_FAB2_LIB.BASEBOARD_FAB2(SCH_1):PAGE75
  BU10    GND @BASEBOARD_FAB2_LIB.BASEBOARD_FAB2(SCH_1):GND    I17 @BASEBOARD_FAB2_LIB.BASEBOARD_FAB2(SCH_1):PAGE75
  BV17    GND @BASEBOARD_FAB2_LIB.BASEBOARD_FAB2(SCH_1):GND    I17 @BASEBOARD_FAB2_LIB.BASEBOARD_FAB2(SCH_1):PAGE75
  BV25    GND @BASEBOARD_FAB2_LIB.BASEBOARD_FAB2(SCH_1):GND    I17 @BASEBOARD_FAB2_LIB.BASEBOARD_FAB2(SCH_1):PAGE75
   BW6    GND @BASEBOARD_FAB2_LIB.BASEBOARD_FAB2(SCH_1):GND    I17 @BASEBOARD_FAB2_LIB.BASEBOARD_FAB2(SCH_1):PAGE75
   P55    GND @BASEBOARD_FAB2_LIB.BASEBOARD_FAB2(SCH_1):GND    I17 @BASEBOARD_FAB2_LIB.BASEBOARD_FAB2(SCH_1):PAGE75
  BW12    GND @BASEBOARD_FAB2_LIB.BASEBOARD_FAB2(SCH_1):GND    I17 @BASEBOARD_FAB2_LIB.BASEBOARD_FAB2(SCH_1):PAGE75
  BW14    GND @BASEBOARD_FAB2_LIB.BASEBOARD_FAB2(SCH_1):GND    I17 @BASEBOARD_FAB2_LIB.BASEBOARD_FAB2(SCH_1):PAGE75
  BW16    GND @BASEBOARD_FAB2_LIB.BASEBOARD_FAB2(SCH_1):GND    I17 @BASEBOARD_FAB2_LIB.BASEBOARD_FAB2(SCH_1):PAGE75
  BW18    GND @BASEBOARD_FAB2_LIB.BASEBOARD_FAB2(SCH_1):GND    I17 @BASEBOARD_FAB2_LIB.BASEBOARD_FAB2(SCH_1):PAGE75
  BW26    GND @BASEBOARD_FAB2_LIB.BASEBOARD_FAB2(SCH_1):GND    I17 @BASEBOARD_FAB2_LIB.BASEBOARD_FAB2(SCH_1):PAGE75
  BW72    GND @BASEBOARD_FAB2_LIB.BASEBOARD_FAB2(SCH_1):GND    I17 @BASEBOARD_FAB2_LIB.BASEBOARD_FAB2(SCH_1):PAGE75
  BW74    GND @BASEBOARD_FAB2_LIB.BASEBOARD_FAB2(SCH_1):GND    I17 @BASEBOARD_FAB2_LIB.BASEBOARD_FAB2(SCH_1):PAGE75
  BW76    GND @BASEBOARD_FAB2_LIB.BASEBOARD_FAB2(SCH_1):GND    I17 @BASEBOARD_FAB2_LIB.BASEBOARD_FAB2(SCH_1):PAGE75
  BW78    GND @BASEBOARD_FAB2_LIB.BASEBOARD_FAB2(SCH_1):GND    I17 @BASEBOARD_FAB2_LIB.BASEBOARD_FAB2(SCH_1):PAGE75
  BW80    GND @BASEBOARD_FAB2_LIB.BASEBOARD_FAB2(SCH_1):GND    I17 @BASEBOARD_FAB2_LIB.BASEBOARD_FAB2(SCH_1):PAGE75
  BW82    GND @BASEBOARD_FAB2_LIB.BASEBOARD_FAB2(SCH_1):GND    I17 @BASEBOARD_FAB2_LIB.BASEBOARD_FAB2(SCH_1):PAGE75
  BY11    GND @BASEBOARD_FAB2_LIB.BASEBOARD_FAB2(SCH_1):GND    I17 @BASEBOARD_FAB2_LIB.BASEBOARD_FAB2(SCH_1):PAGE75
  BY13    GND @BASEBOARD_FAB2_LIB.BASEBOARD_FAB2(SCH_1):GND    I17 @BASEBOARD_FAB2_LIB.BASEBOARD_FAB2(SCH_1):PAGE75
  BY23    GND @BASEBOARD_FAB2_LIB.BASEBOARD_FAB2(SCH_1):GND    I17 @BASEBOARD_FAB2_LIB.BASEBOARD_FAB2(SCH_1):PAGE75
  BY63    GND @BASEBOARD_FAB2_LIB.BASEBOARD_FAB2(SCH_1):GND    I17 @BASEBOARD_FAB2_LIB.BASEBOARD_FAB2(SCH_1):PAGE75
  BY65    GND @BASEBOARD_FAB2_LIB.BASEBOARD_FAB2(SCH_1):GND    I17 @BASEBOARD_FAB2_LIB.BASEBOARD_FAB2(SCH_1):PAGE75
  BY67    GND @BASEBOARD_FAB2_LIB.BASEBOARD_FAB2(SCH_1):GND    I17 @BASEBOARD_FAB2_LIB.BASEBOARD_FAB2(SCH_1):PAGE75
  BY69    GND @BASEBOARD_FAB2_LIB.BASEBOARD_FAB2(SCH_1):GND    I17 @BASEBOARD_FAB2_LIB.BASEBOARD_FAB2(SCH_1):PAGE75
  BY71    GND @BASEBOARD_FAB2_LIB.BASEBOARD_FAB2(SCH_1):GND    I17 @BASEBOARD_FAB2_LIB.BASEBOARD_FAB2(SCH_1):PAGE75
   CA2    GND @BASEBOARD_FAB2_LIB.BASEBOARD_FAB2(SCH_1):GND    I17 @BASEBOARD_FAB2_LIB.BASEBOARD_FAB2(SCH_1):PAGE75
   CA6    GND @BASEBOARD_FAB2_LIB.BASEBOARD_FAB2(SCH_1):GND    I17 @BASEBOARD_FAB2_LIB.BASEBOARD_FAB2(SCH_1):PAGE75
   CA8    GND @BASEBOARD_FAB2_LIB.BASEBOARD_FAB2(SCH_1):GND    I17 @BASEBOARD_FAB2_LIB.BASEBOARD_FAB2(SCH_1):PAGE75
  CA10    GND @BASEBOARD_FAB2_LIB.BASEBOARD_FAB2(SCH_1):GND    I17 @BASEBOARD_FAB2_LIB.BASEBOARD_FAB2(SCH_1):PAGE75
  CA14    GND @BASEBOARD_FAB2_LIB.BASEBOARD_FAB2(SCH_1):GND    I17 @BASEBOARD_FAB2_LIB.BASEBOARD_FAB2(SCH_1):PAGE75
  CA18    GND @BASEBOARD_FAB2_LIB.BASEBOARD_FAB2(SCH_1):GND    I17 @BASEBOARD_FAB2_LIB.BASEBOARD_FAB2(SCH_1):PAGE75
  CA26    GND @BASEBOARD_FAB2_LIB.BASEBOARD_FAB2(SCH_1):GND    I17 @BASEBOARD_FAB2_LIB.BASEBOARD_FAB2(SCH_1):PAGE75
  CA64    GND @BASEBOARD_FAB2_LIB.BASEBOARD_FAB2(SCH_1):GND    I17 @BASEBOARD_FAB2_LIB.BASEBOARD_FAB2(SCH_1):PAGE75
  CA66    GND @BASEBOARD_FAB2_LIB.BASEBOARD_FAB2(SCH_1):GND    I17 @BASEBOARD_FAB2_LIB.BASEBOARD_FAB2(SCH_1):PAGE75
  CA68    GND @BASEBOARD_FAB2_LIB.BASEBOARD_FAB2(SCH_1):GND    I17 @BASEBOARD_FAB2_LIB.BASEBOARD_FAB2(SCH_1):PAGE75
  CA70    GND @BASEBOARD_FAB2_LIB.BASEBOARD_FAB2(SCH_1):GND    I17 @BASEBOARD_FAB2_LIB.BASEBOARD_FAB2(SCH_1):PAGE75
   CB7    GND @BASEBOARD_FAB2_LIB.BASEBOARD_FAB2(SCH_1):GND    I17 @BASEBOARD_FAB2_LIB.BASEBOARD_FAB2(SCH_1):PAGE75
   CB9    GND @BASEBOARD_FAB2_LIB.BASEBOARD_FAB2(SCH_1):GND    I17 @BASEBOARD_FAB2_LIB.BASEBOARD_FAB2(SCH_1):PAGE75
  CB27    GND @BASEBOARD_FAB2_LIB.BASEBOARD_FAB2(SCH_1):GND    I17 @BASEBOARD_FAB2_LIB.BASEBOARD_FAB2(SCH_1):PAGE75
  CB63    GND @BASEBOARD_FAB2_LIB.BASEBOARD_FAB2(SCH_1):GND    I17 @BASEBOARD_FAB2_LIB.BASEBOARD_FAB2(SCH_1):PAGE75
  CB71    GND @BASEBOARD_FAB2_LIB.BASEBOARD_FAB2(SCH_1):GND    I17 @BASEBOARD_FAB2_LIB.BASEBOARD_FAB2(SCH_1):PAGE75
   CC4    GND @BASEBOARD_FAB2_LIB.BASEBOARD_FAB2(SCH_1):GND    I17 @BASEBOARD_FAB2_LIB.BASEBOARD_FAB2(SCH_1):PAGE75
  CC16    GND @BASEBOARD_FAB2_LIB.BASEBOARD_FAB2(SCH_1):GND    I17 @BASEBOARD_FAB2_LIB.BASEBOARD_FAB2(SCH_1):PAGE75
  CC18    GND @BASEBOARD_FAB2_LIB.BASEBOARD_FAB2(SCH_1):GND    I17 @BASEBOARD_FAB2_LIB.BASEBOARD_FAB2(SCH_1):PAGE75
  CC24    GND @BASEBOARD_FAB2_LIB.BASEBOARD_FAB2(SCH_1):GND    I17 @BASEBOARD_FAB2_LIB.BASEBOARD_FAB2(SCH_1):PAGE75
  CC64    GND @BASEBOARD_FAB2_LIB.BASEBOARD_FAB2(SCH_1):GND    I17 @BASEBOARD_FAB2_LIB.BASEBOARD_FAB2(SCH_1):PAGE75
  CC72    GND @BASEBOARD_FAB2_LIB.BASEBOARD_FAB2(SCH_1):GND    I17 @BASEBOARD_FAB2_LIB.BASEBOARD_FAB2(SCH_1):PAGE75
  CC74    GND @BASEBOARD_FAB2_LIB.BASEBOARD_FAB2(SCH_1):GND    I17 @BASEBOARD_FAB2_LIB.BASEBOARD_FAB2(SCH_1):PAGE75
  CC76    GND @BASEBOARD_FAB2_LIB.BASEBOARD_FAB2(SCH_1):GND    I17 @BASEBOARD_FAB2_LIB.BASEBOARD_FAB2(SCH_1):PAGE75
  CC78    GND @BASEBOARD_FAB2_LIB.BASEBOARD_FAB2(SCH_1):GND    I17 @BASEBOARD_FAB2_LIB.BASEBOARD_FAB2(SCH_1):PAGE75
  CC80    GND @BASEBOARD_FAB2_LIB.BASEBOARD_FAB2(SCH_1):GND    I17 @BASEBOARD_FAB2_LIB.BASEBOARD_FAB2(SCH_1):PAGE75
  CC82    GND @BASEBOARD_FAB2_LIB.BASEBOARD_FAB2(SCH_1):GND    I17 @BASEBOARD_FAB2_LIB.BASEBOARD_FAB2(SCH_1):PAGE75
   CD5    GND @BASEBOARD_FAB2_LIB.BASEBOARD_FAB2(SCH_1):GND    I17 @BASEBOARD_FAB2_LIB.BASEBOARD_FAB2(SCH_1):PAGE75
  CD13    GND @BASEBOARD_FAB2_LIB.BASEBOARD_FAB2(SCH_1):GND    I17 @BASEBOARD_FAB2_LIB.BASEBOARD_FAB2(SCH_1):PAGE75
  CD63    GND @BASEBOARD_FAB2_LIB.BASEBOARD_FAB2(SCH_1):GND    I17 @BASEBOARD_FAB2_LIB.BASEBOARD_FAB2(SCH_1):PAGE75
  CD73    GND @BASEBOARD_FAB2_LIB.BASEBOARD_FAB2(SCH_1):GND    I17 @BASEBOARD_FAB2_LIB.BASEBOARD_FAB2(SCH_1):PAGE75
  CD75    GND @BASEBOARD_FAB2_LIB.BASEBOARD_FAB2(SCH_1):GND    I17 @BASEBOARD_FAB2_LIB.BASEBOARD_FAB2(SCH_1):PAGE75
  CD77    GND @BASEBOARD_FAB2_LIB.BASEBOARD_FAB2(SCH_1):GND    I17 @BASEBOARD_FAB2_LIB.BASEBOARD_FAB2(SCH_1):PAGE75
  CD79    GND @BASEBOARD_FAB2_LIB.BASEBOARD_FAB2(SCH_1):GND    I17 @BASEBOARD_FAB2_LIB.BASEBOARD_FAB2(SCH_1):PAGE75
  CD81    GND @BASEBOARD_FAB2_LIB.BASEBOARD_FAB2(SCH_1):GND    I17 @BASEBOARD_FAB2_LIB.BASEBOARD_FAB2(SCH_1):PAGE75
  CE10    GND @BASEBOARD_FAB2_LIB.BASEBOARD_FAB2(SCH_1):GND    I17 @BASEBOARD_FAB2_LIB.BASEBOARD_FAB2(SCH_1):PAGE75
  CE14    GND @BASEBOARD_FAB2_LIB.BASEBOARD_FAB2(SCH_1):GND    I17 @BASEBOARD_FAB2_LIB.BASEBOARD_FAB2(SCH_1):PAGE75
  CE20    GND @BASEBOARD_FAB2_LIB.BASEBOARD_FAB2(SCH_1):GND    I17 @BASEBOARD_FAB2_LIB.BASEBOARD_FAB2(SCH_1):PAGE75
  CE26    GND @BASEBOARD_FAB2_LIB.BASEBOARD_FAB2(SCH_1):GND    I17 @BASEBOARD_FAB2_LIB.BASEBOARD_FAB2(SCH_1):PAGE75
  CE62    GND @BASEBOARD_FAB2_LIB.BASEBOARD_FAB2(SCH_1):GND    I17 @BASEBOARD_FAB2_LIB.BASEBOARD_FAB2(SCH_1):PAGE75
  CE70    GND @BASEBOARD_FAB2_LIB.BASEBOARD_FAB2(SCH_1):GND    I17 @BASEBOARD_FAB2_LIB.BASEBOARD_FAB2(SCH_1):PAGE75
  CE82    GND @BASEBOARD_FAB2_LIB.BASEBOARD_FAB2(SCH_1):GND    I17 @BASEBOARD_FAB2_LIB.BASEBOARD_FAB2(SCH_1):PAGE75
   P53    GND @BASEBOARD_FAB2_LIB.BASEBOARD_FAB2(SCH_1):GND    I17 @BASEBOARD_FAB2_LIB.BASEBOARD_FAB2(SCH_1):PAGE75
   CF9    GND @BASEBOARD_FAB2_LIB.BASEBOARD_FAB2(SCH_1):GND    I17 @BASEBOARD_FAB2_LIB.BASEBOARD_FAB2(SCH_1):PAGE75
  CF63    GND @BASEBOARD_FAB2_LIB.BASEBOARD_FAB2(SCH_1):GND    I17 @BASEBOARD_FAB2_LIB.BASEBOARD_FAB2(SCH_1):PAGE75
  CF69    GND @BASEBOARD_FAB2_LIB.BASEBOARD_FAB2(SCH_1):GND    I17 @BASEBOARD_FAB2_LIB.BASEBOARD_FAB2(SCH_1):PAGE75
  CF71    GND @BASEBOARD_FAB2_LIB.BASEBOARD_FAB2(SCH_1):GND    I17 @BASEBOARD_FAB2_LIB.BASEBOARD_FAB2(SCH_1):PAGE75
  CF77    GND @BASEBOARD_FAB2_LIB.BASEBOARD_FAB2(SCH_1):GND    I17 @BASEBOARD_FAB2_LIB.BASEBOARD_FAB2(SCH_1):PAGE75
  CF83    GND @BASEBOARD_FAB2_LIB.BASEBOARD_FAB2(SCH_1):GND    I17 @BASEBOARD_FAB2_LIB.BASEBOARD_FAB2(SCH_1):PAGE75
   P51    GND @BASEBOARD_FAB2_LIB.BASEBOARD_FAB2(SCH_1):GND    I17 @BASEBOARD_FAB2_LIB.BASEBOARD_FAB2(SCH_1):PAGE75
  CG18    GND @BASEBOARD_FAB2_LIB.BASEBOARD_FAB2(SCH_1):GND    I17 @BASEBOARD_FAB2_LIB.BASEBOARD_FAB2(SCH_1):PAGE75
  CG22    GND @BASEBOARD_FAB2_LIB.BASEBOARD_FAB2(SCH_1):GND    I17 @BASEBOARD_FAB2_LIB.BASEBOARD_FAB2(SCH_1):PAGE75
  CG62    GND @BASEBOARD_FAB2_LIB.BASEBOARD_FAB2(SCH_1):GND    I17 @BASEBOARD_FAB2_LIB.BASEBOARD_FAB2(SCH_1):PAGE75
  CG68    GND @BASEBOARD_FAB2_LIB.BASEBOARD_FAB2(SCH_1):GND    I17 @BASEBOARD_FAB2_LIB.BASEBOARD_FAB2(SCH_1):PAGE75
  CG72    GND @BASEBOARD_FAB2_LIB.BASEBOARD_FAB2(SCH_1):GND    I17 @BASEBOARD_FAB2_LIB.BASEBOARD_FAB2(SCH_1):PAGE75
  CG80    GND @BASEBOARD_FAB2_LIB.BASEBOARD_FAB2(SCH_1):GND    I17 @BASEBOARD_FAB2_LIB.BASEBOARD_FAB2(SCH_1):PAGE75
   CH1    GND @BASEBOARD_FAB2_LIB.BASEBOARD_FAB2(SCH_1):GND    I17 @BASEBOARD_FAB2_LIB.BASEBOARD_FAB2(SCH_1):PAGE75
   CH3    GND @BASEBOARD_FAB2_LIB.BASEBOARD_FAB2(SCH_1):GND    I17 @BASEBOARD_FAB2_LIB.BASEBOARD_FAB2(SCH_1):PAGE75
  CH15    GND @BASEBOARD_FAB2_LIB.BASEBOARD_FAB2(SCH_1):GND    I17 @BASEBOARD_FAB2_LIB.BASEBOARD_FAB2(SCH_1):PAGE75
  CH19    GND @BASEBOARD_FAB2_LIB.BASEBOARD_FAB2(SCH_1):GND    I17 @BASEBOARD_FAB2_LIB.BASEBOARD_FAB2(SCH_1):PAGE75
  CH63    GND @BASEBOARD_FAB2_LIB.BASEBOARD_FAB2(SCH_1):GND    I17 @BASEBOARD_FAB2_LIB.BASEBOARD_FAB2(SCH_1):PAGE75
  CH67    GND @BASEBOARD_FAB2_LIB.BASEBOARD_FAB2(SCH_1):GND    I17 @BASEBOARD_FAB2_LIB.BASEBOARD_FAB2(SCH_1):PAGE75
  CH73    GND @BASEBOARD_FAB2_LIB.BASEBOARD_FAB2(SCH_1):GND    I17 @BASEBOARD_FAB2_LIB.BASEBOARD_FAB2(SCH_1):PAGE75
  CH79    GND @BASEBOARD_FAB2_LIB.BASEBOARD_FAB2(SCH_1):GND    I17 @BASEBOARD_FAB2_LIB.BASEBOARD_FAB2(SCH_1):PAGE75
  CH81    GND @BASEBOARD_FAB2_LIB.BASEBOARD_FAB2(SCH_1):GND    I17 @BASEBOARD_FAB2_LIB.BASEBOARD_FAB2(SCH_1):PAGE75
  CH83    GND @BASEBOARD_FAB2_LIB.BASEBOARD_FAB2(SCH_1):GND    I17 @BASEBOARD_FAB2_LIB.BASEBOARD_FAB2(SCH_1):PAGE75
   CJ2    GND @BASEBOARD_FAB2_LIB.BASEBOARD_FAB2(SCH_1):GND    I17 @BASEBOARD_FAB2_LIB.BASEBOARD_FAB2(SCH_1):PAGE75
   CJ6    GND @BASEBOARD_FAB2_LIB.BASEBOARD_FAB2(SCH_1):GND    I17 @BASEBOARD_FAB2_LIB.BASEBOARD_FAB2(SCH_1):PAGE75
   CJ8    GND @BASEBOARD_FAB2_LIB.BASEBOARD_FAB2(SCH_1):GND    I17 @BASEBOARD_FAB2_LIB.BASEBOARD_FAB2(SCH_1):PAGE75
  CJ10    GND @BASEBOARD_FAB2_LIB.BASEBOARD_FAB2(SCH_1):GND    I17 @BASEBOARD_FAB2_LIB.BASEBOARD_FAB2(SCH_1):PAGE75
  CJ12    GND @BASEBOARD_FAB2_LIB.BASEBOARD_FAB2(SCH_1):GND    I17 @BASEBOARD_FAB2_LIB.BASEBOARD_FAB2(SCH_1):PAGE75
   P49    GND @BASEBOARD_FAB2_LIB.BASEBOARD_FAB2(SCH_1):GND    I17 @BASEBOARD_FAB2_LIB.BASEBOARD_FAB2(SCH_1):PAGE75
   P47    GND @BASEBOARD_FAB2_LIB.BASEBOARD_FAB2(SCH_1):GND    I18 @BASEBOARD_FAB2_LIB.BASEBOARD_FAB2(SCH_1):PAGE75
  CJ62    GND @BASEBOARD_FAB2_LIB.BASEBOARD_FAB2(SCH_1):GND    I18 @BASEBOARD_FAB2_LIB.BASEBOARD_FAB2(SCH_1):PAGE75
  CJ74    GND @BASEBOARD_FAB2_LIB.BASEBOARD_FAB2(SCH_1):GND    I18 @BASEBOARD_FAB2_LIB.BASEBOARD_FAB2(SCH_1):PAGE75
  CJ76    GND @BASEBOARD_FAB2_LIB.BASEBOARD_FAB2(SCH_1):GND    I18 @BASEBOARD_FAB2_LIB.BASEBOARD_FAB2(SCH_1):PAGE75
  CJ78    GND @BASEBOARD_FAB2_LIB.BASEBOARD_FAB2(SCH_1):GND    I18 @BASEBOARD_FAB2_LIB.BASEBOARD_FAB2(SCH_1):PAGE75
  CJ82    GND @BASEBOARD_FAB2_LIB.BASEBOARD_FAB2(SCH_1):GND    I18 @BASEBOARD_FAB2_LIB.BASEBOARD_FAB2(SCH_1):PAGE75
  CJ84    GND @BASEBOARD_FAB2_LIB.BASEBOARD_FAB2(SCH_1):GND    I18 @BASEBOARD_FAB2_LIB.BASEBOARD_FAB2(SCH_1):PAGE75
  CJ86    GND @BASEBOARD_FAB2_LIB.BASEBOARD_FAB2(SCH_1):GND    I18 @BASEBOARD_FAB2_LIB.BASEBOARD_FAB2(SCH_1):PAGE75
  CK11    GND @BASEBOARD_FAB2_LIB.BASEBOARD_FAB2(SCH_1):GND    I18 @BASEBOARD_FAB2_LIB.BASEBOARD_FAB2(SCH_1):PAGE75
  CK15    GND @BASEBOARD_FAB2_LIB.BASEBOARD_FAB2(SCH_1):GND    I18 @BASEBOARD_FAB2_LIB.BASEBOARD_FAB2(SCH_1):PAGE75
  CK21    GND @BASEBOARD_FAB2_LIB.BASEBOARD_FAB2(SCH_1):GND    I18 @BASEBOARD_FAB2_LIB.BASEBOARD_FAB2(SCH_1):PAGE75
  CK27    GND @BASEBOARD_FAB2_LIB.BASEBOARD_FAB2(SCH_1):GND    I18 @BASEBOARD_FAB2_LIB.BASEBOARD_FAB2(SCH_1):PAGE75
  CK63    GND @BASEBOARD_FAB2_LIB.BASEBOARD_FAB2(SCH_1):GND    I18 @BASEBOARD_FAB2_LIB.BASEBOARD_FAB2(SCH_1):PAGE75
  CK65    GND @BASEBOARD_FAB2_LIB.BASEBOARD_FAB2(SCH_1):GND    I18 @BASEBOARD_FAB2_LIB.BASEBOARD_FAB2(SCH_1):PAGE75
  CK67    GND @BASEBOARD_FAB2_LIB.BASEBOARD_FAB2(SCH_1):GND    I18 @BASEBOARD_FAB2_LIB.BASEBOARD_FAB2(SCH_1):PAGE75
  CK69    GND @BASEBOARD_FAB2_LIB.BASEBOARD_FAB2(SCH_1):GND    I18 @BASEBOARD_FAB2_LIB.BASEBOARD_FAB2(SCH_1):PAGE75
  CK71    GND @BASEBOARD_FAB2_LIB.BASEBOARD_FAB2(SCH_1):GND    I18 @BASEBOARD_FAB2_LIB.BASEBOARD_FAB2(SCH_1):PAGE75
  CK73    GND @BASEBOARD_FAB2_LIB.BASEBOARD_FAB2(SCH_1):GND    I18 @BASEBOARD_FAB2_LIB.BASEBOARD_FAB2(SCH_1):PAGE75
  CK75    GND @BASEBOARD_FAB2_LIB.BASEBOARD_FAB2(SCH_1):GND    I18 @BASEBOARD_FAB2_LIB.BASEBOARD_FAB2(SCH_1):PAGE75
  CK83    GND @BASEBOARD_FAB2_LIB.BASEBOARD_FAB2(SCH_1):GND    I18 @BASEBOARD_FAB2_LIB.BASEBOARD_FAB2(SCH_1):PAGE75
  CK85    GND @BASEBOARD_FAB2_LIB.BASEBOARD_FAB2(SCH_1):GND    I18 @BASEBOARD_FAB2_LIB.BASEBOARD_FAB2(SCH_1):PAGE75
   CL8    GND @BASEBOARD_FAB2_LIB.BASEBOARD_FAB2(SCH_1):GND    I18 @BASEBOARD_FAB2_LIB.BASEBOARD_FAB2(SCH_1):PAGE75
  CL14    GND @BASEBOARD_FAB2_LIB.BASEBOARD_FAB2(SCH_1):GND    I18 @BASEBOARD_FAB2_LIB.BASEBOARD_FAB2(SCH_1):PAGE75
  CL18    GND @BASEBOARD_FAB2_LIB.BASEBOARD_FAB2(SCH_1):GND    I18 @BASEBOARD_FAB2_LIB.BASEBOARD_FAB2(SCH_1):PAGE75
   P45    GND @BASEBOARD_FAB2_LIB.BASEBOARD_FAB2(SCH_1):GND    I18 @BASEBOARD_FAB2_LIB.BASEBOARD_FAB2(SCH_1):PAGE75
   H63    GND @BASEBOARD_FAB2_LIB.BASEBOARD_FAB2(SCH_1):GND    I18 @BASEBOARD_FAB2_LIB.BASEBOARD_FAB2(SCH_1):PAGE75
  CL62    GND @BASEBOARD_FAB2_LIB.BASEBOARD_FAB2(SCH_1):GND    I18 @BASEBOARD_FAB2_LIB.BASEBOARD_FAB2(SCH_1):PAGE75
  CL64    GND @BASEBOARD_FAB2_LIB.BASEBOARD_FAB2(SCH_1):GND    I18 @BASEBOARD_FAB2_LIB.BASEBOARD_FAB2(SCH_1):PAGE75
  CL66    GND @BASEBOARD_FAB2_LIB.BASEBOARD_FAB2(SCH_1):GND    I18 @BASEBOARD_FAB2_LIB.BASEBOARD_FAB2(SCH_1):PAGE75
  CL74    GND @BASEBOARD_FAB2_LIB.BASEBOARD_FAB2(SCH_1):GND    I18 @BASEBOARD_FAB2_LIB.BASEBOARD_FAB2(SCH_1):PAGE75
  CL76    GND @BASEBOARD_FAB2_LIB.BASEBOARD_FAB2(SCH_1):GND    I18 @BASEBOARD_FAB2_LIB.BASEBOARD_FAB2(SCH_1):PAGE75
  CL78    GND @BASEBOARD_FAB2_LIB.BASEBOARD_FAB2(SCH_1):GND    I18 @BASEBOARD_FAB2_LIB.BASEBOARD_FAB2(SCH_1):PAGE75
  CL80    GND @BASEBOARD_FAB2_LIB.BASEBOARD_FAB2(SCH_1):GND    I18 @BASEBOARD_FAB2_LIB.BASEBOARD_FAB2(SCH_1):PAGE75
  CM19    GND @BASEBOARD_FAB2_LIB.BASEBOARD_FAB2(SCH_1):GND    I18 @BASEBOARD_FAB2_LIB.BASEBOARD_FAB2(SCH_1):PAGE75
  CM29    GND @BASEBOARD_FAB2_LIB.BASEBOARD_FAB2(SCH_1):GND    I18 @BASEBOARD_FAB2_LIB.BASEBOARD_FAB2(SCH_1):PAGE75
   CM5    GND @BASEBOARD_FAB2_LIB.BASEBOARD_FAB2(SCH_1):GND    I18 @BASEBOARD_FAB2_LIB.BASEBOARD_FAB2(SCH_1):PAGE75
  CM31    GND @BASEBOARD_FAB2_LIB.BASEBOARD_FAB2(SCH_1):GND    I18 @BASEBOARD_FAB2_LIB.BASEBOARD_FAB2(SCH_1):PAGE75
  CM61    GND @BASEBOARD_FAB2_LIB.BASEBOARD_FAB2(SCH_1):GND    I18 @BASEBOARD_FAB2_LIB.BASEBOARD_FAB2(SCH_1):PAGE75
  CM63    GND @BASEBOARD_FAB2_LIB.BASEBOARD_FAB2(SCH_1):GND    I18 @BASEBOARD_FAB2_LIB.BASEBOARD_FAB2(SCH_1):PAGE75
  CM67    GND @BASEBOARD_FAB2_LIB.BASEBOARD_FAB2(SCH_1):GND    I18 @BASEBOARD_FAB2_LIB.BASEBOARD_FAB2(SCH_1):PAGE75
  CM73    GND @BASEBOARD_FAB2_LIB.BASEBOARD_FAB2(SCH_1):GND    I18 @BASEBOARD_FAB2_LIB.BASEBOARD_FAB2(SCH_1):PAGE75
  CM77    GND @BASEBOARD_FAB2_LIB.BASEBOARD_FAB2(SCH_1):GND    I18 @BASEBOARD_FAB2_LIB.BASEBOARD_FAB2(SCH_1):PAGE75
  CM83    GND @BASEBOARD_FAB2_LIB.BASEBOARD_FAB2(SCH_1):GND    I18 @BASEBOARD_FAB2_LIB.BASEBOARD_FAB2(SCH_1):PAGE75
  CM85    GND @BASEBOARD_FAB2_LIB.BASEBOARD_FAB2(SCH_1):GND    I18 @BASEBOARD_FAB2_LIB.BASEBOARD_FAB2(SCH_1):PAGE75
   CN2    GND @BASEBOARD_FAB2_LIB.BASEBOARD_FAB2(SCH_1):GND    I18 @BASEBOARD_FAB2_LIB.BASEBOARD_FAB2(SCH_1):PAGE75
  CN12    GND @BASEBOARD_FAB2_LIB.BASEBOARD_FAB2(SCH_1):GND    I18 @BASEBOARD_FAB2_LIB.BASEBOARD_FAB2(SCH_1):PAGE75
   H61    GND @BASEBOARD_FAB2_LIB.BASEBOARD_FAB2(SCH_1):GND    I18 @BASEBOARD_FAB2_LIB.BASEBOARD_FAB2(SCH_1):PAGE75
  CN26    GND @BASEBOARD_FAB2_LIB.BASEBOARD_FAB2(SCH_1):GND    I18 @BASEBOARD_FAB2_LIB.BASEBOARD_FAB2(SCH_1):PAGE75
  CN32    GND @BASEBOARD_FAB2_LIB.BASEBOARD_FAB2(SCH_1):GND    I18 @BASEBOARD_FAB2_LIB.BASEBOARD_FAB2(SCH_1):PAGE75
  CN60    GND @BASEBOARD_FAB2_LIB.BASEBOARD_FAB2(SCH_1):GND    I18 @BASEBOARD_FAB2_LIB.BASEBOARD_FAB2(SCH_1):PAGE75
  CN62    GND @BASEBOARD_FAB2_LIB.BASEBOARD_FAB2(SCH_1):GND    I18 @BASEBOARD_FAB2_LIB.BASEBOARD_FAB2(SCH_1):PAGE75
  CN68    GND @BASEBOARD_FAB2_LIB.BASEBOARD_FAB2(SCH_1):GND    I18 @BASEBOARD_FAB2_LIB.BASEBOARD_FAB2(SCH_1):PAGE75
  CN78    GND @BASEBOARD_FAB2_LIB.BASEBOARD_FAB2(SCH_1):GND    I18 @BASEBOARD_FAB2_LIB.BASEBOARD_FAB2(SCH_1):PAGE75
   CP1    GND @BASEBOARD_FAB2_LIB.BASEBOARD_FAB2(SCH_1):GND    I18 @BASEBOARD_FAB2_LIB.BASEBOARD_FAB2(SCH_1):PAGE75
   H59    GND @BASEBOARD_FAB2_LIB.BASEBOARD_FAB2(SCH_1):GND    I18 @BASEBOARD_FAB2_LIB.BASEBOARD_FAB2(SCH_1):PAGE75
  CP25    GND @BASEBOARD_FAB2_LIB.BASEBOARD_FAB2(SCH_1):GND    I18 @BASEBOARD_FAB2_LIB.BASEBOARD_FAB2(SCH_1):PAGE75
  CP59    GND @BASEBOARD_FAB2_LIB.BASEBOARD_FAB2(SCH_1):GND    I18 @BASEBOARD_FAB2_LIB.BASEBOARD_FAB2(SCH_1):PAGE75
  CP69    GND @BASEBOARD_FAB2_LIB.BASEBOARD_FAB2(SCH_1):GND    I18 @BASEBOARD_FAB2_LIB.BASEBOARD_FAB2(SCH_1):PAGE75
  CP73    GND @BASEBOARD_FAB2_LIB.BASEBOARD_FAB2(SCH_1):GND    I18 @BASEBOARD_FAB2_LIB.BASEBOARD_FAB2(SCH_1):PAGE75
  CP75    GND @BASEBOARD_FAB2_LIB.BASEBOARD_FAB2(SCH_1):GND    I18 @BASEBOARD_FAB2_LIB.BASEBOARD_FAB2(SCH_1):PAGE75
  CP81    GND @BASEBOARD_FAB2_LIB.BASEBOARD_FAB2(SCH_1):GND    I18 @BASEBOARD_FAB2_LIB.BASEBOARD_FAB2(SCH_1):PAGE75
  CP83    GND @BASEBOARD_FAB2_LIB.BASEBOARD_FAB2(SCH_1):GND    I18 @BASEBOARD_FAB2_LIB.BASEBOARD_FAB2(SCH_1):PAGE75
   CR6    GND @BASEBOARD_FAB2_LIB.BASEBOARD_FAB2(SCH_1):GND    I18 @BASEBOARD_FAB2_LIB.BASEBOARD_FAB2(SCH_1):PAGE75
  CR10    GND @BASEBOARD_FAB2_LIB.BASEBOARD_FAB2(SCH_1):GND    I18 @BASEBOARD_FAB2_LIB.BASEBOARD_FAB2(SCH_1):PAGE75
  CR22    GND @BASEBOARD_FAB2_LIB.BASEBOARD_FAB2(SCH_1):GND    I18 @BASEBOARD_FAB2_LIB.BASEBOARD_FAB2(SCH_1):PAGE75
  CR24    GND @BASEBOARD_FAB2_LIB.BASEBOARD_FAB2(SCH_1):GND    I18 @BASEBOARD_FAB2_LIB.BASEBOARD_FAB2(SCH_1):PAGE75
  CR32    GND @BASEBOARD_FAB2_LIB.BASEBOARD_FAB2(SCH_1):GND    I18 @BASEBOARD_FAB2_LIB.BASEBOARD_FAB2(SCH_1):PAGE75
  CR58    GND @BASEBOARD_FAB2_LIB.BASEBOARD_FAB2(SCH_1):GND    I18 @BASEBOARD_FAB2_LIB.BASEBOARD_FAB2(SCH_1):PAGE75
  CR62    GND @BASEBOARD_FAB2_LIB.BASEBOARD_FAB2(SCH_1):GND    I18 @BASEBOARD_FAB2_LIB.BASEBOARD_FAB2(SCH_1):PAGE75
  CR64    GND @BASEBOARD_FAB2_LIB.BASEBOARD_FAB2(SCH_1):GND    I18 @BASEBOARD_FAB2_LIB.BASEBOARD_FAB2(SCH_1):PAGE75
  CR66    GND @BASEBOARD_FAB2_LIB.BASEBOARD_FAB2(SCH_1):GND    I18 @BASEBOARD_FAB2_LIB.BASEBOARD_FAB2(SCH_1):PAGE75
  CR68    GND @BASEBOARD_FAB2_LIB.BASEBOARD_FAB2(SCH_1):GND    I18 @BASEBOARD_FAB2_LIB.BASEBOARD_FAB2(SCH_1):PAGE75
  CR78    GND @BASEBOARD_FAB2_LIB.BASEBOARD_FAB2(SCH_1):GND    I18 @BASEBOARD_FAB2_LIB.BASEBOARD_FAB2(SCH_1):PAGE75
  CR86    GND @BASEBOARD_FAB2_LIB.BASEBOARD_FAB2(SCH_1):GND    I18 @BASEBOARD_FAB2_LIB.BASEBOARD_FAB2(SCH_1):PAGE75
   H57    GND @BASEBOARD_FAB2_LIB.BASEBOARD_FAB2(SCH_1):GND    I18 @BASEBOARD_FAB2_LIB.BASEBOARD_FAB2(SCH_1):PAGE75
  CT13    GND @BASEBOARD_FAB2_LIB.BASEBOARD_FAB2(SCH_1):GND    I18 @BASEBOARD_FAB2_LIB.BASEBOARD_FAB2(SCH_1):PAGE75
  CT19    GND @BASEBOARD_FAB2_LIB.BASEBOARD_FAB2(SCH_1):GND    I18 @BASEBOARD_FAB2_LIB.BASEBOARD_FAB2(SCH_1):PAGE75
  CT27    GND @BASEBOARD_FAB2_LIB.BASEBOARD_FAB2(SCH_1):GND    I18 @BASEBOARD_FAB2_LIB.BASEBOARD_FAB2(SCH_1):PAGE75
  CT29    GND @BASEBOARD_FAB2_LIB.BASEBOARD_FAB2(SCH_1):GND    I18 @BASEBOARD_FAB2_LIB.BASEBOARD_FAB2(SCH_1):PAGE75
  CT33    GND @BASEBOARD_FAB2_LIB.BASEBOARD_FAB2(SCH_1):GND    I18 @BASEBOARD_FAB2_LIB.BASEBOARD_FAB2(SCH_1):PAGE75
  CT35    GND @BASEBOARD_FAB2_LIB.BASEBOARD_FAB2(SCH_1):GND    I18 @BASEBOARD_FAB2_LIB.BASEBOARD_FAB2(SCH_1):PAGE75
  CT57    GND @BASEBOARD_FAB2_LIB.BASEBOARD_FAB2(SCH_1):GND    I18 @BASEBOARD_FAB2_LIB.BASEBOARD_FAB2(SCH_1):PAGE75
  CT73    GND @BASEBOARD_FAB2_LIB.BASEBOARD_FAB2(SCH_1):GND    I18 @BASEBOARD_FAB2_LIB.BASEBOARD_FAB2(SCH_1):PAGE75
  CT79    GND @BASEBOARD_FAB2_LIB.BASEBOARD_FAB2(SCH_1):GND    I18 @BASEBOARD_FAB2_LIB.BASEBOARD_FAB2(SCH_1):PAGE75
  CT83    GND @BASEBOARD_FAB2_LIB.BASEBOARD_FAB2(SCH_1):GND    I18 @BASEBOARD_FAB2_LIB.BASEBOARD_FAB2(SCH_1):PAGE75
  CT85    GND @BASEBOARD_FAB2_LIB.BASEBOARD_FAB2(SCH_1):GND    I18 @BASEBOARD_FAB2_LIB.BASEBOARD_FAB2(SCH_1):PAGE75
   CU4    GND @BASEBOARD_FAB2_LIB.BASEBOARD_FAB2(SCH_1):GND    I18 @BASEBOARD_FAB2_LIB.BASEBOARD_FAB2(SCH_1):PAGE75
  CU22    GND @BASEBOARD_FAB2_LIB.BASEBOARD_FAB2(SCH_1):GND    I18 @BASEBOARD_FAB2_LIB.BASEBOARD_FAB2(SCH_1):PAGE75
  CU28    GND @BASEBOARD_FAB2_LIB.BASEBOARD_FAB2(SCH_1):GND    I18 @BASEBOARD_FAB2_LIB.BASEBOARD_FAB2(SCH_1):PAGE75
  CU30    GND @BASEBOARD_FAB2_LIB.BASEBOARD_FAB2(SCH_1):GND    I18 @BASEBOARD_FAB2_LIB.BASEBOARD_FAB2(SCH_1):PAGE75
  CU34    GND @BASEBOARD_FAB2_LIB.BASEBOARD_FAB2(SCH_1):GND    I18 @BASEBOARD_FAB2_LIB.BASEBOARD_FAB2(SCH_1):PAGE75
  CU36    GND @BASEBOARD_FAB2_LIB.BASEBOARD_FAB2(SCH_1):GND    I18 @BASEBOARD_FAB2_LIB.BASEBOARD_FAB2(SCH_1):PAGE75
  CU56    GND @BASEBOARD_FAB2_LIB.BASEBOARD_FAB2(SCH_1):GND    I18 @BASEBOARD_FAB2_LIB.BASEBOARD_FAB2(SCH_1):PAGE75
  CU62    GND @BASEBOARD_FAB2_LIB.BASEBOARD_FAB2(SCH_1):GND    I18 @BASEBOARD_FAB2_LIB.BASEBOARD_FAB2(SCH_1):PAGE75
  CU68    GND @BASEBOARD_FAB2_LIB.BASEBOARD_FAB2(SCH_1):GND    I18 @BASEBOARD_FAB2_LIB.BASEBOARD_FAB2(SCH_1):PAGE75
  CU76    GND @BASEBOARD_FAB2_LIB.BASEBOARD_FAB2(SCH_1):GND    I18 @BASEBOARD_FAB2_LIB.BASEBOARD_FAB2(SCH_1):PAGE75
  CU78    GND @BASEBOARD_FAB2_LIB.BASEBOARD_FAB2(SCH_1):GND    I18 @BASEBOARD_FAB2_LIB.BASEBOARD_FAB2(SCH_1):PAGE75
  CU80    GND @BASEBOARD_FAB2_LIB.BASEBOARD_FAB2(SCH_1):GND    I18 @BASEBOARD_FAB2_LIB.BASEBOARD_FAB2(SCH_1):PAGE75
  CU82    GND @BASEBOARD_FAB2_LIB.BASEBOARD_FAB2(SCH_1):GND    I18 @BASEBOARD_FAB2_LIB.BASEBOARD_FAB2(SCH_1):PAGE75
  CU86    GND @BASEBOARD_FAB2_LIB.BASEBOARD_FAB2(SCH_1):GND    I18 @BASEBOARD_FAB2_LIB.BASEBOARD_FAB2(SCH_1):PAGE75
   CV1    GND @BASEBOARD_FAB2_LIB.BASEBOARD_FAB2(SCH_1):GND    I18 @BASEBOARD_FAB2_LIB.BASEBOARD_FAB2(SCH_1):PAGE75
   H55    GND @BASEBOARD_FAB2_LIB.BASEBOARD_FAB2(SCH_1):GND    I18 @BASEBOARD_FAB2_LIB.BASEBOARD_FAB2(SCH_1):PAGE75
  CV17    GND @BASEBOARD_FAB2_LIB.BASEBOARD_FAB2(SCH_1):GND    I18 @BASEBOARD_FAB2_LIB.BASEBOARD_FAB2(SCH_1):PAGE75
  CV25    GND @BASEBOARD_FAB2_LIB.BASEBOARD_FAB2(SCH_1):GND    I18 @BASEBOARD_FAB2_LIB.BASEBOARD_FAB2(SCH_1):PAGE75
  CV27    GND @BASEBOARD_FAB2_LIB.BASEBOARD_FAB2(SCH_1):GND    I18 @BASEBOARD_FAB2_LIB.BASEBOARD_FAB2(SCH_1):PAGE75
  CV31    GND @BASEBOARD_FAB2_LIB.BASEBOARD_FAB2(SCH_1):GND    I18 @BASEBOARD_FAB2_LIB.BASEBOARD_FAB2(SCH_1):PAGE75
  CV33    GND @BASEBOARD_FAB2_LIB.BASEBOARD_FAB2(SCH_1):GND    I18 @BASEBOARD_FAB2_LIB.BASEBOARD_FAB2(SCH_1):PAGE75
  CV37    GND @BASEBOARD_FAB2_LIB.BASEBOARD_FAB2(SCH_1):GND    I18 @BASEBOARD_FAB2_LIB.BASEBOARD_FAB2(SCH_1):PAGE75
  CV39    GND @BASEBOARD_FAB2_LIB.BASEBOARD_FAB2(SCH_1):GND    I18 @BASEBOARD_FAB2_LIB.BASEBOARD_FAB2(SCH_1):PAGE75
  CV41    GND @BASEBOARD_FAB2_LIB.BASEBOARD_FAB2(SCH_1):GND    I18 @BASEBOARD_FAB2_LIB.BASEBOARD_FAB2(SCH_1):PAGE75
  CV53    GND @BASEBOARD_FAB2_LIB.BASEBOARD_FAB2(SCH_1):GND    I18 @BASEBOARD_FAB2_LIB.BASEBOARD_FAB2(SCH_1):PAGE75
  CV55    GND @BASEBOARD_FAB2_LIB.BASEBOARD_FAB2(SCH_1):GND    I18 @BASEBOARD_FAB2_LIB.BASEBOARD_FAB2(SCH_1):PAGE75
  CV63    GND @BASEBOARD_FAB2_LIB.BASEBOARD_FAB2(SCH_1):GND    I18 @BASEBOARD_FAB2_LIB.BASEBOARD_FAB2(SCH_1):PAGE75
  CV67    GND @BASEBOARD_FAB2_LIB.BASEBOARD_FAB2(SCH_1):GND    I18 @BASEBOARD_FAB2_LIB.BASEBOARD_FAB2(SCH_1):PAGE75
  CV73    GND @BASEBOARD_FAB2_LIB.BASEBOARD_FAB2(SCH_1):GND    I18 @BASEBOARD_FAB2_LIB.BASEBOARD_FAB2(SCH_1):PAGE75
  CV79    GND @BASEBOARD_FAB2_LIB.BASEBOARD_FAB2(SCH_1):GND    I18 @BASEBOARD_FAB2_LIB.BASEBOARD_FAB2(SCH_1):PAGE75
  CV81    GND @BASEBOARD_FAB2_LIB.BASEBOARD_FAB2(SCH_1):GND    I18 @BASEBOARD_FAB2_LIB.BASEBOARD_FAB2(SCH_1):PAGE75
  CV83    GND @BASEBOARD_FAB2_LIB.BASEBOARD_FAB2(SCH_1):GND    I18 @BASEBOARD_FAB2_LIB.BASEBOARD_FAB2(SCH_1):PAGE75
  CW12    GND @BASEBOARD_FAB2_LIB.BASEBOARD_FAB2(SCH_1):GND    I18 @BASEBOARD_FAB2_LIB.BASEBOARD_FAB2(SCH_1):PAGE75
  CW26    GND @BASEBOARD_FAB2_LIB.BASEBOARD_FAB2(SCH_1):GND    I18 @BASEBOARD_FAB2_LIB.BASEBOARD_FAB2(SCH_1):PAGE75
  CW32    GND @BASEBOARD_FAB2_LIB.BASEBOARD_FAB2(SCH_1):GND    I18 @BASEBOARD_FAB2_LIB.BASEBOARD_FAB2(SCH_1):PAGE75
  CW38    GND @BASEBOARD_FAB2_LIB.BASEBOARD_FAB2(SCH_1):GND    I18 @BASEBOARD_FAB2_LIB.BASEBOARD_FAB2(SCH_1):PAGE75
  CW40    GND @BASEBOARD_FAB2_LIB.BASEBOARD_FAB2(SCH_1):GND    I18 @BASEBOARD_FAB2_LIB.BASEBOARD_FAB2(SCH_1):PAGE75
  CW42    GND @BASEBOARD_FAB2_LIB.BASEBOARD_FAB2(SCH_1):GND    I18 @BASEBOARD_FAB2_LIB.BASEBOARD_FAB2(SCH_1):PAGE75
  CW52    GND @BASEBOARD_FAB2_LIB.BASEBOARD_FAB2(SCH_1):GND    I18 @BASEBOARD_FAB2_LIB.BASEBOARD_FAB2(SCH_1):PAGE75
  CW54    GND @BASEBOARD_FAB2_LIB.BASEBOARD_FAB2(SCH_1):GND    I18 @BASEBOARD_FAB2_LIB.BASEBOARD_FAB2(SCH_1):PAGE75
  CW64    GND @BASEBOARD_FAB2_LIB.BASEBOARD_FAB2(SCH_1):GND    I18 @BASEBOARD_FAB2_LIB.BASEBOARD_FAB2(SCH_1):PAGE75
  CW66    GND @BASEBOARD_FAB2_LIB.BASEBOARD_FAB2(SCH_1):GND    I18 @BASEBOARD_FAB2_LIB.BASEBOARD_FAB2(SCH_1):PAGE75
  CW68    GND @BASEBOARD_FAB2_LIB.BASEBOARD_FAB2(SCH_1):GND    I18 @BASEBOARD_FAB2_LIB.BASEBOARD_FAB2(SCH_1):PAGE75
  CW74    GND @BASEBOARD_FAB2_LIB.BASEBOARD_FAB2(SCH_1):GND    I18 @BASEBOARD_FAB2_LIB.BASEBOARD_FAB2(SCH_1):PAGE75
  CW78    GND @BASEBOARD_FAB2_LIB.BASEBOARD_FAB2(SCH_1):GND    I18 @BASEBOARD_FAB2_LIB.BASEBOARD_FAB2(SCH_1):PAGE75
  CW82    GND @BASEBOARD_FAB2_LIB.BASEBOARD_FAB2(SCH_1):GND    I18 @BASEBOARD_FAB2_LIB.BASEBOARD_FAB2(SCH_1):PAGE75
   CY1    GND @BASEBOARD_FAB2_LIB.BASEBOARD_FAB2(SCH_1):GND    I18 @BASEBOARD_FAB2_LIB.BASEBOARD_FAB2(SCH_1):PAGE75
   CY9    GND @BASEBOARD_FAB2_LIB.BASEBOARD_FAB2(SCH_1):GND    I18 @BASEBOARD_FAB2_LIB.BASEBOARD_FAB2(SCH_1):PAGE75
  CY13    GND @BASEBOARD_FAB2_LIB.BASEBOARD_FAB2(SCH_1):GND    I18 @BASEBOARD_FAB2_LIB.BASEBOARD_FAB2(SCH_1):PAGE75
  CY15    GND @BASEBOARD_FAB2_LIB.BASEBOARD_FAB2(SCH_1):GND    I18 @BASEBOARD_FAB2_LIB.BASEBOARD_FAB2(SCH_1):PAGE75
  CY21    GND @BASEBOARD_FAB2_LIB.BASEBOARD_FAB2(SCH_1):GND    I18 @BASEBOARD_FAB2_LIB.BASEBOARD_FAB2(SCH_1):PAGE75
  CY41    GND @BASEBOARD_FAB2_LIB.BASEBOARD_FAB2(SCH_1):GND    I18 @BASEBOARD_FAB2_LIB.BASEBOARD_FAB2(SCH_1):PAGE75
  CY45    GND @BASEBOARD_FAB2_LIB.BASEBOARD_FAB2(SCH_1):GND    I18 @BASEBOARD_FAB2_LIB.BASEBOARD_FAB2(SCH_1):PAGE75
  CY51    GND @BASEBOARD_FAB2_LIB.BASEBOARD_FAB2(SCH_1):GND    I18 @BASEBOARD_FAB2_LIB.BASEBOARD_FAB2(SCH_1):PAGE75
  CY59    GND @BASEBOARD_FAB2_LIB.BASEBOARD_FAB2(SCH_1):GND    I18 @BASEBOARD_FAB2_LIB.BASEBOARD_FAB2(SCH_1):PAGE75
  CY61    GND @BASEBOARD_FAB2_LIB.BASEBOARD_FAB2(SCH_1):GND    I18 @BASEBOARD_FAB2_LIB.BASEBOARD_FAB2(SCH_1):PAGE75
  CY65    GND @BASEBOARD_FAB2_LIB.BASEBOARD_FAB2(SCH_1):GND    I18 @BASEBOARD_FAB2_LIB.BASEBOARD_FAB2(SCH_1):PAGE75
  CY69    GND @BASEBOARD_FAB2_LIB.BASEBOARD_FAB2(SCH_1):GND    I18 @BASEBOARD_FAB2_LIB.BASEBOARD_FAB2(SCH_1):PAGE75
  CY75    GND @BASEBOARD_FAB2_LIB.BASEBOARD_FAB2(SCH_1):GND    I18 @BASEBOARD_FAB2_LIB.BASEBOARD_FAB2(SCH_1):PAGE75
  CY77    GND @BASEBOARD_FAB2_LIB.BASEBOARD_FAB2(SCH_1):GND    I18 @BASEBOARD_FAB2_LIB.BASEBOARD_FAB2(SCH_1):PAGE75
  CY83    GND @BASEBOARD_FAB2_LIB.BASEBOARD_FAB2(SCH_1):GND    I18 @BASEBOARD_FAB2_LIB.BASEBOARD_FAB2(SCH_1):PAGE75
  CY85    GND @BASEBOARD_FAB2_LIB.BASEBOARD_FAB2(SCH_1):GND    I18 @BASEBOARD_FAB2_LIB.BASEBOARD_FAB2(SCH_1):PAGE75
   DA6    GND @BASEBOARD_FAB2_LIB.BASEBOARD_FAB2(SCH_1):GND    I18 @BASEBOARD_FAB2_LIB.BASEBOARD_FAB2(SCH_1):PAGE75
   H53    GND @BASEBOARD_FAB2_LIB.BASEBOARD_FAB2(SCH_1):GND    I18 @BASEBOARD_FAB2_LIB.BASEBOARD_FAB2(SCH_1):PAGE75
  DA18    GND @BASEBOARD_FAB2_LIB.BASEBOARD_FAB2(SCH_1):GND    I18 @BASEBOARD_FAB2_LIB.BASEBOARD_FAB2(SCH_1):PAGE75
  DA26    GND @BASEBOARD_FAB2_LIB.BASEBOARD_FAB2(SCH_1):GND    I18 @BASEBOARD_FAB2_LIB.BASEBOARD_FAB2(SCH_1):PAGE75
  DA28    GND @BASEBOARD_FAB2_LIB.BASEBOARD_FAB2(SCH_1):GND    I18 @BASEBOARD_FAB2_LIB.BASEBOARD_FAB2(SCH_1):PAGE75
  DA30    GND @BASEBOARD_FAB2_LIB.BASEBOARD_FAB2(SCH_1):GND    I18 @BASEBOARD_FAB2_LIB.BASEBOARD_FAB2(SCH_1):PAGE75
  DA32    GND @BASEBOARD_FAB2_LIB.BASEBOARD_FAB2(SCH_1):GND    I18 @BASEBOARD_FAB2_LIB.BASEBOARD_FAB2(SCH_1):PAGE75
  DA34    GND @BASEBOARD_FAB2_LIB.BASEBOARD_FAB2(SCH_1):GND    I18 @BASEBOARD_FAB2_LIB.BASEBOARD_FAB2(SCH_1):PAGE75
  DA36    GND @BASEBOARD_FAB2_LIB.BASEBOARD_FAB2(SCH_1):GND    I18 @BASEBOARD_FAB2_LIB.BASEBOARD_FAB2(SCH_1):PAGE75
  DA38    GND @BASEBOARD_FAB2_LIB.BASEBOARD_FAB2(SCH_1):GND    I18 @BASEBOARD_FAB2_LIB.BASEBOARD_FAB2(SCH_1):PAGE75
  DA44    GND @BASEBOARD_FAB2_LIB.BASEBOARD_FAB2(SCH_1):GND    I18 @BASEBOARD_FAB2_LIB.BASEBOARD_FAB2(SCH_1):PAGE75
  DA46    GND @BASEBOARD_FAB2_LIB.BASEBOARD_FAB2(SCH_1):GND    I18 @BASEBOARD_FAB2_LIB.BASEBOARD_FAB2(SCH_1):PAGE75
  DA48    GND @BASEBOARD_FAB2_LIB.BASEBOARD_FAB2(SCH_1):GND    I19 @BASEBOARD_FAB2_LIB.BASEBOARD_FAB2(SCH_1):PAGE75
  DA50    GND @BASEBOARD_FAB2_LIB.BASEBOARD_FAB2(SCH_1):GND    I19 @BASEBOARD_FAB2_LIB.BASEBOARD_FAB2(SCH_1):PAGE75
  DA64    GND @BASEBOARD_FAB2_LIB.BASEBOARD_FAB2(SCH_1):GND    I19 @BASEBOARD_FAB2_LIB.BASEBOARD_FAB2(SCH_1):PAGE75
  DA70    GND @BASEBOARD_FAB2_LIB.BASEBOARD_FAB2(SCH_1):GND    I19 @BASEBOARD_FAB2_LIB.BASEBOARD_FAB2(SCH_1):PAGE75
  DA74    GND @BASEBOARD_FAB2_LIB.BASEBOARD_FAB2(SCH_1):GND    I19 @BASEBOARD_FAB2_LIB.BASEBOARD_FAB2(SCH_1):PAGE75
  DA76    GND @BASEBOARD_FAB2_LIB.BASEBOARD_FAB2(SCH_1):GND    I19 @BASEBOARD_FAB2_LIB.BASEBOARD_FAB2(SCH_1):PAGE75
  DA78    GND @BASEBOARD_FAB2_LIB.BASEBOARD_FAB2(SCH_1):GND    I19 @BASEBOARD_FAB2_LIB.BASEBOARD_FAB2(SCH_1):PAGE75
  DA80    GND @BASEBOARD_FAB2_LIB.BASEBOARD_FAB2(SCH_1):GND    I19 @BASEBOARD_FAB2_LIB.BASEBOARD_FAB2(SCH_1):PAGE75
   DB3    GND @BASEBOARD_FAB2_LIB.BASEBOARD_FAB2(SCH_1):GND    I19 @BASEBOARD_FAB2_LIB.BASEBOARD_FAB2(SCH_1):PAGE75
  DB13    GND @BASEBOARD_FAB2_LIB.BASEBOARD_FAB2(SCH_1):GND    I19 @BASEBOARD_FAB2_LIB.BASEBOARD_FAB2(SCH_1):PAGE75
  DB17    GND @BASEBOARD_FAB2_LIB.BASEBOARD_FAB2(SCH_1):GND    I19 @BASEBOARD_FAB2_LIB.BASEBOARD_FAB2(SCH_1):PAGE75
  DB23    GND @BASEBOARD_FAB2_LIB.BASEBOARD_FAB2(SCH_1):GND    I19 @BASEBOARD_FAB2_LIB.BASEBOARD_FAB2(SCH_1):PAGE75
  DB25    GND @BASEBOARD_FAB2_LIB.BASEBOARD_FAB2(SCH_1):GND    I19 @BASEBOARD_FAB2_LIB.BASEBOARD_FAB2(SCH_1):PAGE75
  DB39    GND @BASEBOARD_FAB2_LIB.BASEBOARD_FAB2(SCH_1):GND    I19 @BASEBOARD_FAB2_LIB.BASEBOARD_FAB2(SCH_1):PAGE75
  DB41    GND @BASEBOARD_FAB2_LIB.BASEBOARD_FAB2(SCH_1):GND    I19 @BASEBOARD_FAB2_LIB.BASEBOARD_FAB2(SCH_1):PAGE75
  DB47    GND @BASEBOARD_FAB2_LIB.BASEBOARD_FAB2(SCH_1):GND    I19 @BASEBOARD_FAB2_LIB.BASEBOARD_FAB2(SCH_1):PAGE75
  DB49    GND @BASEBOARD_FAB2_LIB.BASEBOARD_FAB2(SCH_1):GND    I19 @BASEBOARD_FAB2_LIB.BASEBOARD_FAB2(SCH_1):PAGE75
  DB73    GND @BASEBOARD_FAB2_LIB.BASEBOARD_FAB2(SCH_1):GND    I19 @BASEBOARD_FAB2_LIB.BASEBOARD_FAB2(SCH_1):PAGE75
  DB77    GND @BASEBOARD_FAB2_LIB.BASEBOARD_FAB2(SCH_1):GND    I19 @BASEBOARD_FAB2_LIB.BASEBOARD_FAB2(SCH_1):PAGE75
  DB83    GND @BASEBOARD_FAB2_LIB.BASEBOARD_FAB2(SCH_1):GND    I19 @BASEBOARD_FAB2_LIB.BASEBOARD_FAB2(SCH_1):PAGE75
  DB85    GND @BASEBOARD_FAB2_LIB.BASEBOARD_FAB2(SCH_1):GND    I19 @BASEBOARD_FAB2_LIB.BASEBOARD_FAB2(SCH_1):PAGE75
  DC14    GND @BASEBOARD_FAB2_LIB.BASEBOARD_FAB2(SCH_1):GND    I19 @BASEBOARD_FAB2_LIB.BASEBOARD_FAB2(SCH_1):PAGE75
  DC24    GND @BASEBOARD_FAB2_LIB.BASEBOARD_FAB2(SCH_1):GND    I19 @BASEBOARD_FAB2_LIB.BASEBOARD_FAB2(SCH_1):PAGE75
  DC26    GND @BASEBOARD_FAB2_LIB.BASEBOARD_FAB2(SCH_1):GND    I19 @BASEBOARD_FAB2_LIB.BASEBOARD_FAB2(SCH_1):PAGE75
  DC32    GND @BASEBOARD_FAB2_LIB.BASEBOARD_FAB2(SCH_1):GND    I19 @BASEBOARD_FAB2_LIB.BASEBOARD_FAB2(SCH_1):PAGE75
  DC38    GND @BASEBOARD_FAB2_LIB.BASEBOARD_FAB2(SCH_1):GND    I19 @BASEBOARD_FAB2_LIB.BASEBOARD_FAB2(SCH_1):PAGE75
  DC42    GND @BASEBOARD_FAB2_LIB.BASEBOARD_FAB2(SCH_1):GND    I19 @BASEBOARD_FAB2_LIB.BASEBOARD_FAB2(SCH_1):PAGE75
  DC64    GND @BASEBOARD_FAB2_LIB.BASEBOARD_FAB2(SCH_1):GND    I19 @BASEBOARD_FAB2_LIB.BASEBOARD_FAB2(SCH_1):PAGE75
  DC66    GND @BASEBOARD_FAB2_LIB.BASEBOARD_FAB2(SCH_1):GND    I19 @BASEBOARD_FAB2_LIB.BASEBOARD_FAB2(SCH_1):PAGE75
  DC68    GND @BASEBOARD_FAB2_LIB.BASEBOARD_FAB2(SCH_1):GND    I19 @BASEBOARD_FAB2_LIB.BASEBOARD_FAB2(SCH_1):PAGE75
  DC70    GND @BASEBOARD_FAB2_LIB.BASEBOARD_FAB2(SCH_1):GND    I19 @BASEBOARD_FAB2_LIB.BASEBOARD_FAB2(SCH_1):PAGE75
  DC78    GND @BASEBOARD_FAB2_LIB.BASEBOARD_FAB2(SCH_1):GND    I19 @BASEBOARD_FAB2_LIB.BASEBOARD_FAB2(SCH_1):PAGE75
  DC84    GND @BASEBOARD_FAB2_LIB.BASEBOARD_FAB2(SCH_1):GND    I19 @BASEBOARD_FAB2_LIB.BASEBOARD_FAB2(SCH_1):PAGE75
  DC86    GND @BASEBOARD_FAB2_LIB.BASEBOARD_FAB2(SCH_1):GND    I19 @BASEBOARD_FAB2_LIB.BASEBOARD_FAB2(SCH_1):PAGE75
  DD11    GND @BASEBOARD_FAB2_LIB.BASEBOARD_FAB2(SCH_1):GND    I19 @BASEBOARD_FAB2_LIB.BASEBOARD_FAB2(SCH_1):PAGE75
  DD23    GND @BASEBOARD_FAB2_LIB.BASEBOARD_FAB2(SCH_1):GND    I19 @BASEBOARD_FAB2_LIB.BASEBOARD_FAB2(SCH_1):PAGE75
  DD27    GND @BASEBOARD_FAB2_LIB.BASEBOARD_FAB2(SCH_1):GND    I19 @BASEBOARD_FAB2_LIB.BASEBOARD_FAB2(SCH_1):PAGE75
  DD31    GND @BASEBOARD_FAB2_LIB.BASEBOARD_FAB2(SCH_1):GND    I19 @BASEBOARD_FAB2_LIB.BASEBOARD_FAB2(SCH_1):PAGE75
  DD33    GND @BASEBOARD_FAB2_LIB.BASEBOARD_FAB2(SCH_1):GND    I19 @BASEBOARD_FAB2_LIB.BASEBOARD_FAB2(SCH_1):PAGE75
  DD37    GND @BASEBOARD_FAB2_LIB.BASEBOARD_FAB2(SCH_1):GND    I19 @BASEBOARD_FAB2_LIB.BASEBOARD_FAB2(SCH_1):PAGE75
  DD71    GND @BASEBOARD_FAB2_LIB.BASEBOARD_FAB2(SCH_1):GND    I19 @BASEBOARD_FAB2_LIB.BASEBOARD_FAB2(SCH_1):PAGE75
  DD73    GND @BASEBOARD_FAB2_LIB.BASEBOARD_FAB2(SCH_1):GND    I19 @BASEBOARD_FAB2_LIB.BASEBOARD_FAB2(SCH_1):PAGE75
  DD75    GND @BASEBOARD_FAB2_LIB.BASEBOARD_FAB2(SCH_1):GND    I19 @BASEBOARD_FAB2_LIB.BASEBOARD_FAB2(SCH_1):PAGE75
  DD81    GND @BASEBOARD_FAB2_LIB.BASEBOARD_FAB2(SCH_1):GND    I19 @BASEBOARD_FAB2_LIB.BASEBOARD_FAB2(SCH_1):PAGE75
  DD83    GND @BASEBOARD_FAB2_LIB.BASEBOARD_FAB2(SCH_1):GND    I19 @BASEBOARD_FAB2_LIB.BASEBOARD_FAB2(SCH_1):PAGE75
   DE6    GND @BASEBOARD_FAB2_LIB.BASEBOARD_FAB2(SCH_1):GND    I19 @BASEBOARD_FAB2_LIB.BASEBOARD_FAB2(SCH_1):PAGE75
   DE8    GND @BASEBOARD_FAB2_LIB.BASEBOARD_FAB2(SCH_1):GND    I19 @BASEBOARD_FAB2_LIB.BASEBOARD_FAB2(SCH_1):PAGE75
  DE18    GND @BASEBOARD_FAB2_LIB.BASEBOARD_FAB2(SCH_1):GND    I19 @BASEBOARD_FAB2_LIB.BASEBOARD_FAB2(SCH_1):PAGE75
  DE20    GND @BASEBOARD_FAB2_LIB.BASEBOARD_FAB2(SCH_1):GND    I19 @BASEBOARD_FAB2_LIB.BASEBOARD_FAB2(SCH_1):PAGE75
  DE24    GND @BASEBOARD_FAB2_LIB.BASEBOARD_FAB2(SCH_1):GND    I19 @BASEBOARD_FAB2_LIB.BASEBOARD_FAB2(SCH_1):PAGE75
  DE28    GND @BASEBOARD_FAB2_LIB.BASEBOARD_FAB2(SCH_1):GND    I19 @BASEBOARD_FAB2_LIB.BASEBOARD_FAB2(SCH_1):PAGE75
  DE30    GND @BASEBOARD_FAB2_LIB.BASEBOARD_FAB2(SCH_1):GND    I19 @BASEBOARD_FAB2_LIB.BASEBOARD_FAB2(SCH_1):PAGE75
  DE34    GND @BASEBOARD_FAB2_LIB.BASEBOARD_FAB2(SCH_1):GND    I19 @BASEBOARD_FAB2_LIB.BASEBOARD_FAB2(SCH_1):PAGE75
  DE36    GND @BASEBOARD_FAB2_LIB.BASEBOARD_FAB2(SCH_1):GND    I19 @BASEBOARD_FAB2_LIB.BASEBOARD_FAB2(SCH_1):PAGE75
  DE64    GND @BASEBOARD_FAB2_LIB.BASEBOARD_FAB2(SCH_1):GND    I19 @BASEBOARD_FAB2_LIB.BASEBOARD_FAB2(SCH_1):PAGE75
  DE70    GND @BASEBOARD_FAB2_LIB.BASEBOARD_FAB2(SCH_1):GND    I19 @BASEBOARD_FAB2_LIB.BASEBOARD_FAB2(SCH_1):PAGE75
  DE72    GND @BASEBOARD_FAB2_LIB.BASEBOARD_FAB2(SCH_1):GND    I19 @BASEBOARD_FAB2_LIB.BASEBOARD_FAB2(SCH_1):PAGE75
  DE78    GND @BASEBOARD_FAB2_LIB.BASEBOARD_FAB2(SCH_1):GND    I19 @BASEBOARD_FAB2_LIB.BASEBOARD_FAB2(SCH_1):PAGE75
   DF5    GND @BASEBOARD_FAB2_LIB.BASEBOARD_FAB2(SCH_1):GND    I19 @BASEBOARD_FAB2_LIB.BASEBOARD_FAB2(SCH_1):PAGE75
   DF7    GND @BASEBOARD_FAB2_LIB.BASEBOARD_FAB2(SCH_1):GND    I19 @BASEBOARD_FAB2_LIB.BASEBOARD_FAB2(SCH_1):PAGE75
   H51    GND @BASEBOARD_FAB2_LIB.BASEBOARD_FAB2(SCH_1):GND    I19 @BASEBOARD_FAB2_LIB.BASEBOARD_FAB2(SCH_1):PAGE75
  DF19    GND @BASEBOARD_FAB2_LIB.BASEBOARD_FAB2(SCH_1):GND    I19 @BASEBOARD_FAB2_LIB.BASEBOARD_FAB2(SCH_1):PAGE75
  DF29    GND @BASEBOARD_FAB2_LIB.BASEBOARD_FAB2(SCH_1):GND    I19 @BASEBOARD_FAB2_LIB.BASEBOARD_FAB2(SCH_1):PAGE75
  DF35    GND @BASEBOARD_FAB2_LIB.BASEBOARD_FAB2(SCH_1):GND    I19 @BASEBOARD_FAB2_LIB.BASEBOARD_FAB2(SCH_1):PAGE75
  DF37    GND @BASEBOARD_FAB2_LIB.BASEBOARD_FAB2(SCH_1):GND    I19 @BASEBOARD_FAB2_LIB.BASEBOARD_FAB2(SCH_1):PAGE75
  DF39    GND @BASEBOARD_FAB2_LIB.BASEBOARD_FAB2(SCH_1):GND    I19 @BASEBOARD_FAB2_LIB.BASEBOARD_FAB2(SCH_1):PAGE75
  DF41    GND @BASEBOARD_FAB2_LIB.BASEBOARD_FAB2(SCH_1):GND    I19 @BASEBOARD_FAB2_LIB.BASEBOARD_FAB2(SCH_1):PAGE75
  DF65    GND @BASEBOARD_FAB2_LIB.BASEBOARD_FAB2(SCH_1):GND    I19 @BASEBOARD_FAB2_LIB.BASEBOARD_FAB2(SCH_1):PAGE75
  DF69    GND @BASEBOARD_FAB2_LIB.BASEBOARD_FAB2(SCH_1):GND    I19 @BASEBOARD_FAB2_LIB.BASEBOARD_FAB2(SCH_1):PAGE75
  DF73    GND @BASEBOARD_FAB2_LIB.BASEBOARD_FAB2(SCH_1):GND    I19 @BASEBOARD_FAB2_LIB.BASEBOARD_FAB2(SCH_1):PAGE75
  DF79    GND @BASEBOARD_FAB2_LIB.BASEBOARD_FAB2(SCH_1):GND    I19 @BASEBOARD_FAB2_LIB.BASEBOARD_FAB2(SCH_1):PAGE75
  DF83    GND @BASEBOARD_FAB2_LIB.BASEBOARD_FAB2(SCH_1):GND    I19 @BASEBOARD_FAB2_LIB.BASEBOARD_FAB2(SCH_1):PAGE75
  DF85    GND @BASEBOARD_FAB2_LIB.BASEBOARD_FAB2(SCH_1):GND    I19 @BASEBOARD_FAB2_LIB.BASEBOARD_FAB2(SCH_1):PAGE75
   DG2    GND @BASEBOARD_FAB2_LIB.BASEBOARD_FAB2(SCH_1):GND    I19 @BASEBOARD_FAB2_LIB.BASEBOARD_FAB2(SCH_1):PAGE75
   H49    GND @BASEBOARD_FAB2_LIB.BASEBOARD_FAB2(SCH_1):GND    I19 @BASEBOARD_FAB2_LIB.BASEBOARD_FAB2(SCH_1):PAGE75
  DG14    GND @BASEBOARD_FAB2_LIB.BASEBOARD_FAB2(SCH_1):GND    I19 @BASEBOARD_FAB2_LIB.BASEBOARD_FAB2(SCH_1):PAGE75
  DG16    GND @BASEBOARD_FAB2_LIB.BASEBOARD_FAB2(SCH_1):GND    I19 @BASEBOARD_FAB2_LIB.BASEBOARD_FAB2(SCH_1):PAGE75
  DG24    GND @BASEBOARD_FAB2_LIB.BASEBOARD_FAB2(SCH_1):GND    I19 @BASEBOARD_FAB2_LIB.BASEBOARD_FAB2(SCH_1):PAGE75
  DG66    GND @BASEBOARD_FAB2_LIB.BASEBOARD_FAB2(SCH_1):GND    I19 @BASEBOARD_FAB2_LIB.BASEBOARD_FAB2(SCH_1):PAGE75
  DG68    GND @BASEBOARD_FAB2_LIB.BASEBOARD_FAB2(SCH_1):GND    I19 @BASEBOARD_FAB2_LIB.BASEBOARD_FAB2(SCH_1):PAGE75
  DG76    GND @BASEBOARD_FAB2_LIB.BASEBOARD_FAB2(SCH_1):GND    I19 @BASEBOARD_FAB2_LIB.BASEBOARD_FAB2(SCH_1):PAGE75
  DG78    GND @BASEBOARD_FAB2_LIB.BASEBOARD_FAB2(SCH_1):GND    I19 @BASEBOARD_FAB2_LIB.BASEBOARD_FAB2(SCH_1):PAGE75
  DG80    GND @BASEBOARD_FAB2_LIB.BASEBOARD_FAB2(SCH_1):GND    I19 @BASEBOARD_FAB2_LIB.BASEBOARD_FAB2(SCH_1):PAGE75
  DG82    GND @BASEBOARD_FAB2_LIB.BASEBOARD_FAB2(SCH_1):GND    I19 @BASEBOARD_FAB2_LIB.BASEBOARD_FAB2(SCH_1):PAGE75
  DH13    GND @BASEBOARD_FAB2_LIB.BASEBOARD_FAB2(SCH_1):GND    I19 @BASEBOARD_FAB2_LIB.BASEBOARD_FAB2(SCH_1):PAGE75
  DH15    GND @BASEBOARD_FAB2_LIB.BASEBOARD_FAB2(SCH_1):GND    I19 @BASEBOARD_FAB2_LIB.BASEBOARD_FAB2(SCH_1):PAGE75
  DH23    GND @BASEBOARD_FAB2_LIB.BASEBOARD_FAB2(SCH_1):GND    I19 @BASEBOARD_FAB2_LIB.BASEBOARD_FAB2(SCH_1):PAGE75
  DH25    GND @BASEBOARD_FAB2_LIB.BASEBOARD_FAB2(SCH_1):GND    I19 @BASEBOARD_FAB2_LIB.BASEBOARD_FAB2(SCH_1):PAGE75
  DH27    GND @BASEBOARD_FAB2_LIB.BASEBOARD_FAB2(SCH_1):GND    I19 @BASEBOARD_FAB2_LIB.BASEBOARD_FAB2(SCH_1):PAGE75
  DH29    GND @BASEBOARD_FAB2_LIB.BASEBOARD_FAB2(SCH_1):GND    I19 @BASEBOARD_FAB2_LIB.BASEBOARD_FAB2(SCH_1):PAGE75
  DH31    GND @BASEBOARD_FAB2_LIB.BASEBOARD_FAB2(SCH_1):GND    I19 @BASEBOARD_FAB2_LIB.BASEBOARD_FAB2(SCH_1):PAGE75
  DH33    GND @BASEBOARD_FAB2_LIB.BASEBOARD_FAB2(SCH_1):GND    I19 @BASEBOARD_FAB2_LIB.BASEBOARD_FAB2(SCH_1):PAGE75
  DH35    GND @BASEBOARD_FAB2_LIB.BASEBOARD_FAB2(SCH_1):GND    I19 @BASEBOARD_FAB2_LIB.BASEBOARD_FAB2(SCH_1):PAGE75
  DH37    GND @BASEBOARD_FAB2_LIB.BASEBOARD_FAB2(SCH_1):GND    I19 @BASEBOARD_FAB2_LIB.BASEBOARD_FAB2(SCH_1):PAGE75
  DH41    GND @BASEBOARD_FAB2_LIB.BASEBOARD_FAB2(SCH_1):GND    I19 @BASEBOARD_FAB2_LIB.BASEBOARD_FAB2(SCH_1):PAGE75
  DH67    GND @BASEBOARD_FAB2_LIB.BASEBOARD_FAB2(SCH_1):GND    I19 @BASEBOARD_FAB2_LIB.BASEBOARD_FAB2(SCH_1):PAGE75
  DH71    GND @BASEBOARD_FAB2_LIB.BASEBOARD_FAB2(SCH_1):GND    I19 @BASEBOARD_FAB2_LIB.BASEBOARD_FAB2(SCH_1):PAGE75
  DH73    GND @BASEBOARD_FAB2_LIB.BASEBOARD_FAB2(SCH_1):GND    I19 @BASEBOARD_FAB2_LIB.BASEBOARD_FAB2(SCH_1):PAGE75
  DH79    GND @BASEBOARD_FAB2_LIB.BASEBOARD_FAB2(SCH_1):GND    I19 @BASEBOARD_FAB2_LIB.BASEBOARD_FAB2(SCH_1):PAGE75
  DH81    GND @BASEBOARD_FAB2_LIB.BASEBOARD_FAB2(SCH_1):GND    I19 @BASEBOARD_FAB2_LIB.BASEBOARD_FAB2(SCH_1):PAGE75
  DH83    GND @BASEBOARD_FAB2_LIB.BASEBOARD_FAB2(SCH_1):GND    I19 @BASEBOARD_FAB2_LIB.BASEBOARD_FAB2(SCH_1):PAGE75
   DJ2    GND @BASEBOARD_FAB2_LIB.BASEBOARD_FAB2(SCH_1):GND    I19 @BASEBOARD_FAB2_LIB.BASEBOARD_FAB2(SCH_1):PAGE75
  DJ10    GND @BASEBOARD_FAB2_LIB.BASEBOARD_FAB2(SCH_1):GND    I19 @BASEBOARD_FAB2_LIB.BASEBOARD_FAB2(SCH_1):PAGE75
   H47    GND @BASEBOARD_FAB2_LIB.BASEBOARD_FAB2(SCH_1):GND    I19 @BASEBOARD_FAB2_LIB.BASEBOARD_FAB2(SCH_1):PAGE75
  DJ22    GND @BASEBOARD_FAB2_LIB.BASEBOARD_FAB2(SCH_1):GND    I19 @BASEBOARD_FAB2_LIB.BASEBOARD_FAB2(SCH_1):PAGE75
  DJ38    GND @BASEBOARD_FAB2_LIB.BASEBOARD_FAB2(SCH_1):GND    I19 @BASEBOARD_FAB2_LIB.BASEBOARD_FAB2(SCH_1):PAGE75
  DJ42    GND @BASEBOARD_FAB2_LIB.BASEBOARD_FAB2(SCH_1):GND    I19 @BASEBOARD_FAB2_LIB.BASEBOARD_FAB2(SCH_1):PAGE75
  DJ68    GND @BASEBOARD_FAB2_LIB.BASEBOARD_FAB2(SCH_1):GND    I19 @BASEBOARD_FAB2_LIB.BASEBOARD_FAB2(SCH_1):PAGE75
  DJ74    GND @BASEBOARD_FAB2_LIB.BASEBOARD_FAB2(SCH_1):GND    I19 @BASEBOARD_FAB2_LIB.BASEBOARD_FAB2(SCH_1):PAGE75
  DJ78    GND @BASEBOARD_FAB2_LIB.BASEBOARD_FAB2(SCH_1):GND    I19 @BASEBOARD_FAB2_LIB.BASEBOARD_FAB2(SCH_1):PAGE75
  DJ82    GND @BASEBOARD_FAB2_LIB.BASEBOARD_FAB2(SCH_1):GND    I19 @BASEBOARD_FAB2_LIB.BASEBOARD_FAB2(SCH_1):PAGE75
  DJ84    GND @BASEBOARD_FAB2_LIB.BASEBOARD_FAB2(SCH_1):GND    I19 @BASEBOARD_FAB2_LIB.BASEBOARD_FAB2(SCH_1):PAGE75
   DK7    GND @BASEBOARD_FAB2_LIB.BASEBOARD_FAB2(SCH_1):GND    I19 @BASEBOARD_FAB2_LIB.BASEBOARD_FAB2(SCH_1):PAGE75
  DK23    GND @BASEBOARD_FAB2_LIB.BASEBOARD_FAB2(SCH_1):GND    I19 @BASEBOARD_FAB2_LIB.BASEBOARD_FAB2(SCH_1):PAGE75
  DK29    GND @BASEBOARD_FAB2_LIB.BASEBOARD_FAB2(SCH_1):GND    I19 @BASEBOARD_FAB2_LIB.BASEBOARD_FAB2(SCH_1):PAGE75
  DK35    GND @BASEBOARD_FAB2_LIB.BASEBOARD_FAB2(SCH_1):GND    I19 @BASEBOARD_FAB2_LIB.BASEBOARD_FAB2(SCH_1):PAGE75
  DK39    GND @BASEBOARD_FAB2_LIB.BASEBOARD_FAB2(SCH_1):GND    I19 @BASEBOARD_FAB2_LIB.BASEBOARD_FAB2(SCH_1):PAGE75
  DK41    GND @BASEBOARD_FAB2_LIB.BASEBOARD_FAB2(SCH_1):GND    I19 @BASEBOARD_FAB2_LIB.BASEBOARD_FAB2(SCH_1):PAGE75
  DK73    GND @BASEBOARD_FAB2_LIB.BASEBOARD_FAB2(SCH_1):GND    I19 @BASEBOARD_FAB2_LIB.BASEBOARD_FAB2(SCH_1):PAGE75
  DK75    GND @BASEBOARD_FAB2_LIB.BASEBOARD_FAB2(SCH_1):GND    I19 @BASEBOARD_FAB2_LIB.BASEBOARD_FAB2(SCH_1):PAGE75
  DK77    GND @BASEBOARD_FAB2_LIB.BASEBOARD_FAB2(SCH_1):GND    I19 @BASEBOARD_FAB2_LIB.BASEBOARD_FAB2(SCH_1):PAGE75
  DK83    GND @BASEBOARD_FAB2_LIB.BASEBOARD_FAB2(SCH_1):GND    I19 @BASEBOARD_FAB2_LIB.BASEBOARD_FAB2(SCH_1):PAGE75
  DK85    GND @BASEBOARD_FAB2_LIB.BASEBOARD_FAB2(SCH_1):GND    I19 @BASEBOARD_FAB2_LIB.BASEBOARD_FAB2(SCH_1):PAGE75
  DL16    GND @BASEBOARD_FAB2_LIB.BASEBOARD_FAB2(SCH_1):GND    I19 @BASEBOARD_FAB2_LIB.BASEBOARD_FAB2(SCH_1):PAGE75
  DL18    GND @BASEBOARD_FAB2_LIB.BASEBOARD_FAB2(SCH_1):GND    I19 @BASEBOARD_FAB2_LIB.BASEBOARD_FAB2(SCH_1):PAGE75
   DL4    GND @BASEBOARD_FAB2_LIB.BASEBOARD_FAB2(SCH_1):GND    I19 @BASEBOARD_FAB2_LIB.BASEBOARD_FAB2(SCH_1):PAGE75
  DL22    GND @BASEBOARD_FAB2_LIB.BASEBOARD_FAB2(SCH_1):GND    I19 @BASEBOARD_FAB2_LIB.BASEBOARD_FAB2(SCH_1):PAGE75
  DL24    GND @BASEBOARD_FAB2_LIB.BASEBOARD_FAB2(SCH_1):GND    I19 @BASEBOARD_FAB2_LIB.BASEBOARD_FAB2(SCH_1):PAGE75
  DL28    GND @BASEBOARD_FAB2_LIB.BASEBOARD_FAB2(SCH_1):GND    I19 @BASEBOARD_FAB2_LIB.BASEBOARD_FAB2(SCH_1):PAGE75
  DL30    GND @BASEBOARD_FAB2_LIB.BASEBOARD_FAB2(SCH_1):GND    I19 @BASEBOARD_FAB2_LIB.BASEBOARD_FAB2(SCH_1):PAGE75
  DL34    GND @BASEBOARD_FAB2_LIB.BASEBOARD_FAB2(SCH_1):GND    I19 @BASEBOARD_FAB2_LIB.BASEBOARD_FAB2(SCH_1):PAGE75
  DL36    GND @BASEBOARD_FAB2_LIB.BASEBOARD_FAB2(SCH_1):GND    I19 @BASEBOARD_FAB2_LIB.BASEBOARD_FAB2(SCH_1):PAGE75
  DL40    GND @BASEBOARD_FAB2_LIB.BASEBOARD_FAB2(SCH_1):GND    I19 @BASEBOARD_FAB2_LIB.BASEBOARD_FAB2(SCH_1):PAGE75
  DL68    GND @BASEBOARD_FAB2_LIB.BASEBOARD_FAB2(SCH_1):GND    I19 @BASEBOARD_FAB2_LIB.BASEBOARD_FAB2(SCH_1):PAGE75
  DL70    GND @BASEBOARD_FAB2_LIB.BASEBOARD_FAB2(SCH_1):GND    I19 @BASEBOARD_FAB2_LIB.BASEBOARD_FAB2(SCH_1):PAGE75
  DL74    GND @BASEBOARD_FAB2_LIB.BASEBOARD_FAB2(SCH_1):GND    I19 @BASEBOARD_FAB2_LIB.BASEBOARD_FAB2(SCH_1):PAGE75
  DL76    GND @BASEBOARD_FAB2_LIB.BASEBOARD_FAB2(SCH_1):GND    I19 @BASEBOARD_FAB2_LIB.BASEBOARD_FAB2(SCH_1):PAGE75
  DL78    GND @BASEBOARD_FAB2_LIB.BASEBOARD_FAB2(SCH_1):GND    I19 @BASEBOARD_FAB2_LIB.BASEBOARD_FAB2(SCH_1):PAGE75
  DL80    GND @BASEBOARD_FAB2_LIB.BASEBOARD_FAB2(SCH_1):GND    I19 @BASEBOARD_FAB2_LIB.BASEBOARD_FAB2(SCH_1):PAGE75
  DM15    GND @BASEBOARD_FAB2_LIB.BASEBOARD_FAB2(SCH_1):GND    I19 @BASEBOARD_FAB2_LIB.BASEBOARD_FAB2(SCH_1):PAGE75
   H45    GND @BASEBOARD_FAB2_LIB.BASEBOARD_FAB2(SCH_1):GND    I19 @BASEBOARD_FAB2_LIB.BASEBOARD_FAB2(SCH_1):PAGE75
  DM25    GND @BASEBOARD_FAB2_LIB.BASEBOARD_FAB2(SCH_1):GND    I19 @BASEBOARD_FAB2_LIB.BASEBOARD_FAB2(SCH_1):PAGE75
  DM27    GND @BASEBOARD_FAB2_LIB.BASEBOARD_FAB2(SCH_1):GND    I19 @BASEBOARD_FAB2_LIB.BASEBOARD_FAB2(SCH_1):PAGE75
  DM31    GND @BASEBOARD_FAB2_LIB.BASEBOARD_FAB2(SCH_1):GND    I19 @BASEBOARD_FAB2_LIB.BASEBOARD_FAB2(SCH_1):PAGE75
  DM33    GND @BASEBOARD_FAB2_LIB.BASEBOARD_FAB2(SCH_1):GND    I19 @BASEBOARD_FAB2_LIB.BASEBOARD_FAB2(SCH_1):PAGE75
  DM37    GND @BASEBOARD_FAB2_LIB.BASEBOARD_FAB2(SCH_1):GND    I19 @BASEBOARD_FAB2_LIB.BASEBOARD_FAB2(SCH_1):PAGE75
  DM39    GND @BASEBOARD_FAB2_LIB.BASEBOARD_FAB2(SCH_1):GND    I19 @BASEBOARD_FAB2_LIB.BASEBOARD_FAB2(SCH_1):PAGE75
  DM65    GND @BASEBOARD_FAB2_LIB.BASEBOARD_FAB2(SCH_1):GND    I19 @BASEBOARD_FAB2_LIB.BASEBOARD_FAB2(SCH_1):PAGE75
  DM73    GND @BASEBOARD_FAB2_LIB.BASEBOARD_FAB2(SCH_1):GND    I19 @BASEBOARD_FAB2_LIB.BASEBOARD_FAB2(SCH_1):PAGE75
  DM77    GND @BASEBOARD_FAB2_LIB.BASEBOARD_FAB2(SCH_1):GND    I19 @BASEBOARD_FAB2_LIB.BASEBOARD_FAB2(SCH_1):PAGE75
  DM83    GND @BASEBOARD_FAB2_LIB.BASEBOARD_FAB2(SCH_1):GND    I19 @BASEBOARD_FAB2_LIB.BASEBOARD_FAB2(SCH_1):PAGE75
   DN2    GND @BASEBOARD_FAB2_LIB.BASEBOARD_FAB2(SCH_1):GND    I19 @BASEBOARD_FAB2_LIB.BASEBOARD_FAB2(SCH_1):PAGE75
  BH17    GND @BASEBOARD_FAB2_LIB.BASEBOARD_FAB2(SCH_1):GND    I19 @BASEBOARD_FAB2_LIB.BASEBOARD_FAB2(SCH_1):PAGE75
  DN12    GND @BASEBOARD_FAB2_LIB.BASEBOARD_FAB2(SCH_1):GND    I19 @BASEBOARD_FAB2_LIB.BASEBOARD_FAB2(SCH_1):PAGE75
  DN22    GND @BASEBOARD_FAB2_LIB.BASEBOARD_FAB2(SCH_1):GND    I19 @BASEBOARD_FAB2_LIB.BASEBOARD_FAB2(SCH_1):PAGE75
  DN26    GND @BASEBOARD_FAB2_LIB.BASEBOARD_FAB2(SCH_1):GND    I19 @BASEBOARD_FAB2_LIB.BASEBOARD_FAB2(SCH_1):PAGE75
  DN32    GND @BASEBOARD_FAB2_LIB.BASEBOARD_FAB2(SCH_1):GND    I19 @BASEBOARD_FAB2_LIB.BASEBOARD_FAB2(SCH_1):PAGE75
  DN38    GND @BASEBOARD_FAB2_LIB.BASEBOARD_FAB2(SCH_1):GND    I19 @BASEBOARD_FAB2_LIB.BASEBOARD_FAB2(SCH_1):PAGE75
  DN68    GND @BASEBOARD_FAB2_LIB.BASEBOARD_FAB2(SCH_1):GND    I19 @BASEBOARD_FAB2_LIB.BASEBOARD_FAB2(SCH_1):PAGE75
  DN72    GND @BASEBOARD_FAB2_LIB.BASEBOARD_FAB2(SCH_1):GND    I19 @BASEBOARD_FAB2_LIB.BASEBOARD_FAB2(SCH_1):PAGE75
  DN78    GND @BASEBOARD_FAB2_LIB.BASEBOARD_FAB2(SCH_1):GND    I20 @BASEBOARD_FAB2_LIB.BASEBOARD_FAB2(SCH_1):PAGE75
  DP67    GND @BASEBOARD_FAB2_LIB.BASEBOARD_FAB2(SCH_1):GND    I20 @BASEBOARD_FAB2_LIB.BASEBOARD_FAB2(SCH_1):PAGE75
  DP69    GND @BASEBOARD_FAB2_LIB.BASEBOARD_FAB2(SCH_1):GND    I20 @BASEBOARD_FAB2_LIB.BASEBOARD_FAB2(SCH_1):PAGE75
  DP71    GND @BASEBOARD_FAB2_LIB.BASEBOARD_FAB2(SCH_1):GND    I20 @BASEBOARD_FAB2_LIB.BASEBOARD_FAB2(SCH_1):PAGE75
  DP81    GND @BASEBOARD_FAB2_LIB.BASEBOARD_FAB2(SCH_1):GND    I20 @BASEBOARD_FAB2_LIB.BASEBOARD_FAB2(SCH_1):PAGE75
  DP83    GND @BASEBOARD_FAB2_LIB.BASEBOARD_FAB2(SCH_1):GND    I20 @BASEBOARD_FAB2_LIB.BASEBOARD_FAB2(SCH_1):PAGE75
  BR26    GND @BASEBOARD_FAB2_LIB.BASEBOARD_FAB2(SCH_1):GND    I20 @BASEBOARD_FAB2_LIB.BASEBOARD_FAB2(SCH_1):PAGE75
   DR6    GND @BASEBOARD_FAB2_LIB.BASEBOARD_FAB2(SCH_1):GND    I20 @BASEBOARD_FAB2_LIB.BASEBOARD_FAB2(SCH_1):PAGE75
  CA20    GND @BASEBOARD_FAB2_LIB.BASEBOARD_FAB2(SCH_1):GND    I20 @BASEBOARD_FAB2_LIB.BASEBOARD_FAB2(SCH_1):PAGE75
  CL22    GND @BASEBOARD_FAB2_LIB.BASEBOARD_FAB2(SCH_1):GND    I20 @BASEBOARD_FAB2_LIB.BASEBOARD_FAB2(SCH_1):PAGE75
  DR20    GND @BASEBOARD_FAB2_LIB.BASEBOARD_FAB2(SCH_1):GND    I20 @BASEBOARD_FAB2_LIB.BASEBOARD_FAB2(SCH_1):PAGE75
  DR22    GND @BASEBOARD_FAB2_LIB.BASEBOARD_FAB2(SCH_1):GND    I20 @BASEBOARD_FAB2_LIB.BASEBOARD_FAB2(SCH_1):PAGE75
  DR24    GND @BASEBOARD_FAB2_LIB.BASEBOARD_FAB2(SCH_1):GND    I20 @BASEBOARD_FAB2_LIB.BASEBOARD_FAB2(SCH_1):PAGE75
  DR26    GND @BASEBOARD_FAB2_LIB.BASEBOARD_FAB2(SCH_1):GND    I20 @BASEBOARD_FAB2_LIB.BASEBOARD_FAB2(SCH_1):PAGE75
  DR28    GND @BASEBOARD_FAB2_LIB.BASEBOARD_FAB2(SCH_1):GND    I20 @BASEBOARD_FAB2_LIB.BASEBOARD_FAB2(SCH_1):PAGE75
  DR30    GND @BASEBOARD_FAB2_LIB.BASEBOARD_FAB2(SCH_1):GND    I20 @BASEBOARD_FAB2_LIB.BASEBOARD_FAB2(SCH_1):PAGE75
  DR32    GND @BASEBOARD_FAB2_LIB.BASEBOARD_FAB2(SCH_1):GND    I20 @BASEBOARD_FAB2_LIB.BASEBOARD_FAB2(SCH_1):PAGE75
  DR34    GND @BASEBOARD_FAB2_LIB.BASEBOARD_FAB2(SCH_1):GND    I20 @BASEBOARD_FAB2_LIB.BASEBOARD_FAB2(SCH_1):PAGE75
  DR36    GND @BASEBOARD_FAB2_LIB.BASEBOARD_FAB2(SCH_1):GND    I20 @BASEBOARD_FAB2_LIB.BASEBOARD_FAB2(SCH_1):PAGE75
  DR38    GND @BASEBOARD_FAB2_LIB.BASEBOARD_FAB2(SCH_1):GND    I20 @BASEBOARD_FAB2_LIB.BASEBOARD_FAB2(SCH_1):PAGE75
  DR40    GND @BASEBOARD_FAB2_LIB.BASEBOARD_FAB2(SCH_1):GND    I20 @BASEBOARD_FAB2_LIB.BASEBOARD_FAB2(SCH_1):PAGE75
  DR42    GND @BASEBOARD_FAB2_LIB.BASEBOARD_FAB2(SCH_1):GND    I20 @BASEBOARD_FAB2_LIB.BASEBOARD_FAB2(SCH_1):PAGE75
  DR66    GND @BASEBOARD_FAB2_LIB.BASEBOARD_FAB2(SCH_1):GND    I20 @BASEBOARD_FAB2_LIB.BASEBOARD_FAB2(SCH_1):PAGE75
  DR68    GND @BASEBOARD_FAB2_LIB.BASEBOARD_FAB2(SCH_1):GND    I20 @BASEBOARD_FAB2_LIB.BASEBOARD_FAB2(SCH_1):PAGE75
  DR70    GND @BASEBOARD_FAB2_LIB.BASEBOARD_FAB2(SCH_1):GND    I20 @BASEBOARD_FAB2_LIB.BASEBOARD_FAB2(SCH_1):PAGE75
  DR72    GND @BASEBOARD_FAB2_LIB.BASEBOARD_FAB2(SCH_1):GND    I20 @BASEBOARD_FAB2_LIB.BASEBOARD_FAB2(SCH_1):PAGE75
  DR74    GND @BASEBOARD_FAB2_LIB.BASEBOARD_FAB2(SCH_1):GND    I20 @BASEBOARD_FAB2_LIB.BASEBOARD_FAB2(SCH_1):PAGE75
  DR76    GND @BASEBOARD_FAB2_LIB.BASEBOARD_FAB2(SCH_1):GND    I20 @BASEBOARD_FAB2_LIB.BASEBOARD_FAB2(SCH_1):PAGE75
  DR78    GND @BASEBOARD_FAB2_LIB.BASEBOARD_FAB2(SCH_1):GND    I20 @BASEBOARD_FAB2_LIB.BASEBOARD_FAB2(SCH_1):PAGE75
   DT3    GND @BASEBOARD_FAB2_LIB.BASEBOARD_FAB2(SCH_1):GND    I20 @BASEBOARD_FAB2_LIB.BASEBOARD_FAB2(SCH_1):PAGE75
  DT17    GND @BASEBOARD_FAB2_LIB.BASEBOARD_FAB2(SCH_1):GND    I20 @BASEBOARD_FAB2_LIB.BASEBOARD_FAB2(SCH_1):PAGE75
  DH21    GND @BASEBOARD_FAB2_LIB.BASEBOARD_FAB2(SCH_1):GND    I20 @BASEBOARD_FAB2_LIB.BASEBOARD_FAB2(SCH_1):PAGE75
  DT65    GND @BASEBOARD_FAB2_LIB.BASEBOARD_FAB2(SCH_1):GND    I20 @BASEBOARD_FAB2_LIB.BASEBOARD_FAB2(SCH_1):PAGE75
  DT69    GND @BASEBOARD_FAB2_LIB.BASEBOARD_FAB2(SCH_1):GND    I20 @BASEBOARD_FAB2_LIB.BASEBOARD_FAB2(SCH_1):PAGE75
  DT79    GND @BASEBOARD_FAB2_LIB.BASEBOARD_FAB2(SCH_1):GND    I20 @BASEBOARD_FAB2_LIB.BASEBOARD_FAB2(SCH_1):PAGE75
  DT83    GND @BASEBOARD_FAB2_LIB.BASEBOARD_FAB2(SCH_1):GND    I20 @BASEBOARD_FAB2_LIB.BASEBOARD_FAB2(SCH_1):PAGE75
  DT85    GND @BASEBOARD_FAB2_LIB.BASEBOARD_FAB2(SCH_1):GND    I20 @BASEBOARD_FAB2_LIB.BASEBOARD_FAB2(SCH_1):PAGE75
  DU10    GND @BASEBOARD_FAB2_LIB.BASEBOARD_FAB2(SCH_1):GND    I20 @BASEBOARD_FAB2_LIB.BASEBOARD_FAB2(SCH_1):PAGE75
  DU14    GND @BASEBOARD_FAB2_LIB.BASEBOARD_FAB2(SCH_1):GND    I20 @BASEBOARD_FAB2_LIB.BASEBOARD_FAB2(SCH_1):PAGE75
  CN14    GND @BASEBOARD_FAB2_LIB.BASEBOARD_FAB2(SCH_1):GND    I20 @BASEBOARD_FAB2_LIB.BASEBOARD_FAB2(SCH_1):PAGE75
  DU22    GND @BASEBOARD_FAB2_LIB.BASEBOARD_FAB2(SCH_1):GND    I20 @BASEBOARD_FAB2_LIB.BASEBOARD_FAB2(SCH_1):PAGE75
  DU26    GND @BASEBOARD_FAB2_LIB.BASEBOARD_FAB2(SCH_1):GND    I20 @BASEBOARD_FAB2_LIB.BASEBOARD_FAB2(SCH_1):PAGE75
  DU32    GND @BASEBOARD_FAB2_LIB.BASEBOARD_FAB2(SCH_1):GND    I20 @BASEBOARD_FAB2_LIB.BASEBOARD_FAB2(SCH_1):PAGE75
  DU38    GND @BASEBOARD_FAB2_LIB.BASEBOARD_FAB2(SCH_1):GND    I20 @BASEBOARD_FAB2_LIB.BASEBOARD_FAB2(SCH_1):PAGE75
  DU70    GND @BASEBOARD_FAB2_LIB.BASEBOARD_FAB2(SCH_1):GND    I20 @BASEBOARD_FAB2_LIB.BASEBOARD_FAB2(SCH_1):PAGE75
  DU72    GND @BASEBOARD_FAB2_LIB.BASEBOARD_FAB2(SCH_1):GND    I20 @BASEBOARD_FAB2_LIB.BASEBOARD_FAB2(SCH_1):PAGE75
  DU78    GND @BASEBOARD_FAB2_LIB.BASEBOARD_FAB2(SCH_1):GND    I20 @BASEBOARD_FAB2_LIB.BASEBOARD_FAB2(SCH_1):PAGE75
  DU80    GND @BASEBOARD_FAB2_LIB.BASEBOARD_FAB2(SCH_1):GND    I20 @BASEBOARD_FAB2_LIB.BASEBOARD_FAB2(SCH_1):PAGE75
  DU82    GND @BASEBOARD_FAB2_LIB.BASEBOARD_FAB2(SCH_1):GND    I20 @BASEBOARD_FAB2_LIB.BASEBOARD_FAB2(SCH_1):PAGE75
  DU84    GND @BASEBOARD_FAB2_LIB.BASEBOARD_FAB2(SCH_1):GND    I20 @BASEBOARD_FAB2_LIB.BASEBOARD_FAB2(SCH_1):PAGE75
  DV21    GND @BASEBOARD_FAB2_LIB.BASEBOARD_FAB2(SCH_1):GND    I20 @BASEBOARD_FAB2_LIB.BASEBOARD_FAB2(SCH_1):PAGE75
  DV25    GND @BASEBOARD_FAB2_LIB.BASEBOARD_FAB2(SCH_1):GND    I20 @BASEBOARD_FAB2_LIB.BASEBOARD_FAB2(SCH_1):PAGE75
  DV27    GND @BASEBOARD_FAB2_LIB.BASEBOARD_FAB2(SCH_1):GND    I20 @BASEBOARD_FAB2_LIB.BASEBOARD_FAB2(SCH_1):PAGE75
  DV31    GND @BASEBOARD_FAB2_LIB.BASEBOARD_FAB2(SCH_1):GND    I20 @BASEBOARD_FAB2_LIB.BASEBOARD_FAB2(SCH_1):PAGE75
  DV33    GND @BASEBOARD_FAB2_LIB.BASEBOARD_FAB2(SCH_1):GND    I20 @BASEBOARD_FAB2_LIB.BASEBOARD_FAB2(SCH_1):PAGE75
  DV37    GND @BASEBOARD_FAB2_LIB.BASEBOARD_FAB2(SCH_1):GND    I20 @BASEBOARD_FAB2_LIB.BASEBOARD_FAB2(SCH_1):PAGE75
  DV39    GND @BASEBOARD_FAB2_LIB.BASEBOARD_FAB2(SCH_1):GND    I20 @BASEBOARD_FAB2_LIB.BASEBOARD_FAB2(SCH_1):PAGE75
  DV73    GND @BASEBOARD_FAB2_LIB.BASEBOARD_FAB2(SCH_1):GND    I20 @BASEBOARD_FAB2_LIB.BASEBOARD_FAB2(SCH_1):PAGE75
  DV77    GND @BASEBOARD_FAB2_LIB.BASEBOARD_FAB2(SCH_1):GND    I20 @BASEBOARD_FAB2_LIB.BASEBOARD_FAB2(SCH_1):PAGE75
  DV81    GND @BASEBOARD_FAB2_LIB.BASEBOARD_FAB2(SCH_1):GND    I20 @BASEBOARD_FAB2_LIB.BASEBOARD_FAB2(SCH_1):PAGE75
  DW12    GND @BASEBOARD_FAB2_LIB.BASEBOARD_FAB2(SCH_1):GND    I20 @BASEBOARD_FAB2_LIB.BASEBOARD_FAB2(SCH_1):PAGE75
  DW20    GND @BASEBOARD_FAB2_LIB.BASEBOARD_FAB2(SCH_1):GND    I20 @BASEBOARD_FAB2_LIB.BASEBOARD_FAB2(SCH_1):PAGE75
  DW24    GND @BASEBOARD_FAB2_LIB.BASEBOARD_FAB2(SCH_1):GND    I20 @BASEBOARD_FAB2_LIB.BASEBOARD_FAB2(SCH_1):PAGE75
  DW28    GND @BASEBOARD_FAB2_LIB.BASEBOARD_FAB2(SCH_1):GND    I20 @BASEBOARD_FAB2_LIB.BASEBOARD_FAB2(SCH_1):PAGE75
  DW30    GND @BASEBOARD_FAB2_LIB.BASEBOARD_FAB2(SCH_1):GND    I20 @BASEBOARD_FAB2_LIB.BASEBOARD_FAB2(SCH_1):PAGE75
  DW34    GND @BASEBOARD_FAB2_LIB.BASEBOARD_FAB2(SCH_1):GND    I20 @BASEBOARD_FAB2_LIB.BASEBOARD_FAB2(SCH_1):PAGE75
  DW36    GND @BASEBOARD_FAB2_LIB.BASEBOARD_FAB2(SCH_1):GND    I20 @BASEBOARD_FAB2_LIB.BASEBOARD_FAB2(SCH_1):PAGE75
  DW40    GND @BASEBOARD_FAB2_LIB.BASEBOARD_FAB2(SCH_1):GND    I20 @BASEBOARD_FAB2_LIB.BASEBOARD_FAB2(SCH_1):PAGE75
  DW64    GND @BASEBOARD_FAB2_LIB.BASEBOARD_FAB2(SCH_1):GND    I20 @BASEBOARD_FAB2_LIB.BASEBOARD_FAB2(SCH_1):PAGE75
  DW66    GND @BASEBOARD_FAB2_LIB.BASEBOARD_FAB2(SCH_1):GND    I20 @BASEBOARD_FAB2_LIB.BASEBOARD_FAB2(SCH_1):PAGE75
  DW68    GND @BASEBOARD_FAB2_LIB.BASEBOARD_FAB2(SCH_1):GND    I20 @BASEBOARD_FAB2_LIB.BASEBOARD_FAB2(SCH_1):PAGE75
  DW70    GND @BASEBOARD_FAB2_LIB.BASEBOARD_FAB2(SCH_1):GND    I20 @BASEBOARD_FAB2_LIB.BASEBOARD_FAB2(SCH_1):PAGE75
  DW72    GND @BASEBOARD_FAB2_LIB.BASEBOARD_FAB2(SCH_1):GND    I20 @BASEBOARD_FAB2_LIB.BASEBOARD_FAB2(SCH_1):PAGE75
  DW74    GND @BASEBOARD_FAB2_LIB.BASEBOARD_FAB2(SCH_1):GND    I20 @BASEBOARD_FAB2_LIB.BASEBOARD_FAB2(SCH_1):PAGE75
  DW76    GND @BASEBOARD_FAB2_LIB.BASEBOARD_FAB2(SCH_1):GND    I20 @BASEBOARD_FAB2_LIB.BASEBOARD_FAB2(SCH_1):PAGE75
   DW8    GND @BASEBOARD_FAB2_LIB.BASEBOARD_FAB2(SCH_1):GND    I20 @BASEBOARD_FAB2_LIB.BASEBOARD_FAB2(SCH_1):PAGE75
  DW82    GND @BASEBOARD_FAB2_LIB.BASEBOARD_FAB2(SCH_1):GND    I20 @BASEBOARD_FAB2_LIB.BASEBOARD_FAB2(SCH_1):PAGE75
  DW84    GND @BASEBOARD_FAB2_LIB.BASEBOARD_FAB2(SCH_1):GND    I20 @BASEBOARD_FAB2_LIB.BASEBOARD_FAB2(SCH_1):PAGE75
   DY5    GND @BASEBOARD_FAB2_LIB.BASEBOARD_FAB2(SCH_1):GND    I20 @BASEBOARD_FAB2_LIB.BASEBOARD_FAB2(SCH_1):PAGE75
  DY19    GND @BASEBOARD_FAB2_LIB.BASEBOARD_FAB2(SCH_1):GND    I20 @BASEBOARD_FAB2_LIB.BASEBOARD_FAB2(SCH_1):PAGE75
  DY23    GND @BASEBOARD_FAB2_LIB.BASEBOARD_FAB2(SCH_1):GND    I20 @BASEBOARD_FAB2_LIB.BASEBOARD_FAB2(SCH_1):PAGE75
  DY29    GND @BASEBOARD_FAB2_LIB.BASEBOARD_FAB2(SCH_1):GND    I20 @BASEBOARD_FAB2_LIB.BASEBOARD_FAB2(SCH_1):PAGE75
  DY35    GND @BASEBOARD_FAB2_LIB.BASEBOARD_FAB2(SCH_1):GND    I20 @BASEBOARD_FAB2_LIB.BASEBOARD_FAB2(SCH_1):PAGE75
  DY41    GND @BASEBOARD_FAB2_LIB.BASEBOARD_FAB2(SCH_1):GND    I20 @BASEBOARD_FAB2_LIB.BASEBOARD_FAB2(SCH_1):PAGE75
  DY71    GND @BASEBOARD_FAB2_LIB.BASEBOARD_FAB2(SCH_1):GND    I20 @BASEBOARD_FAB2_LIB.BASEBOARD_FAB2(SCH_1):PAGE75
  DY75    GND @BASEBOARD_FAB2_LIB.BASEBOARD_FAB2(SCH_1):GND    I20 @BASEBOARD_FAB2_LIB.BASEBOARD_FAB2(SCH_1):PAGE75
   EA6    GND @BASEBOARD_FAB2_LIB.BASEBOARD_FAB2(SCH_1):GND    I20 @BASEBOARD_FAB2_LIB.BASEBOARD_FAB2(SCH_1):PAGE75
   J16    GND @BASEBOARD_FAB2_LIB.BASEBOARD_FAB2(SCH_1):GND    I20 @BASEBOARD_FAB2_LIB.BASEBOARD_FAB2(SCH_1):PAGE75
  EA16    GND @BASEBOARD_FAB2_LIB.BASEBOARD_FAB2(SCH_1):GND    I20 @BASEBOARD_FAB2_LIB.BASEBOARD_FAB2(SCH_1):PAGE75
  EA20    GND @BASEBOARD_FAB2_LIB.BASEBOARD_FAB2(SCH_1):GND    I20 @BASEBOARD_FAB2_LIB.BASEBOARD_FAB2(SCH_1):PAGE75
  EA22    GND @BASEBOARD_FAB2_LIB.BASEBOARD_FAB2(SCH_1):GND    I20 @BASEBOARD_FAB2_LIB.BASEBOARD_FAB2(SCH_1):PAGE75
  EA42    GND @BASEBOARD_FAB2_LIB.BASEBOARD_FAB2(SCH_1):GND    I20 @BASEBOARD_FAB2_LIB.BASEBOARD_FAB2(SCH_1):PAGE75
  EA64    GND @BASEBOARD_FAB2_LIB.BASEBOARD_FAB2(SCH_1):GND    I20 @BASEBOARD_FAB2_LIB.BASEBOARD_FAB2(SCH_1):PAGE75
  EA70    GND @BASEBOARD_FAB2_LIB.BASEBOARD_FAB2(SCH_1):GND    I20 @BASEBOARD_FAB2_LIB.BASEBOARD_FAB2(SCH_1):PAGE75
  EA76    GND @BASEBOARD_FAB2_LIB.BASEBOARD_FAB2(SCH_1):GND    I20 @BASEBOARD_FAB2_LIB.BASEBOARD_FAB2(SCH_1):PAGE75
  EA78    GND @BASEBOARD_FAB2_LIB.BASEBOARD_FAB2(SCH_1):GND    I20 @BASEBOARD_FAB2_LIB.BASEBOARD_FAB2(SCH_1):PAGE75
  EA80    GND @BASEBOARD_FAB2_LIB.BASEBOARD_FAB2(SCH_1):GND    I20 @BASEBOARD_FAB2_LIB.BASEBOARD_FAB2(SCH_1):PAGE75
  EA82    GND @BASEBOARD_FAB2_LIB.BASEBOARD_FAB2(SCH_1):GND    I20 @BASEBOARD_FAB2_LIB.BASEBOARD_FAB2(SCH_1):PAGE75
  EB13    GND @BASEBOARD_FAB2_LIB.BASEBOARD_FAB2(SCH_1):GND    I20 @BASEBOARD_FAB2_LIB.BASEBOARD_FAB2(SCH_1):PAGE75
  BR18    GND @BASEBOARD_FAB2_LIB.BASEBOARD_FAB2(SCH_1):GND    I20 @BASEBOARD_FAB2_LIB.BASEBOARD_FAB2(SCH_1):PAGE75
  EB23    GND @BASEBOARD_FAB2_LIB.BASEBOARD_FAB2(SCH_1):GND    I20 @BASEBOARD_FAB2_LIB.BASEBOARD_FAB2(SCH_1):PAGE75
  EB25    GND @BASEBOARD_FAB2_LIB.BASEBOARD_FAB2(SCH_1):GND    I20 @BASEBOARD_FAB2_LIB.BASEBOARD_FAB2(SCH_1):PAGE75
  EB27    GND @BASEBOARD_FAB2_LIB.BASEBOARD_FAB2(SCH_1):GND    I20 @BASEBOARD_FAB2_LIB.BASEBOARD_FAB2(SCH_1):PAGE75
  EB29    GND @BASEBOARD_FAB2_LIB.BASEBOARD_FAB2(SCH_1):GND    I20 @BASEBOARD_FAB2_LIB.BASEBOARD_FAB2(SCH_1):PAGE75
  EB31    GND @BASEBOARD_FAB2_LIB.BASEBOARD_FAB2(SCH_1):GND    I20 @BASEBOARD_FAB2_LIB.BASEBOARD_FAB2(SCH_1):PAGE75
  EB33    GND @BASEBOARD_FAB2_LIB.BASEBOARD_FAB2(SCH_1):GND    I20 @BASEBOARD_FAB2_LIB.BASEBOARD_FAB2(SCH_1):PAGE75
  EB35    GND @BASEBOARD_FAB2_LIB.BASEBOARD_FAB2(SCH_1):GND    I20 @BASEBOARD_FAB2_LIB.BASEBOARD_FAB2(SCH_1):PAGE75
  EB37    GND @BASEBOARD_FAB2_LIB.BASEBOARD_FAB2(SCH_1):GND    I20 @BASEBOARD_FAB2_LIB.BASEBOARD_FAB2(SCH_1):PAGE75
  EB39    GND @BASEBOARD_FAB2_LIB.BASEBOARD_FAB2(SCH_1):GND    I20 @BASEBOARD_FAB2_LIB.BASEBOARD_FAB2(SCH_1):PAGE75
  EB41    GND @BASEBOARD_FAB2_LIB.BASEBOARD_FAB2(SCH_1):GND    I20 @BASEBOARD_FAB2_LIB.BASEBOARD_FAB2(SCH_1):PAGE75
  EB65    GND @BASEBOARD_FAB2_LIB.BASEBOARD_FAB2(SCH_1):GND    I20 @BASEBOARD_FAB2_LIB.BASEBOARD_FAB2(SCH_1):PAGE75
  EB69    GND @BASEBOARD_FAB2_LIB.BASEBOARD_FAB2(SCH_1):GND    I20 @BASEBOARD_FAB2_LIB.BASEBOARD_FAB2(SCH_1):PAGE75
  EC10    GND @BASEBOARD_FAB2_LIB.BASEBOARD_FAB2(SCH_1):GND    I20 @BASEBOARD_FAB2_LIB.BASEBOARD_FAB2(SCH_1):PAGE75
  EC70    GND @BASEBOARD_FAB2_LIB.BASEBOARD_FAB2(SCH_1):GND    I20 @BASEBOARD_FAB2_LIB.BASEBOARD_FAB2(SCH_1):PAGE75
  EC72    GND @BASEBOARD_FAB2_LIB.BASEBOARD_FAB2(SCH_1):GND    I20 @BASEBOARD_FAB2_LIB.BASEBOARD_FAB2(SCH_1):PAGE75
  EC74    GND @BASEBOARD_FAB2_LIB.BASEBOARD_FAB2(SCH_1):GND    I20 @BASEBOARD_FAB2_LIB.BASEBOARD_FAB2(SCH_1):PAGE75
  EC76    GND @BASEBOARD_FAB2_LIB.BASEBOARD_FAB2(SCH_1):GND    I20 @BASEBOARD_FAB2_LIB.BASEBOARD_FAB2(SCH_1):PAGE75
  ED11    GND @BASEBOARD_FAB2_LIB.BASEBOARD_FAB2(SCH_1):GND    I20 @BASEBOARD_FAB2_LIB.BASEBOARD_FAB2(SCH_1):PAGE75
  ED15    GND @BASEBOARD_FAB2_LIB.BASEBOARD_FAB2(SCH_1):GND    I20 @BASEBOARD_FAB2_LIB.BASEBOARD_FAB2(SCH_1):PAGE75
  ED23    GND @BASEBOARD_FAB2_LIB.BASEBOARD_FAB2(SCH_1):GND    I20 @BASEBOARD_FAB2_LIB.BASEBOARD_FAB2(SCH_1):PAGE75
  ED29    GND @BASEBOARD_FAB2_LIB.BASEBOARD_FAB2(SCH_1):GND    I20 @BASEBOARD_FAB2_LIB.BASEBOARD_FAB2(SCH_1):PAGE75
  ED35    GND @BASEBOARD_FAB2_LIB.BASEBOARD_FAB2(SCH_1):GND    I20 @BASEBOARD_FAB2_LIB.BASEBOARD_FAB2(SCH_1):PAGE75
  ED77    GND @BASEBOARD_FAB2_LIB.BASEBOARD_FAB2(SCH_1):GND    I20 @BASEBOARD_FAB2_LIB.BASEBOARD_FAB2(SCH_1):PAGE75
  EE24    GND @BASEBOARD_FAB2_LIB.BASEBOARD_FAB2(SCH_1):GND    I20 @BASEBOARD_FAB2_LIB.BASEBOARD_FAB2(SCH_1):PAGE75
  EE28    GND @BASEBOARD_FAB2_LIB.BASEBOARD_FAB2(SCH_1):GND    I20 @BASEBOARD_FAB2_LIB.BASEBOARD_FAB2(SCH_1):PAGE75
  EE30    GND @BASEBOARD_FAB2_LIB.BASEBOARD_FAB2(SCH_1):GND    I20 @BASEBOARD_FAB2_LIB.BASEBOARD_FAB2(SCH_1):PAGE75
  EE34    GND @BASEBOARD_FAB2_LIB.BASEBOARD_FAB2(SCH_1):GND    I20 @BASEBOARD_FAB2_LIB.BASEBOARD_FAB2(SCH_1):PAGE75
  EE36    GND @BASEBOARD_FAB2_LIB.BASEBOARD_FAB2(SCH_1):GND    I20 @BASEBOARD_FAB2_LIB.BASEBOARD_FAB2(SCH_1):PAGE75
  EE70    GND @BASEBOARD_FAB2_LIB.BASEBOARD_FAB2(SCH_1):GND    I20 @BASEBOARD_FAB2_LIB.BASEBOARD_FAB2(SCH_1):PAGE75
  EE76    GND @BASEBOARD_FAB2_LIB.BASEBOARD_FAB2(SCH_1):GND    I20 @BASEBOARD_FAB2_LIB.BASEBOARD_FAB2(SCH_1):PAGE75
  EE78    GND @BASEBOARD_FAB2_LIB.BASEBOARD_FAB2(SCH_1):GND    I20 @BASEBOARD_FAB2_LIB.BASEBOARD_FAB2(SCH_1):PAGE75
  EF71    GND @BASEBOARD_FAB2_LIB.BASEBOARD_FAB2(SCH_1):GND    I20 @BASEBOARD_FAB2_LIB.BASEBOARD_FAB2(SCH_1):PAGE75
  EF75    GND @BASEBOARD_FAB2_LIB.BASEBOARD_FAB2(SCH_1):GND    I20 @BASEBOARD_FAB2_LIB.BASEBOARD_FAB2(SCH_1):PAGE75
  EF79    GND @BASEBOARD_FAB2_LIB.BASEBOARD_FAB2(SCH_1):GND    I20 @BASEBOARD_FAB2_LIB.BASEBOARD_FAB2(SCH_1):PAGE75

U2M1 NC7SB3157_SMLF-IC,C99406-001
     6 FM_CPU0_CD_PRES @BASEBOARD_FAB2_LIB.BASEBOARD_FAB2(SCH_1):FM_CPU0_CD_PRES   I255 @BASEBOARD_FAB2_LIB.BASEBOARD_FAB2(SCH_1):PAGE113
     3 JTAG_MCP_CPU1_TDI @BASEBOARD_FAB2_LIB.BASEBOARD_FAB2(SCH_1):JTAG_MCP_CPU1_TDI   I255 @BASEBOARD_FAB2_LIB.BASEBOARD_FAB2(SCH_1):PAGE113
     1 JTAG_MCP_CPU0_TDI @BASEBOARD_FAB2_LIB.BASEBOARD_FAB2(SCH_1):JTAG_MCP_CPU0_TDI   I255 @BASEBOARD_FAB2_LIB.BASEBOARD_FAB2(SCH_1):PAGE113
     4 JTAG_MCP_MUX_TDI @BASEBOARD_FAB2_LIB.BASEBOARD_FAB2(SCH_1):JTAG_MCP_MUX_TDI   I255 @BASEBOARD_FAB2_LIB.BASEBOARD_FAB2(SCH_1):PAGE113
     5 P3V3_STBY @BASEBOARD_FAB2_LIB.BASEBOARD_FAB2(SCH_1):P3V3_STBY   I255 @BASEBOARD_FAB2_LIB.BASEBOARD_FAB2(SCH_1):PAGE113
     2    GND @BASEBOARD_FAB2_LIB.BASEBOARD_FAB2(SCH_1):GND   I255 @BASEBOARD_FAB2_LIB.BASEBOARD_FAB2(SCH_1):PAGE113

U2P1 TTL1G07_A_SOP-74LVC1G07,IC,C88B
     2 FM_M2_SSD_PEDET @BASEBOARD_FAB2_LIB.BASEBOARD_FAB2(SCH_1):FM_M2_SSD_PEDET   I110 @BASEBOARD_FAB2_LIB.BASEBOARD_FAB2(SCH_1):PAGE185
     4 FM_M2_DET_LVC3 @BASEBOARD_FAB2_LIB.BASEBOARD_FAB2(SCH_1):FM_M2_DET_LVC3   I110 @BASEBOARD_FAB2_LIB.BASEBOARD_FAB2(SCH_1):PAGE185

U2R1 TTL2G14_SMLF-74LVC2G14,IC,D184B
     1 FP_NMI_BTN @BASEBOARD_FAB2_LIB.BASEBOARD_FAB2(SCH_1):FP_NMI_BTN   I357 @BASEBOARD_FAB2_LIB.BASEBOARD_FAB2(SCH_1):PAGE157
     6 FP_NMI_BTN_R_N @BASEBOARD_FAB2_LIB.BASEBOARD_FAB2(SCH_1):FP_NMI_BTN_R_N   I357 @BASEBOARD_FAB2_LIB.BASEBOARD_FAB2(SCH_1):PAGE157
     3 FP_NMI_BTN_OUT_N @BASEBOARD_FAB2_LIB.BASEBOARD_FAB2(SCH_1):FP_NMI_BTN_OUT_N   I356 @BASEBOARD_FAB2_LIB.BASEBOARD_FAB2(SCH_1):PAGE157
     4 FP_NMI_BTN @BASEBOARD_FAB2_LIB.BASEBOARD_FAB2(SCH_1):FP_NMI_BTN   I356 @BASEBOARD_FAB2_LIB.BASEBOARD_FAB2(SCH_1):PAGE157

U2T1 PI3B3257A_TSSOPLF-IC,E16801-001
    16 P3V3_STBY @BASEBOARD_FAB2_LIB.BASEBOARD_FAB2(SCH_1):P3V3_STBY    I75 @BASEBOARD_FAB2_LIB.BASEBOARD_FAB2(SCH_1):PAGE154
     8    GND @BASEBOARD_FAB2_LIB.BASEBOARD_FAB2(SCH_1):GND    I75 @BASEBOARD_FAB2_LIB.BASEBOARD_FAB2(SCH_1):PAGE154
    15    GND @BASEBOARD_FAB2_LIB.BASEBOARD_FAB2(SCH_1):GND    I75 @BASEBOARD_FAB2_LIB.BASEBOARD_FAB2(SCH_1):PAGE154
     1 FM_BIOS_SPI_BMC_CTRL @BASEBOARD_FAB2_LIB.BASEBOARD_FAB2(SCH_1):FM_BIOS_SPI_BMC_CTRL    I75 @BASEBOARD_FAB2_LIB.BASEBOARD_FAB2(SCH_1):PAGE154
     4 SPI_BIOS_SOCKET_IO2 @BASEBOARD_FAB2_LIB.BASEBOARD_FAB2(SCH_1):SPI_BIOS_SOCKET_IO2    I75 @BASEBOARD_FAB2_LIB.BASEBOARD_FAB2(SCH_1):PAGE154
     7 SPI_BIOS_SOCKET_IO3 @BASEBOARD_FAB2_LIB.BASEBOARD_FAB2(SCH_1):SPI_BIOS_SOCKET_IO3    I75 @BASEBOARD_FAB2_LIB.BASEBOARD_FAB2(SCH_1):PAGE154
     9 TP_SPI_SWITCH1_9 @BASEBOARD_FAB2_LIB.BASEBOARD_FAB2(SCH_1):TP_SPI_SWITCH1_9    I75 @BASEBOARD_FAB2_LIB.BASEBOARD_FAB2(SCH_1):PAGE154
    12 TP_SPI_SWITCH1_12 @BASEBOARD_FAB2_LIB.BASEBOARD_FAB2(SCH_1):TP_SPI_SWITCH1_12    I75 @BASEBOARD_FAB2_LIB.BASEBOARD_FAB2(SCH_1):PAGE154
     2 SPI_PCH_IO2_R1 @BASEBOARD_FAB2_LIB.BASEBOARD_FAB2(SCH_1):SPI_PCH_IO2_R1    I75 @BASEBOARD_FAB2_LIB.BASEBOARD_FAB2(SCH_1):PAGE154
     3 TP_SPI_SWITCH1_3 @BASEBOARD_FAB2_LIB.BASEBOARD_FAB2(SCH_1):TP_SPI_SWITCH1_3    I75 @BASEBOARD_FAB2_LIB.BASEBOARD_FAB2(SCH_1):PAGE154
     5 SPI_PCH_IO3_R1 @BASEBOARD_FAB2_LIB.BASEBOARD_FAB2(SCH_1):SPI_PCH_IO3_R1    I75 @BASEBOARD_FAB2_LIB.BASEBOARD_FAB2(SCH_1):PAGE154
     6 TP_SPI_SWITCH1_6 @BASEBOARD_FAB2_LIB.BASEBOARD_FAB2(SCH_1):TP_SPI_SWITCH1_6    I75 @BASEBOARD_FAB2_LIB.BASEBOARD_FAB2(SCH_1):PAGE154
    11 TP_SPI_SWITCH1_11 @BASEBOARD_FAB2_LIB.BASEBOARD_FAB2(SCH_1):TP_SPI_SWITCH1_11    I75 @BASEBOARD_FAB2_LIB.BASEBOARD_FAB2(SCH_1):PAGE154
    10 TP_SPI_SWITCH1_10 @BASEBOARD_FAB2_LIB.BASEBOARD_FAB2(SCH_1):TP_SPI_SWITCH1_10    I75 @BASEBOARD_FAB2_LIB.BASEBOARD_FAB2(SCH_1):PAGE154
    14 TP_SPI_SWITCH1_14 @BASEBOARD_FAB2_LIB.BASEBOARD_FAB2(SCH_1):TP_SPI_SWITCH1_14    I75 @BASEBOARD_FAB2_LIB.BASEBOARD_FAB2(SCH_1):PAGE154
    13 TP_SPI_SWITCH1_13 @BASEBOARD_FAB2_LIB.BASEBOARD_FAB2(SCH_1):TP_SPI_SWITCH1_13    I75 @BASEBOARD_FAB2_LIB.BASEBOARD_FAB2(SCH_1):PAGE154

U2T2 TTL1G32_A_SOT-74LVC1G32,IC,E60B
     1 FM_BACKUP_BIOS_SEL_N @BASEBOARD_FAB2_LIB.BASEBOARD_FAB2(SCH_1):FM_BACKUP_BIOS_SEL_N   I100 @BASEBOARD_FAB2_LIB.BASEBOARD_FAB2(SCH_1):PAGE154
     2 SPI_SWITCH_CS0_N @BASEBOARD_FAB2_LIB.BASEBOARD_FAB2(SCH_1):SPI_SWITCH_CS0_N   I100 @BASEBOARD_FAB2_LIB.BASEBOARD_FAB2(SCH_1):PAGE154
     4 SPI_CS0_SECONDARY_N @BASEBOARD_FAB2_LIB.BASEBOARD_FAB2(SCH_1):SPI_CS0_SECONDARY_N   I100 @BASEBOARD_FAB2_LIB.BASEBOARD_FAB2(SCH_1):PAGE154

U2T3 TTL1G32_A_SOT-74LVC1G32,IC,E60B
     1 FM_DUAL_BIOS_SEL_N @BASEBOARD_FAB2_LIB.BASEBOARD_FAB2(SCH_1):FM_DUAL_BIOS_SEL_N    I99 @BASEBOARD_FAB2_LIB.BASEBOARD_FAB2(SCH_1):PAGE154
     2 SPI_SWITCH_CS0_N @BASEBOARD_FAB2_LIB.BASEBOARD_FAB2(SCH_1):SPI_SWITCH_CS0_N    I99 @BASEBOARD_FAB2_LIB.BASEBOARD_FAB2(SCH_1):PAGE154
     4 SPI_CS0_PRIMARY_N @BASEBOARD_FAB2_LIB.BASEBOARD_FAB2(SCH_1):SPI_CS0_PRIMARY_N    I99 @BASEBOARD_FAB2_LIB.BASEBOARD_FAB2(SCH_1):PAGE154

U2T4 GTL2014_SM-IC,D66151-001
    13 FM_CPU1_PROCHOT_LVT3_R_N @BASEBOARD_FAB2_LIB.BASEBOARD_FAB2(SCH_1):FM_CPU1_PROCHOT_LVT3_R_N    I30 @BASEBOARD_FAB2_LIB.BASEBOARD_FAB2(SCH_1):PAGE93
    12 FM_CPU0_PROCHOT_LVT3_R_N @BASEBOARD_FAB2_LIB.BASEBOARD_FAB2(SCH_1):FM_CPU0_PROCHOT_LVT3_R_N    I30 @BASEBOARD_FAB2_LIB.BASEBOARD_FAB2(SCH_1):PAGE93
    10 FM_CPU_ERR1_LVT3_R_N @BASEBOARD_FAB2_LIB.BASEBOARD_FAB2(SCH_1):FM_CPU_ERR1_LVT3_R_N    I30 @BASEBOARD_FAB2_LIB.BASEBOARD_FAB2(SCH_1):PAGE93
     9 FM_CPU_ERR0_LVT3_R_N @BASEBOARD_FAB2_LIB.BASEBOARD_FAB2(SCH_1):FM_CPU_ERR0_LVT3_R_N    I30 @BASEBOARD_FAB2_LIB.BASEBOARD_FAB2(SCH_1):PAGE93
     2 H_CPU1_PROCHOT_G_R_N @BASEBOARD_FAB2_LIB.BASEBOARD_FAB2(SCH_1):H_CPU1_PROCHOT_G_R_N    I30 @BASEBOARD_FAB2_LIB.BASEBOARD_FAB2(SCH_1):PAGE93
     3 H_CPU0_PROCHOT_G_R_N @BASEBOARD_FAB2_LIB.BASEBOARD_FAB2(SCH_1):H_CPU0_PROCHOT_G_R_N    I30 @BASEBOARD_FAB2_LIB.BASEBOARD_FAB2(SCH_1):PAGE93
     5 H_CPU_ERR1_GTL_N @BASEBOARD_FAB2_LIB.BASEBOARD_FAB2(SCH_1):H_CPU_ERR1_GTL_N    I30 @BASEBOARD_FAB2_LIB.BASEBOARD_FAB2(SCH_1):PAGE93
     6 H_CPU_ERR0_GTL_N @BASEBOARD_FAB2_LIB.BASEBOARD_FAB2(SCH_1):H_CPU_ERR0_GTL_N    I30 @BASEBOARD_FAB2_LIB.BASEBOARD_FAB2(SCH_1):PAGE93
     1 PD_GTL2104_4_DIR @BASEBOARD_FAB2_LIB.BASEBOARD_FAB2(SCH_1):PD_GTL2104_4_DIR    I30 @BASEBOARD_FAB2_LIB.BASEBOARD_FAB2(SCH_1):PAGE93
    11    GND @BASEBOARD_FAB2_LIB.BASEBOARD_FAB2(SCH_1):GND    I30 @BASEBOARD_FAB2_LIB.BASEBOARD_FAB2(SCH_1):PAGE93
     8    GND @BASEBOARD_FAB2_LIB.BASEBOARD_FAB2(SCH_1):GND    I30 @BASEBOARD_FAB2_LIB.BASEBOARD_FAB2(SCH_1):PAGE93
     7    GND @BASEBOARD_FAB2_LIB.BASEBOARD_FAB2(SCH_1):GND    I30 @BASEBOARD_FAB2_LIB.BASEBOARD_FAB2(SCH_1):PAGE93
    14   P3V3 @BASEBOARD_FAB2_LIB.BASEBOARD_FAB2(SCH_1):P3V3    I30 @BASEBOARD_FAB2_LIB.BASEBOARD_FAB2(SCH_1):PAGE93
     4 P0V7_GTL2104_5_VREF @BASEBOARD_FAB2_LIB.BASEBOARD_FAB2(SCH_1):P0V7_GTL2104_5_VREF    I30 @BASEBOARD_FAB2_LIB.BASEBOARD_FAB2(SCH_1):PAGE93

U3B1 PCA9617_SSOP-IC,G81764-001-GNDA
     5 TP_SMB_DDR_KLM_EN @BASEBOARD_FAB2_LIB.BASEBOARD_FAB2(SCH_1):TP_SMB_DDR_KLM_EN    I75 @BASEBOARD_FAB2_LIB.BASEBOARD_FAB2(SCH_1):PAGE99
     2 SMB_DDR_KLM_SCL_G @BASEBOARD_FAB2_LIB.BASEBOARD_FAB2(SCH_1):SMB_DDR_KLM_SCL_G    I75 @BASEBOARD_FAB2_LIB.BASEBOARD_FAB2(SCH_1):PAGE99
     7 SMB_DDR_KLM_VPP_SCL_R @BASEBOARD_FAB2_LIB.BASEBOARD_FAB2(SCH_1):SMB_DDR_KLM_VPP_SCL_R    I75 @BASEBOARD_FAB2_LIB.BASEBOARD_FAB2(SCH_1):PAGE99
     3 SMB_DDR_KLM_SDA_G @BASEBOARD_FAB2_LIB.BASEBOARD_FAB2(SCH_1):SMB_DDR_KLM_SDA_G    I75 @BASEBOARD_FAB2_LIB.BASEBOARD_FAB2(SCH_1):PAGE99
     6 SMB_DDR_KLM_VPP_SDA_R @BASEBOARD_FAB2_LIB.BASEBOARD_FAB2(SCH_1):SMB_DDR_KLM_VPP_SDA_R    I75 @BASEBOARD_FAB2_LIB.BASEBOARD_FAB2(SCH_1):PAGE99
     1 PVCCIO_CPU1 @BASEBOARD_FAB2_LIB.BASEBOARD_FAB2(SCH_1):PVCCIO_CPU1    I75 @BASEBOARD_FAB2_LIB.BASEBOARD_FAB2(SCH_1):PAGE99
     8 PVPP_KLM @BASEBOARD_FAB2_LIB.BASEBOARD_FAB2(SCH_1):PVPP_KLM    I75 @BASEBOARD_FAB2_LIB.BASEBOARD_FAB2(SCH_1):PAGE99

U3P1 GTL2014_SM-IC,D66151-001
    13 PWRGD_DRAMPWRGD @BASEBOARD_FAB2_LIB.BASEBOARD_FAB2(SCH_1):PWRGD_DRAMPWRGD    I42 @BASEBOARD_FAB2_LIB.BASEBOARD_FAB2(SCH_1):PAGE96
    12 PWRGD_DRAMPWRGD @BASEBOARD_FAB2_LIB.BASEBOARD_FAB2(SCH_1):PWRGD_DRAMPWRGD    I42 @BASEBOARD_FAB2_LIB.BASEBOARD_FAB2(SCH_1):PAGE96
    10 RST_CPU0_LVC3_N @BASEBOARD_FAB2_LIB.BASEBOARD_FAB2(SCH_1):RST_CPU0_LVC3_N    I42 @BASEBOARD_FAB2_LIB.BASEBOARD_FAB2(SCH_1):PAGE96
     9 PWRGD_CPU0_LVC3 @BASEBOARD_FAB2_LIB.BASEBOARD_FAB2(SCH_1):PWRGD_CPU0_LVC3    I42 @BASEBOARD_FAB2_LIB.BASEBOARD_FAB2(SCH_1):PAGE96
     2 PWRGD_CPU0_DRAMPWROK_DEF_G @BASEBOARD_FAB2_LIB.BASEBOARD_FAB2(SCH_1):PWRGD_CPU0_DRAMPWROK_DEF_G    I42 @BASEBOARD_FAB2_LIB.BASEBOARD_FAB2(SCH_1):PAGE96
     3 PWRGD_CPU0_DRAMPWROK_ABC_G @BASEBOARD_FAB2_LIB.BASEBOARD_FAB2(SCH_1):PWRGD_CPU0_DRAMPWROK_ABC_G    I42 @BASEBOARD_FAB2_LIB.BASEBOARD_FAB2(SCH_1):PAGE96
     5 RST_CPU0_G_N @BASEBOARD_FAB2_LIB.BASEBOARD_FAB2(SCH_1):RST_CPU0_G_N    I42 @BASEBOARD_FAB2_LIB.BASEBOARD_FAB2(SCH_1):PAGE96
     6 PWRGD_CPU0_G @BASEBOARD_FAB2_LIB.BASEBOARD_FAB2(SCH_1):PWRGD_CPU0_G    I42 @BASEBOARD_FAB2_LIB.BASEBOARD_FAB2(SCH_1):PAGE96
     1 PU_GTL2014_1_DIR @BASEBOARD_FAB2_LIB.BASEBOARD_FAB2(SCH_1):PU_GTL2014_1_DIR    I42 @BASEBOARD_FAB2_LIB.BASEBOARD_FAB2(SCH_1):PAGE96
    11    GND @BASEBOARD_FAB2_LIB.BASEBOARD_FAB2(SCH_1):GND    I42 @BASEBOARD_FAB2_LIB.BASEBOARD_FAB2(SCH_1):PAGE96
     8    GND @BASEBOARD_FAB2_LIB.BASEBOARD_FAB2(SCH_1):GND    I42 @BASEBOARD_FAB2_LIB.BASEBOARD_FAB2(SCH_1):PAGE96
     7    GND @BASEBOARD_FAB2_LIB.BASEBOARD_FAB2(SCH_1):GND    I42 @BASEBOARD_FAB2_LIB.BASEBOARD_FAB2(SCH_1):PAGE96
    14 P3V3_STBY @BASEBOARD_FAB2_LIB.BASEBOARD_FAB2(SCH_1):P3V3_STBY    I42 @BASEBOARD_FAB2_LIB.BASEBOARD_FAB2(SCH_1):PAGE96
     4 PD_GTL2014_1_VREF @BASEBOARD_FAB2_LIB.BASEBOARD_FAB2(SCH_1):PD_GTL2014_1_VREF    I42 @BASEBOARD_FAB2_LIB.BASEBOARD_FAB2(SCH_1):PAGE96

U3P2 GTL2014_SM-IC,D66151-001
    13 PWRGD_CPUPWRGD_R1 @BASEBOARD_FAB2_LIB.BASEBOARD_FAB2(SCH_1):PWRGD_CPUPWRGD_R1     I1 @BASEBOARD_FAB2_LIB.BASEBOARD_FAB2(SCH_1):PAGE92
    12 FM_CPU1_FIVR_FAULT_R_LVT3 @BASEBOARD_FAB2_LIB.BASEBOARD_FAB2(SCH_1):FM_CPU1_FIVR_FAULT_R_LVT3     I1 @BASEBOARD_FAB2_LIB.BASEBOARD_FAB2(SCH_1):PAGE92
    10 FM_CPU_CATERR_LVT3_R2_N @BASEBOARD_FAB2_LIB.BASEBOARD_FAB2(SCH_1):FM_CPU_CATERR_LVT3_R2_N     I1 @BASEBOARD_FAB2_LIB.BASEBOARD_FAB2(SCH_1):PAGE92
     9 FM_CPU1_THERMTRIP_LVT3_R_N @BASEBOARD_FAB2_LIB.BASEBOARD_FAB2(SCH_1):FM_CPU1_THERMTRIP_LVT3_R_N     I1 @BASEBOARD_FAB2_LIB.BASEBOARD_FAB2(SCH_1):PAGE92
     2 PWRGD_CPUPWRGD_GTL @BASEBOARD_FAB2_LIB.BASEBOARD_FAB2(SCH_1):PWRGD_CPUPWRGD_GTL     I1 @BASEBOARD_FAB2_LIB.BASEBOARD_FAB2(SCH_1):PAGE92
     3 H_CPU1_FIVR_FAULT_G @BASEBOARD_FAB2_LIB.BASEBOARD_FAB2(SCH_1):H_CPU1_FIVR_FAULT_G     I1 @BASEBOARD_FAB2_LIB.BASEBOARD_FAB2(SCH_1):PAGE92
     5 H_CPU_CATERR_G_N @BASEBOARD_FAB2_LIB.BASEBOARD_FAB2(SCH_1):H_CPU_CATERR_G_N     I1 @BASEBOARD_FAB2_LIB.BASEBOARD_FAB2(SCH_1):PAGE92
     6 H_CPU1_THERMTRIP_G_N @BASEBOARD_FAB2_LIB.BASEBOARD_FAB2(SCH_1):H_CPU1_THERMTRIP_G_N     I1 @BASEBOARD_FAB2_LIB.BASEBOARD_FAB2(SCH_1):PAGE92
     1 PD_GTL2104_DIR_1 @BASEBOARD_FAB2_LIB.BASEBOARD_FAB2(SCH_1):PD_GTL2104_DIR_1     I1 @BASEBOARD_FAB2_LIB.BASEBOARD_FAB2(SCH_1):PAGE92
    11    GND @BASEBOARD_FAB2_LIB.BASEBOARD_FAB2(SCH_1):GND     I1 @BASEBOARD_FAB2_LIB.BASEBOARD_FAB2(SCH_1):PAGE92
     8    GND @BASEBOARD_FAB2_LIB.BASEBOARD_FAB2(SCH_1):GND     I1 @BASEBOARD_FAB2_LIB.BASEBOARD_FAB2(SCH_1):PAGE92
     7    GND @BASEBOARD_FAB2_LIB.BASEBOARD_FAB2(SCH_1):GND     I1 @BASEBOARD_FAB2_LIB.BASEBOARD_FAB2(SCH_1):PAGE92
    14   P3V3 @BASEBOARD_FAB2_LIB.BASEBOARD_FAB2(SCH_1):P3V3     I1 @BASEBOARD_FAB2_LIB.BASEBOARD_FAB2(SCH_1):PAGE92
     4 P0V7_GTL2104_VREF_1 @BASEBOARD_FAB2_LIB.BASEBOARD_FAB2(SCH_1):P0V7_GTL2104_VREF_1     I1 @BASEBOARD_FAB2_LIB.BASEBOARD_FAB2(SCH_1):PAGE92

U3T1 W25Q256_XSOI-IC,H25002-001
     9 PU_BIOS_SPI_WP1_N @BASEBOARD_FAB2_LIB.BASEBOARD_FAB2(SCH_1):PU_BIOS_SPI_WP1_N   I165 @BASEBOARD_FAB2_LIB.BASEBOARD_FAB2(SCH_1):PAGE153
    14 TP_SPI_1_0 @BASEBOARD_FAB2_LIB.BASEBOARD_FAB2(SCH_1):TP_SPI_1_0   I165 @BASEBOARD_FAB2_LIB.BASEBOARD_FAB2(SCH_1):PAGE153
    13 TP_SPI_1_1 @BASEBOARD_FAB2_LIB.BASEBOARD_FAB2(SCH_1):TP_SPI_1_1   I165 @BASEBOARD_FAB2_LIB.BASEBOARD_FAB2(SCH_1):PAGE153
    12 TP_SPI_1_2 @BASEBOARD_FAB2_LIB.BASEBOARD_FAB2(SCH_1):TP_SPI_1_2   I165 @BASEBOARD_FAB2_LIB.BASEBOARD_FAB2(SCH_1):PAGE153
    11 TP_SPI_1_3 @BASEBOARD_FAB2_LIB.BASEBOARD_FAB2(SCH_1):TP_SPI_1_3   I165 @BASEBOARD_FAB2_LIB.BASEBOARD_FAB2(SCH_1):PAGE153
     6 TP_SPI_1_4 @BASEBOARD_FAB2_LIB.BASEBOARD_FAB2(SCH_1):TP_SPI_1_4   I165 @BASEBOARD_FAB2_LIB.BASEBOARD_FAB2(SCH_1):PAGE153
     5 TP_SPI_1_5 @BASEBOARD_FAB2_LIB.BASEBOARD_FAB2(SCH_1):TP_SPI_1_5   I165 @BASEBOARD_FAB2_LIB.BASEBOARD_FAB2(SCH_1):PAGE153
     4 TP_SPI_1_6 @BASEBOARD_FAB2_LIB.BASEBOARD_FAB2(SCH_1):TP_SPI_1_6   I165 @BASEBOARD_FAB2_LIB.BASEBOARD_FAB2(SCH_1):PAGE153
    10    GND @BASEBOARD_FAB2_LIB.BASEBOARD_FAB2(SCH_1):GND   I165 @BASEBOARD_FAB2_LIB.BASEBOARD_FAB2(SCH_1):PAGE153
     8 SPI_MISO_R1 @BASEBOARD_FAB2_LIB.BASEBOARD_FAB2(SCH_1):SPI_MISO_R1   I165 @BASEBOARD_FAB2_LIB.BASEBOARD_FAB2(SCH_1):PAGE153
    16 SPI_CLK_R1 @BASEBOARD_FAB2_LIB.BASEBOARD_FAB2(SCH_1):SPI_CLK_R1   I165 @BASEBOARD_FAB2_LIB.BASEBOARD_FAB2(SCH_1):PAGE153
     2 P3V3_STBY @BASEBOARD_FAB2_LIB.BASEBOARD_FAB2(SCH_1):P3V3_STBY   I165 @BASEBOARD_FAB2_LIB.BASEBOARD_FAB2(SCH_1):PAGE153
     7 SPI_CS0_SECONDARY_R_N @BASEBOARD_FAB2_LIB.BASEBOARD_FAB2(SCH_1):SPI_CS0_SECONDARY_R_N   I165 @BASEBOARD_FAB2_LIB.BASEBOARD_FAB2(SCH_1):PAGE153
    15 SPI_SWITCH_MOSI_R1 @BASEBOARD_FAB2_LIB.BASEBOARD_FAB2(SCH_1):SPI_SWITCH_MOSI_R1   I165 @BASEBOARD_FAB2_LIB.BASEBOARD_FAB2(SCH_1):PAGE153
     3 PU_SPI1_RST @BASEBOARD_FAB2_LIB.BASEBOARD_FAB2(SCH_1):PU_SPI1_RST   I165 @BASEBOARD_FAB2_LIB.BASEBOARD_FAB2(SCH_1):PAGE153
     1 PU_BIOS_SPI_HOLD1_N @BASEBOARD_FAB2_LIB.BASEBOARD_FAB2(SCH_1):PU_BIOS_SPI_HOLD1_N   I165 @BASEBOARD_FAB2_LIB.BASEBOARD_FAB2(SCH_1):PAGE153

U4B1 MAX9634_SOT-IC,H35789-001
     1    GND @BASEBOARD_FAB2_LIB.BASEBOARD_FAB2(SCH_1):GND   I120 @BASEBOARD_FAB2_LIB.BASEBOARD_FAB2(SCH_1):PAGE197
     2    GND @BASEBOARD_FAB2_LIB.BASEBOARD_FAB2(SCH_1):GND   I120 @BASEBOARD_FAB2_LIB.BASEBOARD_FAB2(SCH_1):PAGE197
     3 VR_PVDDQ_DEF_AIINSEN_R @BASEBOARD_FAB2_LIB.BASEBOARD_FAB2(SCH_1):VR_PVDDQ_DEF_AIINSEN_R   I120 @BASEBOARD_FAB2_LIB.BASEBOARD_FAB2(SCH_1):PAGE197
     4 P12V_NVDIMM_DEF @BASEBOARD_FAB2_LIB.BASEBOARD_FAB2(SCH_1):P12V_NVDIMM_DEF   I120 @BASEBOARD_FAB2_LIB.BASEBOARD_FAB2(SCH_1):PAGE197
     5 P12V_STBY @BASEBOARD_FAB2_LIB.BASEBOARD_FAB2(SCH_1):P12V_STBY   I120 @BASEBOARD_FAB2_LIB.BASEBOARD_FAB2(SCH_1):PAGE197

U4C1 ADM4073_SM-EMPTY,G12194-001
     2    GND @BASEBOARD_FAB2_LIB.BASEBOARD_FAB2(SCH_1):GND    I53 @BASEBOARD_FAB2_LIB.BASEBOARD_FAB2(SCH_1):PAGE204
     1    GND @BASEBOARD_FAB2_LIB.BASEBOARD_FAB2(SCH_1):GND    I53 @BASEBOARD_FAB2_LIB.BASEBOARD_FAB2(SCH_1):PAGE204
     6 PVCCIN_PVSA_CPU0_IINSEN @BASEBOARD_FAB2_LIB.BASEBOARD_FAB2(SCH_1):PVCCIN_PVSA_CPU0_IINSEN    I53 @BASEBOARD_FAB2_LIB.BASEBOARD_FAB2(SCH_1):PAGE204
     5 VR_FET_SW_P12V_STBY_PVCCIN_CPU0 @BASEBOARD_FAB2_LIB.BASEBOARD_FAB2(SCH_1):VR_FET_SW_P12V_STBY_PVCCIN_CPU0    I53 @BASEBOARD_FAB2_LIB.BASEBOARD_FAB2(SCH_1):PAGE204
     4 VR_FET_SW_P12V_PVCCIN_CPU0_R @BASEBOARD_FAB2_LIB.BASEBOARD_FAB2(SCH_1):VR_FET_SW_P12V_PVCCIN_CPU0_R    I53 @BASEBOARD_FAB2_LIB.BASEBOARD_FAB2(SCH_1):PAGE204
     3 VR_FET_SW_P12V_PVCCIN_CPU0_R @BASEBOARD_FAB2_LIB.BASEBOARD_FAB2(SCH_1):VR_FET_SW_P12V_PVCCIN_CPU0_R    I53 @BASEBOARD_FAB2_LIB.BASEBOARD_FAB2(SCH_1):PAGE204

U4C2 GTL2014_SM-IC,D66151-001
    13 PWRGD_DRAMPWRGD @BASEBOARD_FAB2_LIB.BASEBOARD_FAB2(SCH_1):PWRGD_DRAMPWRGD    I46 @BASEBOARD_FAB2_LIB.BASEBOARD_FAB2(SCH_1):PAGE96
    12 PWRGD_DRAMPWRGD @BASEBOARD_FAB2_LIB.BASEBOARD_FAB2(SCH_1):PWRGD_DRAMPWRGD    I46 @BASEBOARD_FAB2_LIB.BASEBOARD_FAB2(SCH_1):PAGE96
    10 RST_CPU1_LVC3_N @BASEBOARD_FAB2_LIB.BASEBOARD_FAB2(SCH_1):RST_CPU1_LVC3_N    I46 @BASEBOARD_FAB2_LIB.BASEBOARD_FAB2(SCH_1):PAGE96
     9 PWRGD_CPU1_LVC3 @BASEBOARD_FAB2_LIB.BASEBOARD_FAB2(SCH_1):PWRGD_CPU1_LVC3    I46 @BASEBOARD_FAB2_LIB.BASEBOARD_FAB2(SCH_1):PAGE96
     2 PWRGD_CPU1_DRAMPWROK_KLM_G @BASEBOARD_FAB2_LIB.BASEBOARD_FAB2(SCH_1):PWRGD_CPU1_DRAMPWROK_KLM_G    I46 @BASEBOARD_FAB2_LIB.BASEBOARD_FAB2(SCH_1):PAGE96
     3 PWRGD_CPU1_DRAMPWROK_GHJ_G @BASEBOARD_FAB2_LIB.BASEBOARD_FAB2(SCH_1):PWRGD_CPU1_DRAMPWROK_GHJ_G    I46 @BASEBOARD_FAB2_LIB.BASEBOARD_FAB2(SCH_1):PAGE96
     5 RST_CPU1_G_N @BASEBOARD_FAB2_LIB.BASEBOARD_FAB2(SCH_1):RST_CPU1_G_N    I46 @BASEBOARD_FAB2_LIB.BASEBOARD_FAB2(SCH_1):PAGE96
     6 PWRGD_CPU1_G @BASEBOARD_FAB2_LIB.BASEBOARD_FAB2(SCH_1):PWRGD_CPU1_G    I46 @BASEBOARD_FAB2_LIB.BASEBOARD_FAB2(SCH_1):PAGE96
     1 PU_GTL2014_2_DIR @BASEBOARD_FAB2_LIB.BASEBOARD_FAB2(SCH_1):PU_GTL2014_2_DIR    I46 @BASEBOARD_FAB2_LIB.BASEBOARD_FAB2(SCH_1):PAGE96
    11    GND @BASEBOARD_FAB2_LIB.BASEBOARD_FAB2(SCH_1):GND    I46 @BASEBOARD_FAB2_LIB.BASEBOARD_FAB2(SCH_1):PAGE96
     8    GND @BASEBOARD_FAB2_LIB.BASEBOARD_FAB2(SCH_1):GND    I46 @BASEBOARD_FAB2_LIB.BASEBOARD_FAB2(SCH_1):PAGE96
     7    GND @BASEBOARD_FAB2_LIB.BASEBOARD_FAB2(SCH_1):GND    I46 @BASEBOARD_FAB2_LIB.BASEBOARD_FAB2(SCH_1):PAGE96
    14 P3V3_STBY @BASEBOARD_FAB2_LIB.BASEBOARD_FAB2(SCH_1):P3V3_STBY    I46 @BASEBOARD_FAB2_LIB.BASEBOARD_FAB2(SCH_1):PAGE96
     4 PD_GTL2014_2_VREF @BASEBOARD_FAB2_LIB.BASEBOARD_FAB2(SCH_1):PD_GTL2014_2_VREF    I46 @BASEBOARD_FAB2_LIB.BASEBOARD_FAB2(SCH_1):PAGE96

U4F1 MAX9634_SOT-IC,H35789-001
     1    GND @BASEBOARD_FAB2_LIB.BASEBOARD_FAB2(SCH_1):GND    I97 @BASEBOARD_FAB2_LIB.BASEBOARD_FAB2(SCH_1):PAGE197
     2    GND @BASEBOARD_FAB2_LIB.BASEBOARD_FAB2(SCH_1):GND    I97 @BASEBOARD_FAB2_LIB.BASEBOARD_FAB2(SCH_1):PAGE197
     3 VR_PVDDQ_ABC_AIINSEN_R @BASEBOARD_FAB2_LIB.BASEBOARD_FAB2(SCH_1):VR_PVDDQ_ABC_AIINSEN_R    I97 @BASEBOARD_FAB2_LIB.BASEBOARD_FAB2(SCH_1):PAGE197
     4 P12V_NVDIMM_ABC @BASEBOARD_FAB2_LIB.BASEBOARD_FAB2(SCH_1):P12V_NVDIMM_ABC    I97 @BASEBOARD_FAB2_LIB.BASEBOARD_FAB2(SCH_1):PAGE197
     5 P12V_STBY @BASEBOARD_FAB2_LIB.BASEBOARD_FAB2(SCH_1):P12V_STBY    I97 @BASEBOARD_FAB2_LIB.BASEBOARD_FAB2(SCH_1):PAGE197

U4G1 PCA9617_SSOP-IC,G81764-001-GNDA
     5 TP_SMB_DDR_GHJ_EN @BASEBOARD_FAB2_LIB.BASEBOARD_FAB2(SCH_1):TP_SMB_DDR_GHJ_EN    I63 @BASEBOARD_FAB2_LIB.BASEBOARD_FAB2(SCH_1):PAGE99
     2 SMB_DDR_GHJ_SCL_G @BASEBOARD_FAB2_LIB.BASEBOARD_FAB2(SCH_1):SMB_DDR_GHJ_SCL_G    I63 @BASEBOARD_FAB2_LIB.BASEBOARD_FAB2(SCH_1):PAGE99
     7 SMB_DDR_GHJ_VPP_SCL_R @BASEBOARD_FAB2_LIB.BASEBOARD_FAB2(SCH_1):SMB_DDR_GHJ_VPP_SCL_R    I63 @BASEBOARD_FAB2_LIB.BASEBOARD_FAB2(SCH_1):PAGE99
     3 SMB_DDR_GHJ_SDA_G @BASEBOARD_FAB2_LIB.BASEBOARD_FAB2(SCH_1):SMB_DDR_GHJ_SDA_G    I63 @BASEBOARD_FAB2_LIB.BASEBOARD_FAB2(SCH_1):PAGE99
     6 SMB_DDR_GHJ_VPP_SDA_R @BASEBOARD_FAB2_LIB.BASEBOARD_FAB2(SCH_1):SMB_DDR_GHJ_VPP_SDA_R    I63 @BASEBOARD_FAB2_LIB.BASEBOARD_FAB2(SCH_1):PAGE99
     1 PVCCIO_CPU1 @BASEBOARD_FAB2_LIB.BASEBOARD_FAB2(SCH_1):PVCCIO_CPU1    I63 @BASEBOARD_FAB2_LIB.BASEBOARD_FAB2(SCH_1):PAGE99
     8 PVPP_GHJ @BASEBOARD_FAB2_LIB.BASEBOARD_FAB2(SCH_1):PVPP_GHJ    I63 @BASEBOARD_FAB2_LIB.BASEBOARD_FAB2(SCH_1):PAGE99

U4R1 74CBTLV1G125_SMLF-IC,C88177-00A
     4 JTAG_MCP_CPU0_TDI_R @BASEBOARD_FAB2_LIB.BASEBOARD_FAB2(SCH_1):JTAG_MCP_CPU0_TDI_R   I206 @BASEBOARD_FAB2_LIB.BASEBOARD_FAB2(SCH_1):PAGE113
     1 FM_CPU0_PKGID1 @BASEBOARD_FAB2_LIB.BASEBOARD_FAB2(SCH_1):FM_CPU0_PKGID1   I206 @BASEBOARD_FAB2_LIB.BASEBOARD_FAB2(SCH_1):PAGE113
     2 P1V8_MCP_CPU0 @BASEBOARD_FAB2_LIB.BASEBOARD_FAB2(SCH_1):P1V8_MCP_CPU0   I206 @BASEBOARD_FAB2_LIB.BASEBOARD_FAB2(SCH_1):PAGE113

U5D1 SKX_EXT_B_BGA1-IC,TBD
  AU24 CLK_100M_CPU0_BCLK0_DN @BASEBOARD_FAB2_LIB.BASEBOARD_FAB2(SCH_1):CLK_100M_CPU0_BCLK0_DN   I259 @BASEBOARD_FAB2_LIB.BASEBOARD_FAB2(SCH_1):PAGE21
  AW24 CLK_100M_CPU0_BCLK0_DP @BASEBOARD_FAB2_LIB.BASEBOARD_FAB2(SCH_1):CLK_100M_CPU0_BCLK0_DP   I259 @BASEBOARD_FAB2_LIB.BASEBOARD_FAB2(SCH_1):PAGE21
  CR26 CLK_100M_CPU0_BCLK1_DN @BASEBOARD_FAB2_LIB.BASEBOARD_FAB2(SCH_1):CLK_100M_CPU0_BCLK1_DN   I259 @BASEBOARD_FAB2_LIB.BASEBOARD_FAB2(SCH_1):PAGE21
  CP27 CLK_100M_CPU0_BCLK1_DP @BASEBOARD_FAB2_LIB.BASEBOARD_FAB2(SCH_1):CLK_100M_CPU0_BCLK1_DP   I259 @BASEBOARD_FAB2_LIB.BASEBOARD_FAB2(SCH_1):PAGE21
  CT25 CLK_100M_CPU0_BCLK2_DN @BASEBOARD_FAB2_LIB.BASEBOARD_FAB2(SCH_1):CLK_100M_CPU0_BCLK2_DN   I259 @BASEBOARD_FAB2_LIB.BASEBOARD_FAB2(SCH_1):PAGE21
  CU26 CLK_100M_CPU0_BCLK2_DP @BASEBOARD_FAB2_LIB.BASEBOARD_FAB2(SCH_1):CLK_100M_CPU0_BCLK2_DP   I259 @BASEBOARD_FAB2_LIB.BASEBOARD_FAB2(SCH_1):PAGE21
  BA20 PD_CPU0_BIST_ENABLE @BASEBOARD_FAB2_LIB.BASEBOARD_FAB2(SCH_1):PD_CPU0_BIST_ENABLE   I259 @BASEBOARD_FAB2_LIB.BASEBOARD_FAB2(SCH_1):PAGE21
  BD23 H_CPU0_BMCINIT @BASEBOARD_FAB2_LIB.BASEBOARD_FAB2(SCH_1):H_CPU0_BMCINIT   I259 @BASEBOARD_FAB2_LIB.BASEBOARD_FAB2(SCH_1):PAGE21
  AC12 XDP_CPU_OBSFN_B1_MBP7_N @BASEBOARD_FAB2_LIB.BASEBOARD_FAB2(SCH_1):XDP_CPU_OBSFN_B1_MBP7_N   I259 @BASEBOARD_FAB2_LIB.BASEBOARD_FAB2(SCH_1):PAGE21
  AE12 XDP_CPU_OBSFN_B0_MBP6_N @BASEBOARD_FAB2_LIB.BASEBOARD_FAB2(SCH_1):XDP_CPU_OBSFN_B0_MBP6_N   I259 @BASEBOARD_FAB2_LIB.BASEBOARD_FAB2(SCH_1):PAGE21
   Y11 TP_XDP_CPU0_OBSDATA_A3_MBP5_N @BASEBOARD_FAB2_LIB.BASEBOARD_FAB2(SCH_1):TP_XDP_CPU0_OBSDATA_A3_MBP5_N   I259 @BASEBOARD_FAB2_LIB.BASEBOARD_FAB2(SCH_1):PAGE21
  AA12 TP_XDP_CPU0_OBSDATA_A2_MBP4_N @BASEBOARD_FAB2_LIB.BASEBOARD_FAB2(SCH_1):TP_XDP_CPU0_OBSDATA_A2_MBP4_N   I259 @BASEBOARD_FAB2_LIB.BASEBOARD_FAB2(SCH_1):PAGE21
  AF11 TP_XDP_CPU0_OBSDATA_A1_MBP3_N @BASEBOARD_FAB2_LIB.BASEBOARD_FAB2(SCH_1):TP_XDP_CPU0_OBSDATA_A1_MBP3_N   I259 @BASEBOARD_FAB2_LIB.BASEBOARD_FAB2(SCH_1):PAGE21
  AG10 TP_XDP_CPU0_OBSDATA_A0_MBP2_N @BASEBOARD_FAB2_LIB.BASEBOARD_FAB2(SCH_1):TP_XDP_CPU0_OBSDATA_A0_MBP2_N   I259 @BASEBOARD_FAB2_LIB.BASEBOARD_FAB2(SCH_1):PAGE21
  AH11 XDP_CPU_MBP1_N @BASEBOARD_FAB2_LIB.BASEBOARD_FAB2(SCH_1):XDP_CPU_MBP1_N   I259 @BASEBOARD_FAB2_LIB.BASEBOARD_FAB2(SCH_1):PAGE21
  AJ10 XDP_CPU_MBP0_N @BASEBOARD_FAB2_LIB.BASEBOARD_FAB2(SCH_1):XDP_CPU_MBP0_N   I259 @BASEBOARD_FAB2_LIB.BASEBOARD_FAB2(SCH_1):PAGE21
  AL14 H_CPU0_CATERR_G_N @BASEBOARD_FAB2_LIB.BASEBOARD_FAB2(SCH_1):H_CPU0_CATERR_G_N   I259 @BASEBOARD_FAB2_LIB.BASEBOARD_FAB2(SCH_1):PAGE21
  AN30 PWRGD_CPU0_DRAMPWROK_ABC_G @BASEBOARD_FAB2_LIB.BASEBOARD_FAB2(SCH_1):PWRGD_CPU0_DRAMPWROK_ABC_G   I259 @BASEBOARD_FAB2_LIB.BASEBOARD_FAB2(SCH_1):PAGE21
  AC42 A_CPU0_ABC_RCOMP2 @BASEBOARD_FAB2_LIB.BASEBOARD_FAB2(SCH_1):A_CPU0_ABC_RCOMP2   I259 @BASEBOARD_FAB2_LIB.BASEBOARD_FAB2(SCH_1):PAGE21
  AB43 A_CPU0_ABC_RCOMP1 @BASEBOARD_FAB2_LIB.BASEBOARD_FAB2(SCH_1):A_CPU0_ABC_RCOMP1   I259 @BASEBOARD_FAB2_LIB.BASEBOARD_FAB2(SCH_1):PAGE21
   Y43 A_CPU0_ABC_RCOMP0 @BASEBOARD_FAB2_LIB.BASEBOARD_FAB2(SCH_1):A_CPU0_ABC_RCOMP0   I259 @BASEBOARD_FAB2_LIB.BASEBOARD_FAB2(SCH_1):PAGE21
   U64 M_ABC_RST_N @BASEBOARD_FAB2_LIB.BASEBOARD_FAB2(SCH_1):M_ABC_RST_N   I259 @BASEBOARD_FAB2_LIB.BASEBOARD_FAB2(SCH_1):PAGE21
  AJ18 SMB_DDR_ABC_SCL_G_R @BASEBOARD_FAB2_LIB.BASEBOARD_FAB2(SCH_1):SMB_DDR_ABC_SCL_G_R   I259 @BASEBOARD_FAB2_LIB.BASEBOARD_FAB2(SCH_1):PAGE21
  AF17 SMB_DDR_ABC_SDA_G_R @BASEBOARD_FAB2_LIB.BASEBOARD_FAB2(SCH_1):SMB_DDR_ABC_SDA_G_R   I259 @BASEBOARD_FAB2_LIB.BASEBOARD_FAB2(SCH_1):PAGE21
  AJ64 M_A_CPU_VREF @BASEBOARD_FAB2_LIB.BASEBOARD_FAB2(SCH_1):M_A_CPU_VREF   I259 @BASEBOARD_FAB2_LIB.BASEBOARD_FAB2(SCH_1):PAGE21
  AK63 M_B_CPU_VREF @BASEBOARD_FAB2_LIB.BASEBOARD_FAB2(SCH_1):M_B_CPU_VREF   I259 @BASEBOARD_FAB2_LIB.BASEBOARD_FAB2(SCH_1):PAGE21
  AH63 M_C_CPU_VREF @BASEBOARD_FAB2_LIB.BASEBOARD_FAB2(SCH_1):M_C_CPU_VREF   I259 @BASEBOARD_FAB2_LIB.BASEBOARD_FAB2(SCH_1):PAGE21
  CR28 PWRGD_CPU0_DRAMPWROK_DEF_G @BASEBOARD_FAB2_LIB.BASEBOARD_FAB2(SCH_1):PWRGD_CPU0_DRAMPWROK_DEF_G   I259 @BASEBOARD_FAB2_LIB.BASEBOARD_FAB2(SCH_1):PAGE21
  DD49 A_CPU0_DEF_RCOMP2 @BASEBOARD_FAB2_LIB.BASEBOARD_FAB2(SCH_1):A_CPU0_DEF_RCOMP2   I259 @BASEBOARD_FAB2_LIB.BASEBOARD_FAB2(SCH_1):PAGE21
  DD47 A_CPU0_DEF_RCOMP1 @BASEBOARD_FAB2_LIB.BASEBOARD_FAB2(SCH_1):A_CPU0_DEF_RCOMP1   I259 @BASEBOARD_FAB2_LIB.BASEBOARD_FAB2(SCH_1):PAGE21
  DC48 A_CPU0_DEF_RCOMP0 @BASEBOARD_FAB2_LIB.BASEBOARD_FAB2(SCH_1):A_CPU0_DEF_RCOMP0   I259 @BASEBOARD_FAB2_LIB.BASEBOARD_FAB2(SCH_1):PAGE21
  DV63 M_DEF_RST_N @BASEBOARD_FAB2_LIB.BASEBOARD_FAB2(SCH_1):M_DEF_RST_N   I259 @BASEBOARD_FAB2_LIB.BASEBOARD_FAB2(SCH_1):PAGE21
  AE18 SMB_DDR_DEF_SCL_G_R @BASEBOARD_FAB2_LIB.BASEBOARD_FAB2(SCH_1):SMB_DDR_DEF_SCL_G_R   I259 @BASEBOARD_FAB2_LIB.BASEBOARD_FAB2(SCH_1):PAGE21
  AD17 SMB_DDR_DEF_SDA_G_R @BASEBOARD_FAB2_LIB.BASEBOARD_FAB2(SCH_1):SMB_DDR_DEF_SDA_G_R   I259 @BASEBOARD_FAB2_LIB.BASEBOARD_FAB2(SCH_1):PAGE21
  CP61 M_D_CPU_VREF @BASEBOARD_FAB2_LIB.BASEBOARD_FAB2(SCH_1):M_D_CPU_VREF   I259 @BASEBOARD_FAB2_LIB.BASEBOARD_FAB2(SCH_1):PAGE21
  CT61 M_E_CPU_VREF @BASEBOARD_FAB2_LIB.BASEBOARD_FAB2(SCH_1):M_E_CPU_VREF   I259 @BASEBOARD_FAB2_LIB.BASEBOARD_FAB2(SCH_1):PAGE21
  CV61 M_F_CPU_VREF @BASEBOARD_FAB2_LIB.BASEBOARD_FAB2(SCH_1):M_F_CPU_VREF   I259 @BASEBOARD_FAB2_LIB.BASEBOARD_FAB2(SCH_1):PAGE21
  AJ14 PU_CPU0_EAR_N @BASEBOARD_FAB2_LIB.BASEBOARD_FAB2(SCH_1):PU_CPU0_EAR_N   I259 @BASEBOARD_FAB2_LIB.BASEBOARD_FAB2(SCH_1):PAGE21
  AL12 H_CPU0_ERR2_G_N @BASEBOARD_FAB2_LIB.BASEBOARD_FAB2(SCH_1):H_CPU0_ERR2_G_N   I259 @BASEBOARD_FAB2_LIB.BASEBOARD_FAB2(SCH_1):PAGE21
  AK11 H_CPU0_ERR1_G_N @BASEBOARD_FAB2_LIB.BASEBOARD_FAB2(SCH_1):H_CPU0_ERR1_G_N   I259 @BASEBOARD_FAB2_LIB.BASEBOARD_FAB2(SCH_1):PAGE21
  AJ12 H_CPU0_ERR0_G_N @BASEBOARD_FAB2_LIB.BASEBOARD_FAB2(SCH_1):H_CPU0_ERR0_G_N   I259 @BASEBOARD_FAB2_LIB.BASEBOARD_FAB2(SCH_1):PAGE21
  AV17 PU_CPU0_FRMAGENT @BASEBOARD_FAB2_LIB.BASEBOARD_FAB2(SCH_1):PU_CPU0_FRMAGENT   I259 @BASEBOARD_FAB2_LIB.BASEBOARD_FAB2(SCH_1):PAGE21
  AE20 PU_CPU0_LEGACY_SKT @BASEBOARD_FAB2_LIB.BASEBOARD_FAB2(SCH_1):PU_CPU0_LEGACY_SKT   I259 @BASEBOARD_FAB2_LIB.BASEBOARD_FAB2(SCH_1):PAGE21
  CT31 A_CPU0_MCP01_RBIAS @BASEBOARD_FAB2_LIB.BASEBOARD_FAB2(SCH_1):A_CPU0_MCP01_RBIAS   I259 @BASEBOARD_FAB2_LIB.BASEBOARD_FAB2(SCH_1):PAGE21
  CU32 A_CPU0_MCP01_RBIAS @BASEBOARD_FAB2_LIB.BASEBOARD_FAB2(SCH_1):A_CPU0_MCP01_RBIAS   I259 @BASEBOARD_FAB2_LIB.BASEBOARD_FAB2(SCH_1):PAGE21
  AH13 H_CPU0_MEMABC_MEMHOT_G_N @BASEBOARD_FAB2_LIB.BASEBOARD_FAB2(SCH_1):H_CPU0_MEMABC_MEMHOT_G_N   I259 @BASEBOARD_FAB2_LIB.BASEBOARD_FAB2(SCH_1):PAGE21
  AF13 H_CPU0_MEMDEF_MEMHOT_G_N @BASEBOARD_FAB2_LIB.BASEBOARD_FAB2(SCH_1):H_CPU0_MEMDEF_MEMHOT_G_N   I259 @BASEBOARD_FAB2_LIB.BASEBOARD_FAB2(SCH_1):PAGE21
  AN20 H_CPU0_MSMI_G_N @BASEBOARD_FAB2_LIB.BASEBOARD_FAB2(SCH_1):H_CPU0_MSMI_G_N   I259 @BASEBOARD_FAB2_LIB.BASEBOARD_FAB2(SCH_1):PAGE21
  AP11 TP_NMI_CPU0 @BASEBOARD_FAB2_LIB.BASEBOARD_FAB2(SCH_1):TP_NMI_CPU0   I259 @BASEBOARD_FAB2_LIB.BASEBOARD_FAB2(SCH_1):PAGE21
  CL30 A_CPU0_PE012_RBIAS @BASEBOARD_FAB2_LIB.BASEBOARD_FAB2(SCH_1):A_CPU0_PE012_RBIAS   I259 @BASEBOARD_FAB2_LIB.BASEBOARD_FAB2(SCH_1):PAGE21
  CN30 A_CPU0_PE012_RBIAS @BASEBOARD_FAB2_LIB.BASEBOARD_FAB2(SCH_1):A_CPU0_PE012_RBIAS   I259 @BASEBOARD_FAB2_LIB.BASEBOARD_FAB2(SCH_1):PAGE21
  CR30 A_CPU0_PE3_RBIAS @BASEBOARD_FAB2_LIB.BASEBOARD_FAB2(SCH_1):A_CPU0_PE3_RBIAS   I259 @BASEBOARD_FAB2_LIB.BASEBOARD_FAB2(SCH_1):PAGE21
  CP29 A_CPU0_PE3_RBIAS @BASEBOARD_FAB2_LIB.BASEBOARD_FAB2(SCH_1):A_CPU0_PE3_RBIAS   I259 @BASEBOARD_FAB2_LIB.BASEBOARD_FAB2(SCH_1):PAGE21
  AU12 PECI_CPU_G @BASEBOARD_FAB2_LIB.BASEBOARD_FAB2(SCH_1):PECI_CPU_G   I259 @BASEBOARD_FAB2_LIB.BASEBOARD_FAB2(SCH_1):PAGE21
  AM19 TP_CPU0_PE_HP_SCL @BASEBOARD_FAB2_LIB.BASEBOARD_FAB2(SCH_1):TP_CPU0_PE_HP_SCL   I259 @BASEBOARD_FAB2_LIB.BASEBOARD_FAB2(SCH_1):PAGE21
  AL18 TP_CPU0_PE_HP_SDA @BASEBOARD_FAB2_LIB.BASEBOARD_FAB2(SCH_1):TP_CPU0_PE_HP_SDA   I259 @BASEBOARD_FAB2_LIB.BASEBOARD_FAB2(SCH_1):PAGE21
  CW56 PD_PIROM_CPU0_ADDR2 @BASEBOARD_FAB2_LIB.BASEBOARD_FAB2(SCH_1):PD_PIROM_CPU0_ADDR2   I259 @BASEBOARD_FAB2_LIB.BASEBOARD_FAB2(SCH_1):PAGE21
  CV57 PD_PIROM_CPU0_ADDR1 @BASEBOARD_FAB2_LIB.BASEBOARD_FAB2(SCH_1):PD_PIROM_CPU0_ADDR1   I259 @BASEBOARD_FAB2_LIB.BASEBOARD_FAB2(SCH_1):PAGE21
  CU58 PD_PIROM_CPU0_ADDR0 @BASEBOARD_FAB2_LIB.BASEBOARD_FAB2(SCH_1):PD_PIROM_CPU0_ADDR0   I259 @BASEBOARD_FAB2_LIB.BASEBOARD_FAB2(SCH_1):PAGE21
  DA72 FM_CPU0_PKGID2 @BASEBOARD_FAB2_LIB.BASEBOARD_FAB2(SCH_1):FM_CPU0_PKGID2   I259 @BASEBOARD_FAB2_LIB.BASEBOARD_FAB2(SCH_1):PAGE21
  CW72 FM_CPU0_PKGID1 @BASEBOARD_FAB2_LIB.BASEBOARD_FAB2(SCH_1):FM_CPU0_PKGID1   I259 @BASEBOARD_FAB2_LIB.BASEBOARD_FAB2(SCH_1):PAGE21
  DC72 FM_CPU0_PKGID0 @BASEBOARD_FAB2_LIB.BASEBOARD_FAB2(SCH_1):FM_CPU0_PKGID0   I259 @BASEBOARD_FAB2_LIB.BASEBOARD_FAB2(SCH_1):PAGE21
  AR14 H_PM_SYNC_GTL_R1 @BASEBOARD_FAB2_LIB.BASEBOARD_FAB2(SCH_1):H_PM_SYNC_GTL_R1   I259 @BASEBOARD_FAB2_LIB.BASEBOARD_FAB2(SCH_1):PAGE21
  AT19 H_PMSYNC_CLK_24M_CPU0 @BASEBOARD_FAB2_LIB.BASEBOARD_FAB2(SCH_1):H_PMSYNC_CLK_24M_CPU0   I259 @BASEBOARD_FAB2_LIB.BASEBOARD_FAB2(SCH_1):PAGE21
  AF15 H_CPU0_FAST_WAKE_N @BASEBOARD_FAB2_LIB.BASEBOARD_FAB2(SCH_1):H_CPU0_FAST_WAKE_N   I259 @BASEBOARD_FAB2_LIB.BASEBOARD_FAB2(SCH_1):PAGE21
  AG16 XDP_CPU_PRDY_N @BASEBOARD_FAB2_LIB.BASEBOARD_FAB2(SCH_1):XDP_CPU_PRDY_N   I259 @BASEBOARD_FAB2_LIB.BASEBOARD_FAB2(SCH_1):PAGE21
  AR12 XDP_CPU_PREQ_N @BASEBOARD_FAB2_LIB.BASEBOARD_FAB2(SCH_1):XDP_CPU_PREQ_N   I259 @BASEBOARD_FAB2_LIB.BASEBOARD_FAB2(SCH_1):PAGE21
  AB17 TP_CPU0_PROCDIS_G_N @BASEBOARD_FAB2_LIB.BASEBOARD_FAB2(SCH_1):TP_CPU0_PROCDIS_G_N   I259 @BASEBOARD_FAB2_LIB.BASEBOARD_FAB2(SCH_1):PAGE21
  AC16 H_CPU0_PROCHOT_G_N @BASEBOARD_FAB2_LIB.BASEBOARD_FAB2(SCH_1):H_CPU0_PROCHOT_G_N   I259 @BASEBOARD_FAB2_LIB.BASEBOARD_FAB2(SCH_1):PAGE21
  DB71 FM_CPU0_PROC_ID1 @BASEBOARD_FAB2_LIB.BASEBOARD_FAB2(SCH_1):FM_CPU0_PROC_ID1   I259 @BASEBOARD_FAB2_LIB.BASEBOARD_FAB2(SCH_1):PAGE21
  CY71 FM_CPU0_PROC_ID0 @BASEBOARD_FAB2_LIB.BASEBOARD_FAB2(SCH_1):FM_CPU0_PROC_ID0   I259 @BASEBOARD_FAB2_LIB.BASEBOARD_FAB2(SCH_1):PAGE21
  BC24 PWRGD_CPU0_G @BASEBOARD_FAB2_LIB.BASEBOARD_FAB2(SCH_1):PWRGD_CPU0_G   I259 @BASEBOARD_FAB2_LIB.BASEBOARD_FAB2(SCH_1):PAGE21
  AP21 RST_CPU0_G_N @BASEBOARD_FAB2_LIB.BASEBOARD_FAB2(SCH_1):RST_CPU0_G_N   I259 @BASEBOARD_FAB2_LIB.BASEBOARD_FAB2(SCH_1):PAGE21
  AR18 PU_CPU0_SAFE_MODE_BOOT @BASEBOARD_FAB2_LIB.BASEBOARD_FAB2(SCH_1):PU_CPU0_SAFE_MODE_BOOT   I259 @BASEBOARD_FAB2_LIB.BASEBOARD_FAB2(SCH_1):PAGE21
  AB13 FM_CPU0_SKTOCC_LVT3_N @BASEBOARD_FAB2_LIB.BASEBOARD_FAB2(SCH_1):FM_CPU0_SKTOCC_LVT3_N   I259 @BASEBOARD_FAB2_LIB.BASEBOARD_FAB2(SCH_1):PAGE21
  CT59 SMB_PIROM_CPU0_SCL @BASEBOARD_FAB2_LIB.BASEBOARD_FAB2(SCH_1):SMB_PIROM_CPU0_SCL   I259 @BASEBOARD_FAB2_LIB.BASEBOARD_FAB2(SCH_1):PAGE21
  CW58 SMB_PIROM_CPU0_SDA @BASEBOARD_FAB2_LIB.BASEBOARD_FAB2(SCH_1):SMB_PIROM_CPU0_SDA   I259 @BASEBOARD_FAB2_LIB.BASEBOARD_FAB2(SCH_1):PAGE21
  CV59 FM_CPU0_SM_WP @BASEBOARD_FAB2_LIB.BASEBOARD_FAB2(SCH_1):FM_CPU0_SM_WP   I259 @BASEBOARD_FAB2_LIB.BASEBOARD_FAB2(SCH_1):PAGE21
  AU20 TP_CPU0_SOCKET_ID_2 @BASEBOARD_FAB2_LIB.BASEBOARD_FAB2(SCH_1):TP_CPU0_SOCKET_ID_2   I259 @BASEBOARD_FAB2_LIB.BASEBOARD_FAB2(SCH_1):PAGE21
  AU16 PU_CPU0_SOCKET_ID_1 @BASEBOARD_FAB2_LIB.BASEBOARD_FAB2(SCH_1):PU_CPU0_SOCKET_ID_1   I259 @BASEBOARD_FAB2_LIB.BASEBOARD_FAB2(SCH_1):PAGE21
  AU22 PU_CPU0_SOCKET_ID_0 @BASEBOARD_FAB2_LIB.BASEBOARD_FAB2(SCH_1):PU_CPU0_SOCKET_ID_0   I259 @BASEBOARD_FAB2_LIB.BASEBOARD_FAB2(SCH_1):PAGE21
  DL44 SVID_ALERT1_CPU0_N @BASEBOARD_FAB2_LIB.BASEBOARD_FAB2(SCH_1):SVID_ALERT1_CPU0_N   I259 @BASEBOARD_FAB2_LIB.BASEBOARD_FAB2(SCH_1):PAGE21
  DE44 SVID_ALERT0_CPU0_N @BASEBOARD_FAB2_LIB.BASEBOARD_FAB2(SCH_1):SVID_ALERT0_CPU0_N   I259 @BASEBOARD_FAB2_LIB.BASEBOARD_FAB2(SCH_1):PAGE21
  DG44 SVID_CLK1_CPU0 @BASEBOARD_FAB2_LIB.BASEBOARD_FAB2(SCH_1):SVID_CLK1_CPU0   I259 @BASEBOARD_FAB2_LIB.BASEBOARD_FAB2(SCH_1):PAGE21
  DC44 SVID_CLK0_CPU0 @BASEBOARD_FAB2_LIB.BASEBOARD_FAB2(SCH_1):SVID_CLK0_CPU0   I259 @BASEBOARD_FAB2_LIB.BASEBOARD_FAB2(SCH_1):PAGE21
  DJ44 SVID_DIO1_CPU0 @BASEBOARD_FAB2_LIB.BASEBOARD_FAB2(SCH_1):SVID_DIO1_CPU0   I259 @BASEBOARD_FAB2_LIB.BASEBOARD_FAB2(SCH_1):PAGE21
  DB45 SVID_DIO0_CPU0 @BASEBOARD_FAB2_LIB.BASEBOARD_FAB2(SCH_1):SVID_DIO0_CPU0   I259 @BASEBOARD_FAB2_LIB.BASEBOARD_FAB2(SCH_1):PAGE21
  AA14 XDP_CPU_TCK0 @BASEBOARD_FAB2_LIB.BASEBOARD_FAB2(SCH_1):XDP_CPU_TCK0   I259 @BASEBOARD_FAB2_LIB.BASEBOARD_FAB2(SCH_1):PAGE21
  AC14 XDP_CPU_TDI @BASEBOARD_FAB2_LIB.BASEBOARD_FAB2(SCH_1):XDP_CPU_TDI   I259 @BASEBOARD_FAB2_LIB.BASEBOARD_FAB2(SCH_1):PAGE21
  AE14 XDP_CPU0_TDO @BASEBOARD_FAB2_LIB.BASEBOARD_FAB2(SCH_1):XDP_CPU0_TDO   I259 @BASEBOARD_FAB2_LIB.BASEBOARD_FAB2(SCH_1):PAGE21
  AY19 PD_CPU0_TEST12 @BASEBOARD_FAB2_LIB.BASEBOARD_FAB2(SCH_1):PD_CPU0_TEST12   I259 @BASEBOARD_FAB2_LIB.BASEBOARD_FAB2(SCH_1):PAGE21
  DB51 PD_CPU0_TEST13 @BASEBOARD_FAB2_LIB.BASEBOARD_FAB2(SCH_1):PD_CPU0_TEST13   I259 @BASEBOARD_FAB2_LIB.BASEBOARD_FAB2(SCH_1):PAGE21
  DC50 PD_CPU0_TEST14 @BASEBOARD_FAB2_LIB.BASEBOARD_FAB2(SCH_1):PD_CPU0_TEST14   I259 @BASEBOARD_FAB2_LIB.BASEBOARD_FAB2(SCH_1):PAGE21
  AW14 PD_CPU0_KSFC_DIS @BASEBOARD_FAB2_LIB.BASEBOARD_FAB2(SCH_1):PD_CPU0_KSFC_DIS   I259 @BASEBOARD_FAB2_LIB.BASEBOARD_FAB2(SCH_1):PAGE21
  AB15 H_CPU0_THERMTRIP_G_N @BASEBOARD_FAB2_LIB.BASEBOARD_FAB2(SCH_1):H_CPU0_THERMTRIP_G_N   I259 @BASEBOARD_FAB2_LIB.BASEBOARD_FAB2(SCH_1):PAGE21
   W14 XDP_CPU_TMS @BASEBOARD_FAB2_LIB.BASEBOARD_FAB2(SCH_1):XDP_CPU_TMS   I259 @BASEBOARD_FAB2_LIB.BASEBOARD_FAB2(SCH_1):PAGE21
   Y13 XDP_CPU_TRST_N @BASEBOARD_FAB2_LIB.BASEBOARD_FAB2(SCH_1):XDP_CPU_TRST_N   I259 @BASEBOARD_FAB2_LIB.BASEBOARD_FAB2(SCH_1):PAGE21
  AM11 PU_CPU0_TSC_SYNC @BASEBOARD_FAB2_LIB.BASEBOARD_FAB2(SCH_1):PU_CPU0_TSC_SYNC   I259 @BASEBOARD_FAB2_LIB.BASEBOARD_FAB2(SCH_1):PAGE21
  AW18 PU_CPU0_TXT_AGENT @BASEBOARD_FAB2_LIB.BASEBOARD_FAB2(SCH_1):PU_CPU0_TXT_AGENT   I259 @BASEBOARD_FAB2_LIB.BASEBOARD_FAB2(SCH_1):PAGE21
  AV15 PD_CPU0_TXT_PLTEN @BASEBOARD_FAB2_LIB.BASEBOARD_FAB2(SCH_1):PD_CPU0_TXT_PLTEN   I259 @BASEBOARD_FAB2_LIB.BASEBOARD_FAB2(SCH_1):PAGE21
  AP29 A_CPU0_UPI01_RBIAS @BASEBOARD_FAB2_LIB.BASEBOARD_FAB2(SCH_1):A_CPU0_UPI01_RBIAS   I259 @BASEBOARD_FAB2_LIB.BASEBOARD_FAB2(SCH_1):PAGE21
  AT29 A_CPU0_UPI01_RBIAS @BASEBOARD_FAB2_LIB.BASEBOARD_FAB2(SCH_1):A_CPU0_UPI01_RBIAS   I259 @BASEBOARD_FAB2_LIB.BASEBOARD_FAB2(SCH_1):PAGE21
  CK29 A_CPU0_UPI2_RBIAS @BASEBOARD_FAB2_LIB.BASEBOARD_FAB2(SCH_1):A_CPU0_UPI2_RBIAS   I259 @BASEBOARD_FAB2_LIB.BASEBOARD_FAB2(SCH_1):PAGE21
  CL28 A_CPU0_UPI2_RBIAS @BASEBOARD_FAB2_LIB.BASEBOARD_FAB2(SCH_1):A_CPU0_UPI2_RBIAS   I259 @BASEBOARD_FAB2_LIB.BASEBOARD_FAB2(SCH_1):PAGE21
  AV21 XDP_PRESENT_N @BASEBOARD_FAB2_LIB.BASEBOARD_FAB2(SCH_1):XDP_PRESENT_N   I204 @BASEBOARD_FAB2_LIB.BASEBOARD_FAB2(SCH_1):PAGE22
  AW12 PD_CPU0_DMIMODE_OVERRIDE @BASEBOARD_FAB2_LIB.BASEBOARD_FAB2(SCH_1):PD_CPU0_DMIMODE_OVERRIDE   I204 @BASEBOARD_FAB2_LIB.BASEBOARD_FAB2(SCH_1):PAGE22
  AU14 H_CPU0_FIVR_FAULT_G @BASEBOARD_FAB2_LIB.BASEBOARD_FAB2(SCH_1):H_CPU0_FIVR_FAULT_G   I204 @BASEBOARD_FAB2_LIB.BASEBOARD_FAB2(SCH_1):PAGE22
  AP17 XDP_CPU_PWR_DEBUG_N @BASEBOARD_FAB2_LIB.BASEBOARD_FAB2(SCH_1):XDP_CPU_PWR_DEBUG_N   I204 @BASEBOARD_FAB2_LIB.BASEBOARD_FAB2(SCH_1):PAGE22
    A4 TP_CPU0_RSVD_304 @BASEBOARD_FAB2_LIB.BASEBOARD_FAB2(SCH_1):TP_CPU0_RSVD_304   I204 @BASEBOARD_FAB2_LIB.BASEBOARD_FAB2(SCH_1):PAGE22
    A6 TP_CPU0_RSVD_303 @BASEBOARD_FAB2_LIB.BASEBOARD_FAB2(SCH_1):TP_CPU0_RSVD_303   I204 @BASEBOARD_FAB2_LIB.BASEBOARD_FAB2(SCH_1):PAGE22
   A14 P1V8_MCP_CPU0 @BASEBOARD_FAB2_LIB.BASEBOARD_FAB2(SCH_1):P1V8_MCP_CPU0   I204 @BASEBOARD_FAB2_LIB.BASEBOARD_FAB2(SCH_1):PAGE22
   A16 P1V8_MCP_CPU0 @BASEBOARD_FAB2_LIB.BASEBOARD_FAB2(SCH_1):P1V8_MCP_CPU0   I204 @BASEBOARD_FAB2_LIB.BASEBOARD_FAB2(SCH_1):PAGE22
   A24 TP_CPU0_RSVD_300 @BASEBOARD_FAB2_LIB.BASEBOARD_FAB2(SCH_1):TP_CPU0_RSVD_300   I204 @BASEBOARD_FAB2_LIB.BASEBOARD_FAB2(SCH_1):PAGE22
    B3 TP_CPU0_RSVD_299 @BASEBOARD_FAB2_LIB.BASEBOARD_FAB2(SCH_1):TP_CPU0_RSVD_299   I204 @BASEBOARD_FAB2_LIB.BASEBOARD_FAB2(SCH_1):PAGE22
    B7 TP_CPU0_RSVD_298 @BASEBOARD_FAB2_LIB.BASEBOARD_FAB2(SCH_1):TP_CPU0_RSVD_298   I204 @BASEBOARD_FAB2_LIB.BASEBOARD_FAB2(SCH_1):PAGE22
   B13 P1V8_MCP_CPU0 @BASEBOARD_FAB2_LIB.BASEBOARD_FAB2(SCH_1):P1V8_MCP_CPU0   I204 @BASEBOARD_FAB2_LIB.BASEBOARD_FAB2(SCH_1):PAGE22
   B15 P1V8_MCP_CPU0 @BASEBOARD_FAB2_LIB.BASEBOARD_FAB2(SCH_1):P1V8_MCP_CPU0   I204 @BASEBOARD_FAB2_LIB.BASEBOARD_FAB2(SCH_1):PAGE22
   B17 P1V8_MCP_CPU0 @BASEBOARD_FAB2_LIB.BASEBOARD_FAB2(SCH_1):P1V8_MCP_CPU0   I204 @BASEBOARD_FAB2_LIB.BASEBOARD_FAB2(SCH_1):PAGE22
   B77 TP_CPU0_RSVD_293 @BASEBOARD_FAB2_LIB.BASEBOARD_FAB2(SCH_1):TP_CPU0_RSVD_293   I204 @BASEBOARD_FAB2_LIB.BASEBOARD_FAB2(SCH_1):PAGE22
   B81 TP_CPU0_RSVD_292 @BASEBOARD_FAB2_LIB.BASEBOARD_FAB2(SCH_1):TP_CPU0_RSVD_292   I204 @BASEBOARD_FAB2_LIB.BASEBOARD_FAB2(SCH_1):PAGE22
    C6 TP_CPU0_RSVD_291 @BASEBOARD_FAB2_LIB.BASEBOARD_FAB2(SCH_1):TP_CPU0_RSVD_291   I204 @BASEBOARD_FAB2_LIB.BASEBOARD_FAB2(SCH_1):PAGE22
   C18 TP_CPU0_RSVD_290 @BASEBOARD_FAB2_LIB.BASEBOARD_FAB2(SCH_1):TP_CPU0_RSVD_290   I204 @BASEBOARD_FAB2_LIB.BASEBOARD_FAB2(SCH_1):PAGE22
   C24 TP_CPU0_RSVD_289 @BASEBOARD_FAB2_LIB.BASEBOARD_FAB2(SCH_1):TP_CPU0_RSVD_289   I204 @BASEBOARD_FAB2_LIB.BASEBOARD_FAB2(SCH_1):PAGE22
   C82 TP_CPU0_RSVD_288 @BASEBOARD_FAB2_LIB.BASEBOARD_FAB2(SCH_1):TP_CPU0_RSVD_288   I204 @BASEBOARD_FAB2_LIB.BASEBOARD_FAB2(SCH_1):PAGE22
    D5 TP_CPU0_RSVD_287 @BASEBOARD_FAB2_LIB.BASEBOARD_FAB2(SCH_1):TP_CPU0_RSVD_287   I204 @BASEBOARD_FAB2_LIB.BASEBOARD_FAB2(SCH_1):PAGE22
   D17 TP_CPU0_RSVD_286 @BASEBOARD_FAB2_LIB.BASEBOARD_FAB2(SCH_1):TP_CPU0_RSVD_286   I204 @BASEBOARD_FAB2_LIB.BASEBOARD_FAB2(SCH_1):PAGE22
   D65 TP_CPU0_RSVD_285 @BASEBOARD_FAB2_LIB.BASEBOARD_FAB2(SCH_1):TP_CPU0_RSVD_285   I204 @BASEBOARD_FAB2_LIB.BASEBOARD_FAB2(SCH_1):PAGE22
   D83 TP_CPU0_RSVD_284 @BASEBOARD_FAB2_LIB.BASEBOARD_FAB2(SCH_1):TP_CPU0_RSVD_284   I204 @BASEBOARD_FAB2_LIB.BASEBOARD_FAB2(SCH_1):PAGE22
    E2 TP_CPU0_RSVD_283 @BASEBOARD_FAB2_LIB.BASEBOARD_FAB2(SCH_1):TP_CPU0_RSVD_283   I204 @BASEBOARD_FAB2_LIB.BASEBOARD_FAB2(SCH_1):PAGE22
    E4 TP_CPU0_RSVD_282 @BASEBOARD_FAB2_LIB.BASEBOARD_FAB2(SCH_1):TP_CPU0_RSVD_282   I204 @BASEBOARD_FAB2_LIB.BASEBOARD_FAB2(SCH_1):PAGE22
   E24 TP_CPU0_RSVD_281 @BASEBOARD_FAB2_LIB.BASEBOARD_FAB2(SCH_1):TP_CPU0_RSVD_281   I204 @BASEBOARD_FAB2_LIB.BASEBOARD_FAB2(SCH_1):PAGE22
   E84 TP_CPU0_RSVD_280 @BASEBOARD_FAB2_LIB.BASEBOARD_FAB2(SCH_1):TP_CPU0_RSVD_280   I204 @BASEBOARD_FAB2_LIB.BASEBOARD_FAB2(SCH_1):PAGE22
    F3 TP_CPU0_RSVD_279 @BASEBOARD_FAB2_LIB.BASEBOARD_FAB2(SCH_1):TP_CPU0_RSVD_279   I204 @BASEBOARD_FAB2_LIB.BASEBOARD_FAB2(SCH_1):PAGE22
   F23 TP_CPU0_RSVD_278 @BASEBOARD_FAB2_LIB.BASEBOARD_FAB2(SCH_1):TP_CPU0_RSVD_278   I204 @BASEBOARD_FAB2_LIB.BASEBOARD_FAB2(SCH_1):PAGE22
   F65 TP_CPU0_RSVD_277 @BASEBOARD_FAB2_LIB.BASEBOARD_FAB2(SCH_1):TP_CPU0_RSVD_277   I204 @BASEBOARD_FAB2_LIB.BASEBOARD_FAB2(SCH_1):PAGE22
   F83 TP_CPU0_RSVD_276 @BASEBOARD_FAB2_LIB.BASEBOARD_FAB2(SCH_1):TP_CPU0_RSVD_276   I204 @BASEBOARD_FAB2_LIB.BASEBOARD_FAB2(SCH_1):PAGE22
    G2 TP_CPU0_RSVD_275 @BASEBOARD_FAB2_LIB.BASEBOARD_FAB2(SCH_1):TP_CPU0_RSVD_275   I204 @BASEBOARD_FAB2_LIB.BASEBOARD_FAB2(SCH_1):PAGE22
   G64 TP_CPU0_RSVD_274 @BASEBOARD_FAB2_LIB.BASEBOARD_FAB2(SCH_1):TP_CPU0_RSVD_274   I204 @BASEBOARD_FAB2_LIB.BASEBOARD_FAB2(SCH_1):PAGE22
   G84 TP_CPU0_RSVD_273 @BASEBOARD_FAB2_LIB.BASEBOARD_FAB2(SCH_1):TP_CPU0_RSVD_273   I204 @BASEBOARD_FAB2_LIB.BASEBOARD_FAB2(SCH_1):PAGE22
    H1 TP_CPU0_RSVD_272 @BASEBOARD_FAB2_LIB.BASEBOARD_FAB2(SCH_1):TP_CPU0_RSVD_272   I204 @BASEBOARD_FAB2_LIB.BASEBOARD_FAB2(SCH_1):PAGE22
   H83 TP_CPU0_RSVD_271 @BASEBOARD_FAB2_LIB.BASEBOARD_FAB2(SCH_1):TP_CPU0_RSVD_271   I204 @BASEBOARD_FAB2_LIB.BASEBOARD_FAB2(SCH_1):PAGE22
   H85 TP_CPU0_RSVD_270 @BASEBOARD_FAB2_LIB.BASEBOARD_FAB2(SCH_1):TP_CPU0_RSVD_270   I204 @BASEBOARD_FAB2_LIB.BASEBOARD_FAB2(SCH_1):PAGE22
   J46 TP_CPU0_RSVD_269 @BASEBOARD_FAB2_LIB.BASEBOARD_FAB2(SCH_1):TP_CPU0_RSVD_269   I204 @BASEBOARD_FAB2_LIB.BASEBOARD_FAB2(SCH_1):PAGE22
   J62 TP_CPU0_RSVD_268 @BASEBOARD_FAB2_LIB.BASEBOARD_FAB2(SCH_1):TP_CPU0_RSVD_268   I204 @BASEBOARD_FAB2_LIB.BASEBOARD_FAB2(SCH_1):PAGE22
   K61 TP_CPU0_RSVD_267 @BASEBOARD_FAB2_LIB.BASEBOARD_FAB2(SCH_1):TP_CPU0_RSVD_267   I204 @BASEBOARD_FAB2_LIB.BASEBOARD_FAB2(SCH_1):PAGE22
   M63 TP_CPU0_RSVD_266 @BASEBOARD_FAB2_LIB.BASEBOARD_FAB2(SCH_1):TP_CPU0_RSVD_266   I204 @BASEBOARD_FAB2_LIB.BASEBOARD_FAB2(SCH_1):PAGE22
   P65 TP_CPU0_RSVD_265 @BASEBOARD_FAB2_LIB.BASEBOARD_FAB2(SCH_1):TP_CPU0_RSVD_265   I204 @BASEBOARD_FAB2_LIB.BASEBOARD_FAB2(SCH_1):PAGE22
   R62 TP_CPU0_RSVD_264 @BASEBOARD_FAB2_LIB.BASEBOARD_FAB2(SCH_1):TP_CPU0_RSVD_264   I204 @BASEBOARD_FAB2_LIB.BASEBOARD_FAB2(SCH_1):PAGE22
   R66 TP_CPU0_RSVD_263 @BASEBOARD_FAB2_LIB.BASEBOARD_FAB2(SCH_1):TP_CPU0_RSVD_263   I204 @BASEBOARD_FAB2_LIB.BASEBOARD_FAB2(SCH_1):PAGE22
   T67 TP_CPU0_RSVD_262 @BASEBOARD_FAB2_LIB.BASEBOARD_FAB2(SCH_1):TP_CPU0_RSVD_262   I204 @BASEBOARD_FAB2_LIB.BASEBOARD_FAB2(SCH_1):PAGE22
   U66 TP_CPU0_RSVD_261 @BASEBOARD_FAB2_LIB.BASEBOARD_FAB2(SCH_1):TP_CPU0_RSVD_261   I204 @BASEBOARD_FAB2_LIB.BASEBOARD_FAB2(SCH_1):PAGE22
   V65 TP_CPU0_RSVD_260 @BASEBOARD_FAB2_LIB.BASEBOARD_FAB2(SCH_1):TP_CPU0_RSVD_260   I204 @BASEBOARD_FAB2_LIB.BASEBOARD_FAB2(SCH_1):PAGE22
   V67 TP_CPU0_RSVD_259 @BASEBOARD_FAB2_LIB.BASEBOARD_FAB2(SCH_1):TP_CPU0_RSVD_259   I204 @BASEBOARD_FAB2_LIB.BASEBOARD_FAB2(SCH_1):PAGE22
   W66 TP_CPU0_RSVD_258 @BASEBOARD_FAB2_LIB.BASEBOARD_FAB2(SCH_1):TP_CPU0_RSVD_258   I204 @BASEBOARD_FAB2_LIB.BASEBOARD_FAB2(SCH_1):PAGE22
   Y23 FM_CPU0_RC_ERROR_N @BASEBOARD_FAB2_LIB.BASEBOARD_FAB2(SCH_1):FM_CPU0_RC_ERROR_N   I204 @BASEBOARD_FAB2_LIB.BASEBOARD_FAB2(SCH_1):PAGE22
   Y65 TP_CPU0_RSVD_256 @BASEBOARD_FAB2_LIB.BASEBOARD_FAB2(SCH_1):TP_CPU0_RSVD_256   I204 @BASEBOARD_FAB2_LIB.BASEBOARD_FAB2(SCH_1):PAGE22
  AD47 TP_CPU0_RSVD_254 @BASEBOARD_FAB2_LIB.BASEBOARD_FAB2(SCH_1):TP_CPU0_RSVD_254   I204 @BASEBOARD_FAB2_LIB.BASEBOARD_FAB2(SCH_1):PAGE22
  AD49 TP_CPU0_RSVD_253 @BASEBOARD_FAB2_LIB.BASEBOARD_FAB2(SCH_1):TP_CPU0_RSVD_253   I204 @BASEBOARD_FAB2_LIB.BASEBOARD_FAB2(SCH_1):PAGE22
  AD51 TP_CPU0_RSVD_252 @BASEBOARD_FAB2_LIB.BASEBOARD_FAB2(SCH_1):TP_CPU0_RSVD_252   I204 @BASEBOARD_FAB2_LIB.BASEBOARD_FAB2(SCH_1):PAGE22
  AE46 TP_CPU0_RSVD_251 @BASEBOARD_FAB2_LIB.BASEBOARD_FAB2(SCH_1):TP_CPU0_RSVD_251   I204 @BASEBOARD_FAB2_LIB.BASEBOARD_FAB2(SCH_1):PAGE22
  AE48 TP_CPU0_RSVD_250 @BASEBOARD_FAB2_LIB.BASEBOARD_FAB2(SCH_1):TP_CPU0_RSVD_250   I204 @BASEBOARD_FAB2_LIB.BASEBOARD_FAB2(SCH_1):PAGE22
  AE50 TP_CPU0_RSVD_249 @BASEBOARD_FAB2_LIB.BASEBOARD_FAB2(SCH_1):TP_CPU0_RSVD_249   I204 @BASEBOARD_FAB2_LIB.BASEBOARD_FAB2(SCH_1):PAGE22
  AE52 TP_CPU0_RSVD_248 @BASEBOARD_FAB2_LIB.BASEBOARD_FAB2(SCH_1):TP_CPU0_RSVD_248   I204 @BASEBOARD_FAB2_LIB.BASEBOARD_FAB2(SCH_1):PAGE22
  AE72 TP_CPU0_RSVD_247 @BASEBOARD_FAB2_LIB.BASEBOARD_FAB2(SCH_1):TP_CPU0_RSVD_247   I204 @BASEBOARD_FAB2_LIB.BASEBOARD_FAB2(SCH_1):PAGE22
  AF19 TP_CPU0_RSVD_246 @BASEBOARD_FAB2_LIB.BASEBOARD_FAB2(SCH_1):TP_CPU0_RSVD_246   I204 @BASEBOARD_FAB2_LIB.BASEBOARD_FAB2(SCH_1):PAGE22
  AF47 TP_CPU0_RSVD_245 @BASEBOARD_FAB2_LIB.BASEBOARD_FAB2(SCH_1):TP_CPU0_RSVD_245   I204 @BASEBOARD_FAB2_LIB.BASEBOARD_FAB2(SCH_1):PAGE22
  AF49 TP_CPU0_RSVD_244 @BASEBOARD_FAB2_LIB.BASEBOARD_FAB2(SCH_1):TP_CPU0_RSVD_244   I204 @BASEBOARD_FAB2_LIB.BASEBOARD_FAB2(SCH_1):PAGE22
  AF51 TP_CPU0_RSVD_243 @BASEBOARD_FAB2_LIB.BASEBOARD_FAB2(SCH_1):TP_CPU0_RSVD_243   I204 @BASEBOARD_FAB2_LIB.BASEBOARD_FAB2(SCH_1):PAGE22
  AF53 TP_CPU0_RSVD_242 @BASEBOARD_FAB2_LIB.BASEBOARD_FAB2(SCH_1):TP_CPU0_RSVD_242   I204 @BASEBOARD_FAB2_LIB.BASEBOARD_FAB2(SCH_1):PAGE22
  AF71 TP_CPU0_RSVD_241 @BASEBOARD_FAB2_LIB.BASEBOARD_FAB2(SCH_1):TP_CPU0_RSVD_241   I204 @BASEBOARD_FAB2_LIB.BASEBOARD_FAB2(SCH_1):PAGE22
  AG20 TP_CPU0_RSVD_240 @BASEBOARD_FAB2_LIB.BASEBOARD_FAB2(SCH_1):TP_CPU0_RSVD_240   I204 @BASEBOARD_FAB2_LIB.BASEBOARD_FAB2(SCH_1):PAGE22
  AG48 TP_CPU0_RSVD_239 @BASEBOARD_FAB2_LIB.BASEBOARD_FAB2(SCH_1):TP_CPU0_RSVD_239   I204 @BASEBOARD_FAB2_LIB.BASEBOARD_FAB2(SCH_1):PAGE22
  AG50 TP_CPU0_RSVD_238 @BASEBOARD_FAB2_LIB.BASEBOARD_FAB2(SCH_1):TP_CPU0_RSVD_238   I204 @BASEBOARD_FAB2_LIB.BASEBOARD_FAB2(SCH_1):PAGE22
  AG52 TP_CPU0_RSVD_237 @BASEBOARD_FAB2_LIB.BASEBOARD_FAB2(SCH_1):TP_CPU0_RSVD_237   I204 @BASEBOARD_FAB2_LIB.BASEBOARD_FAB2(SCH_1):PAGE22
  AG54 TP_CPU0_RSVD_236 @BASEBOARD_FAB2_LIB.BASEBOARD_FAB2(SCH_1):TP_CPU0_RSVD_236   I204 @BASEBOARD_FAB2_LIB.BASEBOARD_FAB2(SCH_1):PAGE22
  AG56 TP_CPU0_RSVD_235 @BASEBOARD_FAB2_LIB.BASEBOARD_FAB2(SCH_1):TP_CPU0_RSVD_235   I204 @BASEBOARD_FAB2_LIB.BASEBOARD_FAB2(SCH_1):PAGE22
  AG72 TP_CPU0_RSVD_234 @BASEBOARD_FAB2_LIB.BASEBOARD_FAB2(SCH_1):TP_CPU0_RSVD_234   I204 @BASEBOARD_FAB2_LIB.BASEBOARD_FAB2(SCH_1):PAGE22
  AH15 TP_CPU0_RSVD_233 @BASEBOARD_FAB2_LIB.BASEBOARD_FAB2(SCH_1):TP_CPU0_RSVD_233   I204 @BASEBOARD_FAB2_LIB.BASEBOARD_FAB2(SCH_1):PAGE22
  AH19 TP_CPU0_RSVD_232 @BASEBOARD_FAB2_LIB.BASEBOARD_FAB2(SCH_1):TP_CPU0_RSVD_232   I204 @BASEBOARD_FAB2_LIB.BASEBOARD_FAB2(SCH_1):PAGE22
  AH55 TP_CPU0_RSVD_231 @BASEBOARD_FAB2_LIB.BASEBOARD_FAB2(SCH_1):TP_CPU0_RSVD_231   I204 @BASEBOARD_FAB2_LIB.BASEBOARD_FAB2(SCH_1):PAGE22
  AH57 TP_CPU0_RSVD_230 @BASEBOARD_FAB2_LIB.BASEBOARD_FAB2(SCH_1):TP_CPU0_RSVD_230   I204 @BASEBOARD_FAB2_LIB.BASEBOARD_FAB2(SCH_1):PAGE22
  AH71 TP_CPU0_RSVD_229 @BASEBOARD_FAB2_LIB.BASEBOARD_FAB2(SCH_1):TP_CPU0_RSVD_229   I204 @BASEBOARD_FAB2_LIB.BASEBOARD_FAB2(SCH_1):PAGE22
  AH73 TP_CPU0_RSVD_228 @BASEBOARD_FAB2_LIB.BASEBOARD_FAB2(SCH_1):TP_CPU0_RSVD_228   I204 @BASEBOARD_FAB2_LIB.BASEBOARD_FAB2(SCH_1):PAGE22
  AJ20 TP_CPU0_RSVD_227 @BASEBOARD_FAB2_LIB.BASEBOARD_FAB2(SCH_1):TP_CPU0_RSVD_227   I204 @BASEBOARD_FAB2_LIB.BASEBOARD_FAB2(SCH_1):PAGE22
  AJ56 TP_CPU0_RSVD_226 @BASEBOARD_FAB2_LIB.BASEBOARD_FAB2(SCH_1):TP_CPU0_RSVD_226   I204 @BASEBOARD_FAB2_LIB.BASEBOARD_FAB2(SCH_1):PAGE22
  AJ58 TP_CPU0_RSVD_225 @BASEBOARD_FAB2_LIB.BASEBOARD_FAB2(SCH_1):TP_CPU0_RSVD_225   I204 @BASEBOARD_FAB2_LIB.BASEBOARD_FAB2(SCH_1):PAGE22
  AJ60 TP_CPU0_RSVD_224 @BASEBOARD_FAB2_LIB.BASEBOARD_FAB2(SCH_1):TP_CPU0_RSVD_224   I204 @BASEBOARD_FAB2_LIB.BASEBOARD_FAB2(SCH_1):PAGE22
  AJ62 TP_CPU0_RSVD_223 @BASEBOARD_FAB2_LIB.BASEBOARD_FAB2(SCH_1):TP_CPU0_RSVD_223   I204 @BASEBOARD_FAB2_LIB.BASEBOARD_FAB2(SCH_1):PAGE22
  AJ70 TP_CPU0_RSVD_222 @BASEBOARD_FAB2_LIB.BASEBOARD_FAB2(SCH_1):TP_CPU0_RSVD_222   I204 @BASEBOARD_FAB2_LIB.BASEBOARD_FAB2(SCH_1):PAGE22
  AK21 VSENSE_P1V8MCP_CPU0_SKT_VSEN @BASEBOARD_FAB2_LIB.BASEBOARD_FAB2(SCH_1):VSENSE_P1V8MCP_CPU0_SKT_VSEN   I204 @BASEBOARD_FAB2_LIB.BASEBOARD_FAB2(SCH_1):PAGE22
  AK27 CLK_322M_OSC_CPU0_RC_DP @BASEBOARD_FAB2_LIB.BASEBOARD_FAB2(SCH_1):CLK_322M_OSC_CPU0_RC_DP   I204 @BASEBOARD_FAB2_LIB.BASEBOARD_FAB2(SCH_1):PAGE22
  AK57 TP_CPU0_RSVD_219 @BASEBOARD_FAB2_LIB.BASEBOARD_FAB2(SCH_1):TP_CPU0_RSVD_219   I204 @BASEBOARD_FAB2_LIB.BASEBOARD_FAB2(SCH_1):PAGE22
  AK59 TP_CPU0_RSVD_218 @BASEBOARD_FAB2_LIB.BASEBOARD_FAB2(SCH_1):TP_CPU0_RSVD_218   I204 @BASEBOARD_FAB2_LIB.BASEBOARD_FAB2(SCH_1):PAGE22
  AK61 TP_CPU0_RSVD_217 @BASEBOARD_FAB2_LIB.BASEBOARD_FAB2(SCH_1):TP_CPU0_RSVD_217   I204 @BASEBOARD_FAB2_LIB.BASEBOARD_FAB2(SCH_1):PAGE22
  AK69 TP_CPU0_RSVD_216 @BASEBOARD_FAB2_LIB.BASEBOARD_FAB2(SCH_1):TP_CPU0_RSVD_216   I204 @BASEBOARD_FAB2_LIB.BASEBOARD_FAB2(SCH_1):PAGE22
  AL20 VSENSE_P1V8MCP_CPU0_SKT_VRTN @BASEBOARD_FAB2_LIB.BASEBOARD_FAB2(SCH_1):VSENSE_P1V8MCP_CPU0_SKT_VRTN   I204 @BASEBOARD_FAB2_LIB.BASEBOARD_FAB2(SCH_1):PAGE22
  AL22 TP_CPU0_RSVD_214 @BASEBOARD_FAB2_LIB.BASEBOARD_FAB2(SCH_1):TP_CPU0_RSVD_214   I204 @BASEBOARD_FAB2_LIB.BASEBOARD_FAB2(SCH_1):PAGE22
  AL26 CLK_322M_OSC_CPU0_RC_DN @BASEBOARD_FAB2_LIB.BASEBOARD_FAB2(SCH_1):CLK_322M_OSC_CPU0_RC_DN   I204 @BASEBOARD_FAB2_LIB.BASEBOARD_FAB2(SCH_1):PAGE22
  AL58 TP_CPU0_RSVD_212 @BASEBOARD_FAB2_LIB.BASEBOARD_FAB2(SCH_1):TP_CPU0_RSVD_212   I204 @BASEBOARD_FAB2_LIB.BASEBOARD_FAB2(SCH_1):PAGE22
  AL60 TP_CPU0_RSVD_211 @BASEBOARD_FAB2_LIB.BASEBOARD_FAB2(SCH_1):TP_CPU0_RSVD_211   I204 @BASEBOARD_FAB2_LIB.BASEBOARD_FAB2(SCH_1):PAGE22
  AL62 TP_CPU0_RSVD_210 @BASEBOARD_FAB2_LIB.BASEBOARD_FAB2(SCH_1):TP_CPU0_RSVD_210   I204 @BASEBOARD_FAB2_LIB.BASEBOARD_FAB2(SCH_1):PAGE22
  AM21 PVCCMCP_CPU0 @BASEBOARD_FAB2_LIB.BASEBOARD_FAB2(SCH_1):PVCCMCP_CPU0   I204 @BASEBOARD_FAB2_LIB.BASEBOARD_FAB2(SCH_1):PAGE22
  AM23 TP_CPU0_RSVD_208 @BASEBOARD_FAB2_LIB.BASEBOARD_FAB2(SCH_1):TP_CPU0_RSVD_208   I204 @BASEBOARD_FAB2_LIB.BASEBOARD_FAB2(SCH_1):PAGE22
  AM25 PVCCMCP_CPU0 @BASEBOARD_FAB2_LIB.BASEBOARD_FAB2(SCH_1):PVCCMCP_CPU0   I204 @BASEBOARD_FAB2_LIB.BASEBOARD_FAB2(SCH_1):PAGE22
  AM27 CLK_100M_CPU0_RC_REFCLK0_DP @BASEBOARD_FAB2_LIB.BASEBOARD_FAB2(SCH_1):CLK_100M_CPU0_RC_REFCLK0_DP   I204 @BASEBOARD_FAB2_LIB.BASEBOARD_FAB2(SCH_1):PAGE22
  AM59 TP_CPU0_RSVD_205 @BASEBOARD_FAB2_LIB.BASEBOARD_FAB2(SCH_1):TP_CPU0_RSVD_205   I204 @BASEBOARD_FAB2_LIB.BASEBOARD_FAB2(SCH_1):PAGE22
  AM61 TP_CPU0_RSVD_204 @BASEBOARD_FAB2_LIB.BASEBOARD_FAB2(SCH_1):TP_CPU0_RSVD_204   I204 @BASEBOARD_FAB2_LIB.BASEBOARD_FAB2(SCH_1):PAGE22
  AN18 PVCCMCP_CPU0 @BASEBOARD_FAB2_LIB.BASEBOARD_FAB2(SCH_1):PVCCMCP_CPU0   I204 @BASEBOARD_FAB2_LIB.BASEBOARD_FAB2(SCH_1):PAGE22
  AN22 PVCCMCP_CPU0 @BASEBOARD_FAB2_LIB.BASEBOARD_FAB2(SCH_1):PVCCMCP_CPU0   I204 @BASEBOARD_FAB2_LIB.BASEBOARD_FAB2(SCH_1):PAGE22
  AN24 PVCCMCP_CPU0 @BASEBOARD_FAB2_LIB.BASEBOARD_FAB2(SCH_1):PVCCMCP_CPU0   I204 @BASEBOARD_FAB2_LIB.BASEBOARD_FAB2(SCH_1):PAGE22
  AN26 PVCCMCP_CPU0 @BASEBOARD_FAB2_LIB.BASEBOARD_FAB2(SCH_1):PVCCMCP_CPU0   I204 @BASEBOARD_FAB2_LIB.BASEBOARD_FAB2(SCH_1):PAGE22
  AN60 TP_CPU0_RSVD_199 @BASEBOARD_FAB2_LIB.BASEBOARD_FAB2(SCH_1):TP_CPU0_RSVD_199   I204 @BASEBOARD_FAB2_LIB.BASEBOARD_FAB2(SCH_1):PAGE22
  AN62 TP_CPU0_RSVD_198 @BASEBOARD_FAB2_LIB.BASEBOARD_FAB2(SCH_1):TP_CPU0_RSVD_198   I204 @BASEBOARD_FAB2_LIB.BASEBOARD_FAB2(SCH_1):PAGE22
  AP23 PVCCMCP_CPU0 @BASEBOARD_FAB2_LIB.BASEBOARD_FAB2(SCH_1):PVCCMCP_CPU0   I204 @BASEBOARD_FAB2_LIB.BASEBOARD_FAB2(SCH_1):PAGE22
  AP25 PVCCMCP_CPU0 @BASEBOARD_FAB2_LIB.BASEBOARD_FAB2(SCH_1):PVCCMCP_CPU0   I204 @BASEBOARD_FAB2_LIB.BASEBOARD_FAB2(SCH_1):PAGE22
  AP27 CLK_100M_CPU0_RC_REFCLK0_DN @BASEBOARD_FAB2_LIB.BASEBOARD_FAB2(SCH_1):CLK_100M_CPU0_RC_REFCLK0_DN   I204 @BASEBOARD_FAB2_LIB.BASEBOARD_FAB2(SCH_1):PAGE22
  AP61 TP_CPU0_RSVD_194 @BASEBOARD_FAB2_LIB.BASEBOARD_FAB2(SCH_1):TP_CPU0_RSVD_194   I204 @BASEBOARD_FAB2_LIB.BASEBOARD_FAB2(SCH_1):PAGE22
  AF45 PD_CPU0_RSVD_TEST_1 @BASEBOARD_FAB2_LIB.BASEBOARD_FAB2(SCH_1):PD_CPU0_RSVD_TEST_1   I204 @BASEBOARD_FAB2_LIB.BASEBOARD_FAB2(SCH_1):PAGE22
  AY13 TP_CPU0_RSVD_TEST_11 @BASEBOARD_FAB2_LIB.BASEBOARD_FAB2(SCH_1):TP_CPU0_RSVD_TEST_11   I204 @BASEBOARD_FAB2_LIB.BASEBOARD_FAB2(SCH_1):PAGE22
  AG46 PD_CPU0_RSVD_TEST_2 @BASEBOARD_FAB2_LIB.BASEBOARD_FAB2(SCH_1):PD_CPU0_RSVD_TEST_2   I204 @BASEBOARD_FAB2_LIB.BASEBOARD_FAB2(SCH_1):PAGE22
  AM13 TP_CPU0_RSVD_TEST_3 @BASEBOARD_FAB2_LIB.BASEBOARD_FAB2(SCH_1):TP_CPU0_RSVD_TEST_3   I204 @BASEBOARD_FAB2_LIB.BASEBOARD_FAB2(SCH_1):PAGE22
  AN12 TP_CPU0_RSVD_TEST_4 @BASEBOARD_FAB2_LIB.BASEBOARD_FAB2(SCH_1):TP_CPU0_RSVD_TEST_4   I204 @BASEBOARD_FAB2_LIB.BASEBOARD_FAB2(SCH_1):PAGE22
  AN14 TP_CPU0_RSVD_TEST_5 @BASEBOARD_FAB2_LIB.BASEBOARD_FAB2(SCH_1):TP_CPU0_RSVD_TEST_5   I204 @BASEBOARD_FAB2_LIB.BASEBOARD_FAB2(SCH_1):PAGE22
   J60 M_A_ACT_N @BASEBOARD_FAB2_LIB.BASEBOARD_FAB2(SCH_1):M_A_ACT_N   I172 @BASEBOARD_FAB2_LIB.BASEBOARD_FAB2(SCH_1):PAGE23
   B61 M_A_ALERT_N @BASEBOARD_FAB2_LIB.BASEBOARD_FAB2(SCH_1):M_A_ALERT_N   I172 @BASEBOARD_FAB2_LIB.BASEBOARD_FAB2(SCH_1):PAGE23
   G54 M_A_BA<1> @BASEBOARD_FAB2_LIB.BASEBOARD_FAB2(SCH_1):M_A_BA(1)   I172 @BASEBOARD_FAB2_LIB.BASEBOARD_FAB2(SCH_1):PAGE23
   C52 M_A_BA<0> @BASEBOARD_FAB2_LIB.BASEBOARD_FAB2(SCH_1):M_A_BA(0)   I172 @BASEBOARD_FAB2_LIB.BASEBOARD_FAB2(SCH_1):PAGE23
   F63 M_A_BG<1> @BASEBOARD_FAB2_LIB.BASEBOARD_FAB2(SCH_1):M_A_BG(1)   I172 @BASEBOARD_FAB2_LIB.BASEBOARD_FAB2(SCH_1):PAGE23
   D61 M_A_BG<0> @BASEBOARD_FAB2_LIB.BASEBOARD_FAB2(SCH_1):M_A_BG(0)   I172 @BASEBOARD_FAB2_LIB.BASEBOARD_FAB2(SCH_1):PAGE23
   G46 M_A_C<2> @BASEBOARD_FAB2_LIB.BASEBOARD_FAB2(SCH_1):M_A_C(2)   I172 @BASEBOARD_FAB2_LIB.BASEBOARD_FAB2(SCH_1):PAGE23
   D63 M_A_CKE<3> @BASEBOARD_FAB2_LIB.BASEBOARD_FAB2(SCH_1):M_A_CKE(3)   I172 @BASEBOARD_FAB2_LIB.BASEBOARD_FAB2(SCH_1):PAGE23
   B63 M_A_CKE<2> @BASEBOARD_FAB2_LIB.BASEBOARD_FAB2(SCH_1):M_A_CKE(2)   I172 @BASEBOARD_FAB2_LIB.BASEBOARD_FAB2(SCH_1):PAGE23
   C64 M_A_CKE<1> @BASEBOARD_FAB2_LIB.BASEBOARD_FAB2(SCH_1):M_A_CKE(1)   I172 @BASEBOARD_FAB2_LIB.BASEBOARD_FAB2(SCH_1):PAGE23
   C62 M_A_CKE<0> @BASEBOARD_FAB2_LIB.BASEBOARD_FAB2(SCH_1):M_A_CKE(0)   I172 @BASEBOARD_FAB2_LIB.BASEBOARD_FAB2(SCH_1):PAGE23
   C56 M_A_CLK_DN<3> @BASEBOARD_FAB2_LIB.BASEBOARD_FAB2(SCH_1):M_A_CLK_DN(3)   I172 @BASEBOARD_FAB2_LIB.BASEBOARD_FAB2(SCH_1):PAGE23
   J56 M_A_CLK_DN<2> @BASEBOARD_FAB2_LIB.BASEBOARD_FAB2(SCH_1):M_A_CLK_DN(2)   I172 @BASEBOARD_FAB2_LIB.BASEBOARD_FAB2(SCH_1):PAGE23
   C54 M_A_CLK_DN<1> @BASEBOARD_FAB2_LIB.BASEBOARD_FAB2(SCH_1):M_A_CLK_DN(1)   I172 @BASEBOARD_FAB2_LIB.BASEBOARD_FAB2(SCH_1):PAGE23
   F55 M_A_CLK_DN<0> @BASEBOARD_FAB2_LIB.BASEBOARD_FAB2(SCH_1):M_A_CLK_DN(0)   I172 @BASEBOARD_FAB2_LIB.BASEBOARD_FAB2(SCH_1):PAGE23
   B57 M_A_CLK_DP<3> @BASEBOARD_FAB2_LIB.BASEBOARD_FAB2(SCH_1):M_A_CLK_DP(3)   I172 @BASEBOARD_FAB2_LIB.BASEBOARD_FAB2(SCH_1):PAGE23
   G56 M_A_CLK_DP<2> @BASEBOARD_FAB2_LIB.BASEBOARD_FAB2(SCH_1):M_A_CLK_DP(2)   I172 @BASEBOARD_FAB2_LIB.BASEBOARD_FAB2(SCH_1):PAGE23
   B55 M_A_CLK_DP<1> @BASEBOARD_FAB2_LIB.BASEBOARD_FAB2(SCH_1):M_A_CLK_DP(1)   I172 @BASEBOARD_FAB2_LIB.BASEBOARD_FAB2(SCH_1):PAGE23
   D55 M_A_CLK_DP<0> @BASEBOARD_FAB2_LIB.BASEBOARD_FAB2(SCH_1):M_A_CLK_DP(0)   I172 @BASEBOARD_FAB2_LIB.BASEBOARD_FAB2(SCH_1):PAGE23
   K45 M_A_CS_N<7> @BASEBOARD_FAB2_LIB.BASEBOARD_FAB2(SCH_1):M_A_CS_N(7)   I172 @BASEBOARD_FAB2_LIB.BASEBOARD_FAB2(SCH_1):PAGE23
   F45 M_A_CS_N<6> @BASEBOARD_FAB2_LIB.BASEBOARD_FAB2(SCH_1):M_A_CS_N(6)   I172 @BASEBOARD_FAB2_LIB.BASEBOARD_FAB2(SCH_1):PAGE23
   D49 M_A_CS_N<5> @BASEBOARD_FAB2_LIB.BASEBOARD_FAB2(SCH_1):M_A_CS_N(5)   I172 @BASEBOARD_FAB2_LIB.BASEBOARD_FAB2(SCH_1):PAGE23
   B51 M_A_CS_N<4> @BASEBOARD_FAB2_LIB.BASEBOARD_FAB2(SCH_1):M_A_CS_N(4)   I172 @BASEBOARD_FAB2_LIB.BASEBOARD_FAB2(SCH_1):PAGE23
   F47 M_A_CS_N<3> @BASEBOARD_FAB2_LIB.BASEBOARD_FAB2(SCH_1):M_A_CS_N(3)   I172 @BASEBOARD_FAB2_LIB.BASEBOARD_FAB2(SCH_1):PAGE23
   D47 M_A_CS_N<2> @BASEBOARD_FAB2_LIB.BASEBOARD_FAB2(SCH_1):M_A_CS_N(2)   I172 @BASEBOARD_FAB2_LIB.BASEBOARD_FAB2(SCH_1):PAGE23
   F49 M_A_CS_N<1> @BASEBOARD_FAB2_LIB.BASEBOARD_FAB2(SCH_1):M_A_CS_N(1)   I172 @BASEBOARD_FAB2_LIB.BASEBOARD_FAB2(SCH_1):PAGE23
   G52 M_A_CS_N<0> @BASEBOARD_FAB2_LIB.BASEBOARD_FAB2(SCH_1):M_A_CS_N(0)   I172 @BASEBOARD_FAB2_LIB.BASEBOARD_FAB2(SCH_1):PAGE23
   K23 M_A_DQ<63> @BASEBOARD_FAB2_LIB.BASEBOARD_FAB2(SCH_1):M_A_DQ(63)   I172 @BASEBOARD_FAB2_LIB.BASEBOARD_FAB2(SCH_1):PAGE23
   H23 M_A_DQ<62> @BASEBOARD_FAB2_LIB.BASEBOARD_FAB2(SCH_1):M_A_DQ(62)   I172 @BASEBOARD_FAB2_LIB.BASEBOARD_FAB2(SCH_1):PAGE23
   N26 M_A_DQ<61> @BASEBOARD_FAB2_LIB.BASEBOARD_FAB2(SCH_1):M_A_DQ(61)   I172 @BASEBOARD_FAB2_LIB.BASEBOARD_FAB2(SCH_1):PAGE23
   L26 M_A_DQ<60> @BASEBOARD_FAB2_LIB.BASEBOARD_FAB2(SCH_1):M_A_DQ(60)   I172 @BASEBOARD_FAB2_LIB.BASEBOARD_FAB2(SCH_1):PAGE23
   T23 M_A_DQ<59> @BASEBOARD_FAB2_LIB.BASEBOARD_FAB2(SCH_1):M_A_DQ(59)   I172 @BASEBOARD_FAB2_LIB.BASEBOARD_FAB2(SCH_1):PAGE23
   P23 M_A_DQ<58> @BASEBOARD_FAB2_LIB.BASEBOARD_FAB2(SCH_1):M_A_DQ(58)   I172 @BASEBOARD_FAB2_LIB.BASEBOARD_FAB2(SCH_1):PAGE23
   P25 M_A_DQ<57> @BASEBOARD_FAB2_LIB.BASEBOARD_FAB2(SCH_1):M_A_DQ(57)   I172 @BASEBOARD_FAB2_LIB.BASEBOARD_FAB2(SCH_1):PAGE23
   K25 M_A_DQ<56> @BASEBOARD_FAB2_LIB.BASEBOARD_FAB2(SCH_1):M_A_DQ(56)   I172 @BASEBOARD_FAB2_LIB.BASEBOARD_FAB2(SCH_1):PAGE23
   P29 M_A_DQ<55> @BASEBOARD_FAB2_LIB.BASEBOARD_FAB2(SCH_1):M_A_DQ(55)   I172 @BASEBOARD_FAB2_LIB.BASEBOARD_FAB2(SCH_1):PAGE23
   K29 M_A_DQ<54> @BASEBOARD_FAB2_LIB.BASEBOARD_FAB2(SCH_1):M_A_DQ(54)   I172 @BASEBOARD_FAB2_LIB.BASEBOARD_FAB2(SCH_1):PAGE23
   N32 M_A_DQ<53> @BASEBOARD_FAB2_LIB.BASEBOARD_FAB2(SCH_1):M_A_DQ(53)   I172 @BASEBOARD_FAB2_LIB.BASEBOARD_FAB2(SCH_1):PAGE23
   L32 M_A_DQ<52> @BASEBOARD_FAB2_LIB.BASEBOARD_FAB2(SCH_1):M_A_DQ(52)   I172 @BASEBOARD_FAB2_LIB.BASEBOARD_FAB2(SCH_1):PAGE23
   N28 M_A_DQ<51> @BASEBOARD_FAB2_LIB.BASEBOARD_FAB2(SCH_1):M_A_DQ(51)   I172 @BASEBOARD_FAB2_LIB.BASEBOARD_FAB2(SCH_1):PAGE23
   L28 M_A_DQ<50> @BASEBOARD_FAB2_LIB.BASEBOARD_FAB2(SCH_1):M_A_DQ(50)   I172 @BASEBOARD_FAB2_LIB.BASEBOARD_FAB2(SCH_1):PAGE23
   P31 M_A_DQ<49> @BASEBOARD_FAB2_LIB.BASEBOARD_FAB2(SCH_1):M_A_DQ(49)   I172 @BASEBOARD_FAB2_LIB.BASEBOARD_FAB2(SCH_1):PAGE23
   K31 M_A_DQ<48> @BASEBOARD_FAB2_LIB.BASEBOARD_FAB2(SCH_1):M_A_DQ(48)   I172 @BASEBOARD_FAB2_LIB.BASEBOARD_FAB2(SCH_1):PAGE23
   P35 M_A_DQ<47> @BASEBOARD_FAB2_LIB.BASEBOARD_FAB2(SCH_1):M_A_DQ(47)   I172 @BASEBOARD_FAB2_LIB.BASEBOARD_FAB2(SCH_1):PAGE23
   K35 M_A_DQ<46> @BASEBOARD_FAB2_LIB.BASEBOARD_FAB2(SCH_1):M_A_DQ(46)   I172 @BASEBOARD_FAB2_LIB.BASEBOARD_FAB2(SCH_1):PAGE23
   N38 M_A_DQ<45> @BASEBOARD_FAB2_LIB.BASEBOARD_FAB2(SCH_1):M_A_DQ(45)   I172 @BASEBOARD_FAB2_LIB.BASEBOARD_FAB2(SCH_1):PAGE23
   L38 M_A_DQ<44> @BASEBOARD_FAB2_LIB.BASEBOARD_FAB2(SCH_1):M_A_DQ(44)   I172 @BASEBOARD_FAB2_LIB.BASEBOARD_FAB2(SCH_1):PAGE23
   N34 M_A_DQ<43> @BASEBOARD_FAB2_LIB.BASEBOARD_FAB2(SCH_1):M_A_DQ(43)   I172 @BASEBOARD_FAB2_LIB.BASEBOARD_FAB2(SCH_1):PAGE23
   L34 M_A_DQ<42> @BASEBOARD_FAB2_LIB.BASEBOARD_FAB2(SCH_1):M_A_DQ(42)   I172 @BASEBOARD_FAB2_LIB.BASEBOARD_FAB2(SCH_1):PAGE23
   P37 M_A_DQ<41> @BASEBOARD_FAB2_LIB.BASEBOARD_FAB2(SCH_1):M_A_DQ(41)   I172 @BASEBOARD_FAB2_LIB.BASEBOARD_FAB2(SCH_1):PAGE23
   K37 M_A_DQ<40> @BASEBOARD_FAB2_LIB.BASEBOARD_FAB2(SCH_1):M_A_DQ(40)   I172 @BASEBOARD_FAB2_LIB.BASEBOARD_FAB2(SCH_1):PAGE23
   F39 M_A_DQ<39> @BASEBOARD_FAB2_LIB.BASEBOARD_FAB2(SCH_1):M_A_DQ(39)   I172 @BASEBOARD_FAB2_LIB.BASEBOARD_FAB2(SCH_1):PAGE23
   B39 M_A_DQ<38> @BASEBOARD_FAB2_LIB.BASEBOARD_FAB2(SCH_1):M_A_DQ(38)   I172 @BASEBOARD_FAB2_LIB.BASEBOARD_FAB2(SCH_1):PAGE23
   F41 M_A_DQ<37> @BASEBOARD_FAB2_LIB.BASEBOARD_FAB2(SCH_1):M_A_DQ(37)   I172 @BASEBOARD_FAB2_LIB.BASEBOARD_FAB2(SCH_1):PAGE23
   E42 M_A_DQ<36> @BASEBOARD_FAB2_LIB.BASEBOARD_FAB2(SCH_1):M_A_DQ(36)   I172 @BASEBOARD_FAB2_LIB.BASEBOARD_FAB2(SCH_1):PAGE23
   E38 M_A_DQ<35> @BASEBOARD_FAB2_LIB.BASEBOARD_FAB2(SCH_1):M_A_DQ(35)   I172 @BASEBOARD_FAB2_LIB.BASEBOARD_FAB2(SCH_1):PAGE23
   C38 M_A_DQ<34> @BASEBOARD_FAB2_LIB.BASEBOARD_FAB2(SCH_1):M_A_DQ(34)   I172 @BASEBOARD_FAB2_LIB.BASEBOARD_FAB2(SCH_1):PAGE23
   B41 M_A_DQ<33> @BASEBOARD_FAB2_LIB.BASEBOARD_FAB2(SCH_1):M_A_DQ(33)   I172 @BASEBOARD_FAB2_LIB.BASEBOARD_FAB2(SCH_1):PAGE23
   C42 M_A_DQ<32> @BASEBOARD_FAB2_LIB.BASEBOARD_FAB2(SCH_1):M_A_DQ(32)   I172 @BASEBOARD_FAB2_LIB.BASEBOARD_FAB2(SCH_1):PAGE23
   R74 M_A_DQ<31> @BASEBOARD_FAB2_LIB.BASEBOARD_FAB2(SCH_1):M_A_DQ(31)   I172 @BASEBOARD_FAB2_LIB.BASEBOARD_FAB2(SCH_1):PAGE23
   L74 M_A_DQ<30> @BASEBOARD_FAB2_LIB.BASEBOARD_FAB2(SCH_1):M_A_DQ(30)   I172 @BASEBOARD_FAB2_LIB.BASEBOARD_FAB2(SCH_1):PAGE23
   P77 M_A_DQ<29> @BASEBOARD_FAB2_LIB.BASEBOARD_FAB2(SCH_1):M_A_DQ(29)   I172 @BASEBOARD_FAB2_LIB.BASEBOARD_FAB2(SCH_1):PAGE23
   M77 M_A_DQ<28> @BASEBOARD_FAB2_LIB.BASEBOARD_FAB2(SCH_1):M_A_DQ(28)   I172 @BASEBOARD_FAB2_LIB.BASEBOARD_FAB2(SCH_1):PAGE23
   P73 M_A_DQ<27> @BASEBOARD_FAB2_LIB.BASEBOARD_FAB2(SCH_1):M_A_DQ(27)   I172 @BASEBOARD_FAB2_LIB.BASEBOARD_FAB2(SCH_1):PAGE23
   M73 M_A_DQ<26> @BASEBOARD_FAB2_LIB.BASEBOARD_FAB2(SCH_1):M_A_DQ(26)   I172 @BASEBOARD_FAB2_LIB.BASEBOARD_FAB2(SCH_1):PAGE23
   R76 M_A_DQ<25> @BASEBOARD_FAB2_LIB.BASEBOARD_FAB2(SCH_1):M_A_DQ(25)   I172 @BASEBOARD_FAB2_LIB.BASEBOARD_FAB2(SCH_1):PAGE23
   L76 M_A_DQ<24> @BASEBOARD_FAB2_LIB.BASEBOARD_FAB2(SCH_1):M_A_DQ(24)   I172 @BASEBOARD_FAB2_LIB.BASEBOARD_FAB2(SCH_1):PAGE23
   N80 M_A_DQ<23> @BASEBOARD_FAB2_LIB.BASEBOARD_FAB2(SCH_1):M_A_DQ(23)   I172 @BASEBOARD_FAB2_LIB.BASEBOARD_FAB2(SCH_1):PAGE23
   R82 M_A_DQ<22> @BASEBOARD_FAB2_LIB.BASEBOARD_FAB2(SCH_1):M_A_DQ(22)   I172 @BASEBOARD_FAB2_LIB.BASEBOARD_FAB2(SCH_1):PAGE23
   V79 M_A_DQ<21> @BASEBOARD_FAB2_LIB.BASEBOARD_FAB2(SCH_1):M_A_DQ(21)   I172 @BASEBOARD_FAB2_LIB.BASEBOARD_FAB2(SCH_1):PAGE23
   W80 M_A_DQ<20> @BASEBOARD_FAB2_LIB.BASEBOARD_FAB2(SCH_1):M_A_DQ(20)   I172 @BASEBOARD_FAB2_LIB.BASEBOARD_FAB2(SCH_1):PAGE23
   M81 M_A_DQ<19> @BASEBOARD_FAB2_LIB.BASEBOARD_FAB2(SCH_1):M_A_DQ(19)   I172 @BASEBOARD_FAB2_LIB.BASEBOARD_FAB2(SCH_1):PAGE23
   N82 M_A_DQ<18> @BASEBOARD_FAB2_LIB.BASEBOARD_FAB2(SCH_1):M_A_DQ(18)   I172 @BASEBOARD_FAB2_LIB.BASEBOARD_FAB2(SCH_1):PAGE23
   T79 M_A_DQ<17> @BASEBOARD_FAB2_LIB.BASEBOARD_FAB2(SCH_1):M_A_DQ(17)   I172 @BASEBOARD_FAB2_LIB.BASEBOARD_FAB2(SCH_1):PAGE23
   V81 M_A_DQ<16> @BASEBOARD_FAB2_LIB.BASEBOARD_FAB2(SCH_1):M_A_DQ(16)   I172 @BASEBOARD_FAB2_LIB.BASEBOARD_FAB2(SCH_1):PAGE23
   N84 M_A_DQ<15> @BASEBOARD_FAB2_LIB.BASEBOARD_FAB2(SCH_1):M_A_DQ(15)   I172 @BASEBOARD_FAB2_LIB.BASEBOARD_FAB2(SCH_1):PAGE23
   N86 M_A_DQ<14> @BASEBOARD_FAB2_LIB.BASEBOARD_FAB2(SCH_1):M_A_DQ(14)   I172 @BASEBOARD_FAB2_LIB.BASEBOARD_FAB2(SCH_1):PAGE23
  AA84 M_A_DQ<13> @BASEBOARD_FAB2_LIB.BASEBOARD_FAB2(SCH_1):M_A_DQ(13)   I172 @BASEBOARD_FAB2_LIB.BASEBOARD_FAB2(SCH_1):PAGE23
  AA86 M_A_DQ<12> @BASEBOARD_FAB2_LIB.BASEBOARD_FAB2(SCH_1):M_A_DQ(12)   I172 @BASEBOARD_FAB2_LIB.BASEBOARD_FAB2(SCH_1):PAGE23
   L84 M_A_DQ<11> @BASEBOARD_FAB2_LIB.BASEBOARD_FAB2(SCH_1):M_A_DQ(11)   I172 @BASEBOARD_FAB2_LIB.BASEBOARD_FAB2(SCH_1):PAGE23
   L86 M_A_DQ<10> @BASEBOARD_FAB2_LIB.BASEBOARD_FAB2(SCH_1):M_A_DQ(10)   I172 @BASEBOARD_FAB2_LIB.BASEBOARD_FAB2(SCH_1):PAGE23
   W84 M_A_DQ<9> @BASEBOARD_FAB2_LIB.BASEBOARD_FAB2(SCH_1):M_A_DQ(9)   I172 @BASEBOARD_FAB2_LIB.BASEBOARD_FAB2(SCH_1):PAGE23
   W86 M_A_DQ<8> @BASEBOARD_FAB2_LIB.BASEBOARD_FAB2(SCH_1):M_A_DQ(8)   I172 @BASEBOARD_FAB2_LIB.BASEBOARD_FAB2(SCH_1):PAGE23
  AG84 M_A_DQ<7> @BASEBOARD_FAB2_LIB.BASEBOARD_FAB2(SCH_1):M_A_DQ(7)   I172 @BASEBOARD_FAB2_LIB.BASEBOARD_FAB2(SCH_1):PAGE23
  AG86 M_A_DQ<6> @BASEBOARD_FAB2_LIB.BASEBOARD_FAB2(SCH_1):M_A_DQ(6)   I172 @BASEBOARD_FAB2_LIB.BASEBOARD_FAB2(SCH_1):PAGE23
  AR84 M_A_DQ<5> @BASEBOARD_FAB2_LIB.BASEBOARD_FAB2(SCH_1):M_A_DQ(5)   I172 @BASEBOARD_FAB2_LIB.BASEBOARD_FAB2(SCH_1):PAGE23
  AR86 M_A_DQ<4> @BASEBOARD_FAB2_LIB.BASEBOARD_FAB2(SCH_1):M_A_DQ(4)   I172 @BASEBOARD_FAB2_LIB.BASEBOARD_FAB2(SCH_1):PAGE23
  AE84 M_A_DQ<3> @BASEBOARD_FAB2_LIB.BASEBOARD_FAB2(SCH_1):M_A_DQ(3)   I172 @BASEBOARD_FAB2_LIB.BASEBOARD_FAB2(SCH_1):PAGE23
  AE86 M_A_DQ<2> @BASEBOARD_FAB2_LIB.BASEBOARD_FAB2(SCH_1):M_A_DQ(2)   I172 @BASEBOARD_FAB2_LIB.BASEBOARD_FAB2(SCH_1):PAGE23
  AN84 M_A_DQ<1> @BASEBOARD_FAB2_LIB.BASEBOARD_FAB2(SCH_1):M_A_DQ(1)   I172 @BASEBOARD_FAB2_LIB.BASEBOARD_FAB2(SCH_1):PAGE23
  AN86 M_A_DQ<0> @BASEBOARD_FAB2_LIB.BASEBOARD_FAB2(SCH_1):M_A_DQ(0)   I172 @BASEBOARD_FAB2_LIB.BASEBOARD_FAB2(SCH_1):PAGE23
  AB67 M_A_DQS_DN<17> @BASEBOARD_FAB2_LIB.BASEBOARD_FAB2(SCH_1):M_A_DQS_DN(17)   I172 @BASEBOARD_FAB2_LIB.BASEBOARD_FAB2(SCH_1):PAGE23
   J24 M_A_DQS_DN<16> @BASEBOARD_FAB2_LIB.BASEBOARD_FAB2(SCH_1):M_A_DQS_DN(16)   I172 @BASEBOARD_FAB2_LIB.BASEBOARD_FAB2(SCH_1):PAGE23
   J30 M_A_DQS_DN<15> @BASEBOARD_FAB2_LIB.BASEBOARD_FAB2(SCH_1):M_A_DQS_DN(15)   I172 @BASEBOARD_FAB2_LIB.BASEBOARD_FAB2(SCH_1):PAGE23
   J36 M_A_DQS_DN<14> @BASEBOARD_FAB2_LIB.BASEBOARD_FAB2(SCH_1):M_A_DQS_DN(14)   I172 @BASEBOARD_FAB2_LIB.BASEBOARD_FAB2(SCH_1):PAGE23
   A40 M_A_DQS_DN<13> @BASEBOARD_FAB2_LIB.BASEBOARD_FAB2(SCH_1):M_A_DQS_DN(13)   I172 @BASEBOARD_FAB2_LIB.BASEBOARD_FAB2(SCH_1):PAGE23
   K75 M_A_DQS_DN<12> @BASEBOARD_FAB2_LIB.BASEBOARD_FAB2(SCH_1):M_A_DQS_DN(12)   I172 @BASEBOARD_FAB2_LIB.BASEBOARD_FAB2(SCH_1):PAGE23
   U82 M_A_DQS_DN<11> @BASEBOARD_FAB2_LIB.BASEBOARD_FAB2(SCH_1):M_A_DQS_DN(11)   I172 @BASEBOARD_FAB2_LIB.BASEBOARD_FAB2(SCH_1):PAGE23
   U84 M_A_DQS_DN<10> @BASEBOARD_FAB2_LIB.BASEBOARD_FAB2(SCH_1):M_A_DQS_DN(10)   I172 @BASEBOARD_FAB2_LIB.BASEBOARD_FAB2(SCH_1):PAGE23
  AL84 M_A_DQS_DN<9> @BASEBOARD_FAB2_LIB.BASEBOARD_FAB2(SCH_1):M_A_DQS_DN(9)   I172 @BASEBOARD_FAB2_LIB.BASEBOARD_FAB2(SCH_1):PAGE23
  AH67 M_A_DQS_DN<8> @BASEBOARD_FAB2_LIB.BASEBOARD_FAB2(SCH_1):M_A_DQS_DN(8)   I172 @BASEBOARD_FAB2_LIB.BASEBOARD_FAB2(SCH_1):PAGE23
   N24 M_A_DQS_DN<7> @BASEBOARD_FAB2_LIB.BASEBOARD_FAB2(SCH_1):M_A_DQS_DN(7)   I172 @BASEBOARD_FAB2_LIB.BASEBOARD_FAB2(SCH_1):PAGE23
   R30 M_A_DQS_DN<6> @BASEBOARD_FAB2_LIB.BASEBOARD_FAB2(SCH_1):M_A_DQS_DN(6)   I172 @BASEBOARD_FAB2_LIB.BASEBOARD_FAB2(SCH_1):PAGE23
   R36 M_A_DQS_DN<5> @BASEBOARD_FAB2_LIB.BASEBOARD_FAB2(SCH_1):M_A_DQS_DN(5)   I172 @BASEBOARD_FAB2_LIB.BASEBOARD_FAB2(SCH_1):PAGE23
   G40 M_A_DQS_DN<4> @BASEBOARD_FAB2_LIB.BASEBOARD_FAB2(SCH_1):M_A_DQS_DN(4)   I172 @BASEBOARD_FAB2_LIB.BASEBOARD_FAB2(SCH_1):PAGE23
   T75 M_A_DQS_DN<3> @BASEBOARD_FAB2_LIB.BASEBOARD_FAB2(SCH_1):M_A_DQS_DN(3)   I172 @BASEBOARD_FAB2_LIB.BASEBOARD_FAB2(SCH_1):PAGE23
   P79 M_A_DQS_DN<2> @BASEBOARD_FAB2_LIB.BASEBOARD_FAB2(SCH_1):M_A_DQS_DN(2)   I172 @BASEBOARD_FAB2_LIB.BASEBOARD_FAB2(SCH_1):PAGE23
   R84 M_A_DQS_DN<1> @BASEBOARD_FAB2_LIB.BASEBOARD_FAB2(SCH_1):M_A_DQS_DN(1)   I172 @BASEBOARD_FAB2_LIB.BASEBOARD_FAB2(SCH_1):PAGE23
  AJ84 M_A_DQS_DN<0> @BASEBOARD_FAB2_LIB.BASEBOARD_FAB2(SCH_1):M_A_DQS_DN(0)   I172 @BASEBOARD_FAB2_LIB.BASEBOARD_FAB2(SCH_1):PAGE23
  AD67 M_A_DQS_DP<17> @BASEBOARD_FAB2_LIB.BASEBOARD_FAB2(SCH_1):M_A_DQS_DP(17)   I172 @BASEBOARD_FAB2_LIB.BASEBOARD_FAB2(SCH_1):PAGE23
   L24 M_A_DQS_DP<16> @BASEBOARD_FAB2_LIB.BASEBOARD_FAB2(SCH_1):M_A_DQS_DP(16)   I172 @BASEBOARD_FAB2_LIB.BASEBOARD_FAB2(SCH_1):PAGE23
   L30 M_A_DQS_DP<15> @BASEBOARD_FAB2_LIB.BASEBOARD_FAB2(SCH_1):M_A_DQS_DP(15)   I172 @BASEBOARD_FAB2_LIB.BASEBOARD_FAB2(SCH_1):PAGE23
   L36 M_A_DQS_DP<14> @BASEBOARD_FAB2_LIB.BASEBOARD_FAB2(SCH_1):M_A_DQS_DP(14)   I172 @BASEBOARD_FAB2_LIB.BASEBOARD_FAB2(SCH_1):PAGE23
   C40 M_A_DQS_DP<13> @BASEBOARD_FAB2_LIB.BASEBOARD_FAB2(SCH_1):M_A_DQS_DP(13)   I172 @BASEBOARD_FAB2_LIB.BASEBOARD_FAB2(SCH_1):PAGE23
   M75 M_A_DQS_DP<12> @BASEBOARD_FAB2_LIB.BASEBOARD_FAB2(SCH_1):M_A_DQS_DP(12)   I172 @BASEBOARD_FAB2_LIB.BASEBOARD_FAB2(SCH_1):PAGE23
   T81 M_A_DQS_DP<11> @BASEBOARD_FAB2_LIB.BASEBOARD_FAB2(SCH_1):M_A_DQS_DP(11)   I172 @BASEBOARD_FAB2_LIB.BASEBOARD_FAB2(SCH_1):PAGE23
   V85 M_A_DQS_DP<10> @BASEBOARD_FAB2_LIB.BASEBOARD_FAB2(SCH_1):M_A_DQS_DP(10)   I172 @BASEBOARD_FAB2_LIB.BASEBOARD_FAB2(SCH_1):PAGE23
  AM85 M_A_DQS_DP<9> @BASEBOARD_FAB2_LIB.BASEBOARD_FAB2(SCH_1):M_A_DQS_DP(9)   I172 @BASEBOARD_FAB2_LIB.BASEBOARD_FAB2(SCH_1):PAGE23
  AF67 M_A_DQS_DP<8> @BASEBOARD_FAB2_LIB.BASEBOARD_FAB2(SCH_1):M_A_DQS_DP(8)   I172 @BASEBOARD_FAB2_LIB.BASEBOARD_FAB2(SCH_1):PAGE23
   R24 M_A_DQS_DP<7> @BASEBOARD_FAB2_LIB.BASEBOARD_FAB2(SCH_1):M_A_DQS_DP(7)   I172 @BASEBOARD_FAB2_LIB.BASEBOARD_FAB2(SCH_1):PAGE23
   N30 M_A_DQS_DP<6> @BASEBOARD_FAB2_LIB.BASEBOARD_FAB2(SCH_1):M_A_DQS_DP(6)   I172 @BASEBOARD_FAB2_LIB.BASEBOARD_FAB2(SCH_1):PAGE23
   N36 M_A_DQS_DP<5> @BASEBOARD_FAB2_LIB.BASEBOARD_FAB2(SCH_1):M_A_DQS_DP(5)   I172 @BASEBOARD_FAB2_LIB.BASEBOARD_FAB2(SCH_1):PAGE23
   E40 M_A_DQS_DP<4> @BASEBOARD_FAB2_LIB.BASEBOARD_FAB2(SCH_1):M_A_DQS_DP(4)   I172 @BASEBOARD_FAB2_LIB.BASEBOARD_FAB2(SCH_1):PAGE23
   P75 M_A_DQS_DP<3> @BASEBOARD_FAB2_LIB.BASEBOARD_FAB2(SCH_1):M_A_DQS_DP(3)   I172 @BASEBOARD_FAB2_LIB.BASEBOARD_FAB2(SCH_1):PAGE23
   R80 M_A_DQS_DP<2> @BASEBOARD_FAB2_LIB.BASEBOARD_FAB2(SCH_1):M_A_DQS_DP(2)   I172 @BASEBOARD_FAB2_LIB.BASEBOARD_FAB2(SCH_1):PAGE23
   P85 M_A_DQS_DP<1> @BASEBOARD_FAB2_LIB.BASEBOARD_FAB2(SCH_1):M_A_DQS_DP(1)   I172 @BASEBOARD_FAB2_LIB.BASEBOARD_FAB2(SCH_1):PAGE23
  AH85 M_A_DQS_DP<0> @BASEBOARD_FAB2_LIB.BASEBOARD_FAB2(SCH_1):M_A_DQS_DP(0)   I172 @BASEBOARD_FAB2_LIB.BASEBOARD_FAB2(SCH_1):PAGE23
  AG66 M_A_ECC<7> @BASEBOARD_FAB2_LIB.BASEBOARD_FAB2(SCH_1):M_A_ECC(7)   I172 @BASEBOARD_FAB2_LIB.BASEBOARD_FAB2(SCH_1):PAGE23
  AC66 M_A_ECC<6> @BASEBOARD_FAB2_LIB.BASEBOARD_FAB2(SCH_1):M_A_ECC(6)   I172 @BASEBOARD_FAB2_LIB.BASEBOARD_FAB2(SCH_1):PAGE23
  AF69 M_A_ECC<5> @BASEBOARD_FAB2_LIB.BASEBOARD_FAB2(SCH_1):M_A_ECC(5)   I172 @BASEBOARD_FAB2_LIB.BASEBOARD_FAB2(SCH_1):PAGE23
  AD69 M_A_ECC<4> @BASEBOARD_FAB2_LIB.BASEBOARD_FAB2(SCH_1):M_A_ECC(4)   I172 @BASEBOARD_FAB2_LIB.BASEBOARD_FAB2(SCH_1):PAGE23
  AF65 M_A_ECC<3> @BASEBOARD_FAB2_LIB.BASEBOARD_FAB2(SCH_1):M_A_ECC(3)   I172 @BASEBOARD_FAB2_LIB.BASEBOARD_FAB2(SCH_1):PAGE23
  AD65 M_A_ECC<2> @BASEBOARD_FAB2_LIB.BASEBOARD_FAB2(SCH_1):M_A_ECC(2)   I172 @BASEBOARD_FAB2_LIB.BASEBOARD_FAB2(SCH_1):PAGE23
  AG68 M_A_ECC<1> @BASEBOARD_FAB2_LIB.BASEBOARD_FAB2(SCH_1):M_A_ECC(1)   I172 @BASEBOARD_FAB2_LIB.BASEBOARD_FAB2(SCH_1):PAGE23
  AC68 M_A_ECC<0> @BASEBOARD_FAB2_LIB.BASEBOARD_FAB2(SCH_1):M_A_ECC(0)   I172 @BASEBOARD_FAB2_LIB.BASEBOARD_FAB2(SCH_1):PAGE23
   K47 M_A_MA<17> @BASEBOARD_FAB2_LIB.BASEBOARD_FAB2(SCH_1):M_A_MA(17)   I172 @BASEBOARD_FAB2_LIB.BASEBOARD_FAB2(SCH_1):PAGE23
   D51 M_A_MA<16> @BASEBOARD_FAB2_LIB.BASEBOARD_FAB2(SCH_1):M_A_MA(16)   I172 @BASEBOARD_FAB2_LIB.BASEBOARD_FAB2(SCH_1):PAGE23
   K49 M_A_MA<15> @BASEBOARD_FAB2_LIB.BASEBOARD_FAB2(SCH_1):M_A_MA(15)   I172 @BASEBOARD_FAB2_LIB.BASEBOARD_FAB2(SCH_1):PAGE23
   F51 M_A_MA<14> @BASEBOARD_FAB2_LIB.BASEBOARD_FAB2(SCH_1):M_A_MA(14)   I172 @BASEBOARD_FAB2_LIB.BASEBOARD_FAB2(SCH_1):PAGE23
   J48 M_A_MA<13> @BASEBOARD_FAB2_LIB.BASEBOARD_FAB2(SCH_1):M_A_MA(13)   I172 @BASEBOARD_FAB2_LIB.BASEBOARD_FAB2(SCH_1):PAGE23
   J64 M_A_MA<12> @BASEBOARD_FAB2_LIB.BASEBOARD_FAB2(SCH_1):M_A_MA(12)   I172 @BASEBOARD_FAB2_LIB.BASEBOARD_FAB2(SCH_1):PAGE23
   G62 M_A_MA<11> @BASEBOARD_FAB2_LIB.BASEBOARD_FAB2(SCH_1):M_A_MA(11)   I172 @BASEBOARD_FAB2_LIB.BASEBOARD_FAB2(SCH_1):PAGE23
   J54 M_A_MA<10> @BASEBOARD_FAB2_LIB.BASEBOARD_FAB2(SCH_1):M_A_MA(10)   I172 @BASEBOARD_FAB2_LIB.BASEBOARD_FAB2(SCH_1):PAGE23
   F61 M_A_MA<9> @BASEBOARD_FAB2_LIB.BASEBOARD_FAB2(SCH_1):M_A_MA(9)   I172 @BASEBOARD_FAB2_LIB.BASEBOARD_FAB2(SCH_1):PAGE23
   C60 M_A_MA<8> @BASEBOARD_FAB2_LIB.BASEBOARD_FAB2(SCH_1):M_A_MA(8)   I172 @BASEBOARD_FAB2_LIB.BASEBOARD_FAB2(SCH_1):PAGE23
   G60 M_A_MA<7> @BASEBOARD_FAB2_LIB.BASEBOARD_FAB2(SCH_1):M_A_MA(7)   I172 @BASEBOARD_FAB2_LIB.BASEBOARD_FAB2(SCH_1):PAGE23
   D59 M_A_MA<6> @BASEBOARD_FAB2_LIB.BASEBOARD_FAB2(SCH_1):M_A_MA(6)   I172 @BASEBOARD_FAB2_LIB.BASEBOARD_FAB2(SCH_1):PAGE23
   F59 M_A_MA<5> @BASEBOARD_FAB2_LIB.BASEBOARD_FAB2(SCH_1):M_A_MA(5)   I172 @BASEBOARD_FAB2_LIB.BASEBOARD_FAB2(SCH_1):PAGE23
   G58 M_A_MA<4> @BASEBOARD_FAB2_LIB.BASEBOARD_FAB2(SCH_1):M_A_MA(4)   I172 @BASEBOARD_FAB2_LIB.BASEBOARD_FAB2(SCH_1):PAGE23
   C58 M_A_MA<3> @BASEBOARD_FAB2_LIB.BASEBOARD_FAB2(SCH_1):M_A_MA(3)   I172 @BASEBOARD_FAB2_LIB.BASEBOARD_FAB2(SCH_1):PAGE23
   D57 M_A_MA<2> @BASEBOARD_FAB2_LIB.BASEBOARD_FAB2(SCH_1):M_A_MA(2)   I172 @BASEBOARD_FAB2_LIB.BASEBOARD_FAB2(SCH_1):PAGE23
   F57 M_A_MA<1> @BASEBOARD_FAB2_LIB.BASEBOARD_FAB2(SCH_1):M_A_MA(1)   I172 @BASEBOARD_FAB2_LIB.BASEBOARD_FAB2(SCH_1):PAGE23
   F53 M_A_MA<0> @BASEBOARD_FAB2_LIB.BASEBOARD_FAB2(SCH_1):M_A_MA(0)   I172 @BASEBOARD_FAB2_LIB.BASEBOARD_FAB2(SCH_1):PAGE23
   G48 M_A_ODT<3> @BASEBOARD_FAB2_LIB.BASEBOARD_FAB2(SCH_1):M_A_ODT(3)   I172 @BASEBOARD_FAB2_LIB.BASEBOARD_FAB2(SCH_1):PAGE23
   G50 M_A_ODT<2> @BASEBOARD_FAB2_LIB.BASEBOARD_FAB2(SCH_1):M_A_ODT(2)   I172 @BASEBOARD_FAB2_LIB.BASEBOARD_FAB2(SCH_1):PAGE23
   C48 M_A_ODT<1> @BASEBOARD_FAB2_LIB.BASEBOARD_FAB2(SCH_1):M_A_ODT(1)   I172 @BASEBOARD_FAB2_LIB.BASEBOARD_FAB2(SCH_1):PAGE23
   C50 M_A_ODT<0> @BASEBOARD_FAB2_LIB.BASEBOARD_FAB2(SCH_1):M_A_ODT(0)   I172 @BASEBOARD_FAB2_LIB.BASEBOARD_FAB2(SCH_1):PAGE23
   D53 M_A_PAR @BASEBOARD_FAB2_LIB.BASEBOARD_FAB2(SCH_1):M_A_PAR   I172 @BASEBOARD_FAB2_LIB.BASEBOARD_FAB2(SCH_1):PAGE23
   T63 M_B_ACT_N @BASEBOARD_FAB2_LIB.BASEBOARD_FAB2(SCH_1):M_B_ACT_N   I172 @BASEBOARD_FAB2_LIB.BASEBOARD_FAB2(SCH_1):PAGE24
   W62 M_B_ALERT_N @BASEBOARD_FAB2_LIB.BASEBOARD_FAB2(SCH_1):M_B_ALERT_N   I172 @BASEBOARD_FAB2_LIB.BASEBOARD_FAB2(SCH_1):PAGE24
   K55 M_B_BA<1> @BASEBOARD_FAB2_LIB.BASEBOARD_FAB2(SCH_1):M_B_BA(1)   I172 @BASEBOARD_FAB2_LIB.BASEBOARD_FAB2(SCH_1):PAGE24
   T53 M_B_BA<0> @BASEBOARD_FAB2_LIB.BASEBOARD_FAB2(SCH_1):M_B_BA(0)   I172 @BASEBOARD_FAB2_LIB.BASEBOARD_FAB2(SCH_1):PAGE24
   N60 M_B_BG<1> @BASEBOARD_FAB2_LIB.BASEBOARD_FAB2(SCH_1):M_B_BG(1)   I172 @BASEBOARD_FAB2_LIB.BASEBOARD_FAB2(SCH_1):PAGE24
   M61 M_B_BG<0> @BASEBOARD_FAB2_LIB.BASEBOARD_FAB2(SCH_1):M_B_BG(0)   I172 @BASEBOARD_FAB2_LIB.BASEBOARD_FAB2(SCH_1):PAGE24
   M47 M_B_C<2> @BASEBOARD_FAB2_LIB.BASEBOARD_FAB2(SCH_1):M_B_C(2)   I172 @BASEBOARD_FAB2_LIB.BASEBOARD_FAB2(SCH_1):PAGE24
   L64 M_B_CKE<3> @BASEBOARD_FAB2_LIB.BASEBOARD_FAB2(SCH_1):M_B_CKE(3)   I172 @BASEBOARD_FAB2_LIB.BASEBOARD_FAB2(SCH_1):PAGE24
   K63 M_B_CKE<2> @BASEBOARD_FAB2_LIB.BASEBOARD_FAB2(SCH_1):M_B_CKE(2)   I172 @BASEBOARD_FAB2_LIB.BASEBOARD_FAB2(SCH_1):PAGE24
   R64 M_B_CKE<1> @BASEBOARD_FAB2_LIB.BASEBOARD_FAB2(SCH_1):M_B_CKE(1)   I172 @BASEBOARD_FAB2_LIB.BASEBOARD_FAB2(SCH_1):PAGE24
   N62 M_B_CKE<0> @BASEBOARD_FAB2_LIB.BASEBOARD_FAB2(SCH_1):M_B_CKE(0)   I172 @BASEBOARD_FAB2_LIB.BASEBOARD_FAB2(SCH_1):PAGE24
   R56 M_B_CLK_DN<3> @BASEBOARD_FAB2_LIB.BASEBOARD_FAB2(SCH_1):M_B_CLK_DN(3)   I172 @BASEBOARD_FAB2_LIB.BASEBOARD_FAB2(SCH_1):PAGE24
   N56 M_B_CLK_DN<2> @BASEBOARD_FAB2_LIB.BASEBOARD_FAB2(SCH_1):M_B_CLK_DN(2)   I172 @BASEBOARD_FAB2_LIB.BASEBOARD_FAB2(SCH_1):PAGE24
   R54 M_B_CLK_DN<1> @BASEBOARD_FAB2_LIB.BASEBOARD_FAB2(SCH_1):M_B_CLK_DN(1)   I172 @BASEBOARD_FAB2_LIB.BASEBOARD_FAB2(SCH_1):PAGE24
   M53 M_B_CLK_DN<0> @BASEBOARD_FAB2_LIB.BASEBOARD_FAB2(SCH_1):M_B_CLK_DN(0)   I172 @BASEBOARD_FAB2_LIB.BASEBOARD_FAB2(SCH_1):PAGE24
   T57 M_B_CLK_DP<3> @BASEBOARD_FAB2_LIB.BASEBOARD_FAB2(SCH_1):M_B_CLK_DP(3)   I172 @BASEBOARD_FAB2_LIB.BASEBOARD_FAB2(SCH_1):PAGE24
   M57 M_B_CLK_DP<2> @BASEBOARD_FAB2_LIB.BASEBOARD_FAB2(SCH_1):M_B_CLK_DP(2)   I172 @BASEBOARD_FAB2_LIB.BASEBOARD_FAB2(SCH_1):PAGE24
   T55 M_B_CLK_DP<1> @BASEBOARD_FAB2_LIB.BASEBOARD_FAB2(SCH_1):M_B_CLK_DP(1)   I172 @BASEBOARD_FAB2_LIB.BASEBOARD_FAB2(SCH_1):PAGE24
   N54 M_B_CLK_DP<0> @BASEBOARD_FAB2_LIB.BASEBOARD_FAB2(SCH_1):M_B_CLK_DP(0)   I172 @BASEBOARD_FAB2_LIB.BASEBOARD_FAB2(SCH_1):PAGE24
   R46 M_B_CS_N<7> @BASEBOARD_FAB2_LIB.BASEBOARD_FAB2(SCH_1):M_B_CS_N(7)   I172 @BASEBOARD_FAB2_LIB.BASEBOARD_FAB2(SCH_1):PAGE24
   M45 M_B_CS_N<6> @BASEBOARD_FAB2_LIB.BASEBOARD_FAB2(SCH_1):M_B_CS_N(6)   I172 @BASEBOARD_FAB2_LIB.BASEBOARD_FAB2(SCH_1):PAGE24
   T49 M_B_CS_N<5> @BASEBOARD_FAB2_LIB.BASEBOARD_FAB2(SCH_1):M_B_CS_N(5)   I172 @BASEBOARD_FAB2_LIB.BASEBOARD_FAB2(SCH_1):PAGE24
   J50 M_B_CS_N<4> @BASEBOARD_FAB2_LIB.BASEBOARD_FAB2(SCH_1):M_B_CS_N(4)   I172 @BASEBOARD_FAB2_LIB.BASEBOARD_FAB2(SCH_1):PAGE24
   V47 M_B_CS_N<3> @BASEBOARD_FAB2_LIB.BASEBOARD_FAB2(SCH_1):M_B_CS_N(3)   I172 @BASEBOARD_FAB2_LIB.BASEBOARD_FAB2(SCH_1):PAGE24
   N46 M_B_CS_N<2> @BASEBOARD_FAB2_LIB.BASEBOARD_FAB2(SCH_1):M_B_CS_N(2)   I172 @BASEBOARD_FAB2_LIB.BASEBOARD_FAB2(SCH_1):PAGE24
   R50 M_B_CS_N<1> @BASEBOARD_FAB2_LIB.BASEBOARD_FAB2(SCH_1):M_B_CS_N(1)   I172 @BASEBOARD_FAB2_LIB.BASEBOARD_FAB2(SCH_1):PAGE24
   K51 M_B_CS_N<0> @BASEBOARD_FAB2_LIB.BASEBOARD_FAB2(SCH_1):M_B_CS_N(0)   I172 @BASEBOARD_FAB2_LIB.BASEBOARD_FAB2(SCH_1):PAGE24
  AA26 M_B_DQ<63> @BASEBOARD_FAB2_LIB.BASEBOARD_FAB2(SCH_1):M_B_DQ(63)   I172 @BASEBOARD_FAB2_LIB.BASEBOARD_FAB2(SCH_1):PAGE24
   U26 M_B_DQ<62> @BASEBOARD_FAB2_LIB.BASEBOARD_FAB2(SCH_1):M_B_DQ(62)   I172 @BASEBOARD_FAB2_LIB.BASEBOARD_FAB2(SCH_1):PAGE24
   Y29 M_B_DQ<61> @BASEBOARD_FAB2_LIB.BASEBOARD_FAB2(SCH_1):M_B_DQ(61)   I172 @BASEBOARD_FAB2_LIB.BASEBOARD_FAB2(SCH_1):PAGE24
   V29 M_B_DQ<60> @BASEBOARD_FAB2_LIB.BASEBOARD_FAB2(SCH_1):M_B_DQ(60)   I172 @BASEBOARD_FAB2_LIB.BASEBOARD_FAB2(SCH_1):PAGE24
   Y25 M_B_DQ<59> @BASEBOARD_FAB2_LIB.BASEBOARD_FAB2(SCH_1):M_B_DQ(59)   I172 @BASEBOARD_FAB2_LIB.BASEBOARD_FAB2(SCH_1):PAGE24
   V25 M_B_DQ<58> @BASEBOARD_FAB2_LIB.BASEBOARD_FAB2(SCH_1):M_B_DQ(58)   I172 @BASEBOARD_FAB2_LIB.BASEBOARD_FAB2(SCH_1):PAGE24
  AA28 M_B_DQ<57> @BASEBOARD_FAB2_LIB.BASEBOARD_FAB2(SCH_1):M_B_DQ(57)   I172 @BASEBOARD_FAB2_LIB.BASEBOARD_FAB2(SCH_1):PAGE24
   U28 M_B_DQ<56> @BASEBOARD_FAB2_LIB.BASEBOARD_FAB2(SCH_1):M_B_DQ(56)   I172 @BASEBOARD_FAB2_LIB.BASEBOARD_FAB2(SCH_1):PAGE24
   F27 M_B_DQ<55> @BASEBOARD_FAB2_LIB.BASEBOARD_FAB2(SCH_1):M_B_DQ(55)   I172 @BASEBOARD_FAB2_LIB.BASEBOARD_FAB2(SCH_1):PAGE24
   B27 M_B_DQ<54> @BASEBOARD_FAB2_LIB.BASEBOARD_FAB2(SCH_1):M_B_DQ(54)   I172 @BASEBOARD_FAB2_LIB.BASEBOARD_FAB2(SCH_1):PAGE24
   F29 M_B_DQ<53> @BASEBOARD_FAB2_LIB.BASEBOARD_FAB2(SCH_1):M_B_DQ(53)   I172 @BASEBOARD_FAB2_LIB.BASEBOARD_FAB2(SCH_1):PAGE24
   E30 M_B_DQ<52> @BASEBOARD_FAB2_LIB.BASEBOARD_FAB2(SCH_1):M_B_DQ(52)   I172 @BASEBOARD_FAB2_LIB.BASEBOARD_FAB2(SCH_1):PAGE24
   E26 M_B_DQ<51> @BASEBOARD_FAB2_LIB.BASEBOARD_FAB2(SCH_1):M_B_DQ(51)   I172 @BASEBOARD_FAB2_LIB.BASEBOARD_FAB2(SCH_1):PAGE24
   C26 M_B_DQ<50> @BASEBOARD_FAB2_LIB.BASEBOARD_FAB2(SCH_1):M_B_DQ(50)   I172 @BASEBOARD_FAB2_LIB.BASEBOARD_FAB2(SCH_1):PAGE24
   B29 M_B_DQ<49> @BASEBOARD_FAB2_LIB.BASEBOARD_FAB2(SCH_1):M_B_DQ(49)   I172 @BASEBOARD_FAB2_LIB.BASEBOARD_FAB2(SCH_1):PAGE24
   C30 M_B_DQ<48> @BASEBOARD_FAB2_LIB.BASEBOARD_FAB2(SCH_1):M_B_DQ(48)   I172 @BASEBOARD_FAB2_LIB.BASEBOARD_FAB2(SCH_1):PAGE24
   F33 M_B_DQ<47> @BASEBOARD_FAB2_LIB.BASEBOARD_FAB2(SCH_1):M_B_DQ(47)   I172 @BASEBOARD_FAB2_LIB.BASEBOARD_FAB2(SCH_1):PAGE24
   B33 M_B_DQ<46> @BASEBOARD_FAB2_LIB.BASEBOARD_FAB2(SCH_1):M_B_DQ(46)   I172 @BASEBOARD_FAB2_LIB.BASEBOARD_FAB2(SCH_1):PAGE24
   F35 M_B_DQ<45> @BASEBOARD_FAB2_LIB.BASEBOARD_FAB2(SCH_1):M_B_DQ(45)   I172 @BASEBOARD_FAB2_LIB.BASEBOARD_FAB2(SCH_1):PAGE24
   E36 M_B_DQ<44> @BASEBOARD_FAB2_LIB.BASEBOARD_FAB2(SCH_1):M_B_DQ(44)   I172 @BASEBOARD_FAB2_LIB.BASEBOARD_FAB2(SCH_1):PAGE24
   E32 M_B_DQ<43> @BASEBOARD_FAB2_LIB.BASEBOARD_FAB2(SCH_1):M_B_DQ(43)   I172 @BASEBOARD_FAB2_LIB.BASEBOARD_FAB2(SCH_1):PAGE24
   C32 M_B_DQ<42> @BASEBOARD_FAB2_LIB.BASEBOARD_FAB2(SCH_1):M_B_DQ(42)   I172 @BASEBOARD_FAB2_LIB.BASEBOARD_FAB2(SCH_1):PAGE24
   B35 M_B_DQ<41> @BASEBOARD_FAB2_LIB.BASEBOARD_FAB2(SCH_1):M_B_DQ(41)   I172 @BASEBOARD_FAB2_LIB.BASEBOARD_FAB2(SCH_1):PAGE24
   C36 M_B_DQ<40> @BASEBOARD_FAB2_LIB.BASEBOARD_FAB2(SCH_1):M_B_DQ(40)   I172 @BASEBOARD_FAB2_LIB.BASEBOARD_FAB2(SCH_1):PAGE24
   P41 M_B_DQ<39> @BASEBOARD_FAB2_LIB.BASEBOARD_FAB2(SCH_1):M_B_DQ(39)   I172 @BASEBOARD_FAB2_LIB.BASEBOARD_FAB2(SCH_1):PAGE24
   K41 M_B_DQ<38> @BASEBOARD_FAB2_LIB.BASEBOARD_FAB2(SCH_1):M_B_DQ(38)   I172 @BASEBOARD_FAB2_LIB.BASEBOARD_FAB2(SCH_1):PAGE24
   T43 M_B_DQ<37> @BASEBOARD_FAB2_LIB.BASEBOARD_FAB2(SCH_1):M_B_DQ(37)   I172 @BASEBOARD_FAB2_LIB.BASEBOARD_FAB2(SCH_1):PAGE24
   P43 M_B_DQ<36> @BASEBOARD_FAB2_LIB.BASEBOARD_FAB2(SCH_1):M_B_DQ(36)   I172 @BASEBOARD_FAB2_LIB.BASEBOARD_FAB2(SCH_1):PAGE24
   N40 M_B_DQ<35> @BASEBOARD_FAB2_LIB.BASEBOARD_FAB2(SCH_1):M_B_DQ(35)   I172 @BASEBOARD_FAB2_LIB.BASEBOARD_FAB2(SCH_1):PAGE24
   L40 M_B_DQ<34> @BASEBOARD_FAB2_LIB.BASEBOARD_FAB2(SCH_1):M_B_DQ(34)   I172 @BASEBOARD_FAB2_LIB.BASEBOARD_FAB2(SCH_1):PAGE24
   H43 M_B_DQ<33> @BASEBOARD_FAB2_LIB.BASEBOARD_FAB2(SCH_1):M_B_DQ(33)   I172 @BASEBOARD_FAB2_LIB.BASEBOARD_FAB2(SCH_1):PAGE24
   K43 M_B_DQ<32> @BASEBOARD_FAB2_LIB.BASEBOARD_FAB2(SCH_1):M_B_DQ(32)   I172 @BASEBOARD_FAB2_LIB.BASEBOARD_FAB2(SCH_1):PAGE24
   G72 M_B_DQ<31> @BASEBOARD_FAB2_LIB.BASEBOARD_FAB2(SCH_1):M_B_DQ(31)   I172 @BASEBOARD_FAB2_LIB.BASEBOARD_FAB2(SCH_1):PAGE24
   C72 M_B_DQ<30> @BASEBOARD_FAB2_LIB.BASEBOARD_FAB2(SCH_1):M_B_DQ(30)   I172 @BASEBOARD_FAB2_LIB.BASEBOARD_FAB2(SCH_1):PAGE24
   G74 M_B_DQ<29> @BASEBOARD_FAB2_LIB.BASEBOARD_FAB2(SCH_1):M_B_DQ(29)   I172 @BASEBOARD_FAB2_LIB.BASEBOARD_FAB2(SCH_1):PAGE24
   F75 M_B_DQ<28> @BASEBOARD_FAB2_LIB.BASEBOARD_FAB2(SCH_1):M_B_DQ(28)   I172 @BASEBOARD_FAB2_LIB.BASEBOARD_FAB2(SCH_1):PAGE24
   F71 M_B_DQ<27> @BASEBOARD_FAB2_LIB.BASEBOARD_FAB2(SCH_1):M_B_DQ(27)   I172 @BASEBOARD_FAB2_LIB.BASEBOARD_FAB2(SCH_1):PAGE24
   D71 M_B_DQ<26> @BASEBOARD_FAB2_LIB.BASEBOARD_FAB2(SCH_1):M_B_DQ(26)   I172 @BASEBOARD_FAB2_LIB.BASEBOARD_FAB2(SCH_1):PAGE24
   C74 M_B_DQ<25> @BASEBOARD_FAB2_LIB.BASEBOARD_FAB2(SCH_1):M_B_DQ(25)   I172 @BASEBOARD_FAB2_LIB.BASEBOARD_FAB2(SCH_1):PAGE24
   D75 M_B_DQ<24> @BASEBOARD_FAB2_LIB.BASEBOARD_FAB2(SCH_1):M_B_DQ(24)   I172 @BASEBOARD_FAB2_LIB.BASEBOARD_FAB2(SCH_1):PAGE24
   J78 M_B_DQ<23> @BASEBOARD_FAB2_LIB.BASEBOARD_FAB2(SCH_1):M_B_DQ(23)   I172 @BASEBOARD_FAB2_LIB.BASEBOARD_FAB2(SCH_1):PAGE24
   E78 M_B_DQ<22> @BASEBOARD_FAB2_LIB.BASEBOARD_FAB2(SCH_1):M_B_DQ(22)   I172 @BASEBOARD_FAB2_LIB.BASEBOARD_FAB2(SCH_1):PAGE24
   H81 M_B_DQ<21> @BASEBOARD_FAB2_LIB.BASEBOARD_FAB2(SCH_1):M_B_DQ(21)   I172 @BASEBOARD_FAB2_LIB.BASEBOARD_FAB2(SCH_1):PAGE24
   F81 M_B_DQ<20> @BASEBOARD_FAB2_LIB.BASEBOARD_FAB2(SCH_1):M_B_DQ(20)   I172 @BASEBOARD_FAB2_LIB.BASEBOARD_FAB2(SCH_1):PAGE24
   H77 M_B_DQ<19> @BASEBOARD_FAB2_LIB.BASEBOARD_FAB2(SCH_1):M_B_DQ(19)   I172 @BASEBOARD_FAB2_LIB.BASEBOARD_FAB2(SCH_1):PAGE24
   F77 M_B_DQ<18> @BASEBOARD_FAB2_LIB.BASEBOARD_FAB2(SCH_1):M_B_DQ(18)   I172 @BASEBOARD_FAB2_LIB.BASEBOARD_FAB2(SCH_1):PAGE24
   J80 M_B_DQ<17> @BASEBOARD_FAB2_LIB.BASEBOARD_FAB2(SCH_1):M_B_DQ(17)   I172 @BASEBOARD_FAB2_LIB.BASEBOARD_FAB2(SCH_1):PAGE24
   E80 M_B_DQ<16> @BASEBOARD_FAB2_LIB.BASEBOARD_FAB2(SCH_1):M_B_DQ(16)   I172 @BASEBOARD_FAB2_LIB.BASEBOARD_FAB2(SCH_1):PAGE24
  AC80 M_B_DQ<15> @BASEBOARD_FAB2_LIB.BASEBOARD_FAB2(SCH_1):M_B_DQ(15)   I172 @BASEBOARD_FAB2_LIB.BASEBOARD_FAB2(SCH_1):PAGE24
  AE82 M_B_DQ<14> @BASEBOARD_FAB2_LIB.BASEBOARD_FAB2(SCH_1):M_B_DQ(14)   I172 @BASEBOARD_FAB2_LIB.BASEBOARD_FAB2(SCH_1):PAGE24
  AH79 M_B_DQ<13> @BASEBOARD_FAB2_LIB.BASEBOARD_FAB2(SCH_1):M_B_DQ(13)   I172 @BASEBOARD_FAB2_LIB.BASEBOARD_FAB2(SCH_1):PAGE24
  AJ80 M_B_DQ<12> @BASEBOARD_FAB2_LIB.BASEBOARD_FAB2(SCH_1):M_B_DQ(12)   I172 @BASEBOARD_FAB2_LIB.BASEBOARD_FAB2(SCH_1):PAGE24
  AB81 M_B_DQ<11> @BASEBOARD_FAB2_LIB.BASEBOARD_FAB2(SCH_1):M_B_DQ(11)   I172 @BASEBOARD_FAB2_LIB.BASEBOARD_FAB2(SCH_1):PAGE24
  AC82 M_B_DQ<10> @BASEBOARD_FAB2_LIB.BASEBOARD_FAB2(SCH_1):M_B_DQ(10)   I172 @BASEBOARD_FAB2_LIB.BASEBOARD_FAB2(SCH_1):PAGE24
  AF79 M_B_DQ<9> @BASEBOARD_FAB2_LIB.BASEBOARD_FAB2(SCH_1):M_B_DQ(9)   I172 @BASEBOARD_FAB2_LIB.BASEBOARD_FAB2(SCH_1):PAGE24
  AH81 M_B_DQ<8> @BASEBOARD_FAB2_LIB.BASEBOARD_FAB2(SCH_1):M_B_DQ(8)   I172 @BASEBOARD_FAB2_LIB.BASEBOARD_FAB2(SCH_1):PAGE24
  AN80 M_B_DQ<7> @BASEBOARD_FAB2_LIB.BASEBOARD_FAB2(SCH_1):M_B_DQ(7)   I172 @BASEBOARD_FAB2_LIB.BASEBOARD_FAB2(SCH_1):PAGE24
  AR82 M_B_DQ<6> @BASEBOARD_FAB2_LIB.BASEBOARD_FAB2(SCH_1):M_B_DQ(6)   I172 @BASEBOARD_FAB2_LIB.BASEBOARD_FAB2(SCH_1):PAGE24
  AV79 M_B_DQ<5> @BASEBOARD_FAB2_LIB.BASEBOARD_FAB2(SCH_1):M_B_DQ(5)   I172 @BASEBOARD_FAB2_LIB.BASEBOARD_FAB2(SCH_1):PAGE24
  AW80 M_B_DQ<4> @BASEBOARD_FAB2_LIB.BASEBOARD_FAB2(SCH_1):M_B_DQ(4)   I172 @BASEBOARD_FAB2_LIB.BASEBOARD_FAB2(SCH_1):PAGE24
  AM81 M_B_DQ<3> @BASEBOARD_FAB2_LIB.BASEBOARD_FAB2(SCH_1):M_B_DQ(3)   I172 @BASEBOARD_FAB2_LIB.BASEBOARD_FAB2(SCH_1):PAGE24
  AN82 M_B_DQ<2> @BASEBOARD_FAB2_LIB.BASEBOARD_FAB2(SCH_1):M_B_DQ(2)   I172 @BASEBOARD_FAB2_LIB.BASEBOARD_FAB2(SCH_1):PAGE24
  AT79 M_B_DQ<1> @BASEBOARD_FAB2_LIB.BASEBOARD_FAB2(SCH_1):M_B_DQ(1)   I172 @BASEBOARD_FAB2_LIB.BASEBOARD_FAB2(SCH_1):PAGE24
  AV81 M_B_DQ<0> @BASEBOARD_FAB2_LIB.BASEBOARD_FAB2(SCH_1):M_B_DQ(0)   I172 @BASEBOARD_FAB2_LIB.BASEBOARD_FAB2(SCH_1):PAGE24
   G68 M_B_DQS_DN<17> @BASEBOARD_FAB2_LIB.BASEBOARD_FAB2(SCH_1):M_B_DQS_DN(17)   I172 @BASEBOARD_FAB2_LIB.BASEBOARD_FAB2(SCH_1):PAGE24
   T27 M_B_DQS_DN<16> @BASEBOARD_FAB2_LIB.BASEBOARD_FAB2(SCH_1):M_B_DQS_DN(16)   I172 @BASEBOARD_FAB2_LIB.BASEBOARD_FAB2(SCH_1):PAGE24
   A28 M_B_DQS_DN<15> @BASEBOARD_FAB2_LIB.BASEBOARD_FAB2(SCH_1):M_B_DQS_DN(15)   I172 @BASEBOARD_FAB2_LIB.BASEBOARD_FAB2(SCH_1):PAGE24
   A34 M_B_DQS_DN<14> @BASEBOARD_FAB2_LIB.BASEBOARD_FAB2(SCH_1):M_B_DQS_DN(14)   I172 @BASEBOARD_FAB2_LIB.BASEBOARD_FAB2(SCH_1):PAGE24
   J42 M_B_DQS_DN<13> @BASEBOARD_FAB2_LIB.BASEBOARD_FAB2(SCH_1):M_B_DQS_DN(13)   I172 @BASEBOARD_FAB2_LIB.BASEBOARD_FAB2(SCH_1):PAGE24
   B73 M_B_DQS_DN<12> @BASEBOARD_FAB2_LIB.BASEBOARD_FAB2(SCH_1):M_B_DQS_DN(12)   I172 @BASEBOARD_FAB2_LIB.BASEBOARD_FAB2(SCH_1):PAGE24
   D79 M_B_DQS_DN<11> @BASEBOARD_FAB2_LIB.BASEBOARD_FAB2(SCH_1):M_B_DQS_DN(11)   I172 @BASEBOARD_FAB2_LIB.BASEBOARD_FAB2(SCH_1):PAGE24
  AG82 M_B_DQS_DN<10> @BASEBOARD_FAB2_LIB.BASEBOARD_FAB2(SCH_1):M_B_DQS_DN(10)   I172 @BASEBOARD_FAB2_LIB.BASEBOARD_FAB2(SCH_1):PAGE24
  AU82 M_B_DQS_DN<9> @BASEBOARD_FAB2_LIB.BASEBOARD_FAB2(SCH_1):M_B_DQS_DN(9)   I172 @BASEBOARD_FAB2_LIB.BASEBOARD_FAB2(SCH_1):PAGE24
   N68 M_B_DQS_DN<8> @BASEBOARD_FAB2_LIB.BASEBOARD_FAB2(SCH_1):M_B_DQS_DN(8)   I172 @BASEBOARD_FAB2_LIB.BASEBOARD_FAB2(SCH_1):PAGE24
  AB27 M_B_DQS_DN<7> @BASEBOARD_FAB2_LIB.BASEBOARD_FAB2(SCH_1):M_B_DQS_DN(7)   I172 @BASEBOARD_FAB2_LIB.BASEBOARD_FAB2(SCH_1):PAGE24
   G28 M_B_DQS_DN<6> @BASEBOARD_FAB2_LIB.BASEBOARD_FAB2(SCH_1):M_B_DQS_DN(6)   I172 @BASEBOARD_FAB2_LIB.BASEBOARD_FAB2(SCH_1):PAGE24
   G34 M_B_DQS_DN<5> @BASEBOARD_FAB2_LIB.BASEBOARD_FAB2(SCH_1):M_B_DQS_DN(5)   I172 @BASEBOARD_FAB2_LIB.BASEBOARD_FAB2(SCH_1):PAGE24
   N42 M_B_DQS_DN<4> @BASEBOARD_FAB2_LIB.BASEBOARD_FAB2(SCH_1):M_B_DQS_DN(4)   I172 @BASEBOARD_FAB2_LIB.BASEBOARD_FAB2(SCH_1):PAGE24
   H73 M_B_DQS_DN<3> @BASEBOARD_FAB2_LIB.BASEBOARD_FAB2(SCH_1):M_B_DQS_DN(3)   I172 @BASEBOARD_FAB2_LIB.BASEBOARD_FAB2(SCH_1):PAGE24
   K79 M_B_DQS_DN<2> @BASEBOARD_FAB2_LIB.BASEBOARD_FAB2(SCH_1):M_B_DQS_DN(2)   I172 @BASEBOARD_FAB2_LIB.BASEBOARD_FAB2(SCH_1):PAGE24
  AD79 M_B_DQS_DN<1> @BASEBOARD_FAB2_LIB.BASEBOARD_FAB2(SCH_1):M_B_DQS_DN(1)   I172 @BASEBOARD_FAB2_LIB.BASEBOARD_FAB2(SCH_1):PAGE24
  AP79 M_B_DQS_DN<0> @BASEBOARD_FAB2_LIB.BASEBOARD_FAB2(SCH_1):M_B_DQS_DN(0)   I172 @BASEBOARD_FAB2_LIB.BASEBOARD_FAB2(SCH_1):PAGE24
   J68 M_B_DQS_DP<17> @BASEBOARD_FAB2_LIB.BASEBOARD_FAB2(SCH_1):M_B_DQS_DP(17)   I172 @BASEBOARD_FAB2_LIB.BASEBOARD_FAB2(SCH_1):PAGE24
   V27 M_B_DQS_DP<16> @BASEBOARD_FAB2_LIB.BASEBOARD_FAB2(SCH_1):M_B_DQS_DP(16)   I172 @BASEBOARD_FAB2_LIB.BASEBOARD_FAB2(SCH_1):PAGE24
   C28 M_B_DQS_DP<15> @BASEBOARD_FAB2_LIB.BASEBOARD_FAB2(SCH_1):M_B_DQS_DP(15)   I172 @BASEBOARD_FAB2_LIB.BASEBOARD_FAB2(SCH_1):PAGE24
   C34 M_B_DQS_DP<14> @BASEBOARD_FAB2_LIB.BASEBOARD_FAB2(SCH_1):M_B_DQS_DP(14)   I172 @BASEBOARD_FAB2_LIB.BASEBOARD_FAB2(SCH_1):PAGE24
   L42 M_B_DQS_DP<13> @BASEBOARD_FAB2_LIB.BASEBOARD_FAB2(SCH_1):M_B_DQS_DP(13)   I172 @BASEBOARD_FAB2_LIB.BASEBOARD_FAB2(SCH_1):PAGE24
   D73 M_B_DQS_DP<12> @BASEBOARD_FAB2_LIB.BASEBOARD_FAB2(SCH_1):M_B_DQS_DP(12)   I172 @BASEBOARD_FAB2_LIB.BASEBOARD_FAB2(SCH_1):PAGE24
   F79 M_B_DQS_DP<11> @BASEBOARD_FAB2_LIB.BASEBOARD_FAB2(SCH_1):M_B_DQS_DP(11)   I172 @BASEBOARD_FAB2_LIB.BASEBOARD_FAB2(SCH_1):PAGE24
  AF81 M_B_DQS_DP<10> @BASEBOARD_FAB2_LIB.BASEBOARD_FAB2(SCH_1):M_B_DQS_DP(10)   I172 @BASEBOARD_FAB2_LIB.BASEBOARD_FAB2(SCH_1):PAGE24
  AT81 M_B_DQS_DP<9> @BASEBOARD_FAB2_LIB.BASEBOARD_FAB2(SCH_1):M_B_DQS_DP(9)   I172 @BASEBOARD_FAB2_LIB.BASEBOARD_FAB2(SCH_1):PAGE24
   L68 M_B_DQS_DP<8> @BASEBOARD_FAB2_LIB.BASEBOARD_FAB2(SCH_1):M_B_DQS_DP(8)   I172 @BASEBOARD_FAB2_LIB.BASEBOARD_FAB2(SCH_1):PAGE24
   Y27 M_B_DQS_DP<7> @BASEBOARD_FAB2_LIB.BASEBOARD_FAB2(SCH_1):M_B_DQS_DP(7)   I172 @BASEBOARD_FAB2_LIB.BASEBOARD_FAB2(SCH_1):PAGE24
   E28 M_B_DQS_DP<6> @BASEBOARD_FAB2_LIB.BASEBOARD_FAB2(SCH_1):M_B_DQS_DP(6)   I172 @BASEBOARD_FAB2_LIB.BASEBOARD_FAB2(SCH_1):PAGE24
   E34 M_B_DQS_DP<5> @BASEBOARD_FAB2_LIB.BASEBOARD_FAB2(SCH_1):M_B_DQS_DP(5)   I172 @BASEBOARD_FAB2_LIB.BASEBOARD_FAB2(SCH_1):PAGE24
   R42 M_B_DQS_DP<4> @BASEBOARD_FAB2_LIB.BASEBOARD_FAB2(SCH_1):M_B_DQS_DP(4)   I172 @BASEBOARD_FAB2_LIB.BASEBOARD_FAB2(SCH_1):PAGE24
   F73 M_B_DQS_DP<3> @BASEBOARD_FAB2_LIB.BASEBOARD_FAB2(SCH_1):M_B_DQS_DP(3)   I172 @BASEBOARD_FAB2_LIB.BASEBOARD_FAB2(SCH_1):PAGE24
   H79 M_B_DQS_DP<2> @BASEBOARD_FAB2_LIB.BASEBOARD_FAB2(SCH_1):M_B_DQS_DP(2)   I172 @BASEBOARD_FAB2_LIB.BASEBOARD_FAB2(SCH_1):PAGE24
  AE80 M_B_DQS_DP<1> @BASEBOARD_FAB2_LIB.BASEBOARD_FAB2(SCH_1):M_B_DQS_DP(1)   I172 @BASEBOARD_FAB2_LIB.BASEBOARD_FAB2(SCH_1):PAGE24
  AR80 M_B_DQS_DP<0> @BASEBOARD_FAB2_LIB.BASEBOARD_FAB2(SCH_1):M_B_DQS_DP(0)   I172 @BASEBOARD_FAB2_LIB.BASEBOARD_FAB2(SCH_1):PAGE24
   M67 M_B_ECC<7> @BASEBOARD_FAB2_LIB.BASEBOARD_FAB2(SCH_1):M_B_ECC(7)   I172 @BASEBOARD_FAB2_LIB.BASEBOARD_FAB2(SCH_1):PAGE24
   H67 M_B_ECC<6> @BASEBOARD_FAB2_LIB.BASEBOARD_FAB2(SCH_1):M_B_ECC(6)   I172 @BASEBOARD_FAB2_LIB.BASEBOARD_FAB2(SCH_1):PAGE24
   M69 M_B_ECC<5> @BASEBOARD_FAB2_LIB.BASEBOARD_FAB2(SCH_1):M_B_ECC(5)   I172 @BASEBOARD_FAB2_LIB.BASEBOARD_FAB2(SCH_1):PAGE24
   L70 M_B_ECC<4> @BASEBOARD_FAB2_LIB.BASEBOARD_FAB2(SCH_1):M_B_ECC(4)   I172 @BASEBOARD_FAB2_LIB.BASEBOARD_FAB2(SCH_1):PAGE24
   L66 M_B_ECC<3> @BASEBOARD_FAB2_LIB.BASEBOARD_FAB2(SCH_1):M_B_ECC(3)   I172 @BASEBOARD_FAB2_LIB.BASEBOARD_FAB2(SCH_1):PAGE24
   J66 M_B_ECC<2> @BASEBOARD_FAB2_LIB.BASEBOARD_FAB2(SCH_1):M_B_ECC(2)   I172 @BASEBOARD_FAB2_LIB.BASEBOARD_FAB2(SCH_1):PAGE24
   H69 M_B_ECC<1> @BASEBOARD_FAB2_LIB.BASEBOARD_FAB2(SCH_1):M_B_ECC(1)   I172 @BASEBOARD_FAB2_LIB.BASEBOARD_FAB2(SCH_1):PAGE24
   J70 M_B_ECC<0> @BASEBOARD_FAB2_LIB.BASEBOARD_FAB2(SCH_1):M_B_ECC(0)   I172 @BASEBOARD_FAB2_LIB.BASEBOARD_FAB2(SCH_1):PAGE24
   N48 M_B_MA<17> @BASEBOARD_FAB2_LIB.BASEBOARD_FAB2(SCH_1):M_B_MA(17)   I172 @BASEBOARD_FAB2_LIB.BASEBOARD_FAB2(SCH_1):PAGE24
   R52 M_B_MA<16> @BASEBOARD_FAB2_LIB.BASEBOARD_FAB2(SCH_1):M_B_MA(16)   I172 @BASEBOARD_FAB2_LIB.BASEBOARD_FAB2(SCH_1):PAGE24
   N52 M_B_MA<15> @BASEBOARD_FAB2_LIB.BASEBOARD_FAB2(SCH_1):M_B_MA(15)   I172 @BASEBOARD_FAB2_LIB.BASEBOARD_FAB2(SCH_1):PAGE24
   T51 M_B_MA<14> @BASEBOARD_FAB2_LIB.BASEBOARD_FAB2(SCH_1):M_B_MA(14)   I172 @BASEBOARD_FAB2_LIB.BASEBOARD_FAB2(SCH_1):PAGE24
   M51 M_B_MA<13> @BASEBOARD_FAB2_LIB.BASEBOARD_FAB2(SCH_1):M_B_MA(13)   I172 @BASEBOARD_FAB2_LIB.BASEBOARD_FAB2(SCH_1):PAGE24
   T61 M_B_MA<12> @BASEBOARD_FAB2_LIB.BASEBOARD_FAB2(SCH_1):M_B_MA(12)   I172 @BASEBOARD_FAB2_LIB.BASEBOARD_FAB2(SCH_1):PAGE24
   R60 M_B_MA<11> @BASEBOARD_FAB2_LIB.BASEBOARD_FAB2(SCH_1):M_B_MA(11)   I172 @BASEBOARD_FAB2_LIB.BASEBOARD_FAB2(SCH_1):PAGE24
   M55 M_B_MA<10> @BASEBOARD_FAB2_LIB.BASEBOARD_FAB2(SCH_1):M_B_MA(10)   I172 @BASEBOARD_FAB2_LIB.BASEBOARD_FAB2(SCH_1):PAGE24
   K59 M_B_MA<9> @BASEBOARD_FAB2_LIB.BASEBOARD_FAB2(SCH_1):M_B_MA(9)   I172 @BASEBOARD_FAB2_LIB.BASEBOARD_FAB2(SCH_1):PAGE24
   W60 M_B_MA<8> @BASEBOARD_FAB2_LIB.BASEBOARD_FAB2(SCH_1):M_B_MA(8)   I172 @BASEBOARD_FAB2_LIB.BASEBOARD_FAB2(SCH_1):PAGE24
   V61 M_B_MA<7> @BASEBOARD_FAB2_LIB.BASEBOARD_FAB2(SCH_1):M_B_MA(7)   I172 @BASEBOARD_FAB2_LIB.BASEBOARD_FAB2(SCH_1):PAGE24
   T59 M_B_MA<6> @BASEBOARD_FAB2_LIB.BASEBOARD_FAB2(SCH_1):M_B_MA(6)   I172 @BASEBOARD_FAB2_LIB.BASEBOARD_FAB2(SCH_1):PAGE24
   R58 M_B_MA<5> @BASEBOARD_FAB2_LIB.BASEBOARD_FAB2(SCH_1):M_B_MA(5)   I172 @BASEBOARD_FAB2_LIB.BASEBOARD_FAB2(SCH_1):PAGE24
   M59 M_B_MA<4> @BASEBOARD_FAB2_LIB.BASEBOARD_FAB2(SCH_1):M_B_MA(4)   I172 @BASEBOARD_FAB2_LIB.BASEBOARD_FAB2(SCH_1):PAGE24
   N58 M_B_MA<3> @BASEBOARD_FAB2_LIB.BASEBOARD_FAB2(SCH_1):M_B_MA(3)   I172 @BASEBOARD_FAB2_LIB.BASEBOARD_FAB2(SCH_1):PAGE24
   K57 M_B_MA<2> @BASEBOARD_FAB2_LIB.BASEBOARD_FAB2(SCH_1):M_B_MA(2)   I172 @BASEBOARD_FAB2_LIB.BASEBOARD_FAB2(SCH_1):PAGE24
   J58 M_B_MA<1> @BASEBOARD_FAB2_LIB.BASEBOARD_FAB2(SCH_1):M_B_MA(1)   I172 @BASEBOARD_FAB2_LIB.BASEBOARD_FAB2(SCH_1):PAGE24
   J52 M_B_MA<0> @BASEBOARD_FAB2_LIB.BASEBOARD_FAB2(SCH_1):M_B_MA(0)   I172 @BASEBOARD_FAB2_LIB.BASEBOARD_FAB2(SCH_1):PAGE24
   T47 M_B_ODT<3> @BASEBOARD_FAB2_LIB.BASEBOARD_FAB2(SCH_1):M_B_ODT(3)   I172 @BASEBOARD_FAB2_LIB.BASEBOARD_FAB2(SCH_1):PAGE24
   M49 M_B_ODT<2> @BASEBOARD_FAB2_LIB.BASEBOARD_FAB2(SCH_1):M_B_ODT(2)   I172 @BASEBOARD_FAB2_LIB.BASEBOARD_FAB2(SCH_1):PAGE24
   R48 M_B_ODT<1> @BASEBOARD_FAB2_LIB.BASEBOARD_FAB2(SCH_1):M_B_ODT(1)   I172 @BASEBOARD_FAB2_LIB.BASEBOARD_FAB2(SCH_1):PAGE24
   N50 M_B_ODT<0> @BASEBOARD_FAB2_LIB.BASEBOARD_FAB2(SCH_1):M_B_ODT(0)   I172 @BASEBOARD_FAB2_LIB.BASEBOARD_FAB2(SCH_1):PAGE24
   K53 M_B_PAR @BASEBOARD_FAB2_LIB.BASEBOARD_FAB2(SCH_1):M_B_PAR   I172 @BASEBOARD_FAB2_LIB.BASEBOARD_FAB2(SCH_1):PAGE24
  AB61 M_C_ACT_N @BASEBOARD_FAB2_LIB.BASEBOARD_FAB2(SCH_1):M_C_ACT_N   I172 @BASEBOARD_FAB2_LIB.BASEBOARD_FAB2(SCH_1):PAGE25
  AD61 M_C_ALERT_N @BASEBOARD_FAB2_LIB.BASEBOARD_FAB2(SCH_1):M_C_ALERT_N   I172 @BASEBOARD_FAB2_LIB.BASEBOARD_FAB2(SCH_1):PAGE25
  AE56 M_C_BA<1> @BASEBOARD_FAB2_LIB.BASEBOARD_FAB2(SCH_1):M_C_BA(1)   I172 @BASEBOARD_FAB2_LIB.BASEBOARD_FAB2(SCH_1):PAGE25
   W52 M_C_BA<0> @BASEBOARD_FAB2_LIB.BASEBOARD_FAB2(SCH_1):M_C_BA(0)   I172 @BASEBOARD_FAB2_LIB.BASEBOARD_FAB2(SCH_1):PAGE25
  AE62 M_C_BG<1> @BASEBOARD_FAB2_LIB.BASEBOARD_FAB2(SCH_1):M_C_BG(1)   I172 @BASEBOARD_FAB2_LIB.BASEBOARD_FAB2(SCH_1):PAGE25
  AA60 M_C_BG<0> @BASEBOARD_FAB2_LIB.BASEBOARD_FAB2(SCH_1):M_C_BG(0)   I172 @BASEBOARD_FAB2_LIB.BASEBOARD_FAB2(SCH_1):PAGE25
  AB45 M_C_C<2> @BASEBOARD_FAB2_LIB.BASEBOARD_FAB2(SCH_1):M_C_C(2)   I172 @BASEBOARD_FAB2_LIB.BASEBOARD_FAB2(SCH_1):PAGE25
  AB63 M_C_CKE<3> @BASEBOARD_FAB2_LIB.BASEBOARD_FAB2(SCH_1):M_C_CKE(3)   I172 @BASEBOARD_FAB2_LIB.BASEBOARD_FAB2(SCH_1):PAGE25
   V63 M_C_CKE<2> @BASEBOARD_FAB2_LIB.BASEBOARD_FAB2(SCH_1):M_C_CKE(2)   I172 @BASEBOARD_FAB2_LIB.BASEBOARD_FAB2(SCH_1):PAGE25
  AD63 M_C_CKE<1> @BASEBOARD_FAB2_LIB.BASEBOARD_FAB2(SCH_1):M_C_CKE(1)   I172 @BASEBOARD_FAB2_LIB.BASEBOARD_FAB2(SCH_1):PAGE25
  AA62 M_C_CKE<0> @BASEBOARD_FAB2_LIB.BASEBOARD_FAB2(SCH_1):M_C_CKE(0)   I172 @BASEBOARD_FAB2_LIB.BASEBOARD_FAB2(SCH_1):PAGE25
   W56 M_C_CLK_DN<3> @BASEBOARD_FAB2_LIB.BASEBOARD_FAB2(SCH_1):M_C_CLK_DN(3)   I172 @BASEBOARD_FAB2_LIB.BASEBOARD_FAB2(SCH_1):PAGE25
  AA56 M_C_CLK_DN<2> @BASEBOARD_FAB2_LIB.BASEBOARD_FAB2(SCH_1):M_C_CLK_DN(2)   I172 @BASEBOARD_FAB2_LIB.BASEBOARD_FAB2(SCH_1):PAGE25
   W54 M_C_CLK_DN<1> @BASEBOARD_FAB2_LIB.BASEBOARD_FAB2(SCH_1):M_C_CLK_DN(1)   I172 @BASEBOARD_FAB2_LIB.BASEBOARD_FAB2(SCH_1):PAGE25
  AA54 M_C_CLK_DN<0> @BASEBOARD_FAB2_LIB.BASEBOARD_FAB2(SCH_1):M_C_CLK_DN(0)   I172 @BASEBOARD_FAB2_LIB.BASEBOARD_FAB2(SCH_1):PAGE25
   V57 M_C_CLK_DP<3> @BASEBOARD_FAB2_LIB.BASEBOARD_FAB2(SCH_1):M_C_CLK_DP(3)   I172 @BASEBOARD_FAB2_LIB.BASEBOARD_FAB2(SCH_1):PAGE25
  AB57 M_C_CLK_DP<2> @BASEBOARD_FAB2_LIB.BASEBOARD_FAB2(SCH_1):M_C_CLK_DP(2)   I172 @BASEBOARD_FAB2_LIB.BASEBOARD_FAB2(SCH_1):PAGE25
   V55 M_C_CLK_DP<1> @BASEBOARD_FAB2_LIB.BASEBOARD_FAB2(SCH_1):M_C_CLK_DP(1)   I172 @BASEBOARD_FAB2_LIB.BASEBOARD_FAB2(SCH_1):PAGE25
  AB55 M_C_CLK_DP<0> @BASEBOARD_FAB2_LIB.BASEBOARD_FAB2(SCH_1):M_C_CLK_DP(0)   I172 @BASEBOARD_FAB2_LIB.BASEBOARD_FAB2(SCH_1):PAGE25
   V45 M_C_CS_N<7> @BASEBOARD_FAB2_LIB.BASEBOARD_FAB2(SCH_1):M_C_CS_N(7)   I172 @BASEBOARD_FAB2_LIB.BASEBOARD_FAB2(SCH_1):PAGE25
   T45 M_C_CS_N<6> @BASEBOARD_FAB2_LIB.BASEBOARD_FAB2(SCH_1):M_C_CS_N(6)   I172 @BASEBOARD_FAB2_LIB.BASEBOARD_FAB2(SCH_1):PAGE25
   W48 M_C_CS_N<5> @BASEBOARD_FAB2_LIB.BASEBOARD_FAB2(SCH_1):M_C_CS_N(5)   I172 @BASEBOARD_FAB2_LIB.BASEBOARD_FAB2(SCH_1):PAGE25
  AB51 M_C_CS_N<4> @BASEBOARD_FAB2_LIB.BASEBOARD_FAB2(SCH_1):M_C_CS_N(4)   I172 @BASEBOARD_FAB2_LIB.BASEBOARD_FAB2(SCH_1):PAGE25
  AA46 M_C_CS_N<3> @BASEBOARD_FAB2_LIB.BASEBOARD_FAB2(SCH_1):M_C_CS_N(3)   I172 @BASEBOARD_FAB2_LIB.BASEBOARD_FAB2(SCH_1):PAGE25
   W46 M_C_CS_N<2> @BASEBOARD_FAB2_LIB.BASEBOARD_FAB2(SCH_1):M_C_CS_N(2)   I172 @BASEBOARD_FAB2_LIB.BASEBOARD_FAB2(SCH_1):PAGE25
  AB49 M_C_CS_N<1> @BASEBOARD_FAB2_LIB.BASEBOARD_FAB2(SCH_1):M_C_CS_N(1)   I172 @BASEBOARD_FAB2_LIB.BASEBOARD_FAB2(SCH_1):PAGE25
   V51 M_C_CS_N<0> @BASEBOARD_FAB2_LIB.BASEBOARD_FAB2(SCH_1):M_C_CS_N(0)   I172 @BASEBOARD_FAB2_LIB.BASEBOARD_FAB2(SCH_1):PAGE25
  AH23 M_C_DQ<63> @BASEBOARD_FAB2_LIB.BASEBOARD_FAB2(SCH_1):M_C_DQ(63)   I172 @BASEBOARD_FAB2_LIB.BASEBOARD_FAB2(SCH_1):PAGE25
  AD23 M_C_DQ<62> @BASEBOARD_FAB2_LIB.BASEBOARD_FAB2(SCH_1):M_C_DQ(62)   I172 @BASEBOARD_FAB2_LIB.BASEBOARD_FAB2(SCH_1):PAGE25
  AG26 M_C_DQ<61> @BASEBOARD_FAB2_LIB.BASEBOARD_FAB2(SCH_1):M_C_DQ(61)   I172 @BASEBOARD_FAB2_LIB.BASEBOARD_FAB2(SCH_1):PAGE25
  AE26 M_C_DQ<60> @BASEBOARD_FAB2_LIB.BASEBOARD_FAB2(SCH_1):M_C_DQ(60)   I172 @BASEBOARD_FAB2_LIB.BASEBOARD_FAB2(SCH_1):PAGE25
  AG22 M_C_DQ<59> @BASEBOARD_FAB2_LIB.BASEBOARD_FAB2(SCH_1):M_C_DQ(59)   I172 @BASEBOARD_FAB2_LIB.BASEBOARD_FAB2(SCH_1):PAGE25
  AE22 M_C_DQ<58> @BASEBOARD_FAB2_LIB.BASEBOARD_FAB2(SCH_1):M_C_DQ(58)   I172 @BASEBOARD_FAB2_LIB.BASEBOARD_FAB2(SCH_1):PAGE25
  AH25 M_C_DQ<57> @BASEBOARD_FAB2_LIB.BASEBOARD_FAB2(SCH_1):M_C_DQ(57)   I172 @BASEBOARD_FAB2_LIB.BASEBOARD_FAB2(SCH_1):PAGE25
  AD25 M_C_DQ<56> @BASEBOARD_FAB2_LIB.BASEBOARD_FAB2(SCH_1):M_C_DQ(56)   I172 @BASEBOARD_FAB2_LIB.BASEBOARD_FAB2(SCH_1):PAGE25
  AH29 M_C_DQ<55> @BASEBOARD_FAB2_LIB.BASEBOARD_FAB2(SCH_1):M_C_DQ(55)   I172 @BASEBOARD_FAB2_LIB.BASEBOARD_FAB2(SCH_1):PAGE25
  AD29 M_C_DQ<54> @BASEBOARD_FAB2_LIB.BASEBOARD_FAB2(SCH_1):M_C_DQ(54)   I172 @BASEBOARD_FAB2_LIB.BASEBOARD_FAB2(SCH_1):PAGE25
  AG32 M_C_DQ<53> @BASEBOARD_FAB2_LIB.BASEBOARD_FAB2(SCH_1):M_C_DQ(53)   I172 @BASEBOARD_FAB2_LIB.BASEBOARD_FAB2(SCH_1):PAGE25
  AE32 M_C_DQ<52> @BASEBOARD_FAB2_LIB.BASEBOARD_FAB2(SCH_1):M_C_DQ(52)   I172 @BASEBOARD_FAB2_LIB.BASEBOARD_FAB2(SCH_1):PAGE25
  AG28 M_C_DQ<51> @BASEBOARD_FAB2_LIB.BASEBOARD_FAB2(SCH_1):M_C_DQ(51)   I172 @BASEBOARD_FAB2_LIB.BASEBOARD_FAB2(SCH_1):PAGE25
  AE28 M_C_DQ<50> @BASEBOARD_FAB2_LIB.BASEBOARD_FAB2(SCH_1):M_C_DQ(50)   I172 @BASEBOARD_FAB2_LIB.BASEBOARD_FAB2(SCH_1):PAGE25
  AH31 M_C_DQ<49> @BASEBOARD_FAB2_LIB.BASEBOARD_FAB2(SCH_1):M_C_DQ(49)   I172 @BASEBOARD_FAB2_LIB.BASEBOARD_FAB2(SCH_1):PAGE25
  AD31 M_C_DQ<48> @BASEBOARD_FAB2_LIB.BASEBOARD_FAB2(SCH_1):M_C_DQ(48)   I172 @BASEBOARD_FAB2_LIB.BASEBOARD_FAB2(SCH_1):PAGE25
  AA32 M_C_DQ<47> @BASEBOARD_FAB2_LIB.BASEBOARD_FAB2(SCH_1):M_C_DQ(47)   I172 @BASEBOARD_FAB2_LIB.BASEBOARD_FAB2(SCH_1):PAGE25
   U32 M_C_DQ<46> @BASEBOARD_FAB2_LIB.BASEBOARD_FAB2(SCH_1):M_C_DQ(46)   I172 @BASEBOARD_FAB2_LIB.BASEBOARD_FAB2(SCH_1):PAGE25
   Y35 M_C_DQ<45> @BASEBOARD_FAB2_LIB.BASEBOARD_FAB2(SCH_1):M_C_DQ(45)   I172 @BASEBOARD_FAB2_LIB.BASEBOARD_FAB2(SCH_1):PAGE25
   V35 M_C_DQ<44> @BASEBOARD_FAB2_LIB.BASEBOARD_FAB2(SCH_1):M_C_DQ(44)   I172 @BASEBOARD_FAB2_LIB.BASEBOARD_FAB2(SCH_1):PAGE25
   Y31 M_C_DQ<43> @BASEBOARD_FAB2_LIB.BASEBOARD_FAB2(SCH_1):M_C_DQ(43)   I172 @BASEBOARD_FAB2_LIB.BASEBOARD_FAB2(SCH_1):PAGE25
   V31 M_C_DQ<42> @BASEBOARD_FAB2_LIB.BASEBOARD_FAB2(SCH_1):M_C_DQ(42)   I172 @BASEBOARD_FAB2_LIB.BASEBOARD_FAB2(SCH_1):PAGE25
  AA34 M_C_DQ<41> @BASEBOARD_FAB2_LIB.BASEBOARD_FAB2(SCH_1):M_C_DQ(41)   I172 @BASEBOARD_FAB2_LIB.BASEBOARD_FAB2(SCH_1):PAGE25
   U34 M_C_DQ<40> @BASEBOARD_FAB2_LIB.BASEBOARD_FAB2(SCH_1):M_C_DQ(40)   I172 @BASEBOARD_FAB2_LIB.BASEBOARD_FAB2(SCH_1):PAGE25
  AA38 M_C_DQ<39> @BASEBOARD_FAB2_LIB.BASEBOARD_FAB2(SCH_1):M_C_DQ(39)   I172 @BASEBOARD_FAB2_LIB.BASEBOARD_FAB2(SCH_1):PAGE25
   U38 M_C_DQ<38> @BASEBOARD_FAB2_LIB.BASEBOARD_FAB2(SCH_1):M_C_DQ(38)   I172 @BASEBOARD_FAB2_LIB.BASEBOARD_FAB2(SCH_1):PAGE25
   Y41 M_C_DQ<37> @BASEBOARD_FAB2_LIB.BASEBOARD_FAB2(SCH_1):M_C_DQ(37)   I172 @BASEBOARD_FAB2_LIB.BASEBOARD_FAB2(SCH_1):PAGE25
   V41 M_C_DQ<36> @BASEBOARD_FAB2_LIB.BASEBOARD_FAB2(SCH_1):M_C_DQ(36)   I172 @BASEBOARD_FAB2_LIB.BASEBOARD_FAB2(SCH_1):PAGE25
   Y37 M_C_DQ<35> @BASEBOARD_FAB2_LIB.BASEBOARD_FAB2(SCH_1):M_C_DQ(35)   I172 @BASEBOARD_FAB2_LIB.BASEBOARD_FAB2(SCH_1):PAGE25
   V37 M_C_DQ<34> @BASEBOARD_FAB2_LIB.BASEBOARD_FAB2(SCH_1):M_C_DQ(34)   I172 @BASEBOARD_FAB2_LIB.BASEBOARD_FAB2(SCH_1):PAGE25
  AA40 M_C_DQ<33> @BASEBOARD_FAB2_LIB.BASEBOARD_FAB2(SCH_1):M_C_DQ(33)   I172 @BASEBOARD_FAB2_LIB.BASEBOARD_FAB2(SCH_1):PAGE25
   U40 M_C_DQ<32> @BASEBOARD_FAB2_LIB.BASEBOARD_FAB2(SCH_1):M_C_DQ(32)   I172 @BASEBOARD_FAB2_LIB.BASEBOARD_FAB2(SCH_1):PAGE25
  AT65 M_C_DQ<31> @BASEBOARD_FAB2_LIB.BASEBOARD_FAB2(SCH_1):M_C_DQ(31)   I172 @BASEBOARD_FAB2_LIB.BASEBOARD_FAB2(SCH_1):PAGE25
  AM65 M_C_DQ<30> @BASEBOARD_FAB2_LIB.BASEBOARD_FAB2(SCH_1):M_C_DQ(30)   I172 @BASEBOARD_FAB2_LIB.BASEBOARD_FAB2(SCH_1):PAGE25
  AR68 M_C_DQ<29> @BASEBOARD_FAB2_LIB.BASEBOARD_FAB2(SCH_1):M_C_DQ(29)   I172 @BASEBOARD_FAB2_LIB.BASEBOARD_FAB2(SCH_1):PAGE25
  AN68 M_C_DQ<28> @BASEBOARD_FAB2_LIB.BASEBOARD_FAB2(SCH_1):M_C_DQ(28)   I172 @BASEBOARD_FAB2_LIB.BASEBOARD_FAB2(SCH_1):PAGE25
  AR64 M_C_DQ<27> @BASEBOARD_FAB2_LIB.BASEBOARD_FAB2(SCH_1):M_C_DQ(27)   I172 @BASEBOARD_FAB2_LIB.BASEBOARD_FAB2(SCH_1):PAGE25
  AN64 M_C_DQ<26> @BASEBOARD_FAB2_LIB.BASEBOARD_FAB2(SCH_1):M_C_DQ(26)   I172 @BASEBOARD_FAB2_LIB.BASEBOARD_FAB2(SCH_1):PAGE25
  AT67 M_C_DQ<25> @BASEBOARD_FAB2_LIB.BASEBOARD_FAB2(SCH_1):M_C_DQ(25)   I172 @BASEBOARD_FAB2_LIB.BASEBOARD_FAB2(SCH_1):PAGE25
  AM67 M_C_DQ<24> @BASEBOARD_FAB2_LIB.BASEBOARD_FAB2(SCH_1):M_C_DQ(24)   I172 @BASEBOARD_FAB2_LIB.BASEBOARD_FAB2(SCH_1):PAGE25
   V69 M_C_DQ<23> @BASEBOARD_FAB2_LIB.BASEBOARD_FAB2(SCH_1):M_C_DQ(23)   I172 @BASEBOARD_FAB2_LIB.BASEBOARD_FAB2(SCH_1):PAGE25
   T71 M_C_DQ<22> @BASEBOARD_FAB2_LIB.BASEBOARD_FAB2(SCH_1):M_C_DQ(22)   I172 @BASEBOARD_FAB2_LIB.BASEBOARD_FAB2(SCH_1):PAGE25
  AB71 M_C_DQ<21> @BASEBOARD_FAB2_LIB.BASEBOARD_FAB2(SCH_1):M_C_DQ(21)   I172 @BASEBOARD_FAB2_LIB.BASEBOARD_FAB2(SCH_1):PAGE25
  AA72 M_C_DQ<20> @BASEBOARD_FAB2_LIB.BASEBOARD_FAB2(SCH_1):M_C_DQ(20)   I172 @BASEBOARD_FAB2_LIB.BASEBOARD_FAB2(SCH_1):PAGE25
   T69 M_C_DQ<19> @BASEBOARD_FAB2_LIB.BASEBOARD_FAB2(SCH_1):M_C_DQ(19)   I172 @BASEBOARD_FAB2_LIB.BASEBOARD_FAB2(SCH_1):PAGE25
   R70 M_C_DQ<18> @BASEBOARD_FAB2_LIB.BASEBOARD_FAB2(SCH_1):M_C_DQ(18)   I172 @BASEBOARD_FAB2_LIB.BASEBOARD_FAB2(SCH_1):PAGE25
  AA70 M_C_DQ<17> @BASEBOARD_FAB2_LIB.BASEBOARD_FAB2(SCH_1):M_C_DQ(17)   I172 @BASEBOARD_FAB2_LIB.BASEBOARD_FAB2(SCH_1):PAGE25
   W72 M_C_DQ<16> @BASEBOARD_FAB2_LIB.BASEBOARD_FAB2(SCH_1):M_C_DQ(16)   I172 @BASEBOARD_FAB2_LIB.BASEBOARD_FAB2(SCH_1):PAGE25
   Y75 M_C_DQ<15> @BASEBOARD_FAB2_LIB.BASEBOARD_FAB2(SCH_1):M_C_DQ(15)   I172 @BASEBOARD_FAB2_LIB.BASEBOARD_FAB2(SCH_1):PAGE25
  AB77 M_C_DQ<14> @BASEBOARD_FAB2_LIB.BASEBOARD_FAB2(SCH_1):M_C_DQ(14)   I172 @BASEBOARD_FAB2_LIB.BASEBOARD_FAB2(SCH_1):PAGE25
  AE74 M_C_DQ<13> @BASEBOARD_FAB2_LIB.BASEBOARD_FAB2(SCH_1):M_C_DQ(13)   I172 @BASEBOARD_FAB2_LIB.BASEBOARD_FAB2(SCH_1):PAGE25
  AF75 M_C_DQ<12> @BASEBOARD_FAB2_LIB.BASEBOARD_FAB2(SCH_1):M_C_DQ(12)   I172 @BASEBOARD_FAB2_LIB.BASEBOARD_FAB2(SCH_1):PAGE25
   W76 M_C_DQ<11> @BASEBOARD_FAB2_LIB.BASEBOARD_FAB2(SCH_1):M_C_DQ(11)   I172 @BASEBOARD_FAB2_LIB.BASEBOARD_FAB2(SCH_1):PAGE25
   Y77 M_C_DQ<10> @BASEBOARD_FAB2_LIB.BASEBOARD_FAB2(SCH_1):M_C_DQ(10)   I172 @BASEBOARD_FAB2_LIB.BASEBOARD_FAB2(SCH_1):PAGE25
  AC74 M_C_DQ<9> @BASEBOARD_FAB2_LIB.BASEBOARD_FAB2(SCH_1):M_C_DQ(9)   I172 @BASEBOARD_FAB2_LIB.BASEBOARD_FAB2(SCH_1):PAGE25
  AE76 M_C_DQ<8> @BASEBOARD_FAB2_LIB.BASEBOARD_FAB2(SCH_1):M_C_DQ(8)   I172 @BASEBOARD_FAB2_LIB.BASEBOARD_FAB2(SCH_1):PAGE25
  AK75 M_C_DQ<7> @BASEBOARD_FAB2_LIB.BASEBOARD_FAB2(SCH_1):M_C_DQ(7)   I172 @BASEBOARD_FAB2_LIB.BASEBOARD_FAB2(SCH_1):PAGE25
  AM77 M_C_DQ<6> @BASEBOARD_FAB2_LIB.BASEBOARD_FAB2(SCH_1):M_C_DQ(6)   I172 @BASEBOARD_FAB2_LIB.BASEBOARD_FAB2(SCH_1):PAGE25
  AR74 M_C_DQ<5> @BASEBOARD_FAB2_LIB.BASEBOARD_FAB2(SCH_1):M_C_DQ(5)   I172 @BASEBOARD_FAB2_LIB.BASEBOARD_FAB2(SCH_1):PAGE25
  AT75 M_C_DQ<4> @BASEBOARD_FAB2_LIB.BASEBOARD_FAB2(SCH_1):M_C_DQ(4)   I172 @BASEBOARD_FAB2_LIB.BASEBOARD_FAB2(SCH_1):PAGE25
  AJ76 M_C_DQ<3> @BASEBOARD_FAB2_LIB.BASEBOARD_FAB2(SCH_1):M_C_DQ(3)   I172 @BASEBOARD_FAB2_LIB.BASEBOARD_FAB2(SCH_1):PAGE25
  AK77 M_C_DQ<2> @BASEBOARD_FAB2_LIB.BASEBOARD_FAB2(SCH_1):M_C_DQ(2)   I172 @BASEBOARD_FAB2_LIB.BASEBOARD_FAB2(SCH_1):PAGE25
  AN74 M_C_DQ<1> @BASEBOARD_FAB2_LIB.BASEBOARD_FAB2(SCH_1):M_C_DQ(1)   I172 @BASEBOARD_FAB2_LIB.BASEBOARD_FAB2(SCH_1):PAGE25
  AR76 M_C_DQ<0> @BASEBOARD_FAB2_LIB.BASEBOARD_FAB2(SCH_1):M_C_DQ(0)   I172 @BASEBOARD_FAB2_LIB.BASEBOARD_FAB2(SCH_1):PAGE25
  AT71 M_C_DQS_DN<17> @BASEBOARD_FAB2_LIB.BASEBOARD_FAB2(SCH_1):M_C_DQS_DN(17)   I172 @BASEBOARD_FAB2_LIB.BASEBOARD_FAB2(SCH_1):PAGE25
  AC24 M_C_DQS_DN<16> @BASEBOARD_FAB2_LIB.BASEBOARD_FAB2(SCH_1):M_C_DQS_DN(16)   I172 @BASEBOARD_FAB2_LIB.BASEBOARD_FAB2(SCH_1):PAGE25
  AC30 M_C_DQS_DN<15> @BASEBOARD_FAB2_LIB.BASEBOARD_FAB2(SCH_1):M_C_DQS_DN(15)   I172 @BASEBOARD_FAB2_LIB.BASEBOARD_FAB2(SCH_1):PAGE25
   T33 M_C_DQS_DN<14> @BASEBOARD_FAB2_LIB.BASEBOARD_FAB2(SCH_1):M_C_DQS_DN(14)   I172 @BASEBOARD_FAB2_LIB.BASEBOARD_FAB2(SCH_1):PAGE25
   T39 M_C_DQS_DN<13> @BASEBOARD_FAB2_LIB.BASEBOARD_FAB2(SCH_1):M_C_DQS_DN(13)   I172 @BASEBOARD_FAB2_LIB.BASEBOARD_FAB2(SCH_1):PAGE25
  AL66 M_C_DQS_DN<12> @BASEBOARD_FAB2_LIB.BASEBOARD_FAB2(SCH_1):M_C_DQS_DN(12)   I172 @BASEBOARD_FAB2_LIB.BASEBOARD_FAB2(SCH_1):PAGE25
   U72 M_C_DQS_DN<11> @BASEBOARD_FAB2_LIB.BASEBOARD_FAB2(SCH_1):M_C_DQS_DN(11)   I172 @BASEBOARD_FAB2_LIB.BASEBOARD_FAB2(SCH_1):PAGE25
  AD77 M_C_DQS_DN<10> @BASEBOARD_FAB2_LIB.BASEBOARD_FAB2(SCH_1):M_C_DQS_DN(10)   I172 @BASEBOARD_FAB2_LIB.BASEBOARD_FAB2(SCH_1):PAGE25
  AP77 M_C_DQS_DN<9> @BASEBOARD_FAB2_LIB.BASEBOARD_FAB2(SCH_1):M_C_DQS_DN(9)   I172 @BASEBOARD_FAB2_LIB.BASEBOARD_FAB2(SCH_1):PAGE25
  BB71 M_C_DQS_DN<8> @BASEBOARD_FAB2_LIB.BASEBOARD_FAB2(SCH_1):M_C_DQS_DN(8)   I172 @BASEBOARD_FAB2_LIB.BASEBOARD_FAB2(SCH_1):PAGE25
  AJ24 M_C_DQS_DN<7> @BASEBOARD_FAB2_LIB.BASEBOARD_FAB2(SCH_1):M_C_DQS_DN(7)   I172 @BASEBOARD_FAB2_LIB.BASEBOARD_FAB2(SCH_1):PAGE25
  AJ30 M_C_DQS_DN<6> @BASEBOARD_FAB2_LIB.BASEBOARD_FAB2(SCH_1):M_C_DQS_DN(6)   I172 @BASEBOARD_FAB2_LIB.BASEBOARD_FAB2(SCH_1):PAGE25
  AB33 M_C_DQS_DN<5> @BASEBOARD_FAB2_LIB.BASEBOARD_FAB2(SCH_1):M_C_DQS_DN(5)   I172 @BASEBOARD_FAB2_LIB.BASEBOARD_FAB2(SCH_1):PAGE25
  AB39 M_C_DQS_DN<4> @BASEBOARD_FAB2_LIB.BASEBOARD_FAB2(SCH_1):M_C_DQS_DN(4)   I172 @BASEBOARD_FAB2_LIB.BASEBOARD_FAB2(SCH_1):PAGE25
  AU66 M_C_DQS_DN<3> @BASEBOARD_FAB2_LIB.BASEBOARD_FAB2(SCH_1):M_C_DQS_DN(3)   I172 @BASEBOARD_FAB2_LIB.BASEBOARD_FAB2(SCH_1):PAGE25
   Y69 M_C_DQS_DN<2> @BASEBOARD_FAB2_LIB.BASEBOARD_FAB2(SCH_1):M_C_DQS_DN(2)   I172 @BASEBOARD_FAB2_LIB.BASEBOARD_FAB2(SCH_1):PAGE25
  AA74 M_C_DQS_DN<1> @BASEBOARD_FAB2_LIB.BASEBOARD_FAB2(SCH_1):M_C_DQS_DN(1)   I172 @BASEBOARD_FAB2_LIB.BASEBOARD_FAB2(SCH_1):PAGE25
  AL74 M_C_DQS_DN<0> @BASEBOARD_FAB2_LIB.BASEBOARD_FAB2(SCH_1):M_C_DQS_DN(0)   I172 @BASEBOARD_FAB2_LIB.BASEBOARD_FAB2(SCH_1):PAGE25
  AV71 M_C_DQS_DP<17> @BASEBOARD_FAB2_LIB.BASEBOARD_FAB2(SCH_1):M_C_DQS_DP(17)   I172 @BASEBOARD_FAB2_LIB.BASEBOARD_FAB2(SCH_1):PAGE25
  AE24 M_C_DQS_DP<16> @BASEBOARD_FAB2_LIB.BASEBOARD_FAB2(SCH_1):M_C_DQS_DP(16)   I172 @BASEBOARD_FAB2_LIB.BASEBOARD_FAB2(SCH_1):PAGE25
  AE30 M_C_DQS_DP<15> @BASEBOARD_FAB2_LIB.BASEBOARD_FAB2(SCH_1):M_C_DQS_DP(15)   I172 @BASEBOARD_FAB2_LIB.BASEBOARD_FAB2(SCH_1):PAGE25
   V33 M_C_DQS_DP<14> @BASEBOARD_FAB2_LIB.BASEBOARD_FAB2(SCH_1):M_C_DQS_DP(14)   I172 @BASEBOARD_FAB2_LIB.BASEBOARD_FAB2(SCH_1):PAGE25
   V39 M_C_DQS_DP<13> @BASEBOARD_FAB2_LIB.BASEBOARD_FAB2(SCH_1):M_C_DQS_DP(13)   I172 @BASEBOARD_FAB2_LIB.BASEBOARD_FAB2(SCH_1):PAGE25
  AN66 M_C_DQS_DP<12> @BASEBOARD_FAB2_LIB.BASEBOARD_FAB2(SCH_1):M_C_DQS_DP(12)   I172 @BASEBOARD_FAB2_LIB.BASEBOARD_FAB2(SCH_1):PAGE25
   V71 M_C_DQS_DP<11> @BASEBOARD_FAB2_LIB.BASEBOARD_FAB2(SCH_1):M_C_DQS_DP(11)   I172 @BASEBOARD_FAB2_LIB.BASEBOARD_FAB2(SCH_1):PAGE25
  AC76 M_C_DQS_DP<10> @BASEBOARD_FAB2_LIB.BASEBOARD_FAB2(SCH_1):M_C_DQS_DP(10)   I172 @BASEBOARD_FAB2_LIB.BASEBOARD_FAB2(SCH_1):PAGE25
  AN76 M_C_DQS_DP<9> @BASEBOARD_FAB2_LIB.BASEBOARD_FAB2(SCH_1):M_C_DQS_DP(9)   I172 @BASEBOARD_FAB2_LIB.BASEBOARD_FAB2(SCH_1):PAGE25
  AY71 M_C_DQS_DP<8> @BASEBOARD_FAB2_LIB.BASEBOARD_FAB2(SCH_1):M_C_DQS_DP(8)   I172 @BASEBOARD_FAB2_LIB.BASEBOARD_FAB2(SCH_1):PAGE25
  AG24 M_C_DQS_DP<7> @BASEBOARD_FAB2_LIB.BASEBOARD_FAB2(SCH_1):M_C_DQS_DP(7)   I172 @BASEBOARD_FAB2_LIB.BASEBOARD_FAB2(SCH_1):PAGE25
  AG30 M_C_DQS_DP<6> @BASEBOARD_FAB2_LIB.BASEBOARD_FAB2(SCH_1):M_C_DQS_DP(6)   I172 @BASEBOARD_FAB2_LIB.BASEBOARD_FAB2(SCH_1):PAGE25
   Y33 M_C_DQS_DP<5> @BASEBOARD_FAB2_LIB.BASEBOARD_FAB2(SCH_1):M_C_DQS_DP(5)   I172 @BASEBOARD_FAB2_LIB.BASEBOARD_FAB2(SCH_1):PAGE25
   Y39 M_C_DQS_DP<4> @BASEBOARD_FAB2_LIB.BASEBOARD_FAB2(SCH_1):M_C_DQS_DP(4)   I172 @BASEBOARD_FAB2_LIB.BASEBOARD_FAB2(SCH_1):PAGE25
  AR66 M_C_DQS_DP<3> @BASEBOARD_FAB2_LIB.BASEBOARD_FAB2(SCH_1):M_C_DQS_DP(3)   I172 @BASEBOARD_FAB2_LIB.BASEBOARD_FAB2(SCH_1):PAGE25
   W70 M_C_DQS_DP<2> @BASEBOARD_FAB2_LIB.BASEBOARD_FAB2(SCH_1):M_C_DQS_DP(2)   I172 @BASEBOARD_FAB2_LIB.BASEBOARD_FAB2(SCH_1):PAGE25
  AB75 M_C_DQS_DP<1> @BASEBOARD_FAB2_LIB.BASEBOARD_FAB2(SCH_1):M_C_DQS_DP(1)   I172 @BASEBOARD_FAB2_LIB.BASEBOARD_FAB2(SCH_1):PAGE25
  AM75 M_C_DQS_DP<0> @BASEBOARD_FAB2_LIB.BASEBOARD_FAB2(SCH_1):M_C_DQS_DP(0)   I172 @BASEBOARD_FAB2_LIB.BASEBOARD_FAB2(SCH_1):PAGE25
  BA70 M_C_ECC<7> @BASEBOARD_FAB2_LIB.BASEBOARD_FAB2(SCH_1):M_C_ECC(7)   I172 @BASEBOARD_FAB2_LIB.BASEBOARD_FAB2(SCH_1):PAGE25
  AU70 M_C_ECC<6> @BASEBOARD_FAB2_LIB.BASEBOARD_FAB2(SCH_1):M_C_ECC(6)   I172 @BASEBOARD_FAB2_LIB.BASEBOARD_FAB2(SCH_1):PAGE25
  AY73 M_C_ECC<5> @BASEBOARD_FAB2_LIB.BASEBOARD_FAB2(SCH_1):M_C_ECC(5)   I172 @BASEBOARD_FAB2_LIB.BASEBOARD_FAB2(SCH_1):PAGE25
  AV73 M_C_ECC<4> @BASEBOARD_FAB2_LIB.BASEBOARD_FAB2(SCH_1):M_C_ECC(4)   I172 @BASEBOARD_FAB2_LIB.BASEBOARD_FAB2(SCH_1):PAGE25
  AY69 M_C_ECC<3> @BASEBOARD_FAB2_LIB.BASEBOARD_FAB2(SCH_1):M_C_ECC(3)   I172 @BASEBOARD_FAB2_LIB.BASEBOARD_FAB2(SCH_1):PAGE25
  AV69 M_C_ECC<2> @BASEBOARD_FAB2_LIB.BASEBOARD_FAB2(SCH_1):M_C_ECC(2)   I172 @BASEBOARD_FAB2_LIB.BASEBOARD_FAB2(SCH_1):PAGE25
  BA72 M_C_ECC<1> @BASEBOARD_FAB2_LIB.BASEBOARD_FAB2(SCH_1):M_C_ECC(1)   I172 @BASEBOARD_FAB2_LIB.BASEBOARD_FAB2(SCH_1):PAGE25
  AU72 M_C_ECC<0> @BASEBOARD_FAB2_LIB.BASEBOARD_FAB2(SCH_1):M_C_ECC(0)   I172 @BASEBOARD_FAB2_LIB.BASEBOARD_FAB2(SCH_1):PAGE25
  AC46 M_C_MA<17> @BASEBOARD_FAB2_LIB.BASEBOARD_FAB2(SCH_1):M_C_MA(17)   I172 @BASEBOARD_FAB2_LIB.BASEBOARD_FAB2(SCH_1):PAGE25
  AA52 M_C_MA<16> @BASEBOARD_FAB2_LIB.BASEBOARD_FAB2(SCH_1):M_C_MA(16)   I172 @BASEBOARD_FAB2_LIB.BASEBOARD_FAB2(SCH_1):PAGE25
  AE54 M_C_MA<15> @BASEBOARD_FAB2_LIB.BASEBOARD_FAB2(SCH_1):M_C_MA(15)   I172 @BASEBOARD_FAB2_LIB.BASEBOARD_FAB2(SCH_1):PAGE25
   W50 M_C_MA<14> @BASEBOARD_FAB2_LIB.BASEBOARD_FAB2(SCH_1):M_C_MA(14)   I172 @BASEBOARD_FAB2_LIB.BASEBOARD_FAB2(SCH_1):PAGE25
  AD53 M_C_MA<13> @BASEBOARD_FAB2_LIB.BASEBOARD_FAB2(SCH_1):M_C_MA(13)   I172 @BASEBOARD_FAB2_LIB.BASEBOARD_FAB2(SCH_1):PAGE25
  AG62 M_C_MA<12> @BASEBOARD_FAB2_LIB.BASEBOARD_FAB2(SCH_1):M_C_MA(12)   I172 @BASEBOARD_FAB2_LIB.BASEBOARD_FAB2(SCH_1):PAGE25
  AG60 M_C_MA<11> @BASEBOARD_FAB2_LIB.BASEBOARD_FAB2(SCH_1):M_C_MA(11)   I172 @BASEBOARD_FAB2_LIB.BASEBOARD_FAB2(SCH_1):PAGE25
  AD55 M_C_MA<10> @BASEBOARD_FAB2_LIB.BASEBOARD_FAB2(SCH_1):M_C_MA(10)   I172 @BASEBOARD_FAB2_LIB.BASEBOARD_FAB2(SCH_1):PAGE25
  AG58 M_C_MA<9> @BASEBOARD_FAB2_LIB.BASEBOARD_FAB2(SCH_1):M_C_MA(9)   I172 @BASEBOARD_FAB2_LIB.BASEBOARD_FAB2(SCH_1):PAGE25
  AD59 M_C_MA<8> @BASEBOARD_FAB2_LIB.BASEBOARD_FAB2(SCH_1):M_C_MA(8)   I172 @BASEBOARD_FAB2_LIB.BASEBOARD_FAB2(SCH_1):PAGE25
  AE60 M_C_MA<7> @BASEBOARD_FAB2_LIB.BASEBOARD_FAB2(SCH_1):M_C_MA(7)   I172 @BASEBOARD_FAB2_LIB.BASEBOARD_FAB2(SCH_1):PAGE25
  AB59 M_C_MA<6> @BASEBOARD_FAB2_LIB.BASEBOARD_FAB2(SCH_1):M_C_MA(6)   I172 @BASEBOARD_FAB2_LIB.BASEBOARD_FAB2(SCH_1):PAGE25
   V59 M_C_MA<5> @BASEBOARD_FAB2_LIB.BASEBOARD_FAB2(SCH_1):M_C_MA(5)   I172 @BASEBOARD_FAB2_LIB.BASEBOARD_FAB2(SCH_1):PAGE25
  AA58 M_C_MA<4> @BASEBOARD_FAB2_LIB.BASEBOARD_FAB2(SCH_1):M_C_MA(4)   I172 @BASEBOARD_FAB2_LIB.BASEBOARD_FAB2(SCH_1):PAGE25
   W58 M_C_MA<3> @BASEBOARD_FAB2_LIB.BASEBOARD_FAB2(SCH_1):M_C_MA(3)   I172 @BASEBOARD_FAB2_LIB.BASEBOARD_FAB2(SCH_1):PAGE25
  AD57 M_C_MA<2> @BASEBOARD_FAB2_LIB.BASEBOARD_FAB2(SCH_1):M_C_MA(2)   I172 @BASEBOARD_FAB2_LIB.BASEBOARD_FAB2(SCH_1):PAGE25
  AE58 M_C_MA<1> @BASEBOARD_FAB2_LIB.BASEBOARD_FAB2(SCH_1):M_C_MA(1)   I172 @BASEBOARD_FAB2_LIB.BASEBOARD_FAB2(SCH_1):PAGE25
  AB53 M_C_MA<0> @BASEBOARD_FAB2_LIB.BASEBOARD_FAB2(SCH_1):M_C_MA(0)   I172 @BASEBOARD_FAB2_LIB.BASEBOARD_FAB2(SCH_1):PAGE25
  AB47 M_C_ODT<3> @BASEBOARD_FAB2_LIB.BASEBOARD_FAB2(SCH_1):M_C_ODT(3)   I172 @BASEBOARD_FAB2_LIB.BASEBOARD_FAB2(SCH_1):PAGE25
   V49 M_C_ODT<2> @BASEBOARD_FAB2_LIB.BASEBOARD_FAB2(SCH_1):M_C_ODT(2)   I172 @BASEBOARD_FAB2_LIB.BASEBOARD_FAB2(SCH_1):PAGE25
  AA48 M_C_ODT<1> @BASEBOARD_FAB2_LIB.BASEBOARD_FAB2(SCH_1):M_C_ODT(1)   I172 @BASEBOARD_FAB2_LIB.BASEBOARD_FAB2(SCH_1):PAGE25
  AA50 M_C_ODT<0> @BASEBOARD_FAB2_LIB.BASEBOARD_FAB2(SCH_1):M_C_ODT(0)   I172 @BASEBOARD_FAB2_LIB.BASEBOARD_FAB2(SCH_1):PAGE25
   V53 M_C_PAR @BASEBOARD_FAB2_LIB.BASEBOARD_FAB2(SCH_1):M_C_PAR   I172 @BASEBOARD_FAB2_LIB.BASEBOARD_FAB2(SCH_1):PAGE25
  DW60 M_D_ACT_N @BASEBOARD_FAB2_LIB.BASEBOARD_FAB2(SCH_1):M_D_ACT_N   I172 @BASEBOARD_FAB2_LIB.BASEBOARD_FAB2(SCH_1):PAGE26
  ED63 M_D_ALERT_N @BASEBOARD_FAB2_LIB.BASEBOARD_FAB2(SCH_1):M_D_ALERT_N   I172 @BASEBOARD_FAB2_LIB.BASEBOARD_FAB2(SCH_1):PAGE26
  EA54 M_D_BA<1> @BASEBOARD_FAB2_LIB.BASEBOARD_FAB2(SCH_1):M_D_BA(1)   I172 @BASEBOARD_FAB2_LIB.BASEBOARD_FAB2(SCH_1):PAGE26
  EE52 M_D_BA<0> @BASEBOARD_FAB2_LIB.BASEBOARD_FAB2(SCH_1):M_D_BA(0)   I172 @BASEBOARD_FAB2_LIB.BASEBOARD_FAB2(SCH_1):PAGE26
  DW62 M_D_BG<1> @BASEBOARD_FAB2_LIB.BASEBOARD_FAB2(SCH_1):M_D_BG(1)   I172 @BASEBOARD_FAB2_LIB.BASEBOARD_FAB2(SCH_1):PAGE26
  ED61 M_D_BG<0> @BASEBOARD_FAB2_LIB.BASEBOARD_FAB2(SCH_1):M_D_BG(0)   I172 @BASEBOARD_FAB2_LIB.BASEBOARD_FAB2(SCH_1):PAGE26
  DV47 M_D_C<2> @BASEBOARD_FAB2_LIB.BASEBOARD_FAB2(SCH_1):M_D_C(2)   I172 @BASEBOARD_FAB2_LIB.BASEBOARD_FAB2(SCH_1):PAGE26
  EB63 M_D_CKE<3> @BASEBOARD_FAB2_LIB.BASEBOARD_FAB2(SCH_1):M_D_CKE(3)   I172 @BASEBOARD_FAB2_LIB.BASEBOARD_FAB2(SCH_1):PAGE26
  EA62 M_D_CKE<2> @BASEBOARD_FAB2_LIB.BASEBOARD_FAB2(SCH_1):M_D_CKE(2)   I172 @BASEBOARD_FAB2_LIB.BASEBOARD_FAB2(SCH_1):PAGE26
  EF63 M_D_CKE<1> @BASEBOARD_FAB2_LIB.BASEBOARD_FAB2(SCH_1):M_D_CKE(1)   I172 @BASEBOARD_FAB2_LIB.BASEBOARD_FAB2(SCH_1):PAGE26
  EE62 M_D_CKE<0> @BASEBOARD_FAB2_LIB.BASEBOARD_FAB2(SCH_1):M_D_CKE(0)   I172 @BASEBOARD_FAB2_LIB.BASEBOARD_FAB2(SCH_1):PAGE26
  EF57 M_D_CLK_DN<3> @BASEBOARD_FAB2_LIB.BASEBOARD_FAB2(SCH_1):M_D_CLK_DN(3)   I172 @BASEBOARD_FAB2_LIB.BASEBOARD_FAB2(SCH_1):PAGE26
  DW56 M_D_CLK_DN<2> @BASEBOARD_FAB2_LIB.BASEBOARD_FAB2(SCH_1):M_D_CLK_DN(2)   I172 @BASEBOARD_FAB2_LIB.BASEBOARD_FAB2(SCH_1):PAGE26
  EF55 M_D_CLK_DN<1> @BASEBOARD_FAB2_LIB.BASEBOARD_FAB2(SCH_1):M_D_CLK_DN(1)   I172 @BASEBOARD_FAB2_LIB.BASEBOARD_FAB2(SCH_1):PAGE26
  ED55 M_D_CLK_DN<0> @BASEBOARD_FAB2_LIB.BASEBOARD_FAB2(SCH_1):M_D_CLK_DN(0)   I172 @BASEBOARD_FAB2_LIB.BASEBOARD_FAB2(SCH_1):PAGE26
  EE56 M_D_CLK_DP<3> @BASEBOARD_FAB2_LIB.BASEBOARD_FAB2(SCH_1):M_D_CLK_DP(3)   I172 @BASEBOARD_FAB2_LIB.BASEBOARD_FAB2(SCH_1):PAGE26
  EA56 M_D_CLK_DP<2> @BASEBOARD_FAB2_LIB.BASEBOARD_FAB2(SCH_1):M_D_CLK_DP(2)   I172 @BASEBOARD_FAB2_LIB.BASEBOARD_FAB2(SCH_1):PAGE26
  EE54 M_D_CLK_DP<1> @BASEBOARD_FAB2_LIB.BASEBOARD_FAB2(SCH_1):M_D_CLK_DP(1)   I172 @BASEBOARD_FAB2_LIB.BASEBOARD_FAB2(SCH_1):PAGE26
  EB55 M_D_CLK_DP<0> @BASEBOARD_FAB2_LIB.BASEBOARD_FAB2(SCH_1):M_D_CLK_DP(0)   I172 @BASEBOARD_FAB2_LIB.BASEBOARD_FAB2(SCH_1):PAGE26
  EB45 M_D_CS_N<7> @BASEBOARD_FAB2_LIB.BASEBOARD_FAB2(SCH_1):M_D_CS_N(7)   I172 @BASEBOARD_FAB2_LIB.BASEBOARD_FAB2(SCH_1):PAGE26
  DV45 M_D_CS_N<6> @BASEBOARD_FAB2_LIB.BASEBOARD_FAB2(SCH_1):M_D_CS_N(6)   I172 @BASEBOARD_FAB2_LIB.BASEBOARD_FAB2(SCH_1):PAGE26
  EB49 M_D_CS_N<5> @BASEBOARD_FAB2_LIB.BASEBOARD_FAB2(SCH_1):M_D_CS_N(5)   I172 @BASEBOARD_FAB2_LIB.BASEBOARD_FAB2(SCH_1):PAGE26
  EB51 M_D_CS_N<4> @BASEBOARD_FAB2_LIB.BASEBOARD_FAB2(SCH_1):M_D_CS_N(4)   I172 @BASEBOARD_FAB2_LIB.BASEBOARD_FAB2(SCH_1):PAGE26
  EB47 M_D_CS_N<3> @BASEBOARD_FAB2_LIB.BASEBOARD_FAB2(SCH_1):M_D_CS_N(3)   I172 @BASEBOARD_FAB2_LIB.BASEBOARD_FAB2(SCH_1):PAGE26
  ED47 M_D_CS_N<2> @BASEBOARD_FAB2_LIB.BASEBOARD_FAB2(SCH_1):M_D_CS_N(2)   I172 @BASEBOARD_FAB2_LIB.BASEBOARD_FAB2(SCH_1):PAGE26
  ED49 M_D_CS_N<1> @BASEBOARD_FAB2_LIB.BASEBOARD_FAB2(SCH_1):M_D_CS_N(1)   I172 @BASEBOARD_FAB2_LIB.BASEBOARD_FAB2(SCH_1):PAGE26
  EF51 M_D_CS_N<0> @BASEBOARD_FAB2_LIB.BASEBOARD_FAB2(SCH_1):M_D_CS_N(0)   I172 @BASEBOARD_FAB2_LIB.BASEBOARD_FAB2(SCH_1):PAGE26
  DW22 M_D_DQ<63> @BASEBOARD_FAB2_LIB.BASEBOARD_FAB2(SCH_1):M_D_DQ(63)   I172 @BASEBOARD_FAB2_LIB.BASEBOARD_FAB2(SCH_1):PAGE26
  EC22 M_D_DQ<62> @BASEBOARD_FAB2_LIB.BASEBOARD_FAB2(SCH_1):M_D_DQ(62)   I172 @BASEBOARD_FAB2_LIB.BASEBOARD_FAB2(SCH_1):PAGE26
  DT25 M_D_DQ<61> @BASEBOARD_FAB2_LIB.BASEBOARD_FAB2(SCH_1):M_D_DQ(61)   I172 @BASEBOARD_FAB2_LIB.BASEBOARD_FAB2(SCH_1):PAGE26
  DP25 M_D_DQ<60> @BASEBOARD_FAB2_LIB.BASEBOARD_FAB2(SCH_1):M_D_DQ(60)   I172 @BASEBOARD_FAB2_LIB.BASEBOARD_FAB2(SCH_1):PAGE26
  EB21 M_D_DQ<59> @BASEBOARD_FAB2_LIB.BASEBOARD_FAB2(SCH_1):M_D_DQ(59)   I172 @BASEBOARD_FAB2_LIB.BASEBOARD_FAB2(SCH_1):PAGE26
  DY21 M_D_DQ<58> @BASEBOARD_FAB2_LIB.BASEBOARD_FAB2(SCH_1):M_D_DQ(58)   I172 @BASEBOARD_FAB2_LIB.BASEBOARD_FAB2(SCH_1):PAGE26
  DU24 M_D_DQ<57> @BASEBOARD_FAB2_LIB.BASEBOARD_FAB2(SCH_1):M_D_DQ(57)   I172 @BASEBOARD_FAB2_LIB.BASEBOARD_FAB2(SCH_1):PAGE26
  DN24 M_D_DQ<56> @BASEBOARD_FAB2_LIB.BASEBOARD_FAB2(SCH_1):M_D_DQ(56)   I172 @BASEBOARD_FAB2_LIB.BASEBOARD_FAB2(SCH_1):PAGE26
  DU28 M_D_DQ<55> @BASEBOARD_FAB2_LIB.BASEBOARD_FAB2(SCH_1):M_D_DQ(55)   I172 @BASEBOARD_FAB2_LIB.BASEBOARD_FAB2(SCH_1):PAGE26
  DN28 M_D_DQ<54> @BASEBOARD_FAB2_LIB.BASEBOARD_FAB2(SCH_1):M_D_DQ(54)   I172 @BASEBOARD_FAB2_LIB.BASEBOARD_FAB2(SCH_1):PAGE26
  DT31 M_D_DQ<53> @BASEBOARD_FAB2_LIB.BASEBOARD_FAB2(SCH_1):M_D_DQ(53)   I172 @BASEBOARD_FAB2_LIB.BASEBOARD_FAB2(SCH_1):PAGE26
  DP31 M_D_DQ<52> @BASEBOARD_FAB2_LIB.BASEBOARD_FAB2(SCH_1):M_D_DQ(52)   I172 @BASEBOARD_FAB2_LIB.BASEBOARD_FAB2(SCH_1):PAGE26
  DT27 M_D_DQ<51> @BASEBOARD_FAB2_LIB.BASEBOARD_FAB2(SCH_1):M_D_DQ(51)   I172 @BASEBOARD_FAB2_LIB.BASEBOARD_FAB2(SCH_1):PAGE26
  DP27 M_D_DQ<50> @BASEBOARD_FAB2_LIB.BASEBOARD_FAB2(SCH_1):M_D_DQ(50)   I172 @BASEBOARD_FAB2_LIB.BASEBOARD_FAB2(SCH_1):PAGE26
  DU30 M_D_DQ<49> @BASEBOARD_FAB2_LIB.BASEBOARD_FAB2(SCH_1):M_D_DQ(49)   I172 @BASEBOARD_FAB2_LIB.BASEBOARD_FAB2(SCH_1):PAGE26
  DN30 M_D_DQ<48> @BASEBOARD_FAB2_LIB.BASEBOARD_FAB2(SCH_1):M_D_DQ(48)   I172 @BASEBOARD_FAB2_LIB.BASEBOARD_FAB2(SCH_1):PAGE26
  DU34 M_D_DQ<47> @BASEBOARD_FAB2_LIB.BASEBOARD_FAB2(SCH_1):M_D_DQ(47)   I172 @BASEBOARD_FAB2_LIB.BASEBOARD_FAB2(SCH_1):PAGE26
  DN34 M_D_DQ<46> @BASEBOARD_FAB2_LIB.BASEBOARD_FAB2(SCH_1):M_D_DQ(46)   I172 @BASEBOARD_FAB2_LIB.BASEBOARD_FAB2(SCH_1):PAGE26
  DT37 M_D_DQ<45> @BASEBOARD_FAB2_LIB.BASEBOARD_FAB2(SCH_1):M_D_DQ(45)   I172 @BASEBOARD_FAB2_LIB.BASEBOARD_FAB2(SCH_1):PAGE26
  DP37 M_D_DQ<44> @BASEBOARD_FAB2_LIB.BASEBOARD_FAB2(SCH_1):M_D_DQ(44)   I172 @BASEBOARD_FAB2_LIB.BASEBOARD_FAB2(SCH_1):PAGE26
  DT33 M_D_DQ<43> @BASEBOARD_FAB2_LIB.BASEBOARD_FAB2(SCH_1):M_D_DQ(43)   I172 @BASEBOARD_FAB2_LIB.BASEBOARD_FAB2(SCH_1):PAGE26
  DP33 M_D_DQ<42> @BASEBOARD_FAB2_LIB.BASEBOARD_FAB2(SCH_1):M_D_DQ(42)   I172 @BASEBOARD_FAB2_LIB.BASEBOARD_FAB2(SCH_1):PAGE26
  DU36 M_D_DQ<41> @BASEBOARD_FAB2_LIB.BASEBOARD_FAB2(SCH_1):M_D_DQ(41)   I172 @BASEBOARD_FAB2_LIB.BASEBOARD_FAB2(SCH_1):PAGE26
  DN36 M_D_DQ<40> @BASEBOARD_FAB2_LIB.BASEBOARD_FAB2(SCH_1):M_D_DQ(40)   I172 @BASEBOARD_FAB2_LIB.BASEBOARD_FAB2(SCH_1):PAGE26
  ED37 M_D_DQ<39> @BASEBOARD_FAB2_LIB.BASEBOARD_FAB2(SCH_1):M_D_DQ(39)   I172 @BASEBOARD_FAB2_LIB.BASEBOARD_FAB2(SCH_1):PAGE26
  DY37 M_D_DQ<38> @BASEBOARD_FAB2_LIB.BASEBOARD_FAB2(SCH_1):M_D_DQ(38)   I172 @BASEBOARD_FAB2_LIB.BASEBOARD_FAB2(SCH_1):PAGE26
  EA40 M_D_DQ<37> @BASEBOARD_FAB2_LIB.BASEBOARD_FAB2(SCH_1):M_D_DQ(37)   I172 @BASEBOARD_FAB2_LIB.BASEBOARD_FAB2(SCH_1):PAGE26
  DY39 M_D_DQ<36> @BASEBOARD_FAB2_LIB.BASEBOARD_FAB2(SCH_1):M_D_DQ(36)   I172 @BASEBOARD_FAB2_LIB.BASEBOARD_FAB2(SCH_1):PAGE26
  EC36 M_D_DQ<35> @BASEBOARD_FAB2_LIB.BASEBOARD_FAB2(SCH_1):M_D_DQ(35)   I172 @BASEBOARD_FAB2_LIB.BASEBOARD_FAB2(SCH_1):PAGE26
  EA36 M_D_DQ<34> @BASEBOARD_FAB2_LIB.BASEBOARD_FAB2(SCH_1):M_D_DQ(34)   I172 @BASEBOARD_FAB2_LIB.BASEBOARD_FAB2(SCH_1):PAGE26
  ED39 M_D_DQ<33> @BASEBOARD_FAB2_LIB.BASEBOARD_FAB2(SCH_1):M_D_DQ(33)   I172 @BASEBOARD_FAB2_LIB.BASEBOARD_FAB2(SCH_1):PAGE26
  EC40 M_D_DQ<32> @BASEBOARD_FAB2_LIB.BASEBOARD_FAB2(SCH_1):M_D_DQ(32)   I172 @BASEBOARD_FAB2_LIB.BASEBOARD_FAB2(SCH_1):PAGE26
  DU74 M_D_DQ<31> @BASEBOARD_FAB2_LIB.BASEBOARD_FAB2(SCH_1):M_D_DQ(31)   I172 @BASEBOARD_FAB2_LIB.BASEBOARD_FAB2(SCH_1):PAGE26
  DN74 M_D_DQ<30> @BASEBOARD_FAB2_LIB.BASEBOARD_FAB2(SCH_1):M_D_DQ(30)   I172 @BASEBOARD_FAB2_LIB.BASEBOARD_FAB2(SCH_1):PAGE26
  DT77 M_D_DQ<29> @BASEBOARD_FAB2_LIB.BASEBOARD_FAB2(SCH_1):M_D_DQ(29)   I172 @BASEBOARD_FAB2_LIB.BASEBOARD_FAB2(SCH_1):PAGE26
  DP77 M_D_DQ<28> @BASEBOARD_FAB2_LIB.BASEBOARD_FAB2(SCH_1):M_D_DQ(28)   I172 @BASEBOARD_FAB2_LIB.BASEBOARD_FAB2(SCH_1):PAGE26
  DT73 M_D_DQ<27> @BASEBOARD_FAB2_LIB.BASEBOARD_FAB2(SCH_1):M_D_DQ(27)   I172 @BASEBOARD_FAB2_LIB.BASEBOARD_FAB2(SCH_1):PAGE26
  DP73 M_D_DQ<26> @BASEBOARD_FAB2_LIB.BASEBOARD_FAB2(SCH_1):M_D_DQ(26)   I172 @BASEBOARD_FAB2_LIB.BASEBOARD_FAB2(SCH_1):PAGE26
  DU76 M_D_DQ<25> @BASEBOARD_FAB2_LIB.BASEBOARD_FAB2(SCH_1):M_D_DQ(25)   I172 @BASEBOARD_FAB2_LIB.BASEBOARD_FAB2(SCH_1):PAGE26
  DN76 M_D_DQ<24> @BASEBOARD_FAB2_LIB.BASEBOARD_FAB2(SCH_1):M_D_DQ(24)   I172 @BASEBOARD_FAB2_LIB.BASEBOARD_FAB2(SCH_1):PAGE26
  DN82 M_D_DQ<23> @BASEBOARD_FAB2_LIB.BASEBOARD_FAB2(SCH_1):M_D_DQ(23)   I172 @BASEBOARD_FAB2_LIB.BASEBOARD_FAB2(SCH_1):PAGE26
  DR80 M_D_DQ<22> @BASEBOARD_FAB2_LIB.BASEBOARD_FAB2(SCH_1):M_D_DQ(22)   I172 @BASEBOARD_FAB2_LIB.BASEBOARD_FAB2(SCH_1):PAGE26
  DJ80 M_D_DQ<21> @BASEBOARD_FAB2_LIB.BASEBOARD_FAB2(SCH_1):M_D_DQ(21)   I172 @BASEBOARD_FAB2_LIB.BASEBOARD_FAB2(SCH_1):PAGE26
  DK79 M_D_DQ<20> @BASEBOARD_FAB2_LIB.BASEBOARD_FAB2(SCH_1):M_D_DQ(20)   I172 @BASEBOARD_FAB2_LIB.BASEBOARD_FAB2(SCH_1):PAGE26
  DR82 M_D_DQ<19> @BASEBOARD_FAB2_LIB.BASEBOARD_FAB2(SCH_1):M_D_DQ(19)   I172 @BASEBOARD_FAB2_LIB.BASEBOARD_FAB2(SCH_1):PAGE26
  DT81 M_D_DQ<18> @BASEBOARD_FAB2_LIB.BASEBOARD_FAB2(SCH_1):M_D_DQ(18)   I172 @BASEBOARD_FAB2_LIB.BASEBOARD_FAB2(SCH_1):PAGE26
  DK81 M_D_DQ<17> @BASEBOARD_FAB2_LIB.BASEBOARD_FAB2(SCH_1):M_D_DQ(17)   I172 @BASEBOARD_FAB2_LIB.BASEBOARD_FAB2(SCH_1):PAGE26
  DM79 M_D_DQ<16> @BASEBOARD_FAB2_LIB.BASEBOARD_FAB2(SCH_1):M_D_DQ(16)   I172 @BASEBOARD_FAB2_LIB.BASEBOARD_FAB2(SCH_1):PAGE26
  DV85 M_D_DQ<15> @BASEBOARD_FAB2_LIB.BASEBOARD_FAB2(SCH_1):M_D_DQ(15)   I172 @BASEBOARD_FAB2_LIB.BASEBOARD_FAB2(SCH_1):PAGE26
  DR84 M_D_DQ<14> @BASEBOARD_FAB2_LIB.BASEBOARD_FAB2(SCH_1):M_D_DQ(14)   I172 @BASEBOARD_FAB2_LIB.BASEBOARD_FAB2(SCH_1):PAGE26
  DE84 M_D_DQ<13> @BASEBOARD_FAB2_LIB.BASEBOARD_FAB2(SCH_1):M_D_DQ(13)   I172 @BASEBOARD_FAB2_LIB.BASEBOARD_FAB2(SCH_1):PAGE26
  DD85 M_D_DQ<12> @BASEBOARD_FAB2_LIB.BASEBOARD_FAB2(SCH_1):M_D_DQ(12)   I172 @BASEBOARD_FAB2_LIB.BASEBOARD_FAB2(SCH_1):PAGE26
  DY83 M_D_DQ<11> @BASEBOARD_FAB2_LIB.BASEBOARD_FAB2(SCH_1):M_D_DQ(11)   I172 @BASEBOARD_FAB2_LIB.BASEBOARD_FAB2(SCH_1):PAGE26
  DV83 M_D_DQ<10> @BASEBOARD_FAB2_LIB.BASEBOARD_FAB2(SCH_1):M_D_DQ(10)   I172 @BASEBOARD_FAB2_LIB.BASEBOARD_FAB2(SCH_1):PAGE26
  DH85 M_D_DQ<9> @BASEBOARD_FAB2_LIB.BASEBOARD_FAB2(SCH_1):M_D_DQ(9)   I172 @BASEBOARD_FAB2_LIB.BASEBOARD_FAB2(SCH_1):PAGE26
  DG84 M_D_DQ<8> @BASEBOARD_FAB2_LIB.BASEBOARD_FAB2(SCH_1):M_D_DQ(8)   I172 @BASEBOARD_FAB2_LIB.BASEBOARD_FAB2(SCH_1):PAGE26
  CW84 M_D_DQ<7> @BASEBOARD_FAB2_LIB.BASEBOARD_FAB2(SCH_1):M_D_DQ(7)   I172 @BASEBOARD_FAB2_LIB.BASEBOARD_FAB2(SCH_1):PAGE26
  CW86 M_D_DQ<6> @BASEBOARD_FAB2_LIB.BASEBOARD_FAB2(SCH_1):M_D_DQ(6)   I172 @BASEBOARD_FAB2_LIB.BASEBOARD_FAB2(SCH_1):PAGE26
  CL86 M_D_DQ<5> @BASEBOARD_FAB2_LIB.BASEBOARD_FAB2(SCH_1):M_D_DQ(5)   I172 @BASEBOARD_FAB2_LIB.BASEBOARD_FAB2(SCH_1):PAGE26
  CL84 M_D_DQ<4> @BASEBOARD_FAB2_LIB.BASEBOARD_FAB2(SCH_1):M_D_DQ(4)   I172 @BASEBOARD_FAB2_LIB.BASEBOARD_FAB2(SCH_1):PAGE26
  DA84 M_D_DQ<3> @BASEBOARD_FAB2_LIB.BASEBOARD_FAB2(SCH_1):M_D_DQ(3)   I172 @BASEBOARD_FAB2_LIB.BASEBOARD_FAB2(SCH_1):PAGE26
  DA86 M_D_DQ<2> @BASEBOARD_FAB2_LIB.BASEBOARD_FAB2(SCH_1):M_D_DQ(2)   I172 @BASEBOARD_FAB2_LIB.BASEBOARD_FAB2(SCH_1):PAGE26
  CN86 M_D_DQ<1> @BASEBOARD_FAB2_LIB.BASEBOARD_FAB2(SCH_1):M_D_DQ(1)   I172 @BASEBOARD_FAB2_LIB.BASEBOARD_FAB2(SCH_1):PAGE26
  CN84 M_D_DQ<0> @BASEBOARD_FAB2_LIB.BASEBOARD_FAB2(SCH_1):M_D_DQ(0)   I172 @BASEBOARD_FAB2_LIB.BASEBOARD_FAB2(SCH_1):PAGE26
  DB67 M_D_DQS_DN<17> @BASEBOARD_FAB2_LIB.BASEBOARD_FAB2(SCH_1):M_D_DQS_DN(17)   I172 @BASEBOARD_FAB2_LIB.BASEBOARD_FAB2(SCH_1):PAGE26
  DM23 M_D_DQS_DN<16> @BASEBOARD_FAB2_LIB.BASEBOARD_FAB2(SCH_1):M_D_DQS_DN(16)   I172 @BASEBOARD_FAB2_LIB.BASEBOARD_FAB2(SCH_1):PAGE26
  DM29 M_D_DQS_DN<15> @BASEBOARD_FAB2_LIB.BASEBOARD_FAB2(SCH_1):M_D_DQS_DN(15)   I172 @BASEBOARD_FAB2_LIB.BASEBOARD_FAB2(SCH_1):PAGE26
  DP35 M_D_DQS_DN<14> @BASEBOARD_FAB2_LIB.BASEBOARD_FAB2(SCH_1):M_D_DQS_DN(14)   I172 @BASEBOARD_FAB2_LIB.BASEBOARD_FAB2(SCH_1):PAGE26
  EA38 M_D_DQS_DN<13> @BASEBOARD_FAB2_LIB.BASEBOARD_FAB2(SCH_1):M_D_DQS_DN(13)   I172 @BASEBOARD_FAB2_LIB.BASEBOARD_FAB2(SCH_1):PAGE26
  DP75 M_D_DQS_DN<12> @BASEBOARD_FAB2_LIB.BASEBOARD_FAB2(SCH_1):M_D_DQS_DN(12)   I172 @BASEBOARD_FAB2_LIB.BASEBOARD_FAB2(SCH_1):PAGE26
  DN80 M_D_DQS_DN<11> @BASEBOARD_FAB2_LIB.BASEBOARD_FAB2(SCH_1):M_D_DQS_DN(11)   I172 @BASEBOARD_FAB2_LIB.BASEBOARD_FAB2(SCH_1):PAGE26
  DM85 M_D_DQS_DN<10> @BASEBOARD_FAB2_LIB.BASEBOARD_FAB2(SCH_1):M_D_DQS_DN(10)   I172 @BASEBOARD_FAB2_LIB.BASEBOARD_FAB2(SCH_1):PAGE26
  CR84 M_D_DQS_DN<9> @BASEBOARD_FAB2_LIB.BASEBOARD_FAB2(SCH_1):M_D_DQS_DN(9)   I172 @BASEBOARD_FAB2_LIB.BASEBOARD_FAB2(SCH_1):PAGE26
  DF67 M_D_DQS_DN<8> @BASEBOARD_FAB2_LIB.BASEBOARD_FAB2(SCH_1):M_D_DQS_DN(8)   I172 @BASEBOARD_FAB2_LIB.BASEBOARD_FAB2(SCH_1):PAGE26
  DV23 M_D_DQS_DN<7> @BASEBOARD_FAB2_LIB.BASEBOARD_FAB2(SCH_1):M_D_DQS_DN(7)   I172 @BASEBOARD_FAB2_LIB.BASEBOARD_FAB2(SCH_1):PAGE26
  DV29 M_D_DQS_DN<6> @BASEBOARD_FAB2_LIB.BASEBOARD_FAB2(SCH_1):M_D_DQS_DN(6)   I172 @BASEBOARD_FAB2_LIB.BASEBOARD_FAB2(SCH_1):PAGE26
  DV35 M_D_DQS_DN<5> @BASEBOARD_FAB2_LIB.BASEBOARD_FAB2(SCH_1):M_D_DQS_DN(5)   I172 @BASEBOARD_FAB2_LIB.BASEBOARD_FAB2(SCH_1):PAGE26
  EE38 M_D_DQS_DN<4> @BASEBOARD_FAB2_LIB.BASEBOARD_FAB2(SCH_1):M_D_DQS_DN(4)   I172 @BASEBOARD_FAB2_LIB.BASEBOARD_FAB2(SCH_1):PAGE26
  DV75 M_D_DQS_DN<3> @BASEBOARD_FAB2_LIB.BASEBOARD_FAB2(SCH_1):M_D_DQS_DN(3)   I172 @BASEBOARD_FAB2_LIB.BASEBOARD_FAB2(SCH_1):PAGE26
  DL82 M_D_DQS_DN<2> @BASEBOARD_FAB2_LIB.BASEBOARD_FAB2(SCH_1):M_D_DQS_DN(2)   I172 @BASEBOARD_FAB2_LIB.BASEBOARD_FAB2(SCH_1):PAGE26
  DN84 M_D_DQS_DN<1> @BASEBOARD_FAB2_LIB.BASEBOARD_FAB2(SCH_1):M_D_DQS_DN(1)   I172 @BASEBOARD_FAB2_LIB.BASEBOARD_FAB2(SCH_1):PAGE26
  CU84 M_D_DQS_DN<0> @BASEBOARD_FAB2_LIB.BASEBOARD_FAB2(SCH_1):M_D_DQS_DN(0)   I172 @BASEBOARD_FAB2_LIB.BASEBOARD_FAB2(SCH_1):PAGE26
  CY67 M_D_DQS_DP<17> @BASEBOARD_FAB2_LIB.BASEBOARD_FAB2(SCH_1):M_D_DQS_DP(17)   I172 @BASEBOARD_FAB2_LIB.BASEBOARD_FAB2(SCH_1):PAGE26
  DP23 M_D_DQS_DP<16> @BASEBOARD_FAB2_LIB.BASEBOARD_FAB2(SCH_1):M_D_DQS_DP(16)   I172 @BASEBOARD_FAB2_LIB.BASEBOARD_FAB2(SCH_1):PAGE26
  DP29 M_D_DQS_DP<15> @BASEBOARD_FAB2_LIB.BASEBOARD_FAB2(SCH_1):M_D_DQS_DP(15)   I172 @BASEBOARD_FAB2_LIB.BASEBOARD_FAB2(SCH_1):PAGE26
  DM35 M_D_DQS_DP<14> @BASEBOARD_FAB2_LIB.BASEBOARD_FAB2(SCH_1):M_D_DQS_DP(14)   I172 @BASEBOARD_FAB2_LIB.BASEBOARD_FAB2(SCH_1):PAGE26
  DW38 M_D_DQS_DP<13> @BASEBOARD_FAB2_LIB.BASEBOARD_FAB2(SCH_1):M_D_DQS_DP(13)   I172 @BASEBOARD_FAB2_LIB.BASEBOARD_FAB2(SCH_1):PAGE26
  DM75 M_D_DQS_DP<12> @BASEBOARD_FAB2_LIB.BASEBOARD_FAB2(SCH_1):M_D_DQS_DP(12)   I172 @BASEBOARD_FAB2_LIB.BASEBOARD_FAB2(SCH_1):PAGE26
  DP79 M_D_DQS_DP<11> @BASEBOARD_FAB2_LIB.BASEBOARD_FAB2(SCH_1):M_D_DQS_DP(11)   I172 @BASEBOARD_FAB2_LIB.BASEBOARD_FAB2(SCH_1):PAGE26
  DL84 M_D_DQS_DP<10> @BASEBOARD_FAB2_LIB.BASEBOARD_FAB2(SCH_1):M_D_DQS_DP(10)   I172 @BASEBOARD_FAB2_LIB.BASEBOARD_FAB2(SCH_1):PAGE26
  CP85 M_D_DQS_DP<9> @BASEBOARD_FAB2_LIB.BASEBOARD_FAB2(SCH_1):M_D_DQS_DP(9)   I172 @BASEBOARD_FAB2_LIB.BASEBOARD_FAB2(SCH_1):PAGE26
  DD67 M_D_DQS_DP<8> @BASEBOARD_FAB2_LIB.BASEBOARD_FAB2(SCH_1):M_D_DQS_DP(8)   I172 @BASEBOARD_FAB2_LIB.BASEBOARD_FAB2(SCH_1):PAGE26
  DT23 M_D_DQS_DP<7> @BASEBOARD_FAB2_LIB.BASEBOARD_FAB2(SCH_1):M_D_DQS_DP(7)   I172 @BASEBOARD_FAB2_LIB.BASEBOARD_FAB2(SCH_1):PAGE26
  DT29 M_D_DQS_DP<6> @BASEBOARD_FAB2_LIB.BASEBOARD_FAB2(SCH_1):M_D_DQS_DP(6)   I172 @BASEBOARD_FAB2_LIB.BASEBOARD_FAB2(SCH_1):PAGE26
  DT35 M_D_DQS_DP<5> @BASEBOARD_FAB2_LIB.BASEBOARD_FAB2(SCH_1):M_D_DQS_DP(5)   I172 @BASEBOARD_FAB2_LIB.BASEBOARD_FAB2(SCH_1):PAGE26
  EC38 M_D_DQS_DP<4> @BASEBOARD_FAB2_LIB.BASEBOARD_FAB2(SCH_1):M_D_DQS_DP(4)   I172 @BASEBOARD_FAB2_LIB.BASEBOARD_FAB2(SCH_1):PAGE26
  DT75 M_D_DQS_DP<3> @BASEBOARD_FAB2_LIB.BASEBOARD_FAB2(SCH_1):M_D_DQS_DP(3)   I172 @BASEBOARD_FAB2_LIB.BASEBOARD_FAB2(SCH_1):PAGE26
  DM81 M_D_DQS_DP<2> @BASEBOARD_FAB2_LIB.BASEBOARD_FAB2(SCH_1):M_D_DQS_DP(2)   I172 @BASEBOARD_FAB2_LIB.BASEBOARD_FAB2(SCH_1):PAGE26
  DP85 M_D_DQS_DP<1> @BASEBOARD_FAB2_LIB.BASEBOARD_FAB2(SCH_1):M_D_DQS_DP(1)   I172 @BASEBOARD_FAB2_LIB.BASEBOARD_FAB2(SCH_1):PAGE26
  CV85 M_D_DQS_DP<0> @BASEBOARD_FAB2_LIB.BASEBOARD_FAB2(SCH_1):M_D_DQS_DP(0)   I172 @BASEBOARD_FAB2_LIB.BASEBOARD_FAB2(SCH_1):PAGE26
  DE66 M_D_ECC<7> @BASEBOARD_FAB2_LIB.BASEBOARD_FAB2(SCH_1):M_D_ECC(7)   I172 @BASEBOARD_FAB2_LIB.BASEBOARD_FAB2(SCH_1):PAGE26
  DA66 M_D_ECC<6> @BASEBOARD_FAB2_LIB.BASEBOARD_FAB2(SCH_1):M_D_ECC(6)   I172 @BASEBOARD_FAB2_LIB.BASEBOARD_FAB2(SCH_1):PAGE26
  DD69 M_D_ECC<5> @BASEBOARD_FAB2_LIB.BASEBOARD_FAB2(SCH_1):M_D_ECC(5)   I172 @BASEBOARD_FAB2_LIB.BASEBOARD_FAB2(SCH_1):PAGE26
  DB69 M_D_ECC<4> @BASEBOARD_FAB2_LIB.BASEBOARD_FAB2(SCH_1):M_D_ECC(4)   I172 @BASEBOARD_FAB2_LIB.BASEBOARD_FAB2(SCH_1):PAGE26
  DD65 M_D_ECC<3> @BASEBOARD_FAB2_LIB.BASEBOARD_FAB2(SCH_1):M_D_ECC(3)   I172 @BASEBOARD_FAB2_LIB.BASEBOARD_FAB2(SCH_1):PAGE26
  DB65 M_D_ECC<2> @BASEBOARD_FAB2_LIB.BASEBOARD_FAB2(SCH_1):M_D_ECC(2)   I172 @BASEBOARD_FAB2_LIB.BASEBOARD_FAB2(SCH_1):PAGE26
  DE68 M_D_ECC<1> @BASEBOARD_FAB2_LIB.BASEBOARD_FAB2(SCH_1):M_D_ECC(1)   I172 @BASEBOARD_FAB2_LIB.BASEBOARD_FAB2(SCH_1):PAGE26
  DA68 M_D_ECC<0> @BASEBOARD_FAB2_LIB.BASEBOARD_FAB2(SCH_1):M_D_ECC(0)   I172 @BASEBOARD_FAB2_LIB.BASEBOARD_FAB2(SCH_1):PAGE26
  EA46 M_D_MA<17> @BASEBOARD_FAB2_LIB.BASEBOARD_FAB2(SCH_1):M_D_MA(17)   I172 @BASEBOARD_FAB2_LIB.BASEBOARD_FAB2(SCH_1):PAGE26
  EA52 M_D_MA<16> @BASEBOARD_FAB2_LIB.BASEBOARD_FAB2(SCH_1):M_D_MA(16)   I172 @BASEBOARD_FAB2_LIB.BASEBOARD_FAB2(SCH_1):PAGE26
  DV49 M_D_MA<15> @BASEBOARD_FAB2_LIB.BASEBOARD_FAB2(SCH_1):M_D_MA(15)   I172 @BASEBOARD_FAB2_LIB.BASEBOARD_FAB2(SCH_1):PAGE26
  ED51 M_D_MA<14> @BASEBOARD_FAB2_LIB.BASEBOARD_FAB2(SCH_1):M_D_MA(14)   I172 @BASEBOARD_FAB2_LIB.BASEBOARD_FAB2(SCH_1):PAGE26
  DW48 M_D_MA<13> @BASEBOARD_FAB2_LIB.BASEBOARD_FAB2(SCH_1):M_D_MA(13)   I172 @BASEBOARD_FAB2_LIB.BASEBOARD_FAB2(SCH_1):PAGE26
  DT63 M_D_MA<12> @BASEBOARD_FAB2_LIB.BASEBOARD_FAB2(SCH_1):M_D_MA(12)   I172 @BASEBOARD_FAB2_LIB.BASEBOARD_FAB2(SCH_1):PAGE26
  EB61 M_D_MA<11> @BASEBOARD_FAB2_LIB.BASEBOARD_FAB2(SCH_1):M_D_MA(11)   I172 @BASEBOARD_FAB2_LIB.BASEBOARD_FAB2(SCH_1):PAGE26
  DW54 M_D_MA<10> @BASEBOARD_FAB2_LIB.BASEBOARD_FAB2(SCH_1):M_D_MA(10)   I172 @BASEBOARD_FAB2_LIB.BASEBOARD_FAB2(SCH_1):PAGE26
  EF61 M_D_MA<9> @BASEBOARD_FAB2_LIB.BASEBOARD_FAB2(SCH_1):M_D_MA(9)   I172 @BASEBOARD_FAB2_LIB.BASEBOARD_FAB2(SCH_1):PAGE26
  EB59 M_D_MA<8> @BASEBOARD_FAB2_LIB.BASEBOARD_FAB2(SCH_1):M_D_MA(8)   I172 @BASEBOARD_FAB2_LIB.BASEBOARD_FAB2(SCH_1):PAGE26
  EA60 M_D_MA<7> @BASEBOARD_FAB2_LIB.BASEBOARD_FAB2(SCH_1):M_D_MA(7)   I172 @BASEBOARD_FAB2_LIB.BASEBOARD_FAB2(SCH_1):PAGE26
  EE60 M_D_MA<6> @BASEBOARD_FAB2_LIB.BASEBOARD_FAB2(SCH_1):M_D_MA(6)   I172 @BASEBOARD_FAB2_LIB.BASEBOARD_FAB2(SCH_1):PAGE26
  EA58 M_D_MA<5> @BASEBOARD_FAB2_LIB.BASEBOARD_FAB2(SCH_1):M_D_MA(5)   I172 @BASEBOARD_FAB2_LIB.BASEBOARD_FAB2(SCH_1):PAGE26
  ED59 M_D_MA<4> @BASEBOARD_FAB2_LIB.BASEBOARD_FAB2(SCH_1):M_D_MA(4)   I172 @BASEBOARD_FAB2_LIB.BASEBOARD_FAB2(SCH_1):PAGE26
  EB57 M_D_MA<3> @BASEBOARD_FAB2_LIB.BASEBOARD_FAB2(SCH_1):M_D_MA(3)   I172 @BASEBOARD_FAB2_LIB.BASEBOARD_FAB2(SCH_1):PAGE26
  EE58 M_D_MA<2> @BASEBOARD_FAB2_LIB.BASEBOARD_FAB2(SCH_1):M_D_MA(2)   I172 @BASEBOARD_FAB2_LIB.BASEBOARD_FAB2(SCH_1):PAGE26
  ED57 M_D_MA<1> @BASEBOARD_FAB2_LIB.BASEBOARD_FAB2(SCH_1):M_D_MA(1)   I172 @BASEBOARD_FAB2_LIB.BASEBOARD_FAB2(SCH_1):PAGE26
  EB53 M_D_MA<0> @BASEBOARD_FAB2_LIB.BASEBOARD_FAB2(SCH_1):M_D_MA(0)   I172 @BASEBOARD_FAB2_LIB.BASEBOARD_FAB2(SCH_1):PAGE26
  EA48 M_D_ODT<3> @BASEBOARD_FAB2_LIB.BASEBOARD_FAB2(SCH_1):M_D_ODT(3)   I172 @BASEBOARD_FAB2_LIB.BASEBOARD_FAB2(SCH_1):PAGE26
  EA50 M_D_ODT<2> @BASEBOARD_FAB2_LIB.BASEBOARD_FAB2(SCH_1):M_D_ODT(2)   I172 @BASEBOARD_FAB2_LIB.BASEBOARD_FAB2(SCH_1):PAGE26
  EE48 M_D_ODT<1> @BASEBOARD_FAB2_LIB.BASEBOARD_FAB2(SCH_1):M_D_ODT(1)   I172 @BASEBOARD_FAB2_LIB.BASEBOARD_FAB2(SCH_1):PAGE26
  EE50 M_D_ODT<0> @BASEBOARD_FAB2_LIB.BASEBOARD_FAB2(SCH_1):M_D_ODT(0)   I172 @BASEBOARD_FAB2_LIB.BASEBOARD_FAB2(SCH_1):PAGE26
  ED53 M_D_PAR @BASEBOARD_FAB2_LIB.BASEBOARD_FAB2(SCH_1):M_D_PAR   I172 @BASEBOARD_FAB2_LIB.BASEBOARD_FAB2(SCH_1):PAGE26
  DR62 M_E_ACT_N @BASEBOARD_FAB2_LIB.BASEBOARD_FAB2(SCH_1):M_E_ACT_N   I172 @BASEBOARD_FAB2_LIB.BASEBOARD_FAB2(SCH_1):PAGE27
  DT61 M_E_ALERT_N @BASEBOARD_FAB2_LIB.BASEBOARD_FAB2(SCH_1):M_E_ALERT_N   I172 @BASEBOARD_FAB2_LIB.BASEBOARD_FAB2(SCH_1):PAGE27
  DV55 M_E_BA<1> @BASEBOARD_FAB2_LIB.BASEBOARD_FAB2(SCH_1):M_E_BA(1)   I172 @BASEBOARD_FAB2_LIB.BASEBOARD_FAB2(SCH_1):PAGE27
  DM53 M_E_BA<0> @BASEBOARD_FAB2_LIB.BASEBOARD_FAB2(SCH_1):M_E_BA(0)   I172 @BASEBOARD_FAB2_LIB.BASEBOARD_FAB2(SCH_1):PAGE27
  DM61 M_E_BG<1> @BASEBOARD_FAB2_LIB.BASEBOARD_FAB2(SCH_1):M_E_BG(1)   I172 @BASEBOARD_FAB2_LIB.BASEBOARD_FAB2(SCH_1):PAGE27
  DJ62 M_E_BG<0> @BASEBOARD_FAB2_LIB.BASEBOARD_FAB2(SCH_1):M_E_BG(0)   I172 @BASEBOARD_FAB2_LIB.BASEBOARD_FAB2(SCH_1):PAGE27
  DT47 M_E_C<2> @BASEBOARD_FAB2_LIB.BASEBOARD_FAB2(SCH_1):M_E_C(2)   I172 @BASEBOARD_FAB2_LIB.BASEBOARD_FAB2(SCH_1):PAGE27
  DR64 M_E_CKE<3> @BASEBOARD_FAB2_LIB.BASEBOARD_FAB2(SCH_1):M_E_CKE(3)   I172 @BASEBOARD_FAB2_LIB.BASEBOARD_FAB2(SCH_1):PAGE27
  DL64 M_E_CKE<2> @BASEBOARD_FAB2_LIB.BASEBOARD_FAB2(SCH_1):M_E_CKE(2)   I172 @BASEBOARD_FAB2_LIB.BASEBOARD_FAB2(SCH_1):PAGE27
  DN64 M_E_CKE<1> @BASEBOARD_FAB2_LIB.BASEBOARD_FAB2(SCH_1):M_E_CKE(1)   I172 @BASEBOARD_FAB2_LIB.BASEBOARD_FAB2(SCH_1):PAGE27
  DM63 M_E_CKE<0> @BASEBOARD_FAB2_LIB.BASEBOARD_FAB2(SCH_1):M_E_CKE(0)   I172 @BASEBOARD_FAB2_LIB.BASEBOARD_FAB2(SCH_1):PAGE27
  DT57 M_E_CLK_DN<3> @BASEBOARD_FAB2_LIB.BASEBOARD_FAB2(SCH_1):M_E_CLK_DN(3)   I172 @BASEBOARD_FAB2_LIB.BASEBOARD_FAB2(SCH_1):PAGE27
  DM57 M_E_CLK_DN<2> @BASEBOARD_FAB2_LIB.BASEBOARD_FAB2(SCH_1):M_E_CLK_DN(2)   I172 @BASEBOARD_FAB2_LIB.BASEBOARD_FAB2(SCH_1):PAGE27
  DR54 M_E_CLK_DN<1> @BASEBOARD_FAB2_LIB.BASEBOARD_FAB2(SCH_1):M_E_CLK_DN(1)   I172 @BASEBOARD_FAB2_LIB.BASEBOARD_FAB2(SCH_1):PAGE27
  DM55 M_E_CLK_DN<0> @BASEBOARD_FAB2_LIB.BASEBOARD_FAB2(SCH_1):M_E_CLK_DN(0)   I172 @BASEBOARD_FAB2_LIB.BASEBOARD_FAB2(SCH_1):PAGE27
  DR56 M_E_CLK_DP<3> @BASEBOARD_FAB2_LIB.BASEBOARD_FAB2(SCH_1):M_E_CLK_DP(3)   I172 @BASEBOARD_FAB2_LIB.BASEBOARD_FAB2(SCH_1):PAGE27
  DN56 M_E_CLK_DP<2> @BASEBOARD_FAB2_LIB.BASEBOARD_FAB2(SCH_1):M_E_CLK_DP(2)   I172 @BASEBOARD_FAB2_LIB.BASEBOARD_FAB2(SCH_1):PAGE27
  DT53 M_E_CLK_DP<1> @BASEBOARD_FAB2_LIB.BASEBOARD_FAB2(SCH_1):M_E_CLK_DP(1)   I172 @BASEBOARD_FAB2_LIB.BASEBOARD_FAB2(SCH_1):PAGE27
  DN54 M_E_CLK_DP<0> @BASEBOARD_FAB2_LIB.BASEBOARD_FAB2(SCH_1):M_E_CLK_DP(0)   I172 @BASEBOARD_FAB2_LIB.BASEBOARD_FAB2(SCH_1):PAGE27
  DN46 M_E_CS_N<7> @BASEBOARD_FAB2_LIB.BASEBOARD_FAB2(SCH_1):M_E_CS_N(7)   I172 @BASEBOARD_FAB2_LIB.BASEBOARD_FAB2(SCH_1):PAGE27
  DT45 M_E_CS_N<6> @BASEBOARD_FAB2_LIB.BASEBOARD_FAB2(SCH_1):M_E_CS_N(6)   I172 @BASEBOARD_FAB2_LIB.BASEBOARD_FAB2(SCH_1):PAGE27
  DM49 M_E_CS_N<5> @BASEBOARD_FAB2_LIB.BASEBOARD_FAB2(SCH_1):M_E_CS_N(5)   I172 @BASEBOARD_FAB2_LIB.BASEBOARD_FAB2(SCH_1):PAGE27
  DW50 M_E_CS_N<4> @BASEBOARD_FAB2_LIB.BASEBOARD_FAB2(SCH_1):M_E_CS_N(4)   I172 @BASEBOARD_FAB2_LIB.BASEBOARD_FAB2(SCH_1):PAGE27
  DK47 M_E_CS_N<3> @BASEBOARD_FAB2_LIB.BASEBOARD_FAB2(SCH_1):M_E_CS_N(3)   I172 @BASEBOARD_FAB2_LIB.BASEBOARD_FAB2(SCH_1):PAGE27
  DR46 M_E_CS_N<2> @BASEBOARD_FAB2_LIB.BASEBOARD_FAB2(SCH_1):M_E_CS_N(2)   I172 @BASEBOARD_FAB2_LIB.BASEBOARD_FAB2(SCH_1):PAGE27
  DN50 M_E_CS_N<1> @BASEBOARD_FAB2_LIB.BASEBOARD_FAB2(SCH_1):M_E_CS_N(1)   I172 @BASEBOARD_FAB2_LIB.BASEBOARD_FAB2(SCH_1):PAGE27
  DV51 M_E_CS_N<0> @BASEBOARD_FAB2_LIB.BASEBOARD_FAB2(SCH_1):M_E_CS_N(0)   I172 @BASEBOARD_FAB2_LIB.BASEBOARD_FAB2(SCH_1):PAGE27
  DK25 M_E_DQ<63> @BASEBOARD_FAB2_LIB.BASEBOARD_FAB2(SCH_1):M_E_DQ(63)   I172 @BASEBOARD_FAB2_LIB.BASEBOARD_FAB2(SCH_1):PAGE27
  DF25 M_E_DQ<62> @BASEBOARD_FAB2_LIB.BASEBOARD_FAB2(SCH_1):M_E_DQ(62)   I172 @BASEBOARD_FAB2_LIB.BASEBOARD_FAB2(SCH_1):PAGE27
  DJ28 M_E_DQ<61> @BASEBOARD_FAB2_LIB.BASEBOARD_FAB2(SCH_1):M_E_DQ(61)   I172 @BASEBOARD_FAB2_LIB.BASEBOARD_FAB2(SCH_1):PAGE27
  DG28 M_E_DQ<60> @BASEBOARD_FAB2_LIB.BASEBOARD_FAB2(SCH_1):M_E_DQ(60)   I172 @BASEBOARD_FAB2_LIB.BASEBOARD_FAB2(SCH_1):PAGE27
  DJ24 M_E_DQ<59> @BASEBOARD_FAB2_LIB.BASEBOARD_FAB2(SCH_1):M_E_DQ(59)   I172 @BASEBOARD_FAB2_LIB.BASEBOARD_FAB2(SCH_1):PAGE27
  DD25 M_E_DQ<58> @BASEBOARD_FAB2_LIB.BASEBOARD_FAB2(SCH_1):M_E_DQ(58)   I172 @BASEBOARD_FAB2_LIB.BASEBOARD_FAB2(SCH_1):PAGE27
  DK27 M_E_DQ<57> @BASEBOARD_FAB2_LIB.BASEBOARD_FAB2(SCH_1):M_E_DQ(57)   I172 @BASEBOARD_FAB2_LIB.BASEBOARD_FAB2(SCH_1):PAGE27
  DF27 M_E_DQ<56> @BASEBOARD_FAB2_LIB.BASEBOARD_FAB2(SCH_1):M_E_DQ(56)   I172 @BASEBOARD_FAB2_LIB.BASEBOARD_FAB2(SCH_1):PAGE27
  ED25 M_E_DQ<55> @BASEBOARD_FAB2_LIB.BASEBOARD_FAB2(SCH_1):M_E_DQ(55)   I172 @BASEBOARD_FAB2_LIB.BASEBOARD_FAB2(SCH_1):PAGE27
  DY25 M_E_DQ<54> @BASEBOARD_FAB2_LIB.BASEBOARD_FAB2(SCH_1):M_E_DQ(54)   I172 @BASEBOARD_FAB2_LIB.BASEBOARD_FAB2(SCH_1):PAGE27
  EA28 M_E_DQ<53> @BASEBOARD_FAB2_LIB.BASEBOARD_FAB2(SCH_1):M_E_DQ(53)   I172 @BASEBOARD_FAB2_LIB.BASEBOARD_FAB2(SCH_1):PAGE27
  DY27 M_E_DQ<52> @BASEBOARD_FAB2_LIB.BASEBOARD_FAB2(SCH_1):M_E_DQ(52)   I172 @BASEBOARD_FAB2_LIB.BASEBOARD_FAB2(SCH_1):PAGE27
  EC24 M_E_DQ<51> @BASEBOARD_FAB2_LIB.BASEBOARD_FAB2(SCH_1):M_E_DQ(51)   I172 @BASEBOARD_FAB2_LIB.BASEBOARD_FAB2(SCH_1):PAGE27
  EA24 M_E_DQ<50> @BASEBOARD_FAB2_LIB.BASEBOARD_FAB2(SCH_1):M_E_DQ(50)   I172 @BASEBOARD_FAB2_LIB.BASEBOARD_FAB2(SCH_1):PAGE27
  ED27 M_E_DQ<49> @BASEBOARD_FAB2_LIB.BASEBOARD_FAB2(SCH_1):M_E_DQ(49)   I172 @BASEBOARD_FAB2_LIB.BASEBOARD_FAB2(SCH_1):PAGE27
  EC28 M_E_DQ<48> @BASEBOARD_FAB2_LIB.BASEBOARD_FAB2(SCH_1):M_E_DQ(48)   I172 @BASEBOARD_FAB2_LIB.BASEBOARD_FAB2(SCH_1):PAGE27
  ED31 M_E_DQ<47> @BASEBOARD_FAB2_LIB.BASEBOARD_FAB2(SCH_1):M_E_DQ(47)   I172 @BASEBOARD_FAB2_LIB.BASEBOARD_FAB2(SCH_1):PAGE27
  DY31 M_E_DQ<46> @BASEBOARD_FAB2_LIB.BASEBOARD_FAB2(SCH_1):M_E_DQ(46)   I172 @BASEBOARD_FAB2_LIB.BASEBOARD_FAB2(SCH_1):PAGE27
  EA34 M_E_DQ<45> @BASEBOARD_FAB2_LIB.BASEBOARD_FAB2(SCH_1):M_E_DQ(45)   I172 @BASEBOARD_FAB2_LIB.BASEBOARD_FAB2(SCH_1):PAGE27
  DY33 M_E_DQ<44> @BASEBOARD_FAB2_LIB.BASEBOARD_FAB2(SCH_1):M_E_DQ(44)   I172 @BASEBOARD_FAB2_LIB.BASEBOARD_FAB2(SCH_1):PAGE27
  EC30 M_E_DQ<43> @BASEBOARD_FAB2_LIB.BASEBOARD_FAB2(SCH_1):M_E_DQ(43)   I172 @BASEBOARD_FAB2_LIB.BASEBOARD_FAB2(SCH_1):PAGE27
  EA30 M_E_DQ<42> @BASEBOARD_FAB2_LIB.BASEBOARD_FAB2(SCH_1):M_E_DQ(42)   I172 @BASEBOARD_FAB2_LIB.BASEBOARD_FAB2(SCH_1):PAGE27
  ED33 M_E_DQ<41> @BASEBOARD_FAB2_LIB.BASEBOARD_FAB2(SCH_1):M_E_DQ(41)   I172 @BASEBOARD_FAB2_LIB.BASEBOARD_FAB2(SCH_1):PAGE27
  EC34 M_E_DQ<40> @BASEBOARD_FAB2_LIB.BASEBOARD_FAB2(SCH_1):M_E_DQ(40)   I172 @BASEBOARD_FAB2_LIB.BASEBOARD_FAB2(SCH_1):PAGE27
  DU40 M_E_DQ<39> @BASEBOARD_FAB2_LIB.BASEBOARD_FAB2(SCH_1):M_E_DQ(39)   I172 @BASEBOARD_FAB2_LIB.BASEBOARD_FAB2(SCH_1):PAGE27
  DN40 M_E_DQ<38> @BASEBOARD_FAB2_LIB.BASEBOARD_FAB2(SCH_1):M_E_DQ(38)   I172 @BASEBOARD_FAB2_LIB.BASEBOARD_FAB2(SCH_1):PAGE27
  DN42 M_E_DQ<37> @BASEBOARD_FAB2_LIB.BASEBOARD_FAB2(SCH_1):M_E_DQ(37)   I172 @BASEBOARD_FAB2_LIB.BASEBOARD_FAB2(SCH_1):PAGE27
  DL42 M_E_DQ<36> @BASEBOARD_FAB2_LIB.BASEBOARD_FAB2(SCH_1):M_E_DQ(36)   I172 @BASEBOARD_FAB2_LIB.BASEBOARD_FAB2(SCH_1):PAGE27
  DT39 M_E_DQ<35> @BASEBOARD_FAB2_LIB.BASEBOARD_FAB2(SCH_1):M_E_DQ(35)   I172 @BASEBOARD_FAB2_LIB.BASEBOARD_FAB2(SCH_1):PAGE27
  DP39 M_E_DQ<34> @BASEBOARD_FAB2_LIB.BASEBOARD_FAB2(SCH_1):M_E_DQ(34)   I172 @BASEBOARD_FAB2_LIB.BASEBOARD_FAB2(SCH_1):PAGE27
  DW42 M_E_DQ<33> @BASEBOARD_FAB2_LIB.BASEBOARD_FAB2(SCH_1):M_E_DQ(33)   I172 @BASEBOARD_FAB2_LIB.BASEBOARD_FAB2(SCH_1):PAGE27
  DU42 M_E_DQ<32> @BASEBOARD_FAB2_LIB.BASEBOARD_FAB2(SCH_1):M_E_DQ(32)   I172 @BASEBOARD_FAB2_LIB.BASEBOARD_FAB2(SCH_1):PAGE27
  EE72 M_E_DQ<31> @BASEBOARD_FAB2_LIB.BASEBOARD_FAB2(SCH_1):M_E_DQ(31)   I172 @BASEBOARD_FAB2_LIB.BASEBOARD_FAB2(SCH_1):PAGE27
  EA72 M_E_DQ<30> @BASEBOARD_FAB2_LIB.BASEBOARD_FAB2(SCH_1):M_E_DQ(30)   I172 @BASEBOARD_FAB2_LIB.BASEBOARD_FAB2(SCH_1):PAGE27
  EB75 M_E_DQ<29> @BASEBOARD_FAB2_LIB.BASEBOARD_FAB2(SCH_1):M_E_DQ(29)   I172 @BASEBOARD_FAB2_LIB.BASEBOARD_FAB2(SCH_1):PAGE27
  EA74 M_E_DQ<28> @BASEBOARD_FAB2_LIB.BASEBOARD_FAB2(SCH_1):M_E_DQ(28)   I172 @BASEBOARD_FAB2_LIB.BASEBOARD_FAB2(SCH_1):PAGE27
  ED71 M_E_DQ<27> @BASEBOARD_FAB2_LIB.BASEBOARD_FAB2(SCH_1):M_E_DQ(27)   I172 @BASEBOARD_FAB2_LIB.BASEBOARD_FAB2(SCH_1):PAGE27
  EB71 M_E_DQ<26> @BASEBOARD_FAB2_LIB.BASEBOARD_FAB2(SCH_1):M_E_DQ(26)   I172 @BASEBOARD_FAB2_LIB.BASEBOARD_FAB2(SCH_1):PAGE27
  EE74 M_E_DQ<25> @BASEBOARD_FAB2_LIB.BASEBOARD_FAB2(SCH_1):M_E_DQ(25)   I172 @BASEBOARD_FAB2_LIB.BASEBOARD_FAB2(SCH_1):PAGE27
  ED75 M_E_DQ<24> @BASEBOARD_FAB2_LIB.BASEBOARD_FAB2(SCH_1):M_E_DQ(24)   I172 @BASEBOARD_FAB2_LIB.BASEBOARD_FAB2(SCH_1):PAGE27
  EC78 M_E_DQ<23> @BASEBOARD_FAB2_LIB.BASEBOARD_FAB2(SCH_1):M_E_DQ(23)   I172 @BASEBOARD_FAB2_LIB.BASEBOARD_FAB2(SCH_1):PAGE27
  DW78 M_E_DQ<22> @BASEBOARD_FAB2_LIB.BASEBOARD_FAB2(SCH_1):M_E_DQ(22)   I172 @BASEBOARD_FAB2_LIB.BASEBOARD_FAB2(SCH_1):PAGE27
  EB81 M_E_DQ<21> @BASEBOARD_FAB2_LIB.BASEBOARD_FAB2(SCH_1):M_E_DQ(21)   I172 @BASEBOARD_FAB2_LIB.BASEBOARD_FAB2(SCH_1):PAGE27
  DY81 M_E_DQ<20> @BASEBOARD_FAB2_LIB.BASEBOARD_FAB2(SCH_1):M_E_DQ(20)   I172 @BASEBOARD_FAB2_LIB.BASEBOARD_FAB2(SCH_1):PAGE27
  EB77 M_E_DQ<19> @BASEBOARD_FAB2_LIB.BASEBOARD_FAB2(SCH_1):M_E_DQ(19)   I172 @BASEBOARD_FAB2_LIB.BASEBOARD_FAB2(SCH_1):PAGE27
  DY77 M_E_DQ<18> @BASEBOARD_FAB2_LIB.BASEBOARD_FAB2(SCH_1):M_E_DQ(18)   I172 @BASEBOARD_FAB2_LIB.BASEBOARD_FAB2(SCH_1):PAGE27
  EC80 M_E_DQ<17> @BASEBOARD_FAB2_LIB.BASEBOARD_FAB2(SCH_1):M_E_DQ(17)   I172 @BASEBOARD_FAB2_LIB.BASEBOARD_FAB2(SCH_1):PAGE27
  DW80 M_E_DQ<16> @BASEBOARD_FAB2_LIB.BASEBOARD_FAB2(SCH_1):M_E_DQ(16)   I172 @BASEBOARD_FAB2_LIB.BASEBOARD_FAB2(SCH_1):PAGE27
  DE82 M_E_DQ<15> @BASEBOARD_FAB2_LIB.BASEBOARD_FAB2(SCH_1):M_E_DQ(15)   I172 @BASEBOARD_FAB2_LIB.BASEBOARD_FAB2(SCH_1):PAGE27
  DC82 M_E_DQ<14> @BASEBOARD_FAB2_LIB.BASEBOARD_FAB2(SCH_1):M_E_DQ(14)   I172 @BASEBOARD_FAB2_LIB.BASEBOARD_FAB2(SCH_1):PAGE27
  CW80 M_E_DQ<13> @BASEBOARD_FAB2_LIB.BASEBOARD_FAB2(SCH_1):M_E_DQ(13)   I172 @BASEBOARD_FAB2_LIB.BASEBOARD_FAB2(SCH_1):PAGE27
  CY79 M_E_DQ<12> @BASEBOARD_FAB2_LIB.BASEBOARD_FAB2(SCH_1):M_E_DQ(12)   I172 @BASEBOARD_FAB2_LIB.BASEBOARD_FAB2(SCH_1):PAGE27
  DF81 M_E_DQ<11> @BASEBOARD_FAB2_LIB.BASEBOARD_FAB2(SCH_1):M_E_DQ(11)   I172 @BASEBOARD_FAB2_LIB.BASEBOARD_FAB2(SCH_1):PAGE27
  DE80 M_E_DQ<10> @BASEBOARD_FAB2_LIB.BASEBOARD_FAB2(SCH_1):M_E_DQ(10)   I172 @BASEBOARD_FAB2_LIB.BASEBOARD_FAB2(SCH_1):PAGE27
  CY81 M_E_DQ<9> @BASEBOARD_FAB2_LIB.BASEBOARD_FAB2(SCH_1):M_E_DQ(9)   I172 @BASEBOARD_FAB2_LIB.BASEBOARD_FAB2(SCH_1):PAGE27
  DB79 M_E_DQ<8> @BASEBOARD_FAB2_LIB.BASEBOARD_FAB2(SCH_1):M_E_DQ(8)   I172 @BASEBOARD_FAB2_LIB.BASEBOARD_FAB2(SCH_1):PAGE27
  CN82 M_E_DQ<7> @BASEBOARD_FAB2_LIB.BASEBOARD_FAB2(SCH_1):M_E_DQ(7)   I172 @BASEBOARD_FAB2_LIB.BASEBOARD_FAB2(SCH_1):PAGE27
  CR80 M_E_DQ<6> @BASEBOARD_FAB2_LIB.BASEBOARD_FAB2(SCH_1):M_E_DQ(6)   I172 @BASEBOARD_FAB2_LIB.BASEBOARD_FAB2(SCH_1):PAGE27
  CJ80 M_E_DQ<5> @BASEBOARD_FAB2_LIB.BASEBOARD_FAB2(SCH_1):M_E_DQ(5)   I172 @BASEBOARD_FAB2_LIB.BASEBOARD_FAB2(SCH_1):PAGE27
  CK79 M_E_DQ<4> @BASEBOARD_FAB2_LIB.BASEBOARD_FAB2(SCH_1):M_E_DQ(4)   I172 @BASEBOARD_FAB2_LIB.BASEBOARD_FAB2(SCH_1):PAGE27
  CR82 M_E_DQ<3> @BASEBOARD_FAB2_LIB.BASEBOARD_FAB2(SCH_1):M_E_DQ(3)   I172 @BASEBOARD_FAB2_LIB.BASEBOARD_FAB2(SCH_1):PAGE27
  CT81 M_E_DQ<2> @BASEBOARD_FAB2_LIB.BASEBOARD_FAB2(SCH_1):M_E_DQ(2)   I172 @BASEBOARD_FAB2_LIB.BASEBOARD_FAB2(SCH_1):PAGE27
  CK81 M_E_DQ<1> @BASEBOARD_FAB2_LIB.BASEBOARD_FAB2(SCH_1):M_E_DQ(1)   I172 @BASEBOARD_FAB2_LIB.BASEBOARD_FAB2(SCH_1):PAGE27
  CM79 M_E_DQ<0> @BASEBOARD_FAB2_LIB.BASEBOARD_FAB2(SCH_1):M_E_DQ(0)   I172 @BASEBOARD_FAB2_LIB.BASEBOARD_FAB2(SCH_1):PAGE27
  DV67 M_E_DQS_DN<17> @BASEBOARD_FAB2_LIB.BASEBOARD_FAB2(SCH_1):M_E_DQS_DN(17)   I172 @BASEBOARD_FAB2_LIB.BASEBOARD_FAB2(SCH_1):PAGE27
  DG26 M_E_DQS_DN<16> @BASEBOARD_FAB2_LIB.BASEBOARD_FAB2(SCH_1):M_E_DQS_DN(16)   I172 @BASEBOARD_FAB2_LIB.BASEBOARD_FAB2(SCH_1):PAGE27
  EA26 M_E_DQS_DN<15> @BASEBOARD_FAB2_LIB.BASEBOARD_FAB2(SCH_1):M_E_DQS_DN(15)   I172 @BASEBOARD_FAB2_LIB.BASEBOARD_FAB2(SCH_1):PAGE27
  EA32 M_E_DQS_DN<14> @BASEBOARD_FAB2_LIB.BASEBOARD_FAB2(SCH_1):M_E_DQS_DN(14)   I172 @BASEBOARD_FAB2_LIB.BASEBOARD_FAB2(SCH_1):PAGE27
  DP41 M_E_DQS_DN<13> @BASEBOARD_FAB2_LIB.BASEBOARD_FAB2(SCH_1):M_E_DQS_DN(13)   I172 @BASEBOARD_FAB2_LIB.BASEBOARD_FAB2(SCH_1):PAGE27
  EB73 M_E_DQS_DN<12> @BASEBOARD_FAB2_LIB.BASEBOARD_FAB2(SCH_1):M_E_DQS_DN(12)   I172 @BASEBOARD_FAB2_LIB.BASEBOARD_FAB2(SCH_1):PAGE27
  DY79 M_E_DQS_DN<11> @BASEBOARD_FAB2_LIB.BASEBOARD_FAB2(SCH_1):M_E_DQS_DN(11)   I172 @BASEBOARD_FAB2_LIB.BASEBOARD_FAB2(SCH_1):PAGE27
  DC80 M_E_DQS_DN<10> @BASEBOARD_FAB2_LIB.BASEBOARD_FAB2(SCH_1):M_E_DQS_DN(10)   I172 @BASEBOARD_FAB2_LIB.BASEBOARD_FAB2(SCH_1):PAGE27
  CN80 M_E_DQS_DN<9> @BASEBOARD_FAB2_LIB.BASEBOARD_FAB2(SCH_1):M_E_DQS_DN(9)   I172 @BASEBOARD_FAB2_LIB.BASEBOARD_FAB2(SCH_1):PAGE27
  EB67 M_E_DQS_DN<8> @BASEBOARD_FAB2_LIB.BASEBOARD_FAB2(SCH_1):M_E_DQS_DN(8)   I172 @BASEBOARD_FAB2_LIB.BASEBOARD_FAB2(SCH_1):PAGE27
  DL26 M_E_DQS_DN<7> @BASEBOARD_FAB2_LIB.BASEBOARD_FAB2(SCH_1):M_E_DQS_DN(7)   I172 @BASEBOARD_FAB2_LIB.BASEBOARD_FAB2(SCH_1):PAGE27
  EE26 M_E_DQS_DN<6> @BASEBOARD_FAB2_LIB.BASEBOARD_FAB2(SCH_1):M_E_DQS_DN(6)   I172 @BASEBOARD_FAB2_LIB.BASEBOARD_FAB2(SCH_1):PAGE27
  EE32 M_E_DQS_DN<5> @BASEBOARD_FAB2_LIB.BASEBOARD_FAB2(SCH_1):M_E_DQS_DN(5)   I172 @BASEBOARD_FAB2_LIB.BASEBOARD_FAB2(SCH_1):PAGE27
  DV41 M_E_DQS_DN<4> @BASEBOARD_FAB2_LIB.BASEBOARD_FAB2(SCH_1):M_E_DQS_DN(4)   I172 @BASEBOARD_FAB2_LIB.BASEBOARD_FAB2(SCH_1):PAGE27
  EF73 M_E_DQS_DN<3> @BASEBOARD_FAB2_LIB.BASEBOARD_FAB2(SCH_1):M_E_DQS_DN(3)   I172 @BASEBOARD_FAB2_LIB.BASEBOARD_FAB2(SCH_1):PAGE27
  ED79 M_E_DQS_DN<2> @BASEBOARD_FAB2_LIB.BASEBOARD_FAB2(SCH_1):M_E_DQS_DN(2)   I172 @BASEBOARD_FAB2_LIB.BASEBOARD_FAB2(SCH_1):PAGE27
  DA82 M_E_DQS_DN<1> @BASEBOARD_FAB2_LIB.BASEBOARD_FAB2(SCH_1):M_E_DQS_DN(1)   I172 @BASEBOARD_FAB2_LIB.BASEBOARD_FAB2(SCH_1):PAGE27
  CL82 M_E_DQS_DN<0> @BASEBOARD_FAB2_LIB.BASEBOARD_FAB2(SCH_1):M_E_DQS_DN(0)   I172 @BASEBOARD_FAB2_LIB.BASEBOARD_FAB2(SCH_1):PAGE27
  DT67 M_E_DQS_DP<17> @BASEBOARD_FAB2_LIB.BASEBOARD_FAB2(SCH_1):M_E_DQS_DP(17)   I172 @BASEBOARD_FAB2_LIB.BASEBOARD_FAB2(SCH_1):PAGE27
  DE26 M_E_DQS_DP<16> @BASEBOARD_FAB2_LIB.BASEBOARD_FAB2(SCH_1):M_E_DQS_DP(16)   I172 @BASEBOARD_FAB2_LIB.BASEBOARD_FAB2(SCH_1):PAGE27
  DW26 M_E_DQS_DP<15> @BASEBOARD_FAB2_LIB.BASEBOARD_FAB2(SCH_1):M_E_DQS_DP(15)   I172 @BASEBOARD_FAB2_LIB.BASEBOARD_FAB2(SCH_1):PAGE27
  DW32 M_E_DQS_DP<14> @BASEBOARD_FAB2_LIB.BASEBOARD_FAB2(SCH_1):M_E_DQS_DP(14)   I172 @BASEBOARD_FAB2_LIB.BASEBOARD_FAB2(SCH_1):PAGE27
  DM41 M_E_DQS_DP<13> @BASEBOARD_FAB2_LIB.BASEBOARD_FAB2(SCH_1):M_E_DQS_DP(13)   I172 @BASEBOARD_FAB2_LIB.BASEBOARD_FAB2(SCH_1):PAGE27
  DY73 M_E_DQS_DP<12> @BASEBOARD_FAB2_LIB.BASEBOARD_FAB2(SCH_1):M_E_DQS_DP(12)   I172 @BASEBOARD_FAB2_LIB.BASEBOARD_FAB2(SCH_1):PAGE27
  DV79 M_E_DQS_DP<11> @BASEBOARD_FAB2_LIB.BASEBOARD_FAB2(SCH_1):M_E_DQS_DP(11)   I172 @BASEBOARD_FAB2_LIB.BASEBOARD_FAB2(SCH_1):PAGE27
  DD79 M_E_DQS_DP<10> @BASEBOARD_FAB2_LIB.BASEBOARD_FAB2(SCH_1):M_E_DQS_DP(10)   I172 @BASEBOARD_FAB2_LIB.BASEBOARD_FAB2(SCH_1):PAGE27
  CP79 M_E_DQS_DP<9> @BASEBOARD_FAB2_LIB.BASEBOARD_FAB2(SCH_1):M_E_DQS_DP(9)   I172 @BASEBOARD_FAB2_LIB.BASEBOARD_FAB2(SCH_1):PAGE27
  DY67 M_E_DQS_DP<8> @BASEBOARD_FAB2_LIB.BASEBOARD_FAB2(SCH_1):M_E_DQS_DP(8)   I172 @BASEBOARD_FAB2_LIB.BASEBOARD_FAB2(SCH_1):PAGE27
  DJ26 M_E_DQS_DP<7> @BASEBOARD_FAB2_LIB.BASEBOARD_FAB2(SCH_1):M_E_DQS_DP(7)   I172 @BASEBOARD_FAB2_LIB.BASEBOARD_FAB2(SCH_1):PAGE27
  EC26 M_E_DQS_DP<6> @BASEBOARD_FAB2_LIB.BASEBOARD_FAB2(SCH_1):M_E_DQS_DP(6)   I172 @BASEBOARD_FAB2_LIB.BASEBOARD_FAB2(SCH_1):PAGE27
  EC32 M_E_DQS_DP<5> @BASEBOARD_FAB2_LIB.BASEBOARD_FAB2(SCH_1):M_E_DQS_DP(5)   I172 @BASEBOARD_FAB2_LIB.BASEBOARD_FAB2(SCH_1):PAGE27
  DT41 M_E_DQS_DP<4> @BASEBOARD_FAB2_LIB.BASEBOARD_FAB2(SCH_1):M_E_DQS_DP(4)   I172 @BASEBOARD_FAB2_LIB.BASEBOARD_FAB2(SCH_1):PAGE27
  ED73 M_E_DQS_DP<3> @BASEBOARD_FAB2_LIB.BASEBOARD_FAB2(SCH_1):M_E_DQS_DP(3)   I172 @BASEBOARD_FAB2_LIB.BASEBOARD_FAB2(SCH_1):PAGE27
  EB79 M_E_DQS_DP<2> @BASEBOARD_FAB2_LIB.BASEBOARD_FAB2(SCH_1):M_E_DQS_DP(2)   I172 @BASEBOARD_FAB2_LIB.BASEBOARD_FAB2(SCH_1):PAGE27
  DB81 M_E_DQS_DP<1> @BASEBOARD_FAB2_LIB.BASEBOARD_FAB2(SCH_1):M_E_DQS_DP(1)   I172 @BASEBOARD_FAB2_LIB.BASEBOARD_FAB2(SCH_1):PAGE27
  CM81 M_E_DQS_DP<0> @BASEBOARD_FAB2_LIB.BASEBOARD_FAB2(SCH_1):M_E_DQS_DP(0)   I172 @BASEBOARD_FAB2_LIB.BASEBOARD_FAB2(SCH_1):PAGE27
  EA66 M_E_ECC<7> @BASEBOARD_FAB2_LIB.BASEBOARD_FAB2(SCH_1):M_E_ECC(7)   I172 @BASEBOARD_FAB2_LIB.BASEBOARD_FAB2(SCH_1):PAGE27
  DU66 M_E_ECC<6> @BASEBOARD_FAB2_LIB.BASEBOARD_FAB2(SCH_1):M_E_ECC(6)   I172 @BASEBOARD_FAB2_LIB.BASEBOARD_FAB2(SCH_1):PAGE27
  DV69 M_E_ECC<5> @BASEBOARD_FAB2_LIB.BASEBOARD_FAB2(SCH_1):M_E_ECC(5)   I172 @BASEBOARD_FAB2_LIB.BASEBOARD_FAB2(SCH_1):PAGE27
  DU68 M_E_ECC<4> @BASEBOARD_FAB2_LIB.BASEBOARD_FAB2(SCH_1):M_E_ECC(4)   I172 @BASEBOARD_FAB2_LIB.BASEBOARD_FAB2(SCH_1):PAGE27
  DY65 M_E_ECC<3> @BASEBOARD_FAB2_LIB.BASEBOARD_FAB2(SCH_1):M_E_ECC(3)   I172 @BASEBOARD_FAB2_LIB.BASEBOARD_FAB2(SCH_1):PAGE27
  DV65 M_E_ECC<2> @BASEBOARD_FAB2_LIB.BASEBOARD_FAB2(SCH_1):M_E_ECC(2)   I172 @BASEBOARD_FAB2_LIB.BASEBOARD_FAB2(SCH_1):PAGE27
  EA68 M_E_ECC<1> @BASEBOARD_FAB2_LIB.BASEBOARD_FAB2(SCH_1):M_E_ECC(1)   I172 @BASEBOARD_FAB2_LIB.BASEBOARD_FAB2(SCH_1):PAGE27
  DY69 M_E_ECC<0> @BASEBOARD_FAB2_LIB.BASEBOARD_FAB2(SCH_1):M_E_ECC(0)   I172 @BASEBOARD_FAB2_LIB.BASEBOARD_FAB2(SCH_1):PAGE27
  DR48 M_E_MA<17> @BASEBOARD_FAB2_LIB.BASEBOARD_FAB2(SCH_1):M_E_MA(17)   I172 @BASEBOARD_FAB2_LIB.BASEBOARD_FAB2(SCH_1):PAGE27
  DN52 M_E_MA<16> @BASEBOARD_FAB2_LIB.BASEBOARD_FAB2(SCH_1):M_E_MA(16)   I172 @BASEBOARD_FAB2_LIB.BASEBOARD_FAB2(SCH_1):PAGE27
  DR52 M_E_MA<15> @BASEBOARD_FAB2_LIB.BASEBOARD_FAB2(SCH_1):M_E_MA(15)   I172 @BASEBOARD_FAB2_LIB.BASEBOARD_FAB2(SCH_1):PAGE27
  DM51 M_E_MA<14> @BASEBOARD_FAB2_LIB.BASEBOARD_FAB2(SCH_1):M_E_MA(14)   I172 @BASEBOARD_FAB2_LIB.BASEBOARD_FAB2(SCH_1):PAGE27
  DT51 M_E_MA<13> @BASEBOARD_FAB2_LIB.BASEBOARD_FAB2(SCH_1):M_E_MA(13)   I172 @BASEBOARD_FAB2_LIB.BASEBOARD_FAB2(SCH_1):PAGE27
  DN60 M_E_MA<12> @BASEBOARD_FAB2_LIB.BASEBOARD_FAB2(SCH_1):M_E_MA(12)   I172 @BASEBOARD_FAB2_LIB.BASEBOARD_FAB2(SCH_1):PAGE27
  DR60 M_E_MA<11> @BASEBOARD_FAB2_LIB.BASEBOARD_FAB2(SCH_1):M_E_MA(11)   I172 @BASEBOARD_FAB2_LIB.BASEBOARD_FAB2(SCH_1):PAGE27
  DT55 M_E_MA<10> @BASEBOARD_FAB2_LIB.BASEBOARD_FAB2(SCH_1):M_E_MA(10)   I172 @BASEBOARD_FAB2_LIB.BASEBOARD_FAB2(SCH_1):PAGE27
  DV59 M_E_MA<9> @BASEBOARD_FAB2_LIB.BASEBOARD_FAB2(SCH_1):M_E_MA(9)   I172 @BASEBOARD_FAB2_LIB.BASEBOARD_FAB2(SCH_1):PAGE27
  DJ60 M_E_MA<8> @BASEBOARD_FAB2_LIB.BASEBOARD_FAB2(SCH_1):M_E_MA(8)   I172 @BASEBOARD_FAB2_LIB.BASEBOARD_FAB2(SCH_1):PAGE27
  DK61 M_E_MA<7> @BASEBOARD_FAB2_LIB.BASEBOARD_FAB2(SCH_1):M_E_MA(7)   I172 @BASEBOARD_FAB2_LIB.BASEBOARD_FAB2(SCH_1):PAGE27
  DM59 M_E_MA<6> @BASEBOARD_FAB2_LIB.BASEBOARD_FAB2(SCH_1):M_E_MA(6)   I172 @BASEBOARD_FAB2_LIB.BASEBOARD_FAB2(SCH_1):PAGE27
  DN58 M_E_MA<5> @BASEBOARD_FAB2_LIB.BASEBOARD_FAB2(SCH_1):M_E_MA(5)   I172 @BASEBOARD_FAB2_LIB.BASEBOARD_FAB2(SCH_1):PAGE27
  DT59 M_E_MA<4> @BASEBOARD_FAB2_LIB.BASEBOARD_FAB2(SCH_1):M_E_MA(4)   I172 @BASEBOARD_FAB2_LIB.BASEBOARD_FAB2(SCH_1):PAGE27
  DR58 M_E_MA<3> @BASEBOARD_FAB2_LIB.BASEBOARD_FAB2(SCH_1):M_E_MA(3)   I172 @BASEBOARD_FAB2_LIB.BASEBOARD_FAB2(SCH_1):PAGE27
  DV57 M_E_MA<2> @BASEBOARD_FAB2_LIB.BASEBOARD_FAB2(SCH_1):M_E_MA(2)   I172 @BASEBOARD_FAB2_LIB.BASEBOARD_FAB2(SCH_1):PAGE27
  DW58 M_E_MA<1> @BASEBOARD_FAB2_LIB.BASEBOARD_FAB2(SCH_1):M_E_MA(1)   I172 @BASEBOARD_FAB2_LIB.BASEBOARD_FAB2(SCH_1):PAGE27
  DW52 M_E_MA<0> @BASEBOARD_FAB2_LIB.BASEBOARD_FAB2(SCH_1):M_E_MA(0)   I172 @BASEBOARD_FAB2_LIB.BASEBOARD_FAB2(SCH_1):PAGE27
  DM47 M_E_ODT<3> @BASEBOARD_FAB2_LIB.BASEBOARD_FAB2(SCH_1):M_E_ODT(3)   I172 @BASEBOARD_FAB2_LIB.BASEBOARD_FAB2(SCH_1):PAGE27
  DT49 M_E_ODT<2> @BASEBOARD_FAB2_LIB.BASEBOARD_FAB2(SCH_1):M_E_ODT(2)   I172 @BASEBOARD_FAB2_LIB.BASEBOARD_FAB2(SCH_1):PAGE27
  DN48 M_E_ODT<1> @BASEBOARD_FAB2_LIB.BASEBOARD_FAB2(SCH_1):M_E_ODT(1)   I172 @BASEBOARD_FAB2_LIB.BASEBOARD_FAB2(SCH_1):PAGE27
  DR50 M_E_ODT<0> @BASEBOARD_FAB2_LIB.BASEBOARD_FAB2(SCH_1):M_E_ODT(0)   I172 @BASEBOARD_FAB2_LIB.BASEBOARD_FAB2(SCH_1):PAGE27
  DV53 M_E_PAR @BASEBOARD_FAB2_LIB.BASEBOARD_FAB2(SCH_1):M_E_PAR   I172 @BASEBOARD_FAB2_LIB.BASEBOARD_FAB2(SCH_1):PAGE27
  DC62 M_F_ACT_N @BASEBOARD_FAB2_LIB.BASEBOARD_FAB2(SCH_1):M_F_ACT_N   I172 @BASEBOARD_FAB2_LIB.BASEBOARD_FAB2(SCH_1):PAGE28
  DD61 M_F_ALERT_N @BASEBOARD_FAB2_LIB.BASEBOARD_FAB2(SCH_1):M_F_ALERT_N   I172 @BASEBOARD_FAB2_LIB.BASEBOARD_FAB2(SCH_1):PAGE28
  DC56 M_F_BA<1> @BASEBOARD_FAB2_LIB.BASEBOARD_FAB2(SCH_1):M_F_BA(1)   I172 @BASEBOARD_FAB2_LIB.BASEBOARD_FAB2(SCH_1):PAGE28
  DJ52 M_F_BA<0> @BASEBOARD_FAB2_LIB.BASEBOARD_FAB2(SCH_1):M_F_BA(0)   I172 @BASEBOARD_FAB2_LIB.BASEBOARD_FAB2(SCH_1):PAGE28
  DF61 M_F_BG<1> @BASEBOARD_FAB2_LIB.BASEBOARD_FAB2(SCH_1):M_F_BG(1)   I172 @BASEBOARD_FAB2_LIB.BASEBOARD_FAB2(SCH_1):PAGE28
  DA62 M_F_BG<0> @BASEBOARD_FAB2_LIB.BASEBOARD_FAB2(SCH_1):M_F_BG(0)   I172 @BASEBOARD_FAB2_LIB.BASEBOARD_FAB2(SCH_1):PAGE28
  DF45 M_F_C<2> @BASEBOARD_FAB2_LIB.BASEBOARD_FAB2(SCH_1):M_F_C(2)   I172 @BASEBOARD_FAB2_LIB.BASEBOARD_FAB2(SCH_1):PAGE28
  DF63 M_F_CKE<3> @BASEBOARD_FAB2_LIB.BASEBOARD_FAB2(SCH_1):M_F_CKE(3)   I172 @BASEBOARD_FAB2_LIB.BASEBOARD_FAB2(SCH_1):PAGE28
  DK63 M_F_CKE<2> @BASEBOARD_FAB2_LIB.BASEBOARD_FAB2(SCH_1):M_F_CKE(2)   I172 @BASEBOARD_FAB2_LIB.BASEBOARD_FAB2(SCH_1):PAGE28
  DD63 M_F_CKE<1> @BASEBOARD_FAB2_LIB.BASEBOARD_FAB2(SCH_1):M_F_CKE(1)   I172 @BASEBOARD_FAB2_LIB.BASEBOARD_FAB2(SCH_1):PAGE28
  DG62 M_F_CKE<0> @BASEBOARD_FAB2_LIB.BASEBOARD_FAB2(SCH_1):M_F_CKE(0)   I172 @BASEBOARD_FAB2_LIB.BASEBOARD_FAB2(SCH_1):PAGE28
  DF57 M_F_CLK_DN<3> @BASEBOARD_FAB2_LIB.BASEBOARD_FAB2(SCH_1):M_F_CLK_DN(3)   I172 @BASEBOARD_FAB2_LIB.BASEBOARD_FAB2(SCH_1):PAGE28
  DK57 M_F_CLK_DN<2> @BASEBOARD_FAB2_LIB.BASEBOARD_FAB2(SCH_1):M_F_CLK_DN(2)   I172 @BASEBOARD_FAB2_LIB.BASEBOARD_FAB2(SCH_1):PAGE28
  DF55 M_F_CLK_DN<1> @BASEBOARD_FAB2_LIB.BASEBOARD_FAB2(SCH_1):M_F_CLK_DN(1)   I172 @BASEBOARD_FAB2_LIB.BASEBOARD_FAB2(SCH_1):PAGE28
  DK55 M_F_CLK_DN<0> @BASEBOARD_FAB2_LIB.BASEBOARD_FAB2(SCH_1):M_F_CLK_DN(0)   I172 @BASEBOARD_FAB2_LIB.BASEBOARD_FAB2(SCH_1):PAGE28
  DG56 M_F_CLK_DP<3> @BASEBOARD_FAB2_LIB.BASEBOARD_FAB2(SCH_1):M_F_CLK_DP(3)   I172 @BASEBOARD_FAB2_LIB.BASEBOARD_FAB2(SCH_1):PAGE28
  DJ56 M_F_CLK_DP<2> @BASEBOARD_FAB2_LIB.BASEBOARD_FAB2(SCH_1):M_F_CLK_DP(2)   I172 @BASEBOARD_FAB2_LIB.BASEBOARD_FAB2(SCH_1):PAGE28
  DG54 M_F_CLK_DP<1> @BASEBOARD_FAB2_LIB.BASEBOARD_FAB2(SCH_1):M_F_CLK_DP(1)   I172 @BASEBOARD_FAB2_LIB.BASEBOARD_FAB2(SCH_1):PAGE28
  DJ54 M_F_CLK_DP<0> @BASEBOARD_FAB2_LIB.BASEBOARD_FAB2(SCH_1):M_F_CLK_DP(0)   I172 @BASEBOARD_FAB2_LIB.BASEBOARD_FAB2(SCH_1):PAGE28
  DK45 M_F_CS_N<7> @BASEBOARD_FAB2_LIB.BASEBOARD_FAB2(SCH_1):M_F_CS_N(7)   I172 @BASEBOARD_FAB2_LIB.BASEBOARD_FAB2(SCH_1):PAGE28
  DM45 M_F_CS_N<6> @BASEBOARD_FAB2_LIB.BASEBOARD_FAB2(SCH_1):M_F_CS_N(6)   I172 @BASEBOARD_FAB2_LIB.BASEBOARD_FAB2(SCH_1):PAGE28
  DJ48 M_F_CS_N<5> @BASEBOARD_FAB2_LIB.BASEBOARD_FAB2(SCH_1):M_F_CS_N(5)   I172 @BASEBOARD_FAB2_LIB.BASEBOARD_FAB2(SCH_1):PAGE28
  DF51 M_F_CS_N<4> @BASEBOARD_FAB2_LIB.BASEBOARD_FAB2(SCH_1):M_F_CS_N(4)   I172 @BASEBOARD_FAB2_LIB.BASEBOARD_FAB2(SCH_1):PAGE28
  DG46 M_F_CS_N<3> @BASEBOARD_FAB2_LIB.BASEBOARD_FAB2(SCH_1):M_F_CS_N(3)   I172 @BASEBOARD_FAB2_LIB.BASEBOARD_FAB2(SCH_1):PAGE28
  DJ46 M_F_CS_N<2> @BASEBOARD_FAB2_LIB.BASEBOARD_FAB2(SCH_1):M_F_CS_N(2)   I172 @BASEBOARD_FAB2_LIB.BASEBOARD_FAB2(SCH_1):PAGE28
  DF49 M_F_CS_N<1> @BASEBOARD_FAB2_LIB.BASEBOARD_FAB2(SCH_1):M_F_CS_N(1)   I172 @BASEBOARD_FAB2_LIB.BASEBOARD_FAB2(SCH_1):PAGE28
  DK51 M_F_CS_N<0> @BASEBOARD_FAB2_LIB.BASEBOARD_FAB2(SCH_1):M_F_CS_N(0)   I172 @BASEBOARD_FAB2_LIB.BASEBOARD_FAB2(SCH_1):PAGE28
  DC28 M_F_DQ<63> @BASEBOARD_FAB2_LIB.BASEBOARD_FAB2(SCH_1):M_F_DQ(63)   I172 @BASEBOARD_FAB2_LIB.BASEBOARD_FAB2(SCH_1):PAGE28
  CW28 M_F_DQ<62> @BASEBOARD_FAB2_LIB.BASEBOARD_FAB2(SCH_1):M_F_DQ(62)   I172 @BASEBOARD_FAB2_LIB.BASEBOARD_FAB2(SCH_1):PAGE28
  DB31 M_F_DQ<61> @BASEBOARD_FAB2_LIB.BASEBOARD_FAB2(SCH_1):M_F_DQ(61)   I172 @BASEBOARD_FAB2_LIB.BASEBOARD_FAB2(SCH_1):PAGE28
  CY31 M_F_DQ<60> @BASEBOARD_FAB2_LIB.BASEBOARD_FAB2(SCH_1):M_F_DQ(60)   I172 @BASEBOARD_FAB2_LIB.BASEBOARD_FAB2(SCH_1):PAGE28
  DB27 M_F_DQ<59> @BASEBOARD_FAB2_LIB.BASEBOARD_FAB2(SCH_1):M_F_DQ(59)   I172 @BASEBOARD_FAB2_LIB.BASEBOARD_FAB2(SCH_1):PAGE28
  CY27 M_F_DQ<58> @BASEBOARD_FAB2_LIB.BASEBOARD_FAB2(SCH_1):M_F_DQ(58)   I172 @BASEBOARD_FAB2_LIB.BASEBOARD_FAB2(SCH_1):PAGE28
  DC30 M_F_DQ<57> @BASEBOARD_FAB2_LIB.BASEBOARD_FAB2(SCH_1):M_F_DQ(57)   I172 @BASEBOARD_FAB2_LIB.BASEBOARD_FAB2(SCH_1):PAGE28
  CW30 M_F_DQ<56> @BASEBOARD_FAB2_LIB.BASEBOARD_FAB2(SCH_1):M_F_DQ(56)   I172 @BASEBOARD_FAB2_LIB.BASEBOARD_FAB2(SCH_1):PAGE28
  DC34 M_F_DQ<55> @BASEBOARD_FAB2_LIB.BASEBOARD_FAB2(SCH_1):M_F_DQ(55)   I172 @BASEBOARD_FAB2_LIB.BASEBOARD_FAB2(SCH_1):PAGE28
  CW34 M_F_DQ<54> @BASEBOARD_FAB2_LIB.BASEBOARD_FAB2(SCH_1):M_F_DQ(54)   I172 @BASEBOARD_FAB2_LIB.BASEBOARD_FAB2(SCH_1):PAGE28
  DB37 M_F_DQ<53> @BASEBOARD_FAB2_LIB.BASEBOARD_FAB2(SCH_1):M_F_DQ(53)   I172 @BASEBOARD_FAB2_LIB.BASEBOARD_FAB2(SCH_1):PAGE28
  CY37 M_F_DQ<52> @BASEBOARD_FAB2_LIB.BASEBOARD_FAB2(SCH_1):M_F_DQ(52)   I172 @BASEBOARD_FAB2_LIB.BASEBOARD_FAB2(SCH_1):PAGE28
  DB33 M_F_DQ<51> @BASEBOARD_FAB2_LIB.BASEBOARD_FAB2(SCH_1):M_F_DQ(51)   I172 @BASEBOARD_FAB2_LIB.BASEBOARD_FAB2(SCH_1):PAGE28
  CY33 M_F_DQ<50> @BASEBOARD_FAB2_LIB.BASEBOARD_FAB2(SCH_1):M_F_DQ(50)   I172 @BASEBOARD_FAB2_LIB.BASEBOARD_FAB2(SCH_1):PAGE28
  DC36 M_F_DQ<49> @BASEBOARD_FAB2_LIB.BASEBOARD_FAB2(SCH_1):M_F_DQ(49)   I172 @BASEBOARD_FAB2_LIB.BASEBOARD_FAB2(SCH_1):PAGE28
  CW36 M_F_DQ<48> @BASEBOARD_FAB2_LIB.BASEBOARD_FAB2(SCH_1):M_F_DQ(48)   I172 @BASEBOARD_FAB2_LIB.BASEBOARD_FAB2(SCH_1):PAGE28
  DK31 M_F_DQ<47> @BASEBOARD_FAB2_LIB.BASEBOARD_FAB2(SCH_1):M_F_DQ(47)   I172 @BASEBOARD_FAB2_LIB.BASEBOARD_FAB2(SCH_1):PAGE28
  DF31 M_F_DQ<46> @BASEBOARD_FAB2_LIB.BASEBOARD_FAB2(SCH_1):M_F_DQ(46)   I172 @BASEBOARD_FAB2_LIB.BASEBOARD_FAB2(SCH_1):PAGE28
  DJ34 M_F_DQ<45> @BASEBOARD_FAB2_LIB.BASEBOARD_FAB2(SCH_1):M_F_DQ(45)   I172 @BASEBOARD_FAB2_LIB.BASEBOARD_FAB2(SCH_1):PAGE28
  DG34 M_F_DQ<44> @BASEBOARD_FAB2_LIB.BASEBOARD_FAB2(SCH_1):M_F_DQ(44)   I172 @BASEBOARD_FAB2_LIB.BASEBOARD_FAB2(SCH_1):PAGE28
  DJ30 M_F_DQ<43> @BASEBOARD_FAB2_LIB.BASEBOARD_FAB2(SCH_1):M_F_DQ(43)   I172 @BASEBOARD_FAB2_LIB.BASEBOARD_FAB2(SCH_1):PAGE28
  DG30 M_F_DQ<42> @BASEBOARD_FAB2_LIB.BASEBOARD_FAB2(SCH_1):M_F_DQ(42)   I172 @BASEBOARD_FAB2_LIB.BASEBOARD_FAB2(SCH_1):PAGE28
  DK33 M_F_DQ<41> @BASEBOARD_FAB2_LIB.BASEBOARD_FAB2(SCH_1):M_F_DQ(41)   I172 @BASEBOARD_FAB2_LIB.BASEBOARD_FAB2(SCH_1):PAGE28
  DF33 M_F_DQ<40> @BASEBOARD_FAB2_LIB.BASEBOARD_FAB2(SCH_1):M_F_DQ(40)   I172 @BASEBOARD_FAB2_LIB.BASEBOARD_FAB2(SCH_1):PAGE28
  DH39 M_F_DQ<39> @BASEBOARD_FAB2_LIB.BASEBOARD_FAB2(SCH_1):M_F_DQ(39)   I172 @BASEBOARD_FAB2_LIB.BASEBOARD_FAB2(SCH_1):PAGE28
  DD39 M_F_DQ<38> @BASEBOARD_FAB2_LIB.BASEBOARD_FAB2(SCH_1):M_F_DQ(38)   I172 @BASEBOARD_FAB2_LIB.BASEBOARD_FAB2(SCH_1):PAGE28
  DE42 M_F_DQ<37> @BASEBOARD_FAB2_LIB.BASEBOARD_FAB2(SCH_1):M_F_DQ(37)   I172 @BASEBOARD_FAB2_LIB.BASEBOARD_FAB2(SCH_1):PAGE28
  DA42 M_F_DQ<36> @BASEBOARD_FAB2_LIB.BASEBOARD_FAB2(SCH_1):M_F_DQ(36)   I172 @BASEBOARD_FAB2_LIB.BASEBOARD_FAB2(SCH_1):PAGE28
  DG38 M_F_DQ<35> @BASEBOARD_FAB2_LIB.BASEBOARD_FAB2(SCH_1):M_F_DQ(35)   I172 @BASEBOARD_FAB2_LIB.BASEBOARD_FAB2(SCH_1):PAGE28
  DE38 M_F_DQ<34> @BASEBOARD_FAB2_LIB.BASEBOARD_FAB2(SCH_1):M_F_DQ(34)   I172 @BASEBOARD_FAB2_LIB.BASEBOARD_FAB2(SCH_1):PAGE28
  DG42 M_F_DQ<33> @BASEBOARD_FAB2_LIB.BASEBOARD_FAB2(SCH_1):M_F_DQ(33)   I172 @BASEBOARD_FAB2_LIB.BASEBOARD_FAB2(SCH_1):PAGE28
  DD41 M_F_DQ<32> @BASEBOARD_FAB2_LIB.BASEBOARD_FAB2(SCH_1):M_F_DQ(32)   I172 @BASEBOARD_FAB2_LIB.BASEBOARD_FAB2(SCH_1):PAGE28
  CU64 M_F_DQ<31> @BASEBOARD_FAB2_LIB.BASEBOARD_FAB2(SCH_1):M_F_DQ(31)   I172 @BASEBOARD_FAB2_LIB.BASEBOARD_FAB2(SCH_1):PAGE28
  CN64 M_F_DQ<30> @BASEBOARD_FAB2_LIB.BASEBOARD_FAB2(SCH_1):M_F_DQ(30)   I172 @BASEBOARD_FAB2_LIB.BASEBOARD_FAB2(SCH_1):PAGE28
  CT67 M_F_DQ<29> @BASEBOARD_FAB2_LIB.BASEBOARD_FAB2(SCH_1):M_F_DQ(29)   I172 @BASEBOARD_FAB2_LIB.BASEBOARD_FAB2(SCH_1):PAGE28
  CP67 M_F_DQ<28> @BASEBOARD_FAB2_LIB.BASEBOARD_FAB2(SCH_1):M_F_DQ(28)   I172 @BASEBOARD_FAB2_LIB.BASEBOARD_FAB2(SCH_1):PAGE28
  CT63 M_F_DQ<27> @BASEBOARD_FAB2_LIB.BASEBOARD_FAB2(SCH_1):M_F_DQ(27)   I172 @BASEBOARD_FAB2_LIB.BASEBOARD_FAB2(SCH_1):PAGE28
  CP63 M_F_DQ<26> @BASEBOARD_FAB2_LIB.BASEBOARD_FAB2(SCH_1):M_F_DQ(26)   I172 @BASEBOARD_FAB2_LIB.BASEBOARD_FAB2(SCH_1):PAGE28
  CU66 M_F_DQ<25> @BASEBOARD_FAB2_LIB.BASEBOARD_FAB2(SCH_1):M_F_DQ(25)   I172 @BASEBOARD_FAB2_LIB.BASEBOARD_FAB2(SCH_1):PAGE28
  CN66 M_F_DQ<24> @BASEBOARD_FAB2_LIB.BASEBOARD_FAB2(SCH_1):M_F_DQ(24)   I172 @BASEBOARD_FAB2_LIB.BASEBOARD_FAB2(SCH_1):PAGE28
  DM71 M_F_DQ<23> @BASEBOARD_FAB2_LIB.BASEBOARD_FAB2(SCH_1):M_F_DQ(23)   I172 @BASEBOARD_FAB2_LIB.BASEBOARD_FAB2(SCH_1):PAGE28
  DK69 M_F_DQ<22> @BASEBOARD_FAB2_LIB.BASEBOARD_FAB2(SCH_1):M_F_DQ(22)   I172 @BASEBOARD_FAB2_LIB.BASEBOARD_FAB2(SCH_1):PAGE28
  DG72 M_F_DQ<21> @BASEBOARD_FAB2_LIB.BASEBOARD_FAB2(SCH_1):M_F_DQ(21)   I172 @BASEBOARD_FAB2_LIB.BASEBOARD_FAB2(SCH_1):PAGE28
  DF71 M_F_DQ<20> @BASEBOARD_FAB2_LIB.BASEBOARD_FAB2(SCH_1):M_F_DQ(20)   I172 @BASEBOARD_FAB2_LIB.BASEBOARD_FAB2(SCH_1):PAGE28
  DN70 M_F_DQ<19> @BASEBOARD_FAB2_LIB.BASEBOARD_FAB2(SCH_1):M_F_DQ(19)   I172 @BASEBOARD_FAB2_LIB.BASEBOARD_FAB2(SCH_1):PAGE28
  DM69 M_F_DQ<18> @BASEBOARD_FAB2_LIB.BASEBOARD_FAB2(SCH_1):M_F_DQ(18)   I172 @BASEBOARD_FAB2_LIB.BASEBOARD_FAB2(SCH_1):PAGE28
  DJ72 M_F_DQ<17> @BASEBOARD_FAB2_LIB.BASEBOARD_FAB2(SCH_1):M_F_DQ(17)   I172 @BASEBOARD_FAB2_LIB.BASEBOARD_FAB2(SCH_1):PAGE28
  DG70 M_F_DQ<16> @BASEBOARD_FAB2_LIB.BASEBOARD_FAB2(SCH_1):M_F_DQ(16)   I172 @BASEBOARD_FAB2_LIB.BASEBOARD_FAB2(SCH_1):PAGE28
  DH77 M_F_DQ<15> @BASEBOARD_FAB2_LIB.BASEBOARD_FAB2(SCH_1):M_F_DQ(15)   I172 @BASEBOARD_FAB2_LIB.BASEBOARD_FAB2(SCH_1):PAGE28
  DF77 M_F_DQ<14> @BASEBOARD_FAB2_LIB.BASEBOARD_FAB2(SCH_1):M_F_DQ(14)   I172 @BASEBOARD_FAB2_LIB.BASEBOARD_FAB2(SCH_1):PAGE28
  DB75 M_F_DQ<13> @BASEBOARD_FAB2_LIB.BASEBOARD_FAB2(SCH_1):M_F_DQ(13)   I172 @BASEBOARD_FAB2_LIB.BASEBOARD_FAB2(SCH_1):PAGE28
  DC74 M_F_DQ<12> @BASEBOARD_FAB2_LIB.BASEBOARD_FAB2(SCH_1):M_F_DQ(12)   I172 @BASEBOARD_FAB2_LIB.BASEBOARD_FAB2(SCH_1):PAGE28
  DJ76 M_F_DQ<11> @BASEBOARD_FAB2_LIB.BASEBOARD_FAB2(SCH_1):M_F_DQ(11)   I172 @BASEBOARD_FAB2_LIB.BASEBOARD_FAB2(SCH_1):PAGE28
  DH75 M_F_DQ<10> @BASEBOARD_FAB2_LIB.BASEBOARD_FAB2(SCH_1):M_F_DQ(10)   I172 @BASEBOARD_FAB2_LIB.BASEBOARD_FAB2(SCH_1):PAGE28
  DC76 M_F_DQ<9> @BASEBOARD_FAB2_LIB.BASEBOARD_FAB2(SCH_1):M_F_DQ(9)   I172 @BASEBOARD_FAB2_LIB.BASEBOARD_FAB2(SCH_1):PAGE28
  DE74 M_F_DQ<8> @BASEBOARD_FAB2_LIB.BASEBOARD_FAB2(SCH_1):M_F_DQ(8)   I172 @BASEBOARD_FAB2_LIB.BASEBOARD_FAB2(SCH_1):PAGE28
  CT77 M_F_DQ<7> @BASEBOARD_FAB2_LIB.BASEBOARD_FAB2(SCH_1):M_F_DQ(7)   I172 @BASEBOARD_FAB2_LIB.BASEBOARD_FAB2(SCH_1):PAGE28
  CV75 M_F_DQ<6> @BASEBOARD_FAB2_LIB.BASEBOARD_FAB2(SCH_1):M_F_DQ(6)   I172 @BASEBOARD_FAB2_LIB.BASEBOARD_FAB2(SCH_1):PAGE28
  CM75 M_F_DQ<5> @BASEBOARD_FAB2_LIB.BASEBOARD_FAB2(SCH_1):M_F_DQ(5)   I172 @BASEBOARD_FAB2_LIB.BASEBOARD_FAB2(SCH_1):PAGE28
  CN74 M_F_DQ<4> @BASEBOARD_FAB2_LIB.BASEBOARD_FAB2(SCH_1):M_F_DQ(4)   I172 @BASEBOARD_FAB2_LIB.BASEBOARD_FAB2(SCH_1):PAGE28
  CV77 M_F_DQ<3> @BASEBOARD_FAB2_LIB.BASEBOARD_FAB2(SCH_1):M_F_DQ(3)   I172 @BASEBOARD_FAB2_LIB.BASEBOARD_FAB2(SCH_1):PAGE28
  CW76 M_F_DQ<2> @BASEBOARD_FAB2_LIB.BASEBOARD_FAB2(SCH_1):M_F_DQ(2)   I172 @BASEBOARD_FAB2_LIB.BASEBOARD_FAB2(SCH_1):PAGE28
  CN76 M_F_DQ<1> @BASEBOARD_FAB2_LIB.BASEBOARD_FAB2(SCH_1):M_F_DQ(1)   I172 @BASEBOARD_FAB2_LIB.BASEBOARD_FAB2(SCH_1):PAGE28
  CR74 M_F_DQ<0> @BASEBOARD_FAB2_LIB.BASEBOARD_FAB2(SCH_1):M_F_DQ(0)   I172 @BASEBOARD_FAB2_LIB.BASEBOARD_FAB2(SCH_1):PAGE28
  CJ70 M_F_DQS_DN<17> @BASEBOARD_FAB2_LIB.BASEBOARD_FAB2(SCH_1):M_F_DQS_DN(17)   I172 @BASEBOARD_FAB2_LIB.BASEBOARD_FAB2(SCH_1):PAGE28
  CY29 M_F_DQS_DN<16> @BASEBOARD_FAB2_LIB.BASEBOARD_FAB2(SCH_1):M_F_DQS_DN(16)   I172 @BASEBOARD_FAB2_LIB.BASEBOARD_FAB2(SCH_1):PAGE28
  CY35 M_F_DQS_DN<15> @BASEBOARD_FAB2_LIB.BASEBOARD_FAB2(SCH_1):M_F_DQS_DN(15)   I172 @BASEBOARD_FAB2_LIB.BASEBOARD_FAB2(SCH_1):PAGE28
  DG32 M_F_DQS_DN<14> @BASEBOARD_FAB2_LIB.BASEBOARD_FAB2(SCH_1):M_F_DQS_DN(14)   I172 @BASEBOARD_FAB2_LIB.BASEBOARD_FAB2(SCH_1):PAGE28
  DE40 M_F_DQS_DN<13> @BASEBOARD_FAB2_LIB.BASEBOARD_FAB2(SCH_1):M_F_DQS_DN(13)   I172 @BASEBOARD_FAB2_LIB.BASEBOARD_FAB2(SCH_1):PAGE28
  CP65 M_F_DQS_DN<12> @BASEBOARD_FAB2_LIB.BASEBOARD_FAB2(SCH_1):M_F_DQS_DN(12)   I172 @BASEBOARD_FAB2_LIB.BASEBOARD_FAB2(SCH_1):PAGE28
  DJ70 M_F_DQS_DN<11> @BASEBOARD_FAB2_LIB.BASEBOARD_FAB2(SCH_1):M_F_DQS_DN(11)   I172 @BASEBOARD_FAB2_LIB.BASEBOARD_FAB2(SCH_1):PAGE28
  DF75 M_F_DQS_DN<10> @BASEBOARD_FAB2_LIB.BASEBOARD_FAB2(SCH_1):M_F_DQS_DN(10)   I172 @BASEBOARD_FAB2_LIB.BASEBOARD_FAB2(SCH_1):PAGE28
  CT75 M_F_DQS_DN<9> @BASEBOARD_FAB2_LIB.BASEBOARD_FAB2(SCH_1):M_F_DQS_DN(9)   I172 @BASEBOARD_FAB2_LIB.BASEBOARD_FAB2(SCH_1):PAGE28
  CN70 M_F_DQS_DN<8> @BASEBOARD_FAB2_LIB.BASEBOARD_FAB2(SCH_1):M_F_DQS_DN(8)   I172 @BASEBOARD_FAB2_LIB.BASEBOARD_FAB2(SCH_1):PAGE28
  DD29 M_F_DQS_DN<7> @BASEBOARD_FAB2_LIB.BASEBOARD_FAB2(SCH_1):M_F_DQS_DN(7)   I172 @BASEBOARD_FAB2_LIB.BASEBOARD_FAB2(SCH_1):PAGE28
  DD35 M_F_DQS_DN<6> @BASEBOARD_FAB2_LIB.BASEBOARD_FAB2(SCH_1):M_F_DQS_DN(6)   I172 @BASEBOARD_FAB2_LIB.BASEBOARD_FAB2(SCH_1):PAGE28
  DL32 M_F_DQS_DN<5> @BASEBOARD_FAB2_LIB.BASEBOARD_FAB2(SCH_1):M_F_DQS_DN(5)   I172 @BASEBOARD_FAB2_LIB.BASEBOARD_FAB2(SCH_1):PAGE28
  DG40 M_F_DQS_DN<4> @BASEBOARD_FAB2_LIB.BASEBOARD_FAB2(SCH_1):M_F_DQS_DN(4)   I172 @BASEBOARD_FAB2_LIB.BASEBOARD_FAB2(SCH_1):PAGE28
  CV65 M_F_DQS_DN<3> @BASEBOARD_FAB2_LIB.BASEBOARD_FAB2(SCH_1):M_F_DQS_DN(3)   I172 @BASEBOARD_FAB2_LIB.BASEBOARD_FAB2(SCH_1):PAGE28
  DL72 M_F_DQS_DN<2> @BASEBOARD_FAB2_LIB.BASEBOARD_FAB2(SCH_1):M_F_DQS_DN(2)   I172 @BASEBOARD_FAB2_LIB.BASEBOARD_FAB2(SCH_1):PAGE28
  DD77 M_F_DQS_DN<1> @BASEBOARD_FAB2_LIB.BASEBOARD_FAB2(SCH_1):M_F_DQS_DN(1)   I172 @BASEBOARD_FAB2_LIB.BASEBOARD_FAB2(SCH_1):PAGE28
  CP77 M_F_DQS_DN<0> @BASEBOARD_FAB2_LIB.BASEBOARD_FAB2(SCH_1):M_F_DQS_DN(0)   I172 @BASEBOARD_FAB2_LIB.BASEBOARD_FAB2(SCH_1):PAGE28
  CG70 M_F_DQS_DP<17> @BASEBOARD_FAB2_LIB.BASEBOARD_FAB2(SCH_1):M_F_DQS_DP(17)   I172 @BASEBOARD_FAB2_LIB.BASEBOARD_FAB2(SCH_1):PAGE28
  CV29 M_F_DQS_DP<16> @BASEBOARD_FAB2_LIB.BASEBOARD_FAB2(SCH_1):M_F_DQS_DP(16)   I172 @BASEBOARD_FAB2_LIB.BASEBOARD_FAB2(SCH_1):PAGE28
  CV35 M_F_DQS_DP<15> @BASEBOARD_FAB2_LIB.BASEBOARD_FAB2(SCH_1):M_F_DQS_DP(15)   I172 @BASEBOARD_FAB2_LIB.BASEBOARD_FAB2(SCH_1):PAGE28
  DE32 M_F_DQS_DP<14> @BASEBOARD_FAB2_LIB.BASEBOARD_FAB2(SCH_1):M_F_DQS_DP(14)   I172 @BASEBOARD_FAB2_LIB.BASEBOARD_FAB2(SCH_1):PAGE28
  DC40 M_F_DQS_DP<13> @BASEBOARD_FAB2_LIB.BASEBOARD_FAB2(SCH_1):M_F_DQS_DP(13)   I172 @BASEBOARD_FAB2_LIB.BASEBOARD_FAB2(SCH_1):PAGE28
  CM65 M_F_DQS_DP<12> @BASEBOARD_FAB2_LIB.BASEBOARD_FAB2(SCH_1):M_F_DQS_DP(12)   I172 @BASEBOARD_FAB2_LIB.BASEBOARD_FAB2(SCH_1):PAGE28
  DH69 M_F_DQS_DP<11> @BASEBOARD_FAB2_LIB.BASEBOARD_FAB2(SCH_1):M_F_DQS_DP(11)   I172 @BASEBOARD_FAB2_LIB.BASEBOARD_FAB2(SCH_1):PAGE28
  DG74 M_F_DQS_DP<10> @BASEBOARD_FAB2_LIB.BASEBOARD_FAB2(SCH_1):M_F_DQS_DP(10)   I172 @BASEBOARD_FAB2_LIB.BASEBOARD_FAB2(SCH_1):PAGE28
  CU74 M_F_DQS_DP<9> @BASEBOARD_FAB2_LIB.BASEBOARD_FAB2(SCH_1):M_F_DQS_DP(9)   I172 @BASEBOARD_FAB2_LIB.BASEBOARD_FAB2(SCH_1):PAGE28
  CL70 M_F_DQS_DP<8> @BASEBOARD_FAB2_LIB.BASEBOARD_FAB2(SCH_1):M_F_DQS_DP(8)   I172 @BASEBOARD_FAB2_LIB.BASEBOARD_FAB2(SCH_1):PAGE28
  DB29 M_F_DQS_DP<7> @BASEBOARD_FAB2_LIB.BASEBOARD_FAB2(SCH_1):M_F_DQS_DP(7)   I172 @BASEBOARD_FAB2_LIB.BASEBOARD_FAB2(SCH_1):PAGE28
  DB35 M_F_DQS_DP<6> @BASEBOARD_FAB2_LIB.BASEBOARD_FAB2(SCH_1):M_F_DQS_DP(6)   I172 @BASEBOARD_FAB2_LIB.BASEBOARD_FAB2(SCH_1):PAGE28
  DJ32 M_F_DQS_DP<5> @BASEBOARD_FAB2_LIB.BASEBOARD_FAB2(SCH_1):M_F_DQS_DP(5)   I172 @BASEBOARD_FAB2_LIB.BASEBOARD_FAB2(SCH_1):PAGE28
  DJ40 M_F_DQS_DP<4> @BASEBOARD_FAB2_LIB.BASEBOARD_FAB2(SCH_1):M_F_DQS_DP(4)   I172 @BASEBOARD_FAB2_LIB.BASEBOARD_FAB2(SCH_1):PAGE28
  CT65 M_F_DQS_DP<3> @BASEBOARD_FAB2_LIB.BASEBOARD_FAB2(SCH_1):M_F_DQS_DP(3)   I172 @BASEBOARD_FAB2_LIB.BASEBOARD_FAB2(SCH_1):PAGE28
  DK71 M_F_DQS_DP<2> @BASEBOARD_FAB2_LIB.BASEBOARD_FAB2(SCH_1):M_F_DQS_DP(2)   I172 @BASEBOARD_FAB2_LIB.BASEBOARD_FAB2(SCH_1):PAGE28
  DE76 M_F_DQS_DP<1> @BASEBOARD_FAB2_LIB.BASEBOARD_FAB2(SCH_1):M_F_DQS_DP(1)   I172 @BASEBOARD_FAB2_LIB.BASEBOARD_FAB2(SCH_1):PAGE28
  CR76 M_F_DQS_DP<0> @BASEBOARD_FAB2_LIB.BASEBOARD_FAB2(SCH_1):M_F_DQS_DP(0)   I172 @BASEBOARD_FAB2_LIB.BASEBOARD_FAB2(SCH_1):PAGE28
  CM69 M_F_ECC<7> @BASEBOARD_FAB2_LIB.BASEBOARD_FAB2(SCH_1):M_F_ECC(7)   I172 @BASEBOARD_FAB2_LIB.BASEBOARD_FAB2(SCH_1):PAGE28
  CH69 M_F_ECC<6> @BASEBOARD_FAB2_LIB.BASEBOARD_FAB2(SCH_1):M_F_ECC(6)   I172 @BASEBOARD_FAB2_LIB.BASEBOARD_FAB2(SCH_1):PAGE28
  CL72 M_F_ECC<5> @BASEBOARD_FAB2_LIB.BASEBOARD_FAB2(SCH_1):M_F_ECC(5)   I172 @BASEBOARD_FAB2_LIB.BASEBOARD_FAB2(SCH_1):PAGE28
  CJ72 M_F_ECC<4> @BASEBOARD_FAB2_LIB.BASEBOARD_FAB2(SCH_1):M_F_ECC(4)   I172 @BASEBOARD_FAB2_LIB.BASEBOARD_FAB2(SCH_1):PAGE28
  CL68 M_F_ECC<3> @BASEBOARD_FAB2_LIB.BASEBOARD_FAB2(SCH_1):M_F_ECC(3)   I172 @BASEBOARD_FAB2_LIB.BASEBOARD_FAB2(SCH_1):PAGE28
  CJ68 M_F_ECC<2> @BASEBOARD_FAB2_LIB.BASEBOARD_FAB2(SCH_1):M_F_ECC(2)   I172 @BASEBOARD_FAB2_LIB.BASEBOARD_FAB2(SCH_1):PAGE28
  CM71 M_F_ECC<1> @BASEBOARD_FAB2_LIB.BASEBOARD_FAB2(SCH_1):M_F_ECC(1)   I172 @BASEBOARD_FAB2_LIB.BASEBOARD_FAB2(SCH_1):PAGE28
  CH71 M_F_ECC<0> @BASEBOARD_FAB2_LIB.BASEBOARD_FAB2(SCH_1):M_F_ECC(0)   I172 @BASEBOARD_FAB2_LIB.BASEBOARD_FAB2(SCH_1):PAGE28
  DE46 M_F_MA<17> @BASEBOARD_FAB2_LIB.BASEBOARD_FAB2(SCH_1):M_F_MA(17)   I172 @BASEBOARD_FAB2_LIB.BASEBOARD_FAB2(SCH_1):PAGE28
  DG52 M_F_MA<16> @BASEBOARD_FAB2_LIB.BASEBOARD_FAB2(SCH_1):M_F_MA(16)   I172 @BASEBOARD_FAB2_LIB.BASEBOARD_FAB2(SCH_1):PAGE28
  DC54 M_F_MA<15> @BASEBOARD_FAB2_LIB.BASEBOARD_FAB2(SCH_1):M_F_MA(15)   I172 @BASEBOARD_FAB2_LIB.BASEBOARD_FAB2(SCH_1):PAGE28
  DJ50 M_F_MA<14> @BASEBOARD_FAB2_LIB.BASEBOARD_FAB2(SCH_1):M_F_MA(14)   I172 @BASEBOARD_FAB2_LIB.BASEBOARD_FAB2(SCH_1):PAGE28
  DD53 M_F_MA<13> @BASEBOARD_FAB2_LIB.BASEBOARD_FAB2(SCH_1):M_F_MA(13)   I172 @BASEBOARD_FAB2_LIB.BASEBOARD_FAB2(SCH_1):PAGE28
  DG60 M_F_MA<12> @BASEBOARD_FAB2_LIB.BASEBOARD_FAB2(SCH_1):M_F_MA(12)   I172 @BASEBOARD_FAB2_LIB.BASEBOARD_FAB2(SCH_1):PAGE28
  DA60 M_F_MA<11> @BASEBOARD_FAB2_LIB.BASEBOARD_FAB2(SCH_1):M_F_MA(11)   I172 @BASEBOARD_FAB2_LIB.BASEBOARD_FAB2(SCH_1):PAGE28
  DD55 M_F_MA<10> @BASEBOARD_FAB2_LIB.BASEBOARD_FAB2(SCH_1):M_F_MA(10)   I172 @BASEBOARD_FAB2_LIB.BASEBOARD_FAB2(SCH_1):PAGE28
  DA58 M_F_MA<9> @BASEBOARD_FAB2_LIB.BASEBOARD_FAB2(SCH_1):M_F_MA(9)   I172 @BASEBOARD_FAB2_LIB.BASEBOARD_FAB2(SCH_1):PAGE28
  DD59 M_F_MA<8> @BASEBOARD_FAB2_LIB.BASEBOARD_FAB2(SCH_1):M_F_MA(8)   I172 @BASEBOARD_FAB2_LIB.BASEBOARD_FAB2(SCH_1):PAGE28
  DC60 M_F_MA<7> @BASEBOARD_FAB2_LIB.BASEBOARD_FAB2(SCH_1):M_F_MA(7)   I172 @BASEBOARD_FAB2_LIB.BASEBOARD_FAB2(SCH_1):PAGE28
  DK59 M_F_MA<6> @BASEBOARD_FAB2_LIB.BASEBOARD_FAB2(SCH_1):M_F_MA(6)   I172 @BASEBOARD_FAB2_LIB.BASEBOARD_FAB2(SCH_1):PAGE28
  DF59 M_F_MA<5> @BASEBOARD_FAB2_LIB.BASEBOARD_FAB2(SCH_1):M_F_MA(5)   I172 @BASEBOARD_FAB2_LIB.BASEBOARD_FAB2(SCH_1):PAGE28
  DJ58 M_F_MA<4> @BASEBOARD_FAB2_LIB.BASEBOARD_FAB2(SCH_1):M_F_MA(4)   I172 @BASEBOARD_FAB2_LIB.BASEBOARD_FAB2(SCH_1):PAGE28
  DG58 M_F_MA<3> @BASEBOARD_FAB2_LIB.BASEBOARD_FAB2(SCH_1):M_F_MA(3)   I172 @BASEBOARD_FAB2_LIB.BASEBOARD_FAB2(SCH_1):PAGE28
  DD57 M_F_MA<2> @BASEBOARD_FAB2_LIB.BASEBOARD_FAB2(SCH_1):M_F_MA(2)   I172 @BASEBOARD_FAB2_LIB.BASEBOARD_FAB2(SCH_1):PAGE28
  DC58 M_F_MA<1> @BASEBOARD_FAB2_LIB.BASEBOARD_FAB2(SCH_1):M_F_MA(1)   I172 @BASEBOARD_FAB2_LIB.BASEBOARD_FAB2(SCH_1):PAGE28
  DF53 M_F_MA<0> @BASEBOARD_FAB2_LIB.BASEBOARD_FAB2(SCH_1):M_F_MA(0)   I172 @BASEBOARD_FAB2_LIB.BASEBOARD_FAB2(SCH_1):PAGE28
  DF47 M_F_ODT<3> @BASEBOARD_FAB2_LIB.BASEBOARD_FAB2(SCH_1):M_F_ODT(3)   I172 @BASEBOARD_FAB2_LIB.BASEBOARD_FAB2(SCH_1):PAGE28
  DK49 M_F_ODT<2> @BASEBOARD_FAB2_LIB.BASEBOARD_FAB2(SCH_1):M_F_ODT(2)   I172 @BASEBOARD_FAB2_LIB.BASEBOARD_FAB2(SCH_1):PAGE28
  DG48 M_F_ODT<1> @BASEBOARD_FAB2_LIB.BASEBOARD_FAB2(SCH_1):M_F_ODT(1)   I172 @BASEBOARD_FAB2_LIB.BASEBOARD_FAB2(SCH_1):PAGE28
  DG50 M_F_ODT<0> @BASEBOARD_FAB2_LIB.BASEBOARD_FAB2(SCH_1):M_F_ODT(0)   I172 @BASEBOARD_FAB2_LIB.BASEBOARD_FAB2(SCH_1):PAGE28
  DK53 M_F_PAR @BASEBOARD_FAB2_LIB.BASEBOARD_FAB2(SCH_1):M_F_PAR   I172 @BASEBOARD_FAB2_LIB.BASEBOARD_FAB2(SCH_1):PAGE28
  BN22 SMB_HFI0_CPU0_LVC2_SCL @BASEBOARD_FAB2_LIB.BASEBOARD_FAB2(SCH_1):SMB_HFI0_CPU0_LVC2_SCL    I61 @BASEBOARD_FAB2_LIB.BASEBOARD_FAB2(SCH_1):PAGE29
  BP23 SMB_HFI0_CPU0_LVC2_SDA @BASEBOARD_FAB2_LIB.BASEBOARD_FAB2(SCH_1):SMB_HFI0_CPU0_LVC2_SDA    I61 @BASEBOARD_FAB2_LIB.BASEBOARD_FAB2(SCH_1):PAGE29
  BP19 IRQ_HFI0_CPU0_LVT2_N @BASEBOARD_FAB2_LIB.BASEBOARD_FAB2(SCH_1):IRQ_HFI0_CPU0_LVT2_N    I61 @BASEBOARD_FAB2_LIB.BASEBOARD_FAB2(SCH_1):PAGE29
  BK21 LED_HFI0_CPU0_N @BASEBOARD_FAB2_LIB.BASEBOARD_FAB2(SCH_1):LED_HFI0_CPU0_N    I61 @BASEBOARD_FAB2_LIB.BASEBOARD_FAB2(SCH_1):PAGE29
  BR20 FM_MODPRST_HFI0_CPU0_LVT2_N @BASEBOARD_FAB2_LIB.BASEBOARD_FAB2(SCH_1):FM_MODPRST_HFI0_CPU0_LVT2_N    I61 @BASEBOARD_FAB2_LIB.BASEBOARD_FAB2(SCH_1):PAGE29
  BN24 RST_HFI0_CPU0_LVT2_N @BASEBOARD_FAB2_LIB.BASEBOARD_FAB2(SCH_1):RST_HFI0_CPU0_LVT2_N    I61 @BASEBOARD_FAB2_LIB.BASEBOARD_FAB2(SCH_1):PAGE29
  BJ22 SMB_HFI1_CPU0_LVC2_SCL @BASEBOARD_FAB2_LIB.BASEBOARD_FAB2(SCH_1):SMB_HFI1_CPU0_LVC2_SCL    I61 @BASEBOARD_FAB2_LIB.BASEBOARD_FAB2(SCH_1):PAGE29
  BH23 SMB_HFI1_CPU0_LVC2_SDA @BASEBOARD_FAB2_LIB.BASEBOARD_FAB2(SCH_1):SMB_HFI1_CPU0_LVC2_SDA    I61 @BASEBOARD_FAB2_LIB.BASEBOARD_FAB2(SCH_1):PAGE29
  BM21 IRQ_HFI1_CPU0_LVT2_N @BASEBOARD_FAB2_LIB.BASEBOARD_FAB2(SCH_1):IRQ_HFI1_CPU0_LVT2_N    I61 @BASEBOARD_FAB2_LIB.BASEBOARD_FAB2(SCH_1):PAGE29
  BM23 LED_HFI1_CPU0_N @BASEBOARD_FAB2_LIB.BASEBOARD_FAB2(SCH_1):LED_HFI1_CPU0_N    I61 @BASEBOARD_FAB2_LIB.BASEBOARD_FAB2(SCH_1):PAGE29
  BT19 FM_MODPRST_HFI1_CPU0_LVT2_N @BASEBOARD_FAB2_LIB.BASEBOARD_FAB2(SCH_1):FM_MODPRST_HFI1_CPU0_LVT2_N    I61 @BASEBOARD_FAB2_LIB.BASEBOARD_FAB2(SCH_1):PAGE29
  BK23 RST_HFI1_CPU0_LVT2_N @BASEBOARD_FAB2_LIB.BASEBOARD_FAB2(SCH_1):RST_HFI1_CPU0_LVT2_N    I61 @BASEBOARD_FAB2_LIB.BASEBOARD_FAB2(SCH_1):PAGE29
  BE16 CLK_156M_OSC_CPU0_HFI_DN @BASEBOARD_FAB2_LIB.BASEBOARD_FAB2(SCH_1):CLK_156M_OSC_CPU0_HFI_DN    I61 @BASEBOARD_FAB2_LIB.BASEBOARD_FAB2(SCH_1):PAGE29
  BG16 CLK_156M_OSC_CPU0_HFI_DP @BASEBOARD_FAB2_LIB.BASEBOARD_FAB2(SCH_1):CLK_156M_OSC_CPU0_HFI_DP    I61 @BASEBOARD_FAB2_LIB.BASEBOARD_FAB2(SCH_1):PAGE29
  BU24 CLK_100M_CPU0_PE_REFCLK_DN @BASEBOARD_FAB2_LIB.BASEBOARD_FAB2(SCH_1):CLK_100M_CPU0_PE_REFCLK_DN    I61 @BASEBOARD_FAB2_LIB.BASEBOARD_FAB2(SCH_1):PAGE29
  BW24 CLK_100M_CPU0_PE_REFCLK_DP @BASEBOARD_FAB2_LIB.BASEBOARD_FAB2(SCH_1):CLK_100M_CPU0_PE_REFCLK_DP    I61 @BASEBOARD_FAB2_LIB.BASEBOARD_FAB2(SCH_1):PAGE29
  CF25 RST_CD_CPU0_POR_N @BASEBOARD_FAB2_LIB.BASEBOARD_FAB2(SCH_1):RST_CD_CPU0_POR_N    I61 @BASEBOARD_FAB2_LIB.BASEBOARD_FAB2(SCH_1):PAGE29
  CB23 JTAG_MCP_TCK @BASEBOARD_FAB2_LIB.BASEBOARD_FAB2(SCH_1):JTAG_MCP_TCK    I61 @BASEBOARD_FAB2_LIB.BASEBOARD_FAB2(SCH_1):PAGE29
  BY21 JTAG_MCP_CPU0_TDI @BASEBOARD_FAB2_LIB.BASEBOARD_FAB2(SCH_1):JTAG_MCP_CPU0_TDI    I61 @BASEBOARD_FAB2_LIB.BASEBOARD_FAB2(SCH_1):PAGE29
  CC22 JTAG_MCP_CPU0_TDO @BASEBOARD_FAB2_LIB.BASEBOARD_FAB2(SCH_1):JTAG_MCP_CPU0_TDO    I61 @BASEBOARD_FAB2_LIB.BASEBOARD_FAB2(SCH_1):PAGE29
  CE24 JTAG_MCP_TMS @BASEBOARD_FAB2_LIB.BASEBOARD_FAB2(SCH_1):JTAG_MCP_TMS    I61 @BASEBOARD_FAB2_LIB.BASEBOARD_FAB2(SCH_1):PAGE29
  CD23 JTAG_MCP_TRST_N @BASEBOARD_FAB2_LIB.BASEBOARD_FAB2(SCH_1):JTAG_MCP_TRST_N    I61 @BASEBOARD_FAB2_LIB.BASEBOARD_FAB2(SCH_1):PAGE29
  CT11 DMI_CPU0_PCH_RX_C_DN<3> @BASEBOARD_FAB2_LIB.BASEBOARD_FAB2(SCH_1):DMI_CPU0_PCH_RX_C_DN(3)    I61 @BASEBOARD_FAB2_LIB.BASEBOARD_FAB2(SCH_1):PAGE29
  CR12 DMI_CPU0_PCH_RX_C_DN<2> @BASEBOARD_FAB2_LIB.BASEBOARD_FAB2(SCH_1):DMI_CPU0_PCH_RX_C_DN(2)    I61 @BASEBOARD_FAB2_LIB.BASEBOARD_FAB2(SCH_1):PAGE29
  CM11 DMI_CPU0_PCH_RX_C_DN<1> @BASEBOARD_FAB2_LIB.BASEBOARD_FAB2(SCH_1):DMI_CPU0_PCH_RX_C_DN(1)    I61 @BASEBOARD_FAB2_LIB.BASEBOARD_FAB2(SCH_1):PAGE29
   CK9 DMI_CPU0_PCH_RX_C_DN<0> @BASEBOARD_FAB2_LIB.BASEBOARD_FAB2(SCH_1):DMI_CPU0_PCH_RX_C_DN(0)    I61 @BASEBOARD_FAB2_LIB.BASEBOARD_FAB2(SCH_1):PAGE29
  CV11 DMI_CPU0_PCH_RX_C_DP<3> @BASEBOARD_FAB2_LIB.BASEBOARD_FAB2(SCH_1):DMI_CPU0_PCH_RX_C_DP(3)    I61 @BASEBOARD_FAB2_LIB.BASEBOARD_FAB2(SCH_1):PAGE29
  CP11 DMI_CPU0_PCH_RX_C_DP<2> @BASEBOARD_FAB2_LIB.BASEBOARD_FAB2(SCH_1):DMI_CPU0_PCH_RX_C_DP(2)    I61 @BASEBOARD_FAB2_LIB.BASEBOARD_FAB2(SCH_1):PAGE29
  CN10 DMI_CPU0_PCH_RX_C_DP<1> @BASEBOARD_FAB2_LIB.BASEBOARD_FAB2(SCH_1):DMI_CPU0_PCH_RX_C_DP(1)    I61 @BASEBOARD_FAB2_LIB.BASEBOARD_FAB2(SCH_1):PAGE29
  CL10 DMI_CPU0_PCH_RX_C_DP<0> @BASEBOARD_FAB2_LIB.BASEBOARD_FAB2(SCH_1):DMI_CPU0_PCH_RX_C_DP(0)    I61 @BASEBOARD_FAB2_LIB.BASEBOARD_FAB2(SCH_1):PAGE29
   CP5 DMI_CPU0_PCH_TX_DN<3> @BASEBOARD_FAB2_LIB.BASEBOARD_FAB2(SCH_1):DMI_CPU0_PCH_TX_DN(3)    I61 @BASEBOARD_FAB2_LIB.BASEBOARD_FAB2(SCH_1):PAGE29
   CN4 DMI_CPU0_PCH_TX_DN<2> @BASEBOARD_FAB2_LIB.BASEBOARD_FAB2(SCH_1):DMI_CPU0_PCH_TX_DN(2)    I61 @BASEBOARD_FAB2_LIB.BASEBOARD_FAB2(SCH_1):PAGE29
   CJ4 DMI_CPU0_PCH_TX_DN<1> @BASEBOARD_FAB2_LIB.BASEBOARD_FAB2(SCH_1):DMI_CPU0_PCH_TX_DN(1)    I61 @BASEBOARD_FAB2_LIB.BASEBOARD_FAB2(SCH_1):PAGE29
   CG4 DMI_CPU0_PCH_TX_DN<0> @BASEBOARD_FAB2_LIB.BASEBOARD_FAB2(SCH_1):DMI_CPU0_PCH_TX_DN(0)    I61 @BASEBOARD_FAB2_LIB.BASEBOARD_FAB2(SCH_1):PAGE29
   CR4 DMI_CPU0_PCH_TX_DP<3> @BASEBOARD_FAB2_LIB.BASEBOARD_FAB2(SCH_1):DMI_CPU0_PCH_TX_DP(3)    I61 @BASEBOARD_FAB2_LIB.BASEBOARD_FAB2(SCH_1):PAGE29
   CM3 DMI_CPU0_PCH_TX_DP<2> @BASEBOARD_FAB2_LIB.BASEBOARD_FAB2(SCH_1):DMI_CPU0_PCH_TX_DP(2)    I61 @BASEBOARD_FAB2_LIB.BASEBOARD_FAB2(SCH_1):PAGE29
   CL4 DMI_CPU0_PCH_TX_DP<1> @BASEBOARD_FAB2_LIB.BASEBOARD_FAB2(SCH_1):DMI_CPU0_PCH_TX_DP(1)    I61 @BASEBOARD_FAB2_LIB.BASEBOARD_FAB2(SCH_1):PAGE29
   CH5 DMI_CPU0_PCH_TX_DP<0> @BASEBOARD_FAB2_LIB.BASEBOARD_FAB2(SCH_1):DMI_CPU0_PCH_TX_DP(0)    I61 @BASEBOARD_FAB2_LIB.BASEBOARD_FAB2(SCH_1):PAGE29
  AR20 PVCCMCP_CPU0 @BASEBOARD_FAB2_LIB.BASEBOARD_FAB2(SCH_1):PVCCMCP_CPU0    I61 @BASEBOARD_FAB2_LIB.BASEBOARD_FAB2(SCH_1):PAGE29
  AR22 PVCCMCP_CPU0 @BASEBOARD_FAB2_LIB.BASEBOARD_FAB2(SCH_1):PVCCMCP_CPU0    I61 @BASEBOARD_FAB2_LIB.BASEBOARD_FAB2(SCH_1):PAGE29
  AR26 PVCCMCP_CPU0 @BASEBOARD_FAB2_LIB.BASEBOARD_FAB2(SCH_1):PVCCMCP_CPU0    I61 @BASEBOARD_FAB2_LIB.BASEBOARD_FAB2(SCH_1):PAGE29
  AR62 TP_CPU0_RSVD_190 @BASEBOARD_FAB2_LIB.BASEBOARD_FAB2(SCH_1):TP_CPU0_RSVD_190    I61 @BASEBOARD_FAB2_LIB.BASEBOARD_FAB2(SCH_1):PAGE29
  AT13 TP_CPU0_RSVD_189 @BASEBOARD_FAB2_LIB.BASEBOARD_FAB2(SCH_1):TP_CPU0_RSVD_189    I61 @BASEBOARD_FAB2_LIB.BASEBOARD_FAB2(SCH_1):PAGE29
  AT23 PVCCMCP_CPU0 @BASEBOARD_FAB2_LIB.BASEBOARD_FAB2(SCH_1):PVCCMCP_CPU0    I61 @BASEBOARD_FAB2_LIB.BASEBOARD_FAB2(SCH_1):PAGE29
  AT25 PVCCMCP_CPU0 @BASEBOARD_FAB2_LIB.BASEBOARD_FAB2(SCH_1):PVCCMCP_CPU0    I61 @BASEBOARD_FAB2_LIB.BASEBOARD_FAB2(SCH_1):PAGE29
  AV77 TP_CPU0_RSVD_186 @BASEBOARD_FAB2_LIB.BASEBOARD_FAB2(SCH_1):TP_CPU0_RSVD_186    I61 @BASEBOARD_FAB2_LIB.BASEBOARD_FAB2(SCH_1):PAGE29
  AW64 TP_CPU0_RSVD_184 @BASEBOARD_FAB2_LIB.BASEBOARD_FAB2(SCH_1):TP_CPU0_RSVD_184    I61 @BASEBOARD_FAB2_LIB.BASEBOARD_FAB2(SCH_1):PAGE29
  AW76 TP_CPU0_RSVD_183 @BASEBOARD_FAB2_LIB.BASEBOARD_FAB2(SCH_1):TP_CPU0_RSVD_183    I61 @BASEBOARD_FAB2_LIB.BASEBOARD_FAB2(SCH_1):PAGE29
  AY65 TP_CPU0_RSVD_182 @BASEBOARD_FAB2_LIB.BASEBOARD_FAB2(SCH_1):TP_CPU0_RSVD_182    I61 @BASEBOARD_FAB2_LIB.BASEBOARD_FAB2(SCH_1):PAGE29
  AY67 TP_CPU0_RSVD_181 @BASEBOARD_FAB2_LIB.BASEBOARD_FAB2(SCH_1):TP_CPU0_RSVD_181    I61 @BASEBOARD_FAB2_LIB.BASEBOARD_FAB2(SCH_1):PAGE29
  AY75 TP_CPU0_RSVD_180 @BASEBOARD_FAB2_LIB.BASEBOARD_FAB2(SCH_1):TP_CPU0_RSVD_180    I61 @BASEBOARD_FAB2_LIB.BASEBOARD_FAB2(SCH_1):PAGE29
  AY77 TP_CPU0_RSVD_179 @BASEBOARD_FAB2_LIB.BASEBOARD_FAB2(SCH_1):TP_CPU0_RSVD_179    I61 @BASEBOARD_FAB2_LIB.BASEBOARD_FAB2(SCH_1):PAGE29
  BA14 TP_CPU0_RSVD_178 @BASEBOARD_FAB2_LIB.BASEBOARD_FAB2(SCH_1):TP_CPU0_RSVD_178    I61 @BASEBOARD_FAB2_LIB.BASEBOARD_FAB2(SCH_1):PAGE29
  BA16 TP_CPU0_RSVD_177 @BASEBOARD_FAB2_LIB.BASEBOARD_FAB2(SCH_1):TP_CPU0_RSVD_177    I61 @BASEBOARD_FAB2_LIB.BASEBOARD_FAB2(SCH_1):PAGE29
  BA18 TP_CPU0_RSVD_176 @BASEBOARD_FAB2_LIB.BASEBOARD_FAB2(SCH_1):TP_CPU0_RSVD_176    I61 @BASEBOARD_FAB2_LIB.BASEBOARD_FAB2(SCH_1):PAGE29
  BA22 TP_CPU0_RSVD_175 @BASEBOARD_FAB2_LIB.BASEBOARD_FAB2(SCH_1):TP_CPU0_RSVD_175    I61 @BASEBOARD_FAB2_LIB.BASEBOARD_FAB2(SCH_1):PAGE29
  BA64 TP_CPU0_RSVD_174 @BASEBOARD_FAB2_LIB.BASEBOARD_FAB2(SCH_1):TP_CPU0_RSVD_174    I61 @BASEBOARD_FAB2_LIB.BASEBOARD_FAB2(SCH_1):PAGE29
  BA66 TP_CPU0_RSVD_173 @BASEBOARD_FAB2_LIB.BASEBOARD_FAB2(SCH_1):TP_CPU0_RSVD_173    I61 @BASEBOARD_FAB2_LIB.BASEBOARD_FAB2(SCH_1):PAGE29
  BA76 TP_CPU0_RSVD_172 @BASEBOARD_FAB2_LIB.BASEBOARD_FAB2(SCH_1):TP_CPU0_RSVD_172    I61 @BASEBOARD_FAB2_LIB.BASEBOARD_FAB2(SCH_1):PAGE29
  DU16 P3E_CPU0_PE1_PCH_RXN<15> @BASEBOARD_FAB2_LIB.BASEBOARD_FAB2(SCH_1):P3E_CPU0_PE1_PCH_RXN(15)    I84 @BASEBOARD_FAB2_LIB.BASEBOARD_FAB2(SCH_1):PAGE30
  DY15 P3E_CPU0_PE1_PCH_RXN<14> @BASEBOARD_FAB2_LIB.BASEBOARD_FAB2(SCH_1):P3E_CPU0_PE1_PCH_RXN(14)    I84 @BASEBOARD_FAB2_LIB.BASEBOARD_FAB2(SCH_1):PAGE30
  DW14 P3E_CPU0_PE1_PCH_RXN<13> @BASEBOARD_FAB2_LIB.BASEBOARD_FAB2(SCH_1):P3E_CPU0_PE1_PCH_RXN(13)    I84 @BASEBOARD_FAB2_LIB.BASEBOARD_FAB2(SCH_1):PAGE30
  DV13 P3E_CPU0_PE1_PCH_RXN<12> @BASEBOARD_FAB2_LIB.BASEBOARD_FAB2(SCH_1):P3E_CPU0_PE1_PCH_RXN(12)    I84 @BASEBOARD_FAB2_LIB.BASEBOARD_FAB2(SCH_1):PAGE30
  DT13 P3E_CPU0_PE1_PCH_RXN<11> @BASEBOARD_FAB2_LIB.BASEBOARD_FAB2(SCH_1):P3E_CPU0_PE1_PCH_RXN(11)    I84 @BASEBOARD_FAB2_LIB.BASEBOARD_FAB2(SCH_1):PAGE30
  DT11 P3E_CPU0_PE1_PCH_RXN<10> @BASEBOARD_FAB2_LIB.BASEBOARD_FAB2(SCH_1):P3E_CPU0_PE1_PCH_RXN(10)    I84 @BASEBOARD_FAB2_LIB.BASEBOARD_FAB2(SCH_1):PAGE30
  DP11 P3E_CPU0_PE1_PCH_RXN<9> @BASEBOARD_FAB2_LIB.BASEBOARD_FAB2(SCH_1):P3E_CPU0_PE1_PCH_RXN(9)    I84 @BASEBOARD_FAB2_LIB.BASEBOARD_FAB2(SCH_1):PAGE30
  DM11 P3E_CPU0_PE1_PCH_RXN<8> @BASEBOARD_FAB2_LIB.BASEBOARD_FAB2(SCH_1):P3E_CPU0_PE1_PCH_RXN(8)    I84 @BASEBOARD_FAB2_LIB.BASEBOARD_FAB2(SCH_1):PAGE30
   DM9 P3E_CPU0_PE1_SS_RXN<7> @BASEBOARD_FAB2_LIB.BASEBOARD_FAB2(SCH_1):P3E_CPU0_PE1_SS_RXN(7)    I84 @BASEBOARD_FAB2_LIB.BASEBOARD_FAB2(SCH_1):PAGE30
   DK9 P3E_CPU0_PE1_SS_RXN<6> @BASEBOARD_FAB2_LIB.BASEBOARD_FAB2(SCH_1):P3E_CPU0_PE1_SS_RXN(6)    I84 @BASEBOARD_FAB2_LIB.BASEBOARD_FAB2(SCH_1):PAGE30
   DH9 P3E_CPU0_PE1_SS_RXN<5> @BASEBOARD_FAB2_LIB.BASEBOARD_FAB2(SCH_1):P3E_CPU0_PE1_SS_RXN(5)    I84 @BASEBOARD_FAB2_LIB.BASEBOARD_FAB2(SCH_1):PAGE30
  DE10 P3E_CPU0_PE1_SS_RXN<4> @BASEBOARD_FAB2_LIB.BASEBOARD_FAB2(SCH_1):P3E_CPU0_PE1_SS_RXN(4)    I84 @BASEBOARD_FAB2_LIB.BASEBOARD_FAB2(SCH_1):PAGE30
  DC10 P3E_CPU0_PE1_SS_RXN<3> @BASEBOARD_FAB2_LIB.BASEBOARD_FAB2(SCH_1):P3E_CPU0_PE1_SS_RXN(3)    I84 @BASEBOARD_FAB2_LIB.BASEBOARD_FAB2(SCH_1):PAGE30
   DC8 P3E_CPU0_PE1_SS_RXN<2> @BASEBOARD_FAB2_LIB.BASEBOARD_FAB2(SCH_1):P3E_CPU0_PE1_SS_RXN(2)    I84 @BASEBOARD_FAB2_LIB.BASEBOARD_FAB2(SCH_1):PAGE30
   DA8 P3E_CPU0_PE1_SS_RXN<1> @BASEBOARD_FAB2_LIB.BASEBOARD_FAB2(SCH_1):P3E_CPU0_PE1_SS_RXN(1)    I84 @BASEBOARD_FAB2_LIB.BASEBOARD_FAB2(SCH_1):PAGE30
   CW8 P3E_CPU0_PE1_SS_RXN<0> @BASEBOARD_FAB2_LIB.BASEBOARD_FAB2(SCH_1):P3E_CPU0_PE1_SS_RXN(0)    I84 @BASEBOARD_FAB2_LIB.BASEBOARD_FAB2(SCH_1):PAGE30
  DT15 P3E_CPU0_PE1_PCH_RXP<15> @BASEBOARD_FAB2_LIB.BASEBOARD_FAB2(SCH_1):P3E_CPU0_PE1_PCH_RXP(15)    I84 @BASEBOARD_FAB2_LIB.BASEBOARD_FAB2(SCH_1):PAGE30
  DV15 P3E_CPU0_PE1_PCH_RXP<14> @BASEBOARD_FAB2_LIB.BASEBOARD_FAB2(SCH_1):P3E_CPU0_PE1_PCH_RXP(14)    I84 @BASEBOARD_FAB2_LIB.BASEBOARD_FAB2(SCH_1):PAGE30
  DY13 P3E_CPU0_PE1_PCH_RXP<13> @BASEBOARD_FAB2_LIB.BASEBOARD_FAB2(SCH_1):P3E_CPU0_PE1_PCH_RXP(13)    I84 @BASEBOARD_FAB2_LIB.BASEBOARD_FAB2(SCH_1):PAGE30
  DU12 P3E_CPU0_PE1_PCH_RXP<12> @BASEBOARD_FAB2_LIB.BASEBOARD_FAB2(SCH_1):P3E_CPU0_PE1_PCH_RXP(12)    I84 @BASEBOARD_FAB2_LIB.BASEBOARD_FAB2(SCH_1):PAGE30
  DP13 P3E_CPU0_PE1_PCH_RXP<11> @BASEBOARD_FAB2_LIB.BASEBOARD_FAB2(SCH_1):P3E_CPU0_PE1_PCH_RXP(11)    I84 @BASEBOARD_FAB2_LIB.BASEBOARD_FAB2(SCH_1):PAGE30
  DR12 P3E_CPU0_PE1_PCH_RXP<10> @BASEBOARD_FAB2_LIB.BASEBOARD_FAB2(SCH_1):P3E_CPU0_PE1_PCH_RXP(10)    I84 @BASEBOARD_FAB2_LIB.BASEBOARD_FAB2(SCH_1):PAGE30
  DN10 P3E_CPU0_PE1_PCH_RXP<9> @BASEBOARD_FAB2_LIB.BASEBOARD_FAB2(SCH_1):P3E_CPU0_PE1_PCH_RXP(9)    I84 @BASEBOARD_FAB2_LIB.BASEBOARD_FAB2(SCH_1):PAGE30
  DK11 P3E_CPU0_PE1_PCH_RXP<8> @BASEBOARD_FAB2_LIB.BASEBOARD_FAB2(SCH_1):P3E_CPU0_PE1_PCH_RXP(8)    I84 @BASEBOARD_FAB2_LIB.BASEBOARD_FAB2(SCH_1):PAGE30
  DL10 P3E_CPU0_PE1_SS_RXP<7> @BASEBOARD_FAB2_LIB.BASEBOARD_FAB2(SCH_1):P3E_CPU0_PE1_SS_RXP(7)    I84 @BASEBOARD_FAB2_LIB.BASEBOARD_FAB2(SCH_1):PAGE30
   DJ8 P3E_CPU0_PE1_SS_RXP<6> @BASEBOARD_FAB2_LIB.BASEBOARD_FAB2(SCH_1):P3E_CPU0_PE1_SS_RXP(6)    I84 @BASEBOARD_FAB2_LIB.BASEBOARD_FAB2(SCH_1):PAGE30
   DF9 P3E_CPU0_PE1_SS_RXP<5> @BASEBOARD_FAB2_LIB.BASEBOARD_FAB2(SCH_1):P3E_CPU0_PE1_SS_RXP(5)    I84 @BASEBOARD_FAB2_LIB.BASEBOARD_FAB2(SCH_1):PAGE30
   DD9 P3E_CPU0_PE1_SS_RXP<4> @BASEBOARD_FAB2_LIB.BASEBOARD_FAB2(SCH_1):P3E_CPU0_PE1_SS_RXP(4)    I84 @BASEBOARD_FAB2_LIB.BASEBOARD_FAB2(SCH_1):PAGE30
  DA10 P3E_CPU0_PE1_SS_RXP<3> @BASEBOARD_FAB2_LIB.BASEBOARD_FAB2(SCH_1):P3E_CPU0_PE1_SS_RXP(3)    I84 @BASEBOARD_FAB2_LIB.BASEBOARD_FAB2(SCH_1):PAGE30
   DB9 P3E_CPU0_PE1_SS_RXP<2> @BASEBOARD_FAB2_LIB.BASEBOARD_FAB2(SCH_1):P3E_CPU0_PE1_SS_RXP(2)    I84 @BASEBOARD_FAB2_LIB.BASEBOARD_FAB2(SCH_1):PAGE30
   CY7 P3E_CPU0_PE1_SS_RXP<1> @BASEBOARD_FAB2_LIB.BASEBOARD_FAB2(SCH_1):P3E_CPU0_PE1_SS_RXP(1)    I84 @BASEBOARD_FAB2_LIB.BASEBOARD_FAB2(SCH_1):PAGE30
   CU8 P3E_CPU0_PE1_SS_RXP<0> @BASEBOARD_FAB2_LIB.BASEBOARD_FAB2(SCH_1):P3E_CPU0_PE1_SS_RXP(0)    I84 @BASEBOARD_FAB2_LIB.BASEBOARD_FAB2(SCH_1):PAGE30
   ED9 P3E_CPU0_PE1_PCH_TXN<15> @BASEBOARD_FAB2_LIB.BASEBOARD_FAB2(SCH_1):P3E_CPU0_PE1_PCH_TXN(15)    I84 @BASEBOARD_FAB2_LIB.BASEBOARD_FAB2(SCH_1):PAGE30
   EA8 P3E_CPU0_PE1_PCH_TXN<14> @BASEBOARD_FAB2_LIB.BASEBOARD_FAB2(SCH_1):P3E_CPU0_PE1_PCH_TXN(14)    I84 @BASEBOARD_FAB2_LIB.BASEBOARD_FAB2(SCH_1):PAGE30
   DY7 P3E_CPU0_PE1_PCH_TXN<13> @BASEBOARD_FAB2_LIB.BASEBOARD_FAB2(SCH_1):P3E_CPU0_PE1_PCH_TXN(13)    I84 @BASEBOARD_FAB2_LIB.BASEBOARD_FAB2(SCH_1):PAGE30
   DV7 P3E_CPU0_PE1_PCH_TXN<12> @BASEBOARD_FAB2_LIB.BASEBOARD_FAB2(SCH_1):P3E_CPU0_PE1_PCH_TXN(12)    I84 @BASEBOARD_FAB2_LIB.BASEBOARD_FAB2(SCH_1):PAGE30
   DU6 P3E_CPU0_PE1_PCH_TXN<11> @BASEBOARD_FAB2_LIB.BASEBOARD_FAB2(SCH_1):P3E_CPU0_PE1_PCH_TXN(11)    I84 @BASEBOARD_FAB2_LIB.BASEBOARD_FAB2(SCH_1):PAGE30
   DW4 P3E_CPU0_PE1_PCH_TXN<10> @BASEBOARD_FAB2_LIB.BASEBOARD_FAB2(SCH_1):P3E_CPU0_PE1_PCH_TXN(10)    I84 @BASEBOARD_FAB2_LIB.BASEBOARD_FAB2(SCH_1):PAGE30
   DV3 P3E_CPU0_PE1_PCH_TXN<9> @BASEBOARD_FAB2_LIB.BASEBOARD_FAB2(SCH_1):P3E_CPU0_PE1_PCH_TXN(9)    I84 @BASEBOARD_FAB2_LIB.BASEBOARD_FAB2(SCH_1):PAGE30
   DT5 P3E_CPU0_PE1_PCH_TXN<8> @BASEBOARD_FAB2_LIB.BASEBOARD_FAB2(SCH_1):P3E_CPU0_PE1_PCH_TXN(8)    I84 @BASEBOARD_FAB2_LIB.BASEBOARD_FAB2(SCH_1):PAGE30
   DN4 P3E_CPU0_PE1_SS_TXN<7> @BASEBOARD_FAB2_LIB.BASEBOARD_FAB2(SCH_1):P3E_CPU0_PE1_SS_TXN(7)    I84 @BASEBOARD_FAB2_LIB.BASEBOARD_FAB2(SCH_1):PAGE30
   DM3 P3E_CPU0_PE1_SS_TXN<6> @BASEBOARD_FAB2_LIB.BASEBOARD_FAB2(SCH_1):P3E_CPU0_PE1_SS_TXN(6)    I84 @BASEBOARD_FAB2_LIB.BASEBOARD_FAB2(SCH_1):PAGE30
   DK3 P3E_CPU0_PE1_SS_TXN<5> @BASEBOARD_FAB2_LIB.BASEBOARD_FAB2(SCH_1):P3E_CPU0_PE1_SS_TXN(5)    I84 @BASEBOARD_FAB2_LIB.BASEBOARD_FAB2(SCH_1):PAGE30
   DG4 P3E_CPU0_PE1_SS_TXN<4> @BASEBOARD_FAB2_LIB.BASEBOARD_FAB2(SCH_1):P3E_CPU0_PE1_SS_TXN(4)    I84 @BASEBOARD_FAB2_LIB.BASEBOARD_FAB2(SCH_1):PAGE30
   DE4 P3E_CPU0_PE1_SS_TXN<3> @BASEBOARD_FAB2_LIB.BASEBOARD_FAB2(SCH_1):P3E_CPU0_PE1_SS_TXN(3)    I84 @BASEBOARD_FAB2_LIB.BASEBOARD_FAB2(SCH_1):PAGE30
   DE2 P3E_CPU0_PE1_SS_TXN<2> @BASEBOARD_FAB2_LIB.BASEBOARD_FAB2(SCH_1):P3E_CPU0_PE1_SS_TXN(2)    I84 @BASEBOARD_FAB2_LIB.BASEBOARD_FAB2(SCH_1):PAGE30
   DC2 P3E_CPU0_PE1_SS_TXN<1> @BASEBOARD_FAB2_LIB.BASEBOARD_FAB2(SCH_1):P3E_CPU0_PE1_SS_TXN(1)    I84 @BASEBOARD_FAB2_LIB.BASEBOARD_FAB2(SCH_1):PAGE30
   DA2 P3E_CPU0_PE1_SS_TXN<0> @BASEBOARD_FAB2_LIB.BASEBOARD_FAB2(SCH_1):P3E_CPU0_PE1_SS_TXN(0)    I84 @BASEBOARD_FAB2_LIB.BASEBOARD_FAB2(SCH_1):PAGE30
   EC8 P3E_CPU0_PE1_PCH_TXP<15> @BASEBOARD_FAB2_LIB.BASEBOARD_FAB2(SCH_1):P3E_CPU0_PE1_PCH_TXP(15)    I84 @BASEBOARD_FAB2_LIB.BASEBOARD_FAB2(SCH_1):PAGE30
   EB7 P3E_CPU0_PE1_PCH_TXP<14> @BASEBOARD_FAB2_LIB.BASEBOARD_FAB2(SCH_1):P3E_CPU0_PE1_PCH_TXP(14)    I84 @BASEBOARD_FAB2_LIB.BASEBOARD_FAB2(SCH_1):PAGE30
   DW6 P3E_CPU0_PE1_PCH_TXP<13> @BASEBOARD_FAB2_LIB.BASEBOARD_FAB2(SCH_1):P3E_CPU0_PE1_PCH_TXP(13)    I84 @BASEBOARD_FAB2_LIB.BASEBOARD_FAB2(SCH_1):PAGE30
   DT7 P3E_CPU0_PE1_PCH_TXP<12> @BASEBOARD_FAB2_LIB.BASEBOARD_FAB2(SCH_1):P3E_CPU0_PE1_PCH_TXP(12)    I84 @BASEBOARD_FAB2_LIB.BASEBOARD_FAB2(SCH_1):PAGE30
   DV5 P3E_CPU0_PE1_PCH_TXP<11> @BASEBOARD_FAB2_LIB.BASEBOARD_FAB2(SCH_1):P3E_CPU0_PE1_PCH_TXP(11)    I84 @BASEBOARD_FAB2_LIB.BASEBOARD_FAB2(SCH_1):PAGE30
   DU4 P3E_CPU0_PE1_PCH_TXP<10> @BASEBOARD_FAB2_LIB.BASEBOARD_FAB2(SCH_1):P3E_CPU0_PE1_PCH_TXP(10)    I84 @BASEBOARD_FAB2_LIB.BASEBOARD_FAB2(SCH_1):PAGE30
   DU2 P3E_CPU0_PE1_PCH_TXP<9> @BASEBOARD_FAB2_LIB.BASEBOARD_FAB2(SCH_1):P3E_CPU0_PE1_PCH_TXP(9)    I84 @BASEBOARD_FAB2_LIB.BASEBOARD_FAB2(SCH_1):PAGE30
   DR4 P3E_CPU0_PE1_PCH_TXP<8> @BASEBOARD_FAB2_LIB.BASEBOARD_FAB2(SCH_1):P3E_CPU0_PE1_PCH_TXP(8)    I84 @BASEBOARD_FAB2_LIB.BASEBOARD_FAB2(SCH_1):PAGE30
   DP3 P3E_CPU0_PE1_SS_TXP<7> @BASEBOARD_FAB2_LIB.BASEBOARD_FAB2(SCH_1):P3E_CPU0_PE1_SS_TXP(7)    I84 @BASEBOARD_FAB2_LIB.BASEBOARD_FAB2(SCH_1):PAGE30
   DL2 P3E_CPU0_PE1_SS_TXP<6> @BASEBOARD_FAB2_LIB.BASEBOARD_FAB2(SCH_1):P3E_CPU0_PE1_SS_TXP(6)    I84 @BASEBOARD_FAB2_LIB.BASEBOARD_FAB2(SCH_1):PAGE30
   DH3 P3E_CPU0_PE1_SS_TXP<5> @BASEBOARD_FAB2_LIB.BASEBOARD_FAB2(SCH_1):P3E_CPU0_PE1_SS_TXP(5)    I84 @BASEBOARD_FAB2_LIB.BASEBOARD_FAB2(SCH_1):PAGE30
   DF3 P3E_CPU0_PE1_SS_TXP<4> @BASEBOARD_FAB2_LIB.BASEBOARD_FAB2(SCH_1):P3E_CPU0_PE1_SS_TXP(4)    I84 @BASEBOARD_FAB2_LIB.BASEBOARD_FAB2(SCH_1):PAGE30
   DC4 P3E_CPU0_PE1_SS_TXP<3> @BASEBOARD_FAB2_LIB.BASEBOARD_FAB2(SCH_1):P3E_CPU0_PE1_SS_TXP(3)    I84 @BASEBOARD_FAB2_LIB.BASEBOARD_FAB2(SCH_1):PAGE30
   DD3 P3E_CPU0_PE1_SS_TXP<2> @BASEBOARD_FAB2_LIB.BASEBOARD_FAB2(SCH_1):P3E_CPU0_PE1_SS_TXP(2)    I84 @BASEBOARD_FAB2_LIB.BASEBOARD_FAB2(SCH_1):PAGE30
   DB1 P3E_CPU0_PE1_SS_TXP<1> @BASEBOARD_FAB2_LIB.BASEBOARD_FAB2(SCH_1):P3E_CPU0_PE1_SS_TXP(1)    I84 @BASEBOARD_FAB2_LIB.BASEBOARD_FAB2(SCH_1):PAGE30
   CW2 P3E_CPU0_PE1_SS_TXP<0> @BASEBOARD_FAB2_LIB.BASEBOARD_FAB2(SCH_1):P3E_CPU0_PE1_SS_TXP(0)    I84 @BASEBOARD_FAB2_LIB.BASEBOARD_FAB2(SCH_1):PAGE30
   BK9 P3E_CPU0_PE2_SS_RXN<15> @BASEBOARD_FAB2_LIB.BASEBOARD_FAB2(SCH_1):P3E_CPU0_PE2_SS_RXN(15)   I106 @BASEBOARD_FAB2_LIB.BASEBOARD_FAB2(SCH_1):PAGE31
   BL8 P3E_CPU0_PE2_SS_RXN<14> @BASEBOARD_FAB2_LIB.BASEBOARD_FAB2(SCH_1):P3E_CPU0_PE2_SS_RXN(14)   I106 @BASEBOARD_FAB2_LIB.BASEBOARD_FAB2(SCH_1):PAGE31
   BN8 P3E_CPU0_PE2_SS_RXN<13> @BASEBOARD_FAB2_LIB.BASEBOARD_FAB2(SCH_1):P3E_CPU0_PE2_SS_RXN(13)   I106 @BASEBOARD_FAB2_LIB.BASEBOARD_FAB2(SCH_1):PAGE31
   BR8 P3E_CPU0_PE2_SS_RXN<12> @BASEBOARD_FAB2_LIB.BASEBOARD_FAB2(SCH_1):P3E_CPU0_PE2_SS_RXN(12)   I106 @BASEBOARD_FAB2_LIB.BASEBOARD_FAB2(SCH_1):PAGE31
   BT7 P3E_CPU0_PE2_SS_RXN<11> @BASEBOARD_FAB2_LIB.BASEBOARD_FAB2(SCH_1):P3E_CPU0_PE2_SS_RXN(11)   I106 @BASEBOARD_FAB2_LIB.BASEBOARD_FAB2(SCH_1):PAGE31
   BV7 P3E_CPU0_PE2_SS_RXN<10> @BASEBOARD_FAB2_LIB.BASEBOARD_FAB2(SCH_1):P3E_CPU0_PE2_SS_RXN(10)   I106 @BASEBOARD_FAB2_LIB.BASEBOARD_FAB2(SCH_1):PAGE31
   BY7 P3E_CPU0_PE2_SS_RXN<9> @BASEBOARD_FAB2_LIB.BASEBOARD_FAB2(SCH_1):P3E_CPU0_PE2_SS_RXN(9)   I106 @BASEBOARD_FAB2_LIB.BASEBOARD_FAB2(SCH_1):PAGE31
   BY9 P3E_CPU0_PE2_SS_RXN<8> @BASEBOARD_FAB2_LIB.BASEBOARD_FAB2(SCH_1):P3E_CPU0_PE2_SS_RXN(8)   I106 @BASEBOARD_FAB2_LIB.BASEBOARD_FAB2(SCH_1):PAGE31
   CE8 P3E_CPU0_PE2_SS_RXN<7> @BASEBOARD_FAB2_LIB.BASEBOARD_FAB2(SCH_1):P3E_CPU0_PE2_SS_RXN(7)   I106 @BASEBOARD_FAB2_LIB.BASEBOARD_FAB2(SCH_1):PAGE31
   CE6 P3E_CPU0_PE2_SS_RXN<6> @BASEBOARD_FAB2_LIB.BASEBOARD_FAB2(SCH_1):P3E_CPU0_PE2_SS_RXN(6)   I106 @BASEBOARD_FAB2_LIB.BASEBOARD_FAB2(SCH_1):PAGE31
   CG8 P3E_CPU0_PE2_SS_RXN<5> @BASEBOARD_FAB2_LIB.BASEBOARD_FAB2(SCH_1):P3E_CPU0_PE2_SS_RXN(5)   I106 @BASEBOARD_FAB2_LIB.BASEBOARD_FAB2(SCH_1):PAGE31
   CK7 P3E_CPU0_PE2_SS_RXN<4> @BASEBOARD_FAB2_LIB.BASEBOARD_FAB2(SCH_1):P3E_CPU0_PE2_SS_RXN(4)   I106 @BASEBOARD_FAB2_LIB.BASEBOARD_FAB2(SCH_1):PAGE31
   CM7 P3E_CPU0_PE2_SS_RXN<3> @BASEBOARD_FAB2_LIB.BASEBOARD_FAB2(SCH_1):P3E_CPU0_PE2_SS_RXN(3)   I106 @BASEBOARD_FAB2_LIB.BASEBOARD_FAB2(SCH_1):PAGE31
   CP7 P3E_CPU0_PE2_SS_RXN<2> @BASEBOARD_FAB2_LIB.BASEBOARD_FAB2(SCH_1):P3E_CPU0_PE2_SS_RXN(2)   I106 @BASEBOARD_FAB2_LIB.BASEBOARD_FAB2(SCH_1):PAGE31
   CP9 P3E_CPU0_PE2_SS_RXN<1> @BASEBOARD_FAB2_LIB.BASEBOARD_FAB2(SCH_1):P3E_CPU0_PE2_SS_RXN(1)   I106 @BASEBOARD_FAB2_LIB.BASEBOARD_FAB2(SCH_1):PAGE31
   CT9 P3E_CPU0_PE2_SS_RXN<0> @BASEBOARD_FAB2_LIB.BASEBOARD_FAB2(SCH_1):P3E_CPU0_PE2_SS_RXN(0)   I106 @BASEBOARD_FAB2_LIB.BASEBOARD_FAB2(SCH_1):PAGE31
  BJ10 P3E_CPU0_PE2_SS_RXP<15> @BASEBOARD_FAB2_LIB.BASEBOARD_FAB2(SCH_1):P3E_CPU0_PE2_SS_RXP(15)   I106 @BASEBOARD_FAB2_LIB.BASEBOARD_FAB2(SCH_1):PAGE31
   BJ8 P3E_CPU0_PE2_SS_RXP<14> @BASEBOARD_FAB2_LIB.BASEBOARD_FAB2(SCH_1):P3E_CPU0_PE2_SS_RXP(14)   I106 @BASEBOARD_FAB2_LIB.BASEBOARD_FAB2(SCH_1):PAGE31
   BM7 P3E_CPU0_PE2_SS_RXP<13> @BASEBOARD_FAB2_LIB.BASEBOARD_FAB2(SCH_1):P3E_CPU0_PE2_SS_RXP(13)   I106 @BASEBOARD_FAB2_LIB.BASEBOARD_FAB2(SCH_1):PAGE31
   BP9 P3E_CPU0_PE2_SS_RXP<12> @BASEBOARD_FAB2_LIB.BASEBOARD_FAB2(SCH_1):P3E_CPU0_PE2_SS_RXP(12)   I106 @BASEBOARD_FAB2_LIB.BASEBOARD_FAB2(SCH_1):PAGE31
   BP7 P3E_CPU0_PE2_SS_RXP<11> @BASEBOARD_FAB2_LIB.BASEBOARD_FAB2(SCH_1):P3E_CPU0_PE2_SS_RXP(11)   I106 @BASEBOARD_FAB2_LIB.BASEBOARD_FAB2(SCH_1):PAGE31
   BU6 P3E_CPU0_PE2_SS_RXP<10> @BASEBOARD_FAB2_LIB.BASEBOARD_FAB2(SCH_1):P3E_CPU0_PE2_SS_RXP(10)   I106 @BASEBOARD_FAB2_LIB.BASEBOARD_FAB2(SCH_1):PAGE31
   BW8 P3E_CPU0_PE2_SS_RXP<9> @BASEBOARD_FAB2_LIB.BASEBOARD_FAB2(SCH_1):P3E_CPU0_PE2_SS_RXP(9)   I106 @BASEBOARD_FAB2_LIB.BASEBOARD_FAB2(SCH_1):PAGE31
   BV9 P3E_CPU0_PE2_SS_RXP<8> @BASEBOARD_FAB2_LIB.BASEBOARD_FAB2(SCH_1):P3E_CPU0_PE2_SS_RXP(8)   I106 @BASEBOARD_FAB2_LIB.BASEBOARD_FAB2(SCH_1):PAGE31
   CC8 P3E_CPU0_PE2_SS_RXP<7> @BASEBOARD_FAB2_LIB.BASEBOARD_FAB2(SCH_1):P3E_CPU0_PE2_SS_RXP(7)   I106 @BASEBOARD_FAB2_LIB.BASEBOARD_FAB2(SCH_1):PAGE31
   CD7 P3E_CPU0_PE2_SS_RXP<6> @BASEBOARD_FAB2_LIB.BASEBOARD_FAB2(SCH_1):P3E_CPU0_PE2_SS_RXP(6)   I106 @BASEBOARD_FAB2_LIB.BASEBOARD_FAB2(SCH_1):PAGE31
   CF7 P3E_CPU0_PE2_SS_RXP<5> @BASEBOARD_FAB2_LIB.BASEBOARD_FAB2(SCH_1):P3E_CPU0_PE2_SS_RXP(5)   I106 @BASEBOARD_FAB2_LIB.BASEBOARD_FAB2(SCH_1):PAGE31
   CH7 P3E_CPU0_PE2_SS_RXP<4> @BASEBOARD_FAB2_LIB.BASEBOARD_FAB2(SCH_1):P3E_CPU0_PE2_SS_RXP(4)   I106 @BASEBOARD_FAB2_LIB.BASEBOARD_FAB2(SCH_1):PAGE31
   CL6 P3E_CPU0_PE2_SS_RXP<3> @BASEBOARD_FAB2_LIB.BASEBOARD_FAB2(SCH_1):P3E_CPU0_PE2_SS_RXP(3)   I106 @BASEBOARD_FAB2_LIB.BASEBOARD_FAB2(SCH_1):PAGE31
   CN8 P3E_CPU0_PE2_SS_RXP<2> @BASEBOARD_FAB2_LIB.BASEBOARD_FAB2(SCH_1):P3E_CPU0_PE2_SS_RXP(2)   I106 @BASEBOARD_FAB2_LIB.BASEBOARD_FAB2(SCH_1):PAGE31
   CM9 P3E_CPU0_PE2_SS_RXP<1> @BASEBOARD_FAB2_LIB.BASEBOARD_FAB2(SCH_1):P3E_CPU0_PE2_SS_RXP(1)   I106 @BASEBOARD_FAB2_LIB.BASEBOARD_FAB2(SCH_1):PAGE31
   CR8 P3E_CPU0_PE2_SS_RXP<0> @BASEBOARD_FAB2_LIB.BASEBOARD_FAB2(SCH_1):P3E_CPU0_PE2_SS_RXP(0)   I106 @BASEBOARD_FAB2_LIB.BASEBOARD_FAB2(SCH_1):PAGE31
   BM5 P3E_CPU0_PE2_SS_TXN<15> @BASEBOARD_FAB2_LIB.BASEBOARD_FAB2(SCH_1):P3E_CPU0_PE2_SS_TXN(15)   I106 @BASEBOARD_FAB2_LIB.BASEBOARD_FAB2(SCH_1):PAGE31
   BL4 P3E_CPU0_PE2_SS_TXN<14> @BASEBOARD_FAB2_LIB.BASEBOARD_FAB2(SCH_1):P3E_CPU0_PE2_SS_TXN(14)   I106 @BASEBOARD_FAB2_LIB.BASEBOARD_FAB2(SCH_1):PAGE31
   BP5 P3E_CPU0_PE2_SS_TXN<13> @BASEBOARD_FAB2_LIB.BASEBOARD_FAB2(SCH_1):P3E_CPU0_PE2_SS_TXN(13)   I106 @BASEBOARD_FAB2_LIB.BASEBOARD_FAB2(SCH_1):PAGE31
   BU4 P3E_CPU0_PE2_SS_TXN<12> @BASEBOARD_FAB2_LIB.BASEBOARD_FAB2(SCH_1):P3E_CPU0_PE2_SS_TXN(12)   I106 @BASEBOARD_FAB2_LIB.BASEBOARD_FAB2(SCH_1):PAGE31
   BW4 P3E_CPU0_PE2_SS_TXN<11> @BASEBOARD_FAB2_LIB.BASEBOARD_FAB2(SCH_1):P3E_CPU0_PE2_SS_TXN(11)   I106 @BASEBOARD_FAB2_LIB.BASEBOARD_FAB2(SCH_1):PAGE31
   CA4 P3E_CPU0_PE2_SS_TXN<10> @BASEBOARD_FAB2_LIB.BASEBOARD_FAB2(SCH_1):P3E_CPU0_PE2_SS_TXN(10)   I106 @BASEBOARD_FAB2_LIB.BASEBOARD_FAB2(SCH_1):PAGE31
   CB3 P3E_CPU0_PE2_SS_TXN<9> @BASEBOARD_FAB2_LIB.BASEBOARD_FAB2(SCH_1):P3E_CPU0_PE2_SS_TXN(9)   I106 @BASEBOARD_FAB2_LIB.BASEBOARD_FAB2(SCH_1):PAGE31
   CC2 P3E_CPU0_PE2_SS_TXN<8> @BASEBOARD_FAB2_LIB.BASEBOARD_FAB2(SCH_1):P3E_CPU0_PE2_SS_TXN(8)   I106 @BASEBOARD_FAB2_LIB.BASEBOARD_FAB2(SCH_1):PAGE31
   CF3 P3E_CPU0_PE2_SS_TXN<7> @BASEBOARD_FAB2_LIB.BASEBOARD_FAB2(SCH_1):P3E_CPU0_PE2_SS_TXN(7)   I106 @BASEBOARD_FAB2_LIB.BASEBOARD_FAB2(SCH_1):PAGE31
   CG2 P3E_CPU0_PE2_SS_TXN<6> @BASEBOARD_FAB2_LIB.BASEBOARD_FAB2(SCH_1):P3E_CPU0_PE2_SS_TXN(6)   I106 @BASEBOARD_FAB2_LIB.BASEBOARD_FAB2(SCH_1):PAGE31
   CL2 P3E_CPU0_PE2_SS_TXN<5> @BASEBOARD_FAB2_LIB.BASEBOARD_FAB2(SCH_1):P3E_CPU0_PE2_SS_TXN(5)   I106 @BASEBOARD_FAB2_LIB.BASEBOARD_FAB2(SCH_1):PAGE31
   CM1 P3E_CPU0_PE2_SS_TXN<4> @BASEBOARD_FAB2_LIB.BASEBOARD_FAB2(SCH_1):P3E_CPU0_PE2_SS_TXN(4)   I106 @BASEBOARD_FAB2_LIB.BASEBOARD_FAB2(SCH_1):PAGE31
   CT3 P3E_CPU0_PE2_SS_TXN<3> @BASEBOARD_FAB2_LIB.BASEBOARD_FAB2(SCH_1):P3E_CPU0_PE2_SS_TXN(3)   I106 @BASEBOARD_FAB2_LIB.BASEBOARD_FAB2(SCH_1):PAGE31
   CT1 P3E_CPU0_PE2_SS_TXN<2> @BASEBOARD_FAB2_LIB.BASEBOARD_FAB2(SCH_1):P3E_CPU0_PE2_SS_TXN(2)   I106 @BASEBOARD_FAB2_LIB.BASEBOARD_FAB2(SCH_1):PAGE31
   CV3 P3E_CPU0_PE2_SS_TXN<1> @BASEBOARD_FAB2_LIB.BASEBOARD_FAB2(SCH_1):P3E_CPU0_PE2_SS_TXN(1)   I106 @BASEBOARD_FAB2_LIB.BASEBOARD_FAB2(SCH_1):PAGE31
   CY3 P3E_CPU0_PE2_SS_TXN<0> @BASEBOARD_FAB2_LIB.BASEBOARD_FAB2(SCH_1):P3E_CPU0_PE2_SS_TXN(0)   I106 @BASEBOARD_FAB2_LIB.BASEBOARD_FAB2(SCH_1):PAGE31
   BK5 P3E_CPU0_PE2_SS_TXP<15> @BASEBOARD_FAB2_LIB.BASEBOARD_FAB2(SCH_1):P3E_CPU0_PE2_SS_TXP(15)   I106 @BASEBOARD_FAB2_LIB.BASEBOARD_FAB2(SCH_1):PAGE31
   BM3 P3E_CPU0_PE2_SS_TXP<14> @BASEBOARD_FAB2_LIB.BASEBOARD_FAB2(SCH_1):P3E_CPU0_PE2_SS_TXP(14)   I106 @BASEBOARD_FAB2_LIB.BASEBOARD_FAB2(SCH_1):PAGE31
   BN4 P3E_CPU0_PE2_SS_TXP<13> @BASEBOARD_FAB2_LIB.BASEBOARD_FAB2(SCH_1):P3E_CPU0_PE2_SS_TXP(13)   I106 @BASEBOARD_FAB2_LIB.BASEBOARD_FAB2(SCH_1):PAGE31
   BR4 P3E_CPU0_PE2_SS_TXP<12> @BASEBOARD_FAB2_LIB.BASEBOARD_FAB2(SCH_1):P3E_CPU0_PE2_SS_TXP(12)   I106 @BASEBOARD_FAB2_LIB.BASEBOARD_FAB2(SCH_1):PAGE31
   BV3 P3E_CPU0_PE2_SS_TXP<11> @BASEBOARD_FAB2_LIB.BASEBOARD_FAB2(SCH_1):P3E_CPU0_PE2_SS_TXP(11)   I106 @BASEBOARD_FAB2_LIB.BASEBOARD_FAB2(SCH_1):PAGE31
   BY5 P3E_CPU0_PE2_SS_TXP<10> @BASEBOARD_FAB2_LIB.BASEBOARD_FAB2(SCH_1):P3E_CPU0_PE2_SS_TXP(10)   I106 @BASEBOARD_FAB2_LIB.BASEBOARD_FAB2(SCH_1):PAGE31
   BY3 P3E_CPU0_PE2_SS_TXP<9> @BASEBOARD_FAB2_LIB.BASEBOARD_FAB2(SCH_1):P3E_CPU0_PE2_SS_TXP(9)   I106 @BASEBOARD_FAB2_LIB.BASEBOARD_FAB2(SCH_1):PAGE31
   CD3 P3E_CPU0_PE2_SS_TXP<8> @BASEBOARD_FAB2_LIB.BASEBOARD_FAB2(SCH_1):P3E_CPU0_PE2_SS_TXP(8)   I106 @BASEBOARD_FAB2_LIB.BASEBOARD_FAB2(SCH_1):PAGE31
   CE4 P3E_CPU0_PE2_SS_TXP<7> @BASEBOARD_FAB2_LIB.BASEBOARD_FAB2(SCH_1):P3E_CPU0_PE2_SS_TXP(7)   I106 @BASEBOARD_FAB2_LIB.BASEBOARD_FAB2(SCH_1):PAGE31
   CE2 P3E_CPU0_PE2_SS_TXP<6> @BASEBOARD_FAB2_LIB.BASEBOARD_FAB2(SCH_1):P3E_CPU0_PE2_SS_TXP(6)   I106 @BASEBOARD_FAB2_LIB.BASEBOARD_FAB2(SCH_1):PAGE31
   CK3 P3E_CPU0_PE2_SS_TXP<5> @BASEBOARD_FAB2_LIB.BASEBOARD_FAB2(SCH_1):P3E_CPU0_PE2_SS_TXP(5)   I106 @BASEBOARD_FAB2_LIB.BASEBOARD_FAB2(SCH_1):PAGE31
   CK1 P3E_CPU0_PE2_SS_TXP<4> @BASEBOARD_FAB2_LIB.BASEBOARD_FAB2(SCH_1):P3E_CPU0_PE2_SS_TXP(4)   I106 @BASEBOARD_FAB2_LIB.BASEBOARD_FAB2(SCH_1):PAGE31
   CP3 P3E_CPU0_PE2_SS_TXP<3> @BASEBOARD_FAB2_LIB.BASEBOARD_FAB2(SCH_1):P3E_CPU0_PE2_SS_TXP(3)   I106 @BASEBOARD_FAB2_LIB.BASEBOARD_FAB2(SCH_1):PAGE31
   CR2 P3E_CPU0_PE2_SS_TXP<2> @BASEBOARD_FAB2_LIB.BASEBOARD_FAB2(SCH_1):P3E_CPU0_PE2_SS_TXP(2)   I106 @BASEBOARD_FAB2_LIB.BASEBOARD_FAB2(SCH_1):PAGE31
   CU2 P3E_CPU0_PE2_SS_TXP<1> @BASEBOARD_FAB2_LIB.BASEBOARD_FAB2(SCH_1):P3E_CPU0_PE2_SS_TXP(1)   I106 @BASEBOARD_FAB2_LIB.BASEBOARD_FAB2(SCH_1):PAGE31
   CW4 P3E_CPU0_PE2_SS_TXP<0> @BASEBOARD_FAB2_LIB.BASEBOARD_FAB2(SCH_1):P3E_CPU0_PE2_SS_TXP(0)   I106 @BASEBOARD_FAB2_LIB.BASEBOARD_FAB2(SCH_1):PAGE31
   CV9 P3E_CPU0_PE3_OCP_RXN<15> @BASEBOARD_FAB2_LIB.BASEBOARD_FAB2(SCH_1):P3E_CPU0_PE3_OCP_RXN(15)    I89 @BASEBOARD_FAB2_LIB.BASEBOARD_FAB2(SCH_1):PAGE32
  CY11 P3E_CPU0_PE3_OCP_RXN<14> @BASEBOARD_FAB2_LIB.BASEBOARD_FAB2(SCH_1):P3E_CPU0_PE3_OCP_RXN(14)    I89 @BASEBOARD_FAB2_LIB.BASEBOARD_FAB2(SCH_1):PAGE32
  DB11 P3E_CPU0_PE3_OCP_RXN<13> @BASEBOARD_FAB2_LIB.BASEBOARD_FAB2(SCH_1):P3E_CPU0_PE3_OCP_RXN(13)    I89 @BASEBOARD_FAB2_LIB.BASEBOARD_FAB2(SCH_1):PAGE32
  DD13 P3E_CPU0_PE3_OCP_RXN<12> @BASEBOARD_FAB2_LIB.BASEBOARD_FAB2(SCH_1):P3E_CPU0_PE3_OCP_RXN(12)    I89 @BASEBOARD_FAB2_LIB.BASEBOARD_FAB2(SCH_1):PAGE32
  DG10 P3E_CPU0_PE3_OCP_RXN<11> @BASEBOARD_FAB2_LIB.BASEBOARD_FAB2(SCH_1):P3E_CPU0_PE3_OCP_RXN(11)    I89 @BASEBOARD_FAB2_LIB.BASEBOARD_FAB2(SCH_1):PAGE32
  DG12 P3E_CPU0_PE3_OCP_RXN<10> @BASEBOARD_FAB2_LIB.BASEBOARD_FAB2(SCH_1):P3E_CPU0_PE3_OCP_RXN(10)    I89 @BASEBOARD_FAB2_LIB.BASEBOARD_FAB2(SCH_1):PAGE32
  DJ12 P3E_CPU0_PE3_OCP_RXN<9> @BASEBOARD_FAB2_LIB.BASEBOARD_FAB2(SCH_1):P3E_CPU0_PE3_OCP_RXN(9)    I89 @BASEBOARD_FAB2_LIB.BASEBOARD_FAB2(SCH_1):PAGE32
  DL12 P3E_CPU0_PE3_OCP_RXN<8> @BASEBOARD_FAB2_LIB.BASEBOARD_FAB2(SCH_1):P3E_CPU0_PE3_OCP_RXN(8)    I89 @BASEBOARD_FAB2_LIB.BASEBOARD_FAB2(SCH_1):PAGE32
  DL14 P3E_CPU0_PE3_OCP_RXN<7> @BASEBOARD_FAB2_LIB.BASEBOARD_FAB2(SCH_1):P3E_CPU0_PE3_OCP_RXN(7)    I89 @BASEBOARD_FAB2_LIB.BASEBOARD_FAB2(SCH_1):PAGE32
  DN14 P3E_CPU0_PE3_OCP_RXN<6> @BASEBOARD_FAB2_LIB.BASEBOARD_FAB2(SCH_1):P3E_CPU0_PE3_OCP_RXN(6)    I89 @BASEBOARD_FAB2_LIB.BASEBOARD_FAB2(SCH_1):PAGE32
  DR14 P3E_CPU0_PE3_OCP_RXN<5> @BASEBOARD_FAB2_LIB.BASEBOARD_FAB2(SCH_1):P3E_CPU0_PE3_OCP_RXN(5)    I89 @BASEBOARD_FAB2_LIB.BASEBOARD_FAB2(SCH_1):PAGE32
  DR16 P3E_CPU0_PE3_OCP_RXN<4> @BASEBOARD_FAB2_LIB.BASEBOARD_FAB2(SCH_1):P3E_CPU0_PE3_OCP_RXN(4)    I89 @BASEBOARD_FAB2_LIB.BASEBOARD_FAB2(SCH_1):PAGE32
  DT19 P3E_CPU0_PE3_OCP_RXN<3> @BASEBOARD_FAB2_LIB.BASEBOARD_FAB2(SCH_1):P3E_CPU0_PE3_OCP_RXN(3)    I89 @BASEBOARD_FAB2_LIB.BASEBOARD_FAB2(SCH_1):PAGE32
  DW16 P3E_CPU0_PE3_OCP_RXN<2> @BASEBOARD_FAB2_LIB.BASEBOARD_FAB2(SCH_1):P3E_CPU0_PE3_OCP_RXN(2)    I89 @BASEBOARD_FAB2_LIB.BASEBOARD_FAB2(SCH_1):PAGE32
  DW18 P3E_CPU0_PE3_OCP_RXN<1> @BASEBOARD_FAB2_LIB.BASEBOARD_FAB2(SCH_1):P3E_CPU0_PE3_OCP_RXN(1)    I89 @BASEBOARD_FAB2_LIB.BASEBOARD_FAB2(SCH_1):PAGE32
  EA18 P3E_CPU0_PE3_OCP_RXN<0> @BASEBOARD_FAB2_LIB.BASEBOARD_FAB2(SCH_1):P3E_CPU0_PE3_OCP_RXN(0)    I89 @BASEBOARD_FAB2_LIB.BASEBOARD_FAB2(SCH_1):PAGE32
  CU10 P3E_CPU0_PE3_OCP_RXP<15> @BASEBOARD_FAB2_LIB.BASEBOARD_FAB2(SCH_1):P3E_CPU0_PE3_OCP_RXP(15)    I89 @BASEBOARD_FAB2_LIB.BASEBOARD_FAB2(SCH_1):PAGE32
  CW10 P3E_CPU0_PE3_OCP_RXP<14> @BASEBOARD_FAB2_LIB.BASEBOARD_FAB2(SCH_1):P3E_CPU0_PE3_OCP_RXP(14)    I89 @BASEBOARD_FAB2_LIB.BASEBOARD_FAB2(SCH_1):PAGE32
  DA12 P3E_CPU0_PE3_OCP_RXP<13> @BASEBOARD_FAB2_LIB.BASEBOARD_FAB2(SCH_1):P3E_CPU0_PE3_OCP_RXP(13)    I89 @BASEBOARD_FAB2_LIB.BASEBOARD_FAB2(SCH_1):PAGE32
  DC12 P3E_CPU0_PE3_OCP_RXP<12> @BASEBOARD_FAB2_LIB.BASEBOARD_FAB2(SCH_1):P3E_CPU0_PE3_OCP_RXP(12)    I89 @BASEBOARD_FAB2_LIB.BASEBOARD_FAB2(SCH_1):PAGE32
  DF11 P3E_CPU0_PE3_OCP_RXP<11> @BASEBOARD_FAB2_LIB.BASEBOARD_FAB2(SCH_1):P3E_CPU0_PE3_OCP_RXP(11)    I89 @BASEBOARD_FAB2_LIB.BASEBOARD_FAB2(SCH_1):PAGE32
  DE12 P3E_CPU0_PE3_OCP_RXP<10> @BASEBOARD_FAB2_LIB.BASEBOARD_FAB2(SCH_1):P3E_CPU0_PE3_OCP_RXP(10)    I89 @BASEBOARD_FAB2_LIB.BASEBOARD_FAB2(SCH_1):PAGE32
  DH11 P3E_CPU0_PE3_OCP_RXP<9> @BASEBOARD_FAB2_LIB.BASEBOARD_FAB2(SCH_1):P3E_CPU0_PE3_OCP_RXP(9)    I89 @BASEBOARD_FAB2_LIB.BASEBOARD_FAB2(SCH_1):PAGE32
  DK13 P3E_CPU0_PE3_OCP_RXP<8> @BASEBOARD_FAB2_LIB.BASEBOARD_FAB2(SCH_1):P3E_CPU0_PE3_OCP_RXP(8)    I89 @BASEBOARD_FAB2_LIB.BASEBOARD_FAB2(SCH_1):PAGE32
  DJ14 P3E_CPU0_PE3_OCP_RXP<7> @BASEBOARD_FAB2_LIB.BASEBOARD_FAB2(SCH_1):P3E_CPU0_PE3_OCP_RXP(7)    I89 @BASEBOARD_FAB2_LIB.BASEBOARD_FAB2(SCH_1):PAGE32
  DM13 P3E_CPU0_PE3_OCP_RXP<6> @BASEBOARD_FAB2_LIB.BASEBOARD_FAB2(SCH_1):P3E_CPU0_PE3_OCP_RXP(6)    I89 @BASEBOARD_FAB2_LIB.BASEBOARD_FAB2(SCH_1):PAGE32
  DP15 P3E_CPU0_PE3_OCP_RXP<5> @BASEBOARD_FAB2_LIB.BASEBOARD_FAB2(SCH_1):P3E_CPU0_PE3_OCP_RXP(5)    I89 @BASEBOARD_FAB2_LIB.BASEBOARD_FAB2(SCH_1):PAGE32
  DN16 P3E_CPU0_PE3_OCP_RXP<4> @BASEBOARD_FAB2_LIB.BASEBOARD_FAB2(SCH_1):P3E_CPU0_PE3_OCP_RXP(4)    I89 @BASEBOARD_FAB2_LIB.BASEBOARD_FAB2(SCH_1):PAGE32
  DR18 P3E_CPU0_PE3_OCP_RXP<3> @BASEBOARD_FAB2_LIB.BASEBOARD_FAB2(SCH_1):P3E_CPU0_PE3_OCP_RXP(3)    I89 @BASEBOARD_FAB2_LIB.BASEBOARD_FAB2(SCH_1):PAGE32
  DV17 P3E_CPU0_PE3_OCP_RXP<2> @BASEBOARD_FAB2_LIB.BASEBOARD_FAB2(SCH_1):P3E_CPU0_PE3_OCP_RXP(2)    I89 @BASEBOARD_FAB2_LIB.BASEBOARD_FAB2(SCH_1):PAGE32
  DU18 P3E_CPU0_PE3_OCP_RXP<1> @BASEBOARD_FAB2_LIB.BASEBOARD_FAB2(SCH_1):P3E_CPU0_PE3_OCP_RXP(1)    I89 @BASEBOARD_FAB2_LIB.BASEBOARD_FAB2(SCH_1):PAGE32
  DY17 P3E_CPU0_PE3_OCP_RXP<0> @BASEBOARD_FAB2_LIB.BASEBOARD_FAB2(SCH_1):P3E_CPU0_PE3_OCP_RXP(0)    I89 @BASEBOARD_FAB2_LIB.BASEBOARD_FAB2(SCH_1):PAGE32
   CY5 P3E_CPU0_PE3_OCP_TXN<15> @BASEBOARD_FAB2_LIB.BASEBOARD_FAB2(SCH_1):P3E_CPU0_PE3_OCP_TXN(15)    I89 @BASEBOARD_FAB2_LIB.BASEBOARD_FAB2(SCH_1):PAGE32
   DB5 P3E_CPU0_PE3_OCP_TXN<14> @BASEBOARD_FAB2_LIB.BASEBOARD_FAB2(SCH_1):P3E_CPU0_PE3_OCP_TXN(14)    I89 @BASEBOARD_FAB2_LIB.BASEBOARD_FAB2(SCH_1):PAGE32
   DD5 P3E_CPU0_PE3_OCP_TXN<13> @BASEBOARD_FAB2_LIB.BASEBOARD_FAB2(SCH_1):P3E_CPU0_PE3_OCP_TXN(13)    I89 @BASEBOARD_FAB2_LIB.BASEBOARD_FAB2(SCH_1):PAGE32
   DJ6 P3E_CPU0_PE3_OCP_TXN<12> @BASEBOARD_FAB2_LIB.BASEBOARD_FAB2(SCH_1):P3E_CPU0_PE3_OCP_TXN(12)    I89 @BASEBOARD_FAB2_LIB.BASEBOARD_FAB2(SCH_1):PAGE32
   DJ4 P3E_CPU0_PE3_OCP_TXN<11> @BASEBOARD_FAB2_LIB.BASEBOARD_FAB2(SCH_1):P3E_CPU0_PE3_OCP_TXN(11)    I89 @BASEBOARD_FAB2_LIB.BASEBOARD_FAB2(SCH_1):PAGE32
   DL6 P3E_CPU0_PE3_OCP_TXN<10> @BASEBOARD_FAB2_LIB.BASEBOARD_FAB2(SCH_1):P3E_CPU0_PE3_OCP_TXN(10)    I89 @BASEBOARD_FAB2_LIB.BASEBOARD_FAB2(SCH_1):PAGE32
   DP5 P3E_CPU0_PE3_OCP_TXN<9> @BASEBOARD_FAB2_LIB.BASEBOARD_FAB2(SCH_1):P3E_CPU0_PE3_OCP_TXN(9)    I89 @BASEBOARD_FAB2_LIB.BASEBOARD_FAB2(SCH_1):PAGE32
   DM7 P3E_CPU0_PE3_OCP_TXN<8> @BASEBOARD_FAB2_LIB.BASEBOARD_FAB2(SCH_1):P3E_CPU0_PE3_OCP_TXN(8)    I89 @BASEBOARD_FAB2_LIB.BASEBOARD_FAB2(SCH_1):PAGE32
   DR8 P3E_CPU0_PE3_OCP_TXN<7> @BASEBOARD_FAB2_LIB.BASEBOARD_FAB2(SCH_1):P3E_CPU0_PE3_OCP_TXN(7)    I89 @BASEBOARD_FAB2_LIB.BASEBOARD_FAB2(SCH_1):PAGE32
   DU8 P3E_CPU0_PE3_OCP_TXN<6> @BASEBOARD_FAB2_LIB.BASEBOARD_FAB2(SCH_1):P3E_CPU0_PE3_OCP_TXN(6)    I89 @BASEBOARD_FAB2_LIB.BASEBOARD_FAB2(SCH_1):PAGE32
  DW10 P3E_CPU0_PE3_OCP_TXN<5> @BASEBOARD_FAB2_LIB.BASEBOARD_FAB2(SCH_1):P3E_CPU0_PE3_OCP_TXN(5)    I89 @BASEBOARD_FAB2_LIB.BASEBOARD_FAB2(SCH_1):PAGE32
   EB9 P3E_CPU0_PE3_OCP_TXN<4> @BASEBOARD_FAB2_LIB.BASEBOARD_FAB2(SCH_1):P3E_CPU0_PE3_OCP_TXN(4)    I89 @BASEBOARD_FAB2_LIB.BASEBOARD_FAB2(SCH_1):PAGE32
  DY11 P3E_CPU0_PE3_OCP_TXN<3> @BASEBOARD_FAB2_LIB.BASEBOARD_FAB2(SCH_1):P3E_CPU0_PE3_OCP_TXN(3)    I89 @BASEBOARD_FAB2_LIB.BASEBOARD_FAB2(SCH_1):PAGE32
  EC12 P3E_CPU0_PE3_OCP_TXN<2> @BASEBOARD_FAB2_LIB.BASEBOARD_FAB2(SCH_1):P3E_CPU0_PE3_OCP_TXN(2)    I89 @BASEBOARD_FAB2_LIB.BASEBOARD_FAB2(SCH_1):PAGE32
  EE12 P3E_CPU0_PE3_OCP_TXN<1> @BASEBOARD_FAB2_LIB.BASEBOARD_FAB2(SCH_1):P3E_CPU0_PE3_OCP_TXN(1)    I89 @BASEBOARD_FAB2_LIB.BASEBOARD_FAB2(SCH_1):PAGE32
  EE14 P3E_CPU0_PE3_OCP_TXN<0> @BASEBOARD_FAB2_LIB.BASEBOARD_FAB2(SCH_1):P3E_CPU0_PE3_OCP_TXN(0)    I89 @BASEBOARD_FAB2_LIB.BASEBOARD_FAB2(SCH_1):PAGE32
   CV5 P3E_CPU0_PE3_OCP_TXP<15> @BASEBOARD_FAB2_LIB.BASEBOARD_FAB2(SCH_1):P3E_CPU0_PE3_OCP_TXP(15)    I89 @BASEBOARD_FAB2_LIB.BASEBOARD_FAB2(SCH_1):PAGE32
   DA4 P3E_CPU0_PE3_OCP_TXP<14> @BASEBOARD_FAB2_LIB.BASEBOARD_FAB2(SCH_1):P3E_CPU0_PE3_OCP_TXP(14)    I89 @BASEBOARD_FAB2_LIB.BASEBOARD_FAB2(SCH_1):PAGE32
   DC6 P3E_CPU0_PE3_OCP_TXP<13> @BASEBOARD_FAB2_LIB.BASEBOARD_FAB2(SCH_1):P3E_CPU0_PE3_OCP_TXP(13)    I89 @BASEBOARD_FAB2_LIB.BASEBOARD_FAB2(SCH_1):PAGE32
   DG6 P3E_CPU0_PE3_OCP_TXP<12> @BASEBOARD_FAB2_LIB.BASEBOARD_FAB2(SCH_1):P3E_CPU0_PE3_OCP_TXP(12)    I89 @BASEBOARD_FAB2_LIB.BASEBOARD_FAB2(SCH_1):PAGE32
   DH5 P3E_CPU0_PE3_OCP_TXP<11> @BASEBOARD_FAB2_LIB.BASEBOARD_FAB2(SCH_1):P3E_CPU0_PE3_OCP_TXP(11)    I89 @BASEBOARD_FAB2_LIB.BASEBOARD_FAB2(SCH_1):PAGE32
   DK5 P3E_CPU0_PE3_OCP_TXP<10> @BASEBOARD_FAB2_LIB.BASEBOARD_FAB2(SCH_1):P3E_CPU0_PE3_OCP_TXP(10)    I89 @BASEBOARD_FAB2_LIB.BASEBOARD_FAB2(SCH_1):PAGE32
   DM5 P3E_CPU0_PE3_OCP_TXP<9> @BASEBOARD_FAB2_LIB.BASEBOARD_FAB2(SCH_1):P3E_CPU0_PE3_OCP_TXP(9)    I89 @BASEBOARD_FAB2_LIB.BASEBOARD_FAB2(SCH_1):PAGE32
   DN6 P3E_CPU0_PE3_OCP_TXP<8> @BASEBOARD_FAB2_LIB.BASEBOARD_FAB2(SCH_1):P3E_CPU0_PE3_OCP_TXP(8)    I89 @BASEBOARD_FAB2_LIB.BASEBOARD_FAB2(SCH_1):PAGE32
   DP7 P3E_CPU0_PE3_OCP_TXP<7> @BASEBOARD_FAB2_LIB.BASEBOARD_FAB2(SCH_1):P3E_CPU0_PE3_OCP_TXP(7)    I89 @BASEBOARD_FAB2_LIB.BASEBOARD_FAB2(SCH_1):PAGE32
   DT9 P3E_CPU0_PE3_OCP_TXP<6> @BASEBOARD_FAB2_LIB.BASEBOARD_FAB2(SCH_1):P3E_CPU0_PE3_OCP_TXP(6)    I89 @BASEBOARD_FAB2_LIB.BASEBOARD_FAB2(SCH_1):PAGE32
   DV9 P3E_CPU0_PE3_OCP_TXP<5> @BASEBOARD_FAB2_LIB.BASEBOARD_FAB2(SCH_1):P3E_CPU0_PE3_OCP_TXP(5)    I89 @BASEBOARD_FAB2_LIB.BASEBOARD_FAB2(SCH_1):PAGE32
   DY9 P3E_CPU0_PE3_OCP_TXP<4> @BASEBOARD_FAB2_LIB.BASEBOARD_FAB2(SCH_1):P3E_CPU0_PE3_OCP_TXP(4)    I89 @BASEBOARD_FAB2_LIB.BASEBOARD_FAB2(SCH_1):PAGE32
  EA10 P3E_CPU0_PE3_OCP_TXP<3> @BASEBOARD_FAB2_LIB.BASEBOARD_FAB2(SCH_1):P3E_CPU0_PE3_OCP_TXP(3)    I89 @BASEBOARD_FAB2_LIB.BASEBOARD_FAB2(SCH_1):PAGE32
  EB11 P3E_CPU0_PE3_OCP_TXP<2> @BASEBOARD_FAB2_LIB.BASEBOARD_FAB2(SCH_1):P3E_CPU0_PE3_OCP_TXP(2)    I89 @BASEBOARD_FAB2_LIB.BASEBOARD_FAB2(SCH_1):PAGE32
  ED13 P3E_CPU0_PE3_OCP_TXP<1> @BASEBOARD_FAB2_LIB.BASEBOARD_FAB2(SCH_1):P3E_CPU0_PE3_OCP_TXP(1)    I89 @BASEBOARD_FAB2_LIB.BASEBOARD_FAB2(SCH_1):PAGE32
  EC14 P3E_CPU0_PE3_OCP_TXP<0> @BASEBOARD_FAB2_LIB.BASEBOARD_FAB2(SCH_1):P3E_CPU0_PE3_OCP_TXP(0)    I89 @BASEBOARD_FAB2_LIB.BASEBOARD_FAB2(SCH_1):PAGE32
  BB11 UPI_CPU1_CPU0_P0P0_DN<0> @BASEBOARD_FAB2_LIB.BASEBOARD_FAB2(SCH_1):UPI_CPU1_CPU0_P0P0_DN(0)    I86 @BASEBOARD_FAB2_LIB.BASEBOARD_FAB2(SCH_1):PAGE33
   BD9 UPI_CPU1_CPU0_P0P0_DN<1> @BASEBOARD_FAB2_LIB.BASEBOARD_FAB2(SCH_1):UPI_CPU1_CPU0_P0P0_DN(1)    I86 @BASEBOARD_FAB2_LIB.BASEBOARD_FAB2(SCH_1):PAGE33
   AY9 UPI_CPU1_CPU0_P0P0_DN<2> @BASEBOARD_FAB2_LIB.BASEBOARD_FAB2(SCH_1):UPI_CPU1_CPU0_P0P0_DN(2)    I86 @BASEBOARD_FAB2_LIB.BASEBOARD_FAB2(SCH_1):PAGE33
   AW8 UPI_CPU1_CPU0_P0P0_DN<3> @BASEBOARD_FAB2_LIB.BASEBOARD_FAB2(SCH_1):UPI_CPU1_CPU0_P0P0_DN(3)    I86 @BASEBOARD_FAB2_LIB.BASEBOARD_FAB2(SCH_1):PAGE33
   BD7 UPI_CPU1_CPU0_P0P0_DN<4> @BASEBOARD_FAB2_LIB.BASEBOARD_FAB2(SCH_1):UPI_CPU1_CPU0_P0P0_DN(4)    I86 @BASEBOARD_FAB2_LIB.BASEBOARD_FAB2(SCH_1):PAGE33
   BC6 UPI_CPU1_CPU0_P0P0_DN<5> @BASEBOARD_FAB2_LIB.BASEBOARD_FAB2(SCH_1):UPI_CPU1_CPU0_P0P0_DN(5)    I86 @BASEBOARD_FAB2_LIB.BASEBOARD_FAB2(SCH_1):PAGE33
   BA8 UPI_CPU1_CPU0_P0P0_DN<6> @BASEBOARD_FAB2_LIB.BASEBOARD_FAB2(SCH_1):UPI_CPU1_CPU0_P0P0_DN(6)    I86 @BASEBOARD_FAB2_LIB.BASEBOARD_FAB2(SCH_1):PAGE33
  AU10 UPI_CPU1_CPU0_P0P0_DN<7> @BASEBOARD_FAB2_LIB.BASEBOARD_FAB2(SCH_1):UPI_CPU1_CPU0_P0P0_DN(7)    I86 @BASEBOARD_FAB2_LIB.BASEBOARD_FAB2(SCH_1):PAGE33
   AR8 UPI_CPU1_CPU0_P0P0_DN<8> @BASEBOARD_FAB2_LIB.BASEBOARD_FAB2(SCH_1):UPI_CPU1_CPU0_P0P0_DN(8)    I86 @BASEBOARD_FAB2_LIB.BASEBOARD_FAB2(SCH_1):PAGE33
   AP7 UPI_CPU1_CPU0_P0P0_DN<9> @BASEBOARD_FAB2_LIB.BASEBOARD_FAB2(SCH_1):UPI_CPU1_CPU0_P0P0_DN(9)    I86 @BASEBOARD_FAB2_LIB.BASEBOARD_FAB2(SCH_1):PAGE33
   AM9 UPI_CPU1_CPU0_P0P0_DN<10> @BASEBOARD_FAB2_LIB.BASEBOARD_FAB2(SCH_1):UPI_CPU1_CPU0_P0P0_DN(10)    I86 @BASEBOARD_FAB2_LIB.BASEBOARD_FAB2(SCH_1):PAGE33
   AK7 UPI_CPU1_CPU0_P0P0_DN<11> @BASEBOARD_FAB2_LIB.BASEBOARD_FAB2(SCH_1):UPI_CPU1_CPU0_P0P0_DN(11)    I86 @BASEBOARD_FAB2_LIB.BASEBOARD_FAB2(SCH_1):PAGE33
   AL6 UPI_CPU1_CPU0_P0P0_DN<12> @BASEBOARD_FAB2_LIB.BASEBOARD_FAB2(SCH_1):UPI_CPU1_CPU0_P0P0_DN(12)    I86 @BASEBOARD_FAB2_LIB.BASEBOARD_FAB2(SCH_1):PAGE33
   AJ6 UPI_CPU1_CPU0_P0P0_DN<13> @BASEBOARD_FAB2_LIB.BASEBOARD_FAB2(SCH_1):UPI_CPU1_CPU0_P0P0_DN(13)    I86 @BASEBOARD_FAB2_LIB.BASEBOARD_FAB2(SCH_1):PAGE33
   AG8 UPI_CPU1_CPU0_P0P0_DN<14> @BASEBOARD_FAB2_LIB.BASEBOARD_FAB2(SCH_1):UPI_CPU1_CPU0_P0P0_DN(14)    I86 @BASEBOARD_FAB2_LIB.BASEBOARD_FAB2(SCH_1):PAGE33
   AE6 UPI_CPU1_CPU0_P0P0_DN<15> @BASEBOARD_FAB2_LIB.BASEBOARD_FAB2(SCH_1):UPI_CPU1_CPU0_P0P0_DN(15)    I86 @BASEBOARD_FAB2_LIB.BASEBOARD_FAB2(SCH_1):PAGE33
   AD5 UPI_CPU1_CPU0_P0P0_DN<16> @BASEBOARD_FAB2_LIB.BASEBOARD_FAB2(SCH_1):UPI_CPU1_CPU0_P0P0_DN(16)    I86 @BASEBOARD_FAB2_LIB.BASEBOARD_FAB2(SCH_1):PAGE33
   AB7 UPI_CPU1_CPU0_P0P0_DN<17> @BASEBOARD_FAB2_LIB.BASEBOARD_FAB2(SCH_1):UPI_CPU1_CPU0_P0P0_DN(17)    I86 @BASEBOARD_FAB2_LIB.BASEBOARD_FAB2(SCH_1):PAGE33
   AA8 UPI_CPU1_CPU0_P0P0_DN<18> @BASEBOARD_FAB2_LIB.BASEBOARD_FAB2(SCH_1):UPI_CPU1_CPU0_P0P0_DN(18)    I86 @BASEBOARD_FAB2_LIB.BASEBOARD_FAB2(SCH_1):PAGE33
  AC10 UPI_CPU1_CPU0_P0P0_DN<19> @BASEBOARD_FAB2_LIB.BASEBOARD_FAB2(SCH_1):UPI_CPU1_CPU0_P0P0_DN(19)    I86 @BASEBOARD_FAB2_LIB.BASEBOARD_FAB2(SCH_1):PAGE33
  BA10 UPI_CPU1_CPU0_P0P0_DP<0> @BASEBOARD_FAB2_LIB.BASEBOARD_FAB2(SCH_1):UPI_CPU1_CPU0_P0P0_DP(0)    I86 @BASEBOARD_FAB2_LIB.BASEBOARD_FAB2(SCH_1):PAGE33
  BC10 UPI_CPU1_CPU0_P0P0_DP<1> @BASEBOARD_FAB2_LIB.BASEBOARD_FAB2(SCH_1):UPI_CPU1_CPU0_P0P0_DP(1)    I86 @BASEBOARD_FAB2_LIB.BASEBOARD_FAB2(SCH_1):PAGE33
   BB9 UPI_CPU1_CPU0_P0P0_DP<2> @BASEBOARD_FAB2_LIB.BASEBOARD_FAB2(SCH_1):UPI_CPU1_CPU0_P0P0_DP(2)    I86 @BASEBOARD_FAB2_LIB.BASEBOARD_FAB2(SCH_1):PAGE33
   AV9 UPI_CPU1_CPU0_P0P0_DP<3> @BASEBOARD_FAB2_LIB.BASEBOARD_FAB2(SCH_1):UPI_CPU1_CPU0_P0P0_DP(3)    I86 @BASEBOARD_FAB2_LIB.BASEBOARD_FAB2(SCH_1):PAGE33
   BF7 UPI_CPU1_CPU0_P0P0_DP<4> @BASEBOARD_FAB2_LIB.BASEBOARD_FAB2(SCH_1):UPI_CPU1_CPU0_P0P0_DP(4)    I86 @BASEBOARD_FAB2_LIB.BASEBOARD_FAB2(SCH_1):PAGE33
   BB7 UPI_CPU1_CPU0_P0P0_DP<5> @BASEBOARD_FAB2_LIB.BASEBOARD_FAB2(SCH_1):UPI_CPU1_CPU0_P0P0_DP(5)    I86 @BASEBOARD_FAB2_LIB.BASEBOARD_FAB2(SCH_1):PAGE33
   AY7 UPI_CPU1_CPU0_P0P0_DP<6> @BASEBOARD_FAB2_LIB.BASEBOARD_FAB2(SCH_1):UPI_CPU1_CPU0_P0P0_DP(6)    I86 @BASEBOARD_FAB2_LIB.BASEBOARD_FAB2(SCH_1):PAGE33
   AT9 UPI_CPU1_CPU0_P0P0_DP<7> @BASEBOARD_FAB2_LIB.BASEBOARD_FAB2(SCH_1):UPI_CPU1_CPU0_P0P0_DP(7)    I86 @BASEBOARD_FAB2_LIB.BASEBOARD_FAB2(SCH_1):PAGE33
   AU8 UPI_CPU1_CPU0_P0P0_DP<8> @BASEBOARD_FAB2_LIB.BASEBOARD_FAB2(SCH_1):UPI_CPU1_CPU0_P0P0_DP(8)    I86 @BASEBOARD_FAB2_LIB.BASEBOARD_FAB2(SCH_1):PAGE33
   AN8 UPI_CPU1_CPU0_P0P0_DP<9> @BASEBOARD_FAB2_LIB.BASEBOARD_FAB2(SCH_1):UPI_CPU1_CPU0_P0P0_DP(9)    I86 @BASEBOARD_FAB2_LIB.BASEBOARD_FAB2(SCH_1):PAGE33
   AL8 UPI_CPU1_CPU0_P0P0_DP<10> @BASEBOARD_FAB2_LIB.BASEBOARD_FAB2(SCH_1):UPI_CPU1_CPU0_P0P0_DP(10)    I86 @BASEBOARD_FAB2_LIB.BASEBOARD_FAB2(SCH_1):PAGE33
   AM7 UPI_CPU1_CPU0_P0P0_DP<11> @BASEBOARD_FAB2_LIB.BASEBOARD_FAB2(SCH_1):UPI_CPU1_CPU0_P0P0_DP(11)    I86 @BASEBOARD_FAB2_LIB.BASEBOARD_FAB2(SCH_1):PAGE33
   AK5 UPI_CPU1_CPU0_P0P0_DP<12> @BASEBOARD_FAB2_LIB.BASEBOARD_FAB2(SCH_1):UPI_CPU1_CPU0_P0P0_DP(12)    I86 @BASEBOARD_FAB2_LIB.BASEBOARD_FAB2(SCH_1):PAGE33
   AH7 UPI_CPU1_CPU0_P0P0_DP<13> @BASEBOARD_FAB2_LIB.BASEBOARD_FAB2(SCH_1):UPI_CPU1_CPU0_P0P0_DP(13)    I86 @BASEBOARD_FAB2_LIB.BASEBOARD_FAB2(SCH_1):PAGE33
   AF7 UPI_CPU1_CPU0_P0P0_DP<14> @BASEBOARD_FAB2_LIB.BASEBOARD_FAB2(SCH_1):UPI_CPU1_CPU0_P0P0_DP(14)    I86 @BASEBOARD_FAB2_LIB.BASEBOARD_FAB2(SCH_1):PAGE33
   AG6 UPI_CPU1_CPU0_P0P0_DP<15> @BASEBOARD_FAB2_LIB.BASEBOARD_FAB2(SCH_1):UPI_CPU1_CPU0_P0P0_DP(15)    I86 @BASEBOARD_FAB2_LIB.BASEBOARD_FAB2(SCH_1):PAGE33
   AC6 UPI_CPU1_CPU0_P0P0_DP<16> @BASEBOARD_FAB2_LIB.BASEBOARD_FAB2(SCH_1):UPI_CPU1_CPU0_P0P0_DP(16)    I86 @BASEBOARD_FAB2_LIB.BASEBOARD_FAB2(SCH_1):PAGE33
   AA6 UPI_CPU1_CPU0_P0P0_DP<17> @BASEBOARD_FAB2_LIB.BASEBOARD_FAB2(SCH_1):UPI_CPU1_CPU0_P0P0_DP(17)    I86 @BASEBOARD_FAB2_LIB.BASEBOARD_FAB2(SCH_1):PAGE33
   AC8 UPI_CPU1_CPU0_P0P0_DP<18> @BASEBOARD_FAB2_LIB.BASEBOARD_FAB2(SCH_1):UPI_CPU1_CPU0_P0P0_DP(18)    I86 @BASEBOARD_FAB2_LIB.BASEBOARD_FAB2(SCH_1):PAGE33
   AB9 UPI_CPU1_CPU0_P0P0_DP<19> @BASEBOARD_FAB2_LIB.BASEBOARD_FAB2(SCH_1):UPI_CPU1_CPU0_P0P0_DP(19)    I86 @BASEBOARD_FAB2_LIB.BASEBOARD_FAB2(SCH_1):PAGE33
   BG4 UPI_CPU0_CPU1_P0P0_DN<0> @BASEBOARD_FAB2_LIB.BASEBOARD_FAB2(SCH_1):UPI_CPU0_CPU1_P0P0_DN(0)    I86 @BASEBOARD_FAB2_LIB.BASEBOARD_FAB2(SCH_1):PAGE33
   BF3 UPI_CPU0_CPU1_P0P0_DN<1> @BASEBOARD_FAB2_LIB.BASEBOARD_FAB2(SCH_1):UPI_CPU0_CPU1_P0P0_DN(1)    I86 @BASEBOARD_FAB2_LIB.BASEBOARD_FAB2(SCH_1):PAGE33
   BB3 UPI_CPU0_CPU1_P0P0_DN<2> @BASEBOARD_FAB2_LIB.BASEBOARD_FAB2(SCH_1):UPI_CPU0_CPU1_P0P0_DN(2)    I86 @BASEBOARD_FAB2_LIB.BASEBOARD_FAB2(SCH_1):PAGE33
   BA4 UPI_CPU0_CPU1_P0P0_DN<3> @BASEBOARD_FAB2_LIB.BASEBOARD_FAB2(SCH_1):UPI_CPU0_CPU1_P0P0_DN(3)    I86 @BASEBOARD_FAB2_LIB.BASEBOARD_FAB2(SCH_1):PAGE33
   AV5 UPI_CPU0_CPU1_P0P0_DN<4> @BASEBOARD_FAB2_LIB.BASEBOARD_FAB2(SCH_1):UPI_CPU0_CPU1_P0P0_DN(4)    I86 @BASEBOARD_FAB2_LIB.BASEBOARD_FAB2(SCH_1):PAGE33
   AU4 UPI_CPU0_CPU1_P0P0_DN<5> @BASEBOARD_FAB2_LIB.BASEBOARD_FAB2(SCH_1):UPI_CPU0_CPU1_P0P0_DN(5)    I86 @BASEBOARD_FAB2_LIB.BASEBOARD_FAB2(SCH_1):PAGE33
   AT3 UPI_CPU0_CPU1_P0P0_DN<6> @BASEBOARD_FAB2_LIB.BASEBOARD_FAB2(SCH_1):UPI_CPU0_CPU1_P0P0_DN(6)    I86 @BASEBOARD_FAB2_LIB.BASEBOARD_FAB2(SCH_1):PAGE33
   AT1 UPI_CPU0_CPU1_P0P0_DN<7> @BASEBOARD_FAB2_LIB.BASEBOARD_FAB2(SCH_1):UPI_CPU0_CPU1_P0P0_DN(7)    I86 @BASEBOARD_FAB2_LIB.BASEBOARD_FAB2(SCH_1):PAGE33
   AN4 UPI_CPU0_CPU1_P0P0_DN<8> @BASEBOARD_FAB2_LIB.BASEBOARD_FAB2(SCH_1):UPI_CPU0_CPU1_P0P0_DN(8)    I86 @BASEBOARD_FAB2_LIB.BASEBOARD_FAB2(SCH_1):PAGE33
   AM3 UPI_CPU0_CPU1_P0P0_DN<9> @BASEBOARD_FAB2_LIB.BASEBOARD_FAB2(SCH_1):UPI_CPU0_CPU1_P0P0_DN(9)    I86 @BASEBOARD_FAB2_LIB.BASEBOARD_FAB2(SCH_1):PAGE33
   AL2 UPI_CPU0_CPU1_P0P0_DN<10> @BASEBOARD_FAB2_LIB.BASEBOARD_FAB2(SCH_1):UPI_CPU0_CPU1_P0P0_DN(10)    I86 @BASEBOARD_FAB2_LIB.BASEBOARD_FAB2(SCH_1):PAGE33
   AH3 UPI_CPU0_CPU1_P0P0_DN<11> @BASEBOARD_FAB2_LIB.BASEBOARD_FAB2(SCH_1):UPI_CPU0_CPU1_P0P0_DN(11)    I86 @BASEBOARD_FAB2_LIB.BASEBOARD_FAB2(SCH_1):PAGE33
   AE2 UPI_CPU0_CPU1_P0P0_DN<12> @BASEBOARD_FAB2_LIB.BASEBOARD_FAB2(SCH_1):UPI_CPU0_CPU1_P0P0_DN(12)    I86 @BASEBOARD_FAB2_LIB.BASEBOARD_FAB2(SCH_1):PAGE33
   AG4 UPI_CPU0_CPU1_P0P0_DN<13> @BASEBOARD_FAB2_LIB.BASEBOARD_FAB2(SCH_1):UPI_CPU0_CPU1_P0P0_DN(13)    I86 @BASEBOARD_FAB2_LIB.BASEBOARD_FAB2(SCH_1):PAGE33
   AC2 UPI_CPU0_CPU1_P0P0_DN<14> @BASEBOARD_FAB2_LIB.BASEBOARD_FAB2(SCH_1):UPI_CPU0_CPU1_P0P0_DN(14)    I86 @BASEBOARD_FAB2_LIB.BASEBOARD_FAB2(SCH_1):PAGE33
   AB3 UPI_CPU0_CPU1_P0P0_DN<15> @BASEBOARD_FAB2_LIB.BASEBOARD_FAB2(SCH_1):UPI_CPU0_CPU1_P0P0_DN(15)    I86 @BASEBOARD_FAB2_LIB.BASEBOARD_FAB2(SCH_1):PAGE33
    Y1 UPI_CPU0_CPU1_P0P0_DN<16> @BASEBOARD_FAB2_LIB.BASEBOARD_FAB2(SCH_1):UPI_CPU0_CPU1_P0P0_DN(16)    I86 @BASEBOARD_FAB2_LIB.BASEBOARD_FAB2(SCH_1):PAGE33
    V3 UPI_CPU0_CPU1_P0P0_DN<17> @BASEBOARD_FAB2_LIB.BASEBOARD_FAB2(SCH_1):UPI_CPU0_CPU1_P0P0_DN(17)    I86 @BASEBOARD_FAB2_LIB.BASEBOARD_FAB2(SCH_1):PAGE33
    P1 UPI_CPU0_CPU1_P0P0_DN<18> @BASEBOARD_FAB2_LIB.BASEBOARD_FAB2(SCH_1):UPI_CPU0_CPU1_P0P0_DN(18)    I86 @BASEBOARD_FAB2_LIB.BASEBOARD_FAB2(SCH_1):PAGE33
    N2 UPI_CPU0_CPU1_P0P0_DN<19> @BASEBOARD_FAB2_LIB.BASEBOARD_FAB2(SCH_1):UPI_CPU0_CPU1_P0P0_DN(19)    I86 @BASEBOARD_FAB2_LIB.BASEBOARD_FAB2(SCH_1):PAGE33
   BH3 UPI_CPU0_CPU1_P0P0_DP<0> @BASEBOARD_FAB2_LIB.BASEBOARD_FAB2(SCH_1):UPI_CPU0_CPU1_P0P0_DP(0)    I86 @BASEBOARD_FAB2_LIB.BASEBOARD_FAB2(SCH_1):PAGE33
   BD3 UPI_CPU0_CPU1_P0P0_DP<1> @BASEBOARD_FAB2_LIB.BASEBOARD_FAB2(SCH_1):UPI_CPU0_CPU1_P0P0_DP(1)    I86 @BASEBOARD_FAB2_LIB.BASEBOARD_FAB2(SCH_1):PAGE33
   BC2 UPI_CPU0_CPU1_P0P0_DP<2> @BASEBOARD_FAB2_LIB.BASEBOARD_FAB2(SCH_1):UPI_CPU0_CPU1_P0P0_DP(2)    I86 @BASEBOARD_FAB2_LIB.BASEBOARD_FAB2(SCH_1):PAGE33
   AY3 UPI_CPU0_CPU1_P0P0_DP<3> @BASEBOARD_FAB2_LIB.BASEBOARD_FAB2(SCH_1):UPI_CPU0_CPU1_P0P0_DP(3)    I86 @BASEBOARD_FAB2_LIB.BASEBOARD_FAB2(SCH_1):PAGE33
   AW4 UPI_CPU0_CPU1_P0P0_DP<4> @BASEBOARD_FAB2_LIB.BASEBOARD_FAB2(SCH_1):UPI_CPU0_CPU1_P0P0_DP(4)    I86 @BASEBOARD_FAB2_LIB.BASEBOARD_FAB2(SCH_1):PAGE33
   AR4 UPI_CPU0_CPU1_P0P0_DP<5> @BASEBOARD_FAB2_LIB.BASEBOARD_FAB2(SCH_1):UPI_CPU0_CPU1_P0P0_DP(5)    I86 @BASEBOARD_FAB2_LIB.BASEBOARD_FAB2(SCH_1):PAGE33
   AR2 UPI_CPU0_CPU1_P0P0_DP<6> @BASEBOARD_FAB2_LIB.BASEBOARD_FAB2(SCH_1):UPI_CPU0_CPU1_P0P0_DP(6)    I86 @BASEBOARD_FAB2_LIB.BASEBOARD_FAB2(SCH_1):PAGE33
   AP1 UPI_CPU0_CPU1_P0P0_DP<7> @BASEBOARD_FAB2_LIB.BASEBOARD_FAB2(SCH_1):UPI_CPU0_CPU1_P0P0_DP(7)    I86 @BASEBOARD_FAB2_LIB.BASEBOARD_FAB2(SCH_1):PAGE33
   AP3 UPI_CPU0_CPU1_P0P0_DP<8> @BASEBOARD_FAB2_LIB.BASEBOARD_FAB2(SCH_1):UPI_CPU0_CPU1_P0P0_DP(8)    I86 @BASEBOARD_FAB2_LIB.BASEBOARD_FAB2(SCH_1):PAGE33
   AK3 UPI_CPU0_CPU1_P0P0_DP<9> @BASEBOARD_FAB2_LIB.BASEBOARD_FAB2(SCH_1):UPI_CPU0_CPU1_P0P0_DP(9)    I86 @BASEBOARD_FAB2_LIB.BASEBOARD_FAB2(SCH_1):PAGE33
   AK1 UPI_CPU0_CPU1_P0P0_DP<10> @BASEBOARD_FAB2_LIB.BASEBOARD_FAB2(SCH_1):UPI_CPU0_CPU1_P0P0_DP(10)    I86 @BASEBOARD_FAB2_LIB.BASEBOARD_FAB2(SCH_1):PAGE33
   AJ2 UPI_CPU0_CPU1_P0P0_DP<11> @BASEBOARD_FAB2_LIB.BASEBOARD_FAB2(SCH_1):UPI_CPU0_CPU1_P0P0_DP(11)    I86 @BASEBOARD_FAB2_LIB.BASEBOARD_FAB2(SCH_1):PAGE33
   AG2 UPI_CPU0_CPU1_P0P0_DP<12> @BASEBOARD_FAB2_LIB.BASEBOARD_FAB2(SCH_1):UPI_CPU0_CPU1_P0P0_DP(12)    I86 @BASEBOARD_FAB2_LIB.BASEBOARD_FAB2(SCH_1):PAGE33
   AF3 UPI_CPU0_CPU1_P0P0_DP<13> @BASEBOARD_FAB2_LIB.BASEBOARD_FAB2(SCH_1):UPI_CPU0_CPU1_P0P0_DP(13)    I86 @BASEBOARD_FAB2_LIB.BASEBOARD_FAB2(SCH_1):PAGE33
   AD1 UPI_CPU0_CPU1_P0P0_DP<14> @BASEBOARD_FAB2_LIB.BASEBOARD_FAB2(SCH_1):UPI_CPU0_CPU1_P0P0_DP(14)    I86 @BASEBOARD_FAB2_LIB.BASEBOARD_FAB2(SCH_1):PAGE33
   AA2 UPI_CPU0_CPU1_P0P0_DP<15> @BASEBOARD_FAB2_LIB.BASEBOARD_FAB2(SCH_1):UPI_CPU0_CPU1_P0P0_DP(15)    I86 @BASEBOARD_FAB2_LIB.BASEBOARD_FAB2(SCH_1):PAGE33
    W2 UPI_CPU0_CPU1_P0P0_DP<16> @BASEBOARD_FAB2_LIB.BASEBOARD_FAB2(SCH_1):UPI_CPU0_CPU1_P0P0_DP(16)    I86 @BASEBOARD_FAB2_LIB.BASEBOARD_FAB2(SCH_1):PAGE33
    Y3 UPI_CPU0_CPU1_P0P0_DP<17> @BASEBOARD_FAB2_LIB.BASEBOARD_FAB2(SCH_1):UPI_CPU0_CPU1_P0P0_DP(17)    I86 @BASEBOARD_FAB2_LIB.BASEBOARD_FAB2(SCH_1):PAGE33
    T1 UPI_CPU0_CPU1_P0P0_DP<18> @BASEBOARD_FAB2_LIB.BASEBOARD_FAB2(SCH_1):UPI_CPU0_CPU1_P0P0_DP(18)    I86 @BASEBOARD_FAB2_LIB.BASEBOARD_FAB2(SCH_1):PAGE33
    M1 UPI_CPU0_CPU1_P0P0_DP<19> @BASEBOARD_FAB2_LIB.BASEBOARD_FAB2(SCH_1):UPI_CPU0_CPU1_P0P0_DP(19)    I86 @BASEBOARD_FAB2_LIB.BASEBOARD_FAB2(SCH_1):PAGE33
  AB19 UPI_CPU1_CPU0_P1P1_DN<0> @BASEBOARD_FAB2_LIB.BASEBOARD_FAB2(SCH_1):UPI_CPU1_CPU0_P1P1_DN(0)    I86 @BASEBOARD_FAB2_LIB.BASEBOARD_FAB2(SCH_1):PAGE34
   Y21 UPI_CPU1_CPU0_P1P1_DN<1> @BASEBOARD_FAB2_LIB.BASEBOARD_FAB2(SCH_1):UPI_CPU1_CPU0_P1P1_DN(1)    I86 @BASEBOARD_FAB2_LIB.BASEBOARD_FAB2(SCH_1):PAGE34
   V19 UPI_CPU1_CPU0_P1P1_DN<2> @BASEBOARD_FAB2_LIB.BASEBOARD_FAB2(SCH_1):UPI_CPU1_CPU0_P1P1_DN(2)    I86 @BASEBOARD_FAB2_LIB.BASEBOARD_FAB2(SCH_1):PAGE34
   P21 UPI_CPU1_CPU0_P1P1_DN<3> @BASEBOARD_FAB2_LIB.BASEBOARD_FAB2(SCH_1):UPI_CPU1_CPU0_P1P1_DN(3)    I86 @BASEBOARD_FAB2_LIB.BASEBOARD_FAB2(SCH_1):PAGE34
   U18 UPI_CPU1_CPU0_P1P1_DN<4> @BASEBOARD_FAB2_LIB.BASEBOARD_FAB2(SCH_1):UPI_CPU1_CPU0_P1P1_DN(4)    I86 @BASEBOARD_FAB2_LIB.BASEBOARD_FAB2(SCH_1):PAGE34
   R20 UPI_CPU1_CPU0_P1P1_DN<5> @BASEBOARD_FAB2_LIB.BASEBOARD_FAB2(SCH_1):UPI_CPU1_CPU0_P1P1_DN(5)    I86 @BASEBOARD_FAB2_LIB.BASEBOARD_FAB2(SCH_1):PAGE34
   W18 UPI_CPU1_CPU0_P1P1_DN<6> @BASEBOARD_FAB2_LIB.BASEBOARD_FAB2(SCH_1):UPI_CPU1_CPU0_P1P1_DN(6)    I86 @BASEBOARD_FAB2_LIB.BASEBOARD_FAB2(SCH_1):PAGE34
   U16 UPI_CPU1_CPU0_P1P1_DN<7> @BASEBOARD_FAB2_LIB.BASEBOARD_FAB2(SCH_1):UPI_CPU1_CPU0_P1P1_DN(7)    I86 @BASEBOARD_FAB2_LIB.BASEBOARD_FAB2(SCH_1):PAGE34
   P17 UPI_CPU1_CPU0_P1P1_DN<8> @BASEBOARD_FAB2_LIB.BASEBOARD_FAB2(SCH_1):UPI_CPU1_CPU0_P1P1_DN(8)    I86 @BASEBOARD_FAB2_LIB.BASEBOARD_FAB2(SCH_1):PAGE34
   R16 UPI_CPU1_CPU0_P1P1_DN<9> @BASEBOARD_FAB2_LIB.BASEBOARD_FAB2(SCH_1):UPI_CPU1_CPU0_P1P1_DN(9)    I86 @BASEBOARD_FAB2_LIB.BASEBOARD_FAB2(SCH_1):PAGE34
   R12 UPI_CPU1_CPU0_P1P1_DN<10> @BASEBOARD_FAB2_LIB.BASEBOARD_FAB2(SCH_1):UPI_CPU1_CPU0_P1P1_DN(10)    I86 @BASEBOARD_FAB2_LIB.BASEBOARD_FAB2(SCH_1):PAGE34
   N14 UPI_CPU1_CPU0_P1P1_DN<11> @BASEBOARD_FAB2_LIB.BASEBOARD_FAB2(SCH_1):UPI_CPU1_CPU0_P1P1_DN(11)    I86 @BASEBOARD_FAB2_LIB.BASEBOARD_FAB2(SCH_1):PAGE34
   L12 UPI_CPU1_CPU0_P1P1_DN<12> @BASEBOARD_FAB2_LIB.BASEBOARD_FAB2(SCH_1):UPI_CPU1_CPU0_P1P1_DN(12)    I86 @BASEBOARD_FAB2_LIB.BASEBOARD_FAB2(SCH_1):PAGE34
   U12 UPI_CPU1_CPU0_P1P1_DN<13> @BASEBOARD_FAB2_LIB.BASEBOARD_FAB2(SCH_1):UPI_CPU1_CPU0_P1P1_DN(13)    I86 @BASEBOARD_FAB2_LIB.BASEBOARD_FAB2(SCH_1):PAGE34
   R10 UPI_CPU1_CPU0_P1P1_DN<14> @BASEBOARD_FAB2_LIB.BASEBOARD_FAB2(SCH_1):UPI_CPU1_CPU0_P1P1_DN(14)    I86 @BASEBOARD_FAB2_LIB.BASEBOARD_FAB2(SCH_1):PAGE34
    P9 UPI_CPU1_CPU0_P1P1_DN<15> @BASEBOARD_FAB2_LIB.BASEBOARD_FAB2(SCH_1):UPI_CPU1_CPU0_P1P1_DN(15)    I86 @BASEBOARD_FAB2_LIB.BASEBOARD_FAB2(SCH_1):PAGE34
    T9 UPI_CPU1_CPU0_P1P1_DN<16> @BASEBOARD_FAB2_LIB.BASEBOARD_FAB2(SCH_1):UPI_CPU1_CPU0_P1P1_DN(16)    I86 @BASEBOARD_FAB2_LIB.BASEBOARD_FAB2(SCH_1):PAGE34
    V7 UPI_CPU1_CPU0_P1P1_DN<17> @BASEBOARD_FAB2_LIB.BASEBOARD_FAB2(SCH_1):UPI_CPU1_CPU0_P1P1_DN(17)    I86 @BASEBOARD_FAB2_LIB.BASEBOARD_FAB2(SCH_1):PAGE34
    P7 UPI_CPU1_CPU0_P1P1_DN<18> @BASEBOARD_FAB2_LIB.BASEBOARD_FAB2(SCH_1):UPI_CPU1_CPU0_P1P1_DN(18)    I86 @BASEBOARD_FAB2_LIB.BASEBOARD_FAB2(SCH_1):PAGE34
    T5 UPI_CPU1_CPU0_P1P1_DN<19> @BASEBOARD_FAB2_LIB.BASEBOARD_FAB2(SCH_1):UPI_CPU1_CPU0_P1P1_DN(19)    I86 @BASEBOARD_FAB2_LIB.BASEBOARD_FAB2(SCH_1):PAGE34
  AA20 UPI_CPU1_CPU0_P1P1_DP<0> @BASEBOARD_FAB2_LIB.BASEBOARD_FAB2(SCH_1):UPI_CPU1_CPU0_P1P1_DP(0)    I86 @BASEBOARD_FAB2_LIB.BASEBOARD_FAB2(SCH_1):PAGE34
   W20 UPI_CPU1_CPU0_P1P1_DP<1> @BASEBOARD_FAB2_LIB.BASEBOARD_FAB2(SCH_1):UPI_CPU1_CPU0_P1P1_DP(1)    I86 @BASEBOARD_FAB2_LIB.BASEBOARD_FAB2(SCH_1):PAGE34
   Y19 UPI_CPU1_CPU0_P1P1_DP<2> @BASEBOARD_FAB2_LIB.BASEBOARD_FAB2(SCH_1):UPI_CPU1_CPU0_P1P1_DP(2)    I86 @BASEBOARD_FAB2_LIB.BASEBOARD_FAB2(SCH_1):PAGE34
   T21 UPI_CPU1_CPU0_P1P1_DP<3> @BASEBOARD_FAB2_LIB.BASEBOARD_FAB2(SCH_1):UPI_CPU1_CPU0_P1P1_DP(3)    I86 @BASEBOARD_FAB2_LIB.BASEBOARD_FAB2(SCH_1):PAGE34
   T19 UPI_CPU1_CPU0_P1P1_DP<4> @BASEBOARD_FAB2_LIB.BASEBOARD_FAB2(SCH_1):UPI_CPU1_CPU0_P1P1_DP(4)    I86 @BASEBOARD_FAB2_LIB.BASEBOARD_FAB2(SCH_1):PAGE34
   P19 UPI_CPU1_CPU0_P1P1_DP<5> @BASEBOARD_FAB2_LIB.BASEBOARD_FAB2(SCH_1):UPI_CPU1_CPU0_P1P1_DP(5)    I86 @BASEBOARD_FAB2_LIB.BASEBOARD_FAB2(SCH_1):PAGE34
   V17 UPI_CPU1_CPU0_P1P1_DP<6> @BASEBOARD_FAB2_LIB.BASEBOARD_FAB2(SCH_1):UPI_CPU1_CPU0_P1P1_DP(6)    I86 @BASEBOARD_FAB2_LIB.BASEBOARD_FAB2(SCH_1):PAGE34
   W16 UPI_CPU1_CPU0_P1P1_DP<7> @BASEBOARD_FAB2_LIB.BASEBOARD_FAB2(SCH_1):UPI_CPU1_CPU0_P1P1_DP(7)    I86 @BASEBOARD_FAB2_LIB.BASEBOARD_FAB2(SCH_1):PAGE34
   N16 UPI_CPU1_CPU0_P1P1_DP<8> @BASEBOARD_FAB2_LIB.BASEBOARD_FAB2(SCH_1):UPI_CPU1_CPU0_P1P1_DP(8)    I86 @BASEBOARD_FAB2_LIB.BASEBOARD_FAB2(SCH_1):PAGE34
   T15 UPI_CPU1_CPU0_P1P1_DP<9> @BASEBOARD_FAB2_LIB.BASEBOARD_FAB2(SCH_1):UPI_CPU1_CPU0_P1P1_DP(9)    I86 @BASEBOARD_FAB2_LIB.BASEBOARD_FAB2(SCH_1):PAGE34
   P13 UPI_CPU1_CPU0_P1P1_DP<10> @BASEBOARD_FAB2_LIB.BASEBOARD_FAB2(SCH_1):UPI_CPU1_CPU0_P1P1_DP(10)    I86 @BASEBOARD_FAB2_LIB.BASEBOARD_FAB2(SCH_1):PAGE34
   M13 UPI_CPU1_CPU0_P1P1_DP<11> @BASEBOARD_FAB2_LIB.BASEBOARD_FAB2(SCH_1):UPI_CPU1_CPU0_P1P1_DP(11)    I86 @BASEBOARD_FAB2_LIB.BASEBOARD_FAB2(SCH_1):PAGE34
   N12 UPI_CPU1_CPU0_P1P1_DP<12> @BASEBOARD_FAB2_LIB.BASEBOARD_FAB2(SCH_1):UPI_CPU1_CPU0_P1P1_DP(12)    I86 @BASEBOARD_FAB2_LIB.BASEBOARD_FAB2(SCH_1):PAGE34
   T11 UPI_CPU1_CPU0_P1P1_DP<13> @BASEBOARD_FAB2_LIB.BASEBOARD_FAB2(SCH_1):UPI_CPU1_CPU0_P1P1_DP(13)    I86 @BASEBOARD_FAB2_LIB.BASEBOARD_FAB2(SCH_1):PAGE34
   U10 UPI_CPU1_CPU0_P1P1_DP<14> @BASEBOARD_FAB2_LIB.BASEBOARD_FAB2(SCH_1):UPI_CPU1_CPU0_P1P1_DP(14)    I86 @BASEBOARD_FAB2_LIB.BASEBOARD_FAB2(SCH_1):PAGE34
   N10 UPI_CPU1_CPU0_P1P1_DP<15> @BASEBOARD_FAB2_LIB.BASEBOARD_FAB2(SCH_1):UPI_CPU1_CPU0_P1P1_DP(15)    I86 @BASEBOARD_FAB2_LIB.BASEBOARD_FAB2(SCH_1):PAGE34
    R8 UPI_CPU1_CPU0_P1P1_DP<16> @BASEBOARD_FAB2_LIB.BASEBOARD_FAB2(SCH_1):UPI_CPU1_CPU0_P1P1_DP(16)    I86 @BASEBOARD_FAB2_LIB.BASEBOARD_FAB2(SCH_1):PAGE34
    U8 UPI_CPU1_CPU0_P1P1_DP<17> @BASEBOARD_FAB2_LIB.BASEBOARD_FAB2(SCH_1):UPI_CPU1_CPU0_P1P1_DP(17)    I86 @BASEBOARD_FAB2_LIB.BASEBOARD_FAB2(SCH_1):PAGE34
    T7 UPI_CPU1_CPU0_P1P1_DP<18> @BASEBOARD_FAB2_LIB.BASEBOARD_FAB2(SCH_1):UPI_CPU1_CPU0_P1P1_DP(18)    I86 @BASEBOARD_FAB2_LIB.BASEBOARD_FAB2(SCH_1):PAGE34
    R6 UPI_CPU1_CPU0_P1P1_DP<19> @BASEBOARD_FAB2_LIB.BASEBOARD_FAB2(SCH_1):UPI_CPU1_CPU0_P1P1_DP(19)    I86 @BASEBOARD_FAB2_LIB.BASEBOARD_FAB2(SCH_1):PAGE34
   H21 UPI_CPU0_CPU1_P1P1_DN<0> @BASEBOARD_FAB2_LIB.BASEBOARD_FAB2(SCH_1):UPI_CPU0_CPU1_P1P1_DN(0)    I86 @BASEBOARD_FAB2_LIB.BASEBOARD_FAB2(SCH_1):PAGE34
   F21 UPI_CPU0_CPU1_P1P1_DN<1> @BASEBOARD_FAB2_LIB.BASEBOARD_FAB2(SCH_1):UPI_CPU0_CPU1_P1P1_DN(1)    I86 @BASEBOARD_FAB2_LIB.BASEBOARD_FAB2(SCH_1):PAGE34
   J20 UPI_CPU0_CPU1_P1P1_DN<2> @BASEBOARD_FAB2_LIB.BASEBOARD_FAB2(SCH_1):UPI_CPU0_CPU1_P1P1_DN(2)    I86 @BASEBOARD_FAB2_LIB.BASEBOARD_FAB2(SCH_1):PAGE34
   G18 UPI_CPU0_CPU1_P1P1_DN<3> @BASEBOARD_FAB2_LIB.BASEBOARD_FAB2(SCH_1):UPI_CPU0_CPU1_P1P1_DN(3)    I86 @BASEBOARD_FAB2_LIB.BASEBOARD_FAB2(SCH_1):PAGE34
   K19 UPI_CPU0_CPU1_P1P1_DN<4> @BASEBOARD_FAB2_LIB.BASEBOARD_FAB2(SCH_1):UPI_CPU0_CPU1_P1P1_DN(4)    I86 @BASEBOARD_FAB2_LIB.BASEBOARD_FAB2(SCH_1):PAGE34
   H17 UPI_CPU0_CPU1_P1P1_DN<5> @BASEBOARD_FAB2_LIB.BASEBOARD_FAB2(SCH_1):UPI_CPU0_CPU1_P1P1_DN(5)    I86 @BASEBOARD_FAB2_LIB.BASEBOARD_FAB2(SCH_1):PAGE34
   F15 UPI_CPU0_CPU1_P1P1_DN<6> @BASEBOARD_FAB2_LIB.BASEBOARD_FAB2(SCH_1):UPI_CPU0_CPU1_P1P1_DN(6)    I86 @BASEBOARD_FAB2_LIB.BASEBOARD_FAB2(SCH_1):PAGE34
   D15 UPI_CPU0_CPU1_P1P1_DN<7> @BASEBOARD_FAB2_LIB.BASEBOARD_FAB2(SCH_1):UPI_CPU0_CPU1_P1P1_DN(7)    I86 @BASEBOARD_FAB2_LIB.BASEBOARD_FAB2(SCH_1):PAGE34
   G14 UPI_CPU0_CPU1_P1P1_DN<8> @BASEBOARD_FAB2_LIB.BASEBOARD_FAB2(SCH_1):UPI_CPU0_CPU1_P1P1_DN(8)    I86 @BASEBOARD_FAB2_LIB.BASEBOARD_FAB2(SCH_1):PAGE34
   E12 UPI_CPU0_CPU1_P1P1_DN<9> @BASEBOARD_FAB2_LIB.BASEBOARD_FAB2(SCH_1):UPI_CPU0_CPU1_P1P1_DN(9)    I86 @BASEBOARD_FAB2_LIB.BASEBOARD_FAB2(SCH_1):PAGE34
   G10 UPI_CPU0_CPU1_P1P1_DN<10> @BASEBOARD_FAB2_LIB.BASEBOARD_FAB2(SCH_1):UPI_CPU0_CPU1_P1P1_DN(10)    I86 @BASEBOARD_FAB2_LIB.BASEBOARD_FAB2(SCH_1):PAGE34
   F11 UPI_CPU0_CPU1_P1P1_DN<11> @BASEBOARD_FAB2_LIB.BASEBOARD_FAB2(SCH_1):UPI_CPU0_CPU1_P1P1_DN(11)    I86 @BASEBOARD_FAB2_LIB.BASEBOARD_FAB2(SCH_1):PAGE34
    D9 UPI_CPU0_CPU1_P1P1_DN<12> @BASEBOARD_FAB2_LIB.BASEBOARD_FAB2(SCH_1):UPI_CPU0_CPU1_P1P1_DN(12)    I86 @BASEBOARD_FAB2_LIB.BASEBOARD_FAB2(SCH_1):PAGE34
    K9 UPI_CPU0_CPU1_P1P1_DN<13> @BASEBOARD_FAB2_LIB.BASEBOARD_FAB2(SCH_1):UPI_CPU0_CPU1_P1P1_DN(13)    I86 @BASEBOARD_FAB2_LIB.BASEBOARD_FAB2(SCH_1):PAGE34
    H7 UPI_CPU0_CPU1_P1P1_DN<14> @BASEBOARD_FAB2_LIB.BASEBOARD_FAB2(SCH_1):UPI_CPU0_CPU1_P1P1_DN(14)    I86 @BASEBOARD_FAB2_LIB.BASEBOARD_FAB2(SCH_1):PAGE34
    G6 UPI_CPU0_CPU1_P1P1_DN<15> @BASEBOARD_FAB2_LIB.BASEBOARD_FAB2(SCH_1):UPI_CPU0_CPU1_P1P1_DN(15)    I86 @BASEBOARD_FAB2_LIB.BASEBOARD_FAB2(SCH_1):PAGE34
    J6 UPI_CPU0_CPU1_P1P1_DN<16> @BASEBOARD_FAB2_LIB.BASEBOARD_FAB2(SCH_1):UPI_CPU0_CPU1_P1P1_DN(16)    I86 @BASEBOARD_FAB2_LIB.BASEBOARD_FAB2(SCH_1):PAGE34
    K5 UPI_CPU0_CPU1_P1P1_DN<17> @BASEBOARD_FAB2_LIB.BASEBOARD_FAB2(SCH_1):UPI_CPU0_CPU1_P1P1_DN(17)    I86 @BASEBOARD_FAB2_LIB.BASEBOARD_FAB2(SCH_1):PAGE34
    L4 UPI_CPU0_CPU1_P1P1_DN<18> @BASEBOARD_FAB2_LIB.BASEBOARD_FAB2(SCH_1):UPI_CPU0_CPU1_P1P1_DN(18)    I86 @BASEBOARD_FAB2_LIB.BASEBOARD_FAB2(SCH_1):PAGE34
    M3 UPI_CPU0_CPU1_P1P1_DN<19> @BASEBOARD_FAB2_LIB.BASEBOARD_FAB2(SCH_1):UPI_CPU0_CPU1_P1P1_DN(19)    I86 @BASEBOARD_FAB2_LIB.BASEBOARD_FAB2(SCH_1):PAGE34
   K21 UPI_CPU0_CPU1_P1P1_DP<0> @BASEBOARD_FAB2_LIB.BASEBOARD_FAB2(SCH_1):UPI_CPU0_CPU1_P1P1_DP(0)    I86 @BASEBOARD_FAB2_LIB.BASEBOARD_FAB2(SCH_1):PAGE34
   G20 UPI_CPU0_CPU1_P1P1_DP<1> @BASEBOARD_FAB2_LIB.BASEBOARD_FAB2(SCH_1):UPI_CPU0_CPU1_P1P1_DP(1)    I86 @BASEBOARD_FAB2_LIB.BASEBOARD_FAB2(SCH_1):PAGE34
   H19 UPI_CPU0_CPU1_P1P1_DP<2> @BASEBOARD_FAB2_LIB.BASEBOARD_FAB2(SCH_1):UPI_CPU0_CPU1_P1P1_DP(2)    I86 @BASEBOARD_FAB2_LIB.BASEBOARD_FAB2(SCH_1):PAGE34
   J18 UPI_CPU0_CPU1_P1P1_DP<3> @BASEBOARD_FAB2_LIB.BASEBOARD_FAB2(SCH_1):UPI_CPU0_CPU1_P1P1_DP(3)    I86 @BASEBOARD_FAB2_LIB.BASEBOARD_FAB2(SCH_1):PAGE34
   L18 UPI_CPU0_CPU1_P1P1_DP<4> @BASEBOARD_FAB2_LIB.BASEBOARD_FAB2(SCH_1):UPI_CPU0_CPU1_P1P1_DP(4)    I86 @BASEBOARD_FAB2_LIB.BASEBOARD_FAB2(SCH_1):PAGE34
   G16 UPI_CPU0_CPU1_P1P1_DP<5> @BASEBOARD_FAB2_LIB.BASEBOARD_FAB2(SCH_1):UPI_CPU0_CPU1_P1P1_DP(5)    I86 @BASEBOARD_FAB2_LIB.BASEBOARD_FAB2(SCH_1):PAGE34
   H15 UPI_CPU0_CPU1_P1P1_DP<6> @BASEBOARD_FAB2_LIB.BASEBOARD_FAB2(SCH_1):UPI_CPU0_CPU1_P1P1_DP(6)    I86 @BASEBOARD_FAB2_LIB.BASEBOARD_FAB2(SCH_1):PAGE34
   E14 UPI_CPU0_CPU1_P1P1_DP<7> @BASEBOARD_FAB2_LIB.BASEBOARD_FAB2(SCH_1):UPI_CPU0_CPU1_P1P1_DP(7)    I86 @BASEBOARD_FAB2_LIB.BASEBOARD_FAB2(SCH_1):PAGE34
   F13 UPI_CPU0_CPU1_P1P1_DP<8> @BASEBOARD_FAB2_LIB.BASEBOARD_FAB2(SCH_1):UPI_CPU0_CPU1_P1P1_DP(8)    I86 @BASEBOARD_FAB2_LIB.BASEBOARD_FAB2(SCH_1):PAGE34
   G12 UPI_CPU0_CPU1_P1P1_DP<9> @BASEBOARD_FAB2_LIB.BASEBOARD_FAB2(SCH_1):UPI_CPU0_CPU1_P1P1_DP(9)    I86 @BASEBOARD_FAB2_LIB.BASEBOARD_FAB2(SCH_1):PAGE34
    H9 UPI_CPU0_CPU1_P1P1_DP<10> @BASEBOARD_FAB2_LIB.BASEBOARD_FAB2(SCH_1):UPI_CPU0_CPU1_P1P1_DP(10)    I86 @BASEBOARD_FAB2_LIB.BASEBOARD_FAB2(SCH_1):PAGE34
   E10 UPI_CPU0_CPU1_P1P1_DP<11> @BASEBOARD_FAB2_LIB.BASEBOARD_FAB2(SCH_1):UPI_CPU0_CPU1_P1P1_DP(11)    I86 @BASEBOARD_FAB2_LIB.BASEBOARD_FAB2(SCH_1):PAGE34
    F9 UPI_CPU0_CPU1_P1P1_DP<12> @BASEBOARD_FAB2_LIB.BASEBOARD_FAB2(SCH_1):UPI_CPU0_CPU1_P1P1_DP(12)    I86 @BASEBOARD_FAB2_LIB.BASEBOARD_FAB2(SCH_1):PAGE34
    J8 UPI_CPU0_CPU1_P1P1_DP<13> @BASEBOARD_FAB2_LIB.BASEBOARD_FAB2(SCH_1):UPI_CPU0_CPU1_P1P1_DP(13)    I86 @BASEBOARD_FAB2_LIB.BASEBOARD_FAB2(SCH_1):PAGE34
    K7 UPI_CPU0_CPU1_P1P1_DP<14> @BASEBOARD_FAB2_LIB.BASEBOARD_FAB2(SCH_1):UPI_CPU0_CPU1_P1P1_DP(14)    I86 @BASEBOARD_FAB2_LIB.BASEBOARD_FAB2(SCH_1):PAGE34
    F7 UPI_CPU0_CPU1_P1P1_DP<15> @BASEBOARD_FAB2_LIB.BASEBOARD_FAB2(SCH_1):UPI_CPU0_CPU1_P1P1_DP(15)    I86 @BASEBOARD_FAB2_LIB.BASEBOARD_FAB2(SCH_1):PAGE34
    H5 UPI_CPU0_CPU1_P1P1_DP<16> @BASEBOARD_FAB2_LIB.BASEBOARD_FAB2(SCH_1):UPI_CPU0_CPU1_P1P1_DP(16)    I86 @BASEBOARD_FAB2_LIB.BASEBOARD_FAB2(SCH_1):PAGE34
    M5 UPI_CPU0_CPU1_P1P1_DP<17> @BASEBOARD_FAB2_LIB.BASEBOARD_FAB2(SCH_1):UPI_CPU0_CPU1_P1P1_DP(17)    I86 @BASEBOARD_FAB2_LIB.BASEBOARD_FAB2(SCH_1):PAGE34
    K3 UPI_CPU0_CPU1_P1P1_DP<18> @BASEBOARD_FAB2_LIB.BASEBOARD_FAB2(SCH_1):UPI_CPU0_CPU1_P1P1_DP(18)    I86 @BASEBOARD_FAB2_LIB.BASEBOARD_FAB2(SCH_1):PAGE34
    P3 UPI_CPU0_CPU1_P1P1_DP<19> @BASEBOARD_FAB2_LIB.BASEBOARD_FAB2(SCH_1):UPI_CPU0_CPU1_P1P1_DP(19)    I86 @BASEBOARD_FAB2_LIB.BASEBOARD_FAB2(SCH_1):PAGE34
  BY17    GND @BASEBOARD_FAB2_LIB.BASEBOARD_FAB2(SCH_1):GND     I3 @BASEBOARD_FAB2_LIB.BASEBOARD_FAB2(SCH_1):PAGE35
  CB15    GND @BASEBOARD_FAB2_LIB.BASEBOARD_FAB2(SCH_1):GND     I3 @BASEBOARD_FAB2_LIB.BASEBOARD_FAB2(SCH_1):PAGE35
  CF17    GND @BASEBOARD_FAB2_LIB.BASEBOARD_FAB2(SCH_1):GND     I3 @BASEBOARD_FAB2_LIB.BASEBOARD_FAB2(SCH_1):PAGE35
  CD15    GND @BASEBOARD_FAB2_LIB.BASEBOARD_FAB2(SCH_1):GND     I3 @BASEBOARD_FAB2_LIB.BASEBOARD_FAB2(SCH_1):PAGE35
  CE16    GND @BASEBOARD_FAB2_LIB.BASEBOARD_FAB2(SCH_1):GND     I3 @BASEBOARD_FAB2_LIB.BASEBOARD_FAB2(SCH_1):PAGE35
  CH17    GND @BASEBOARD_FAB2_LIB.BASEBOARD_FAB2(SCH_1):GND     I3 @BASEBOARD_FAB2_LIB.BASEBOARD_FAB2(SCH_1):PAGE35
  CJ18    GND @BASEBOARD_FAB2_LIB.BASEBOARD_FAB2(SCH_1):GND     I3 @BASEBOARD_FAB2_LIB.BASEBOARD_FAB2(SCH_1):PAGE35
  CL16    GND @BASEBOARD_FAB2_LIB.BASEBOARD_FAB2(SCH_1):GND     I3 @BASEBOARD_FAB2_LIB.BASEBOARD_FAB2(SCH_1):PAGE35
  CP21    GND @BASEBOARD_FAB2_LIB.BASEBOARD_FAB2(SCH_1):GND     I3 @BASEBOARD_FAB2_LIB.BASEBOARD_FAB2(SCH_1):PAGE35
  CN20    GND @BASEBOARD_FAB2_LIB.BASEBOARD_FAB2(SCH_1):GND     I3 @BASEBOARD_FAB2_LIB.BASEBOARD_FAB2(SCH_1):PAGE35
  CR18    GND @BASEBOARD_FAB2_LIB.BASEBOARD_FAB2(SCH_1):GND     I3 @BASEBOARD_FAB2_LIB.BASEBOARD_FAB2(SCH_1):PAGE35
  CT21    GND @BASEBOARD_FAB2_LIB.BASEBOARD_FAB2(SCH_1):GND     I3 @BASEBOARD_FAB2_LIB.BASEBOARD_FAB2(SCH_1):PAGE35
  CV19    GND @BASEBOARD_FAB2_LIB.BASEBOARD_FAB2(SCH_1):GND     I3 @BASEBOARD_FAB2_LIB.BASEBOARD_FAB2(SCH_1):PAGE35
  CW20    GND @BASEBOARD_FAB2_LIB.BASEBOARD_FAB2(SCH_1):GND     I3 @BASEBOARD_FAB2_LIB.BASEBOARD_FAB2(SCH_1):PAGE35
  DA20    GND @BASEBOARD_FAB2_LIB.BASEBOARD_FAB2(SCH_1):GND     I3 @BASEBOARD_FAB2_LIB.BASEBOARD_FAB2(SCH_1):PAGE35
  DD19    GND @BASEBOARD_FAB2_LIB.BASEBOARD_FAB2(SCH_1):GND     I3 @BASEBOARD_FAB2_LIB.BASEBOARD_FAB2(SCH_1):PAGE35
  DB21    GND @BASEBOARD_FAB2_LIB.BASEBOARD_FAB2(SCH_1):GND     I3 @BASEBOARD_FAB2_LIB.BASEBOARD_FAB2(SCH_1):PAGE35
  DC22    GND @BASEBOARD_FAB2_LIB.BASEBOARD_FAB2(SCH_1):GND     I3 @BASEBOARD_FAB2_LIB.BASEBOARD_FAB2(SCH_1):PAGE35
  DE22    GND @BASEBOARD_FAB2_LIB.BASEBOARD_FAB2(SCH_1):GND     I3 @BASEBOARD_FAB2_LIB.BASEBOARD_FAB2(SCH_1):PAGE35
  DF23    GND @BASEBOARD_FAB2_LIB.BASEBOARD_FAB2(SCH_1):GND     I3 @BASEBOARD_FAB2_LIB.BASEBOARD_FAB2(SCH_1):PAGE35
  CA16    GND @BASEBOARD_FAB2_LIB.BASEBOARD_FAB2(SCH_1):GND     I3 @BASEBOARD_FAB2_LIB.BASEBOARD_FAB2(SCH_1):PAGE35
  BY15    GND @BASEBOARD_FAB2_LIB.BASEBOARD_FAB2(SCH_1):GND     I3 @BASEBOARD_FAB2_LIB.BASEBOARD_FAB2(SCH_1):PAGE35
  CD17    GND @BASEBOARD_FAB2_LIB.BASEBOARD_FAB2(SCH_1):GND     I3 @BASEBOARD_FAB2_LIB.BASEBOARD_FAB2(SCH_1):PAGE35
  CC14    GND @BASEBOARD_FAB2_LIB.BASEBOARD_FAB2(SCH_1):GND     I3 @BASEBOARD_FAB2_LIB.BASEBOARD_FAB2(SCH_1):PAGE35
  CF15    GND @BASEBOARD_FAB2_LIB.BASEBOARD_FAB2(SCH_1):GND     I3 @BASEBOARD_FAB2_LIB.BASEBOARD_FAB2(SCH_1):PAGE35
  CG16    GND @BASEBOARD_FAB2_LIB.BASEBOARD_FAB2(SCH_1):GND     I3 @BASEBOARD_FAB2_LIB.BASEBOARD_FAB2(SCH_1):PAGE35
  CK17    GND @BASEBOARD_FAB2_LIB.BASEBOARD_FAB2(SCH_1):GND     I3 @BASEBOARD_FAB2_LIB.BASEBOARD_FAB2(SCH_1):PAGE35
  CJ16    GND @BASEBOARD_FAB2_LIB.BASEBOARD_FAB2(SCH_1):GND     I3 @BASEBOARD_FAB2_LIB.BASEBOARD_FAB2(SCH_1):PAGE35
  CM21    GND @BASEBOARD_FAB2_LIB.BASEBOARD_FAB2(SCH_1):GND     I3 @BASEBOARD_FAB2_LIB.BASEBOARD_FAB2(SCH_1):PAGE35
  CP19    GND @BASEBOARD_FAB2_LIB.BASEBOARD_FAB2(SCH_1):GND     I3 @BASEBOARD_FAB2_LIB.BASEBOARD_FAB2(SCH_1):PAGE35
  CN18    GND @BASEBOARD_FAB2_LIB.BASEBOARD_FAB2(SCH_1):GND     I3 @BASEBOARD_FAB2_LIB.BASEBOARD_FAB2(SCH_1):PAGE35
  CR20    GND @BASEBOARD_FAB2_LIB.BASEBOARD_FAB2(SCH_1):GND     I3 @BASEBOARD_FAB2_LIB.BASEBOARD_FAB2(SCH_1):PAGE35
  CW18    GND @BASEBOARD_FAB2_LIB.BASEBOARD_FAB2(SCH_1):GND     I3 @BASEBOARD_FAB2_LIB.BASEBOARD_FAB2(SCH_1):PAGE35
  CU20    GND @BASEBOARD_FAB2_LIB.BASEBOARD_FAB2(SCH_1):GND     I3 @BASEBOARD_FAB2_LIB.BASEBOARD_FAB2(SCH_1):PAGE35
  CY19    GND @BASEBOARD_FAB2_LIB.BASEBOARD_FAB2(SCH_1):GND     I3 @BASEBOARD_FAB2_LIB.BASEBOARD_FAB2(SCH_1):PAGE35
  DB19    GND @BASEBOARD_FAB2_LIB.BASEBOARD_FAB2(SCH_1):GND     I3 @BASEBOARD_FAB2_LIB.BASEBOARD_FAB2(SCH_1):PAGE35
  DC20    GND @BASEBOARD_FAB2_LIB.BASEBOARD_FAB2(SCH_1):GND     I3 @BASEBOARD_FAB2_LIB.BASEBOARD_FAB2(SCH_1):PAGE35
  DA22    GND @BASEBOARD_FAB2_LIB.BASEBOARD_FAB2(SCH_1):GND     I3 @BASEBOARD_FAB2_LIB.BASEBOARD_FAB2(SCH_1):PAGE35
  DD21    GND @BASEBOARD_FAB2_LIB.BASEBOARD_FAB2(SCH_1):GND     I3 @BASEBOARD_FAB2_LIB.BASEBOARD_FAB2(SCH_1):PAGE35
  DG22    GND @BASEBOARD_FAB2_LIB.BASEBOARD_FAB2(SCH_1):GND     I3 @BASEBOARD_FAB2_LIB.BASEBOARD_FAB2(SCH_1):PAGE35
  CC12 TP_CPU0_UPI2_RSVD_DT21 @BASEBOARD_FAB2_LIB.BASEBOARD_FAB2(SCH_1):TP_CPU0_UPI2_RSVD_DT21     I3 @BASEBOARD_FAB2_LIB.BASEBOARD_FAB2(SCH_1):PAGE35
  CC10 TP_CPU0_UPI2_RSVD_DM21 @BASEBOARD_FAB2_LIB.BASEBOARD_FAB2(SCH_1):TP_CPU0_UPI2_RSVD_DM21     I3 @BASEBOARD_FAB2_LIB.BASEBOARD_FAB2(SCH_1):PAGE35
  CE12 TP_CPU0_UPI2_RSVD_DL20 @BASEBOARD_FAB2_LIB.BASEBOARD_FAB2(SCH_1):TP_CPU0_UPI2_RSVD_DL20     I3 @BASEBOARD_FAB2_LIB.BASEBOARD_FAB2(SCH_1):PAGE35
  CH11 TP_CPU0_UPI2_RSVD_DG20 @BASEBOARD_FAB2_LIB.BASEBOARD_FAB2(SCH_1):TP_CPU0_UPI2_RSVD_DG20     I3 @BASEBOARD_FAB2_LIB.BASEBOARD_FAB2(SCH_1):PAGE35
  CF13 TP_CPU0_UPI2_RSVD_DH19 @BASEBOARD_FAB2_LIB.BASEBOARD_FAB2(SCH_1):TP_CPU0_UPI2_RSVD_DH19     I3 @BASEBOARD_FAB2_LIB.BASEBOARD_FAB2(SCH_1):PAGE35
  CJ14 TP_CPU0_UPI2_RSVD_DK17 @BASEBOARD_FAB2_LIB.BASEBOARD_FAB2(SCH_1):TP_CPU0_UPI2_RSVD_DK17     I3 @BASEBOARD_FAB2_LIB.BASEBOARD_FAB2(SCH_1):PAGE35
  CM13 TP_CPU0_UPI2_RSVD_DG18 @BASEBOARD_FAB2_LIB.BASEBOARD_FAB2(SCH_1):TP_CPU0_UPI2_RSVD_DG18     I3 @BASEBOARD_FAB2_LIB.BASEBOARD_FAB2(SCH_1):PAGE35
  CU14 TP_CPU0_UPI2_RSVD_DD17 @BASEBOARD_FAB2_LIB.BASEBOARD_FAB2(SCH_1):TP_CPU0_UPI2_RSVD_DD17     I3 @BASEBOARD_FAB2_LIB.BASEBOARD_FAB2(SCH_1):PAGE35
  CW14 TP_CPU0_UPI2_RSVD_DF15 @BASEBOARD_FAB2_LIB.BASEBOARD_FAB2(SCH_1):TP_CPU0_UPI2_RSVD_DF15     I3 @BASEBOARD_FAB2_LIB.BASEBOARD_FAB2(SCH_1):PAGE35
  DA16 TP_CPU0_UPI2_RSVD_DC16 @BASEBOARD_FAB2_LIB.BASEBOARD_FAB2(SCH_1):TP_CPU0_UPI2_RSVD_DC16     I3 @BASEBOARD_FAB2_LIB.BASEBOARD_FAB2(SCH_1):PAGE35
  DC16 TP_CPU0_UPI2_RSVD_DA16 @BASEBOARD_FAB2_LIB.BASEBOARD_FAB2(SCH_1):TP_CPU0_UPI2_RSVD_DA16     I3 @BASEBOARD_FAB2_LIB.BASEBOARD_FAB2(SCH_1):PAGE35
  DF15 TP_CPU0_UPI2_RSVD_CW14 @BASEBOARD_FAB2_LIB.BASEBOARD_FAB2(SCH_1):TP_CPU0_UPI2_RSVD_CW14     I3 @BASEBOARD_FAB2_LIB.BASEBOARD_FAB2(SCH_1):PAGE35
  DD17 TP_CPU0_UPI2_RSVD_CU14 @BASEBOARD_FAB2_LIB.BASEBOARD_FAB2(SCH_1):TP_CPU0_UPI2_RSVD_CU14     I3 @BASEBOARD_FAB2_LIB.BASEBOARD_FAB2(SCH_1):PAGE35
  DG18 TP_CPU0_UPI2_RSVD_CM13 @BASEBOARD_FAB2_LIB.BASEBOARD_FAB2(SCH_1):TP_CPU0_UPI2_RSVD_CM13     I3 @BASEBOARD_FAB2_LIB.BASEBOARD_FAB2(SCH_1):PAGE35
  DK17 TP_CPU0_UPI2_RSVD_CJ14 @BASEBOARD_FAB2_LIB.BASEBOARD_FAB2(SCH_1):TP_CPU0_UPI2_RSVD_CJ14     I3 @BASEBOARD_FAB2_LIB.BASEBOARD_FAB2(SCH_1):PAGE35
  DH19 TP_CPU0_UPI2_RSVD_CF13 @BASEBOARD_FAB2_LIB.BASEBOARD_FAB2(SCH_1):TP_CPU0_UPI2_RSVD_CF13     I3 @BASEBOARD_FAB2_LIB.BASEBOARD_FAB2(SCH_1):PAGE35
  DG20 TP_CPU0_UPI2_RSVD_CH11 @BASEBOARD_FAB2_LIB.BASEBOARD_FAB2(SCH_1):TP_CPU0_UPI2_RSVD_CH11     I3 @BASEBOARD_FAB2_LIB.BASEBOARD_FAB2(SCH_1):PAGE35
  DL20 TP_CPU0_UPI2_RSVD_CE12 @BASEBOARD_FAB2_LIB.BASEBOARD_FAB2(SCH_1):TP_CPU0_UPI2_RSVD_CE12     I3 @BASEBOARD_FAB2_LIB.BASEBOARD_FAB2(SCH_1):PAGE35
  DM21 TP_CPU0_UPI2_RSVD_CC10 @BASEBOARD_FAB2_LIB.BASEBOARD_FAB2(SCH_1):TP_CPU0_UPI2_RSVD_CC10     I3 @BASEBOARD_FAB2_LIB.BASEBOARD_FAB2(SCH_1):PAGE35
  DT21 TP_CPU0_UPI2_RSVD_CC12 @BASEBOARD_FAB2_LIB.BASEBOARD_FAB2(SCH_1):TP_CPU0_UPI2_RSVD_CC12     I3 @BASEBOARD_FAB2_LIB.BASEBOARD_FAB2(SCH_1):PAGE35
  CA12 TP_CPU0_UPI2_RSVD_DP21 @BASEBOARD_FAB2_LIB.BASEBOARD_FAB2(SCH_1):TP_CPU0_UPI2_RSVD_DP21     I3 @BASEBOARD_FAB2_LIB.BASEBOARD_FAB2(SCH_1):PAGE35
  CB11 TP_CPU0_UPI2_RSVD_DN20 @BASEBOARD_FAB2_LIB.BASEBOARD_FAB2(SCH_1):TP_CPU0_UPI2_RSVD_DN20     I3 @BASEBOARD_FAB2_LIB.BASEBOARD_FAB2(SCH_1):PAGE35
  CD11 TP_CPU0_UPI2_RSVD_DK19 @BASEBOARD_FAB2_LIB.BASEBOARD_FAB2(SCH_1):TP_CPU0_UPI2_RSVD_DK19     I3 @BASEBOARD_FAB2_LIB.BASEBOARD_FAB2(SCH_1):PAGE35
  CF11 TP_CPU0_UPI2_RSVD_DJ20 @BASEBOARD_FAB2_LIB.BASEBOARD_FAB2(SCH_1):TP_CPU0_UPI2_RSVD_DJ20     I3 @BASEBOARD_FAB2_LIB.BASEBOARD_FAB2(SCH_1):PAGE35
  CG12 TP_CPU0_UPI2_RSVD_DJ18 @BASEBOARD_FAB2_LIB.BASEBOARD_FAB2(SCH_1):TP_CPU0_UPI2_RSVD_DJ18     I3 @BASEBOARD_FAB2_LIB.BASEBOARD_FAB2(SCH_1):PAGE35
  CH13 TP_CPU0_UPI2_RSVD_DH17 @BASEBOARD_FAB2_LIB.BASEBOARD_FAB2(SCH_1):TP_CPU0_UPI2_RSVD_DH17     I3 @BASEBOARD_FAB2_LIB.BASEBOARD_FAB2(SCH_1):PAGE35
  CK13 TP_CPU0_UPI2_RSVD_DF17 @BASEBOARD_FAB2_LIB.BASEBOARD_FAB2(SCH_1):TP_CPU0_UPI2_RSVD_DF17     I3 @BASEBOARD_FAB2_LIB.BASEBOARD_FAB2(SCH_1):PAGE35
  CR14 TP_CPU0_UPI2_RSVD_DE16 @BASEBOARD_FAB2_LIB.BASEBOARD_FAB2(SCH_1):TP_CPU0_UPI2_RSVD_DE16     I3 @BASEBOARD_FAB2_LIB.BASEBOARD_FAB2(SCH_1):PAGE35
  CV13 TP_CPU0_UPI2_RSVD_DD15 @BASEBOARD_FAB2_LIB.BASEBOARD_FAB2(SCH_1):TP_CPU0_UPI2_RSVD_DD15     I3 @BASEBOARD_FAB2_LIB.BASEBOARD_FAB2(SCH_1):PAGE35
  CW16 TP_CPU0_UPI2_RSVD_DB15 @BASEBOARD_FAB2_LIB.BASEBOARD_FAB2(SCH_1):TP_CPU0_UPI2_RSVD_DB15     I3 @BASEBOARD_FAB2_LIB.BASEBOARD_FAB2(SCH_1):PAGE35
  DB15 TP_CPU0_UPI2_RSVD_CW16 @BASEBOARD_FAB2_LIB.BASEBOARD_FAB2(SCH_1):TP_CPU0_UPI2_RSVD_CW16     I3 @BASEBOARD_FAB2_LIB.BASEBOARD_FAB2(SCH_1):PAGE35
  DD15 TP_CPU0_UPI2_RSVD_CV13 @BASEBOARD_FAB2_LIB.BASEBOARD_FAB2(SCH_1):TP_CPU0_UPI2_RSVD_CV13     I3 @BASEBOARD_FAB2_LIB.BASEBOARD_FAB2(SCH_1):PAGE35
  DE16 TP_CPU0_UPI2_RSVD_CR14 @BASEBOARD_FAB2_LIB.BASEBOARD_FAB2(SCH_1):TP_CPU0_UPI2_RSVD_CR14     I3 @BASEBOARD_FAB2_LIB.BASEBOARD_FAB2(SCH_1):PAGE35
  DF17 TP_CPU0_UPI2_RSVD_CK13 @BASEBOARD_FAB2_LIB.BASEBOARD_FAB2(SCH_1):TP_CPU0_UPI2_RSVD_CK13     I3 @BASEBOARD_FAB2_LIB.BASEBOARD_FAB2(SCH_1):PAGE35
  DH17 TP_CPU0_UPI2_RSVD_CH13 @BASEBOARD_FAB2_LIB.BASEBOARD_FAB2(SCH_1):TP_CPU0_UPI2_RSVD_CH13     I3 @BASEBOARD_FAB2_LIB.BASEBOARD_FAB2(SCH_1):PAGE35
  DJ18 TP_CPU0_UPI2_RSVD_CG12 @BASEBOARD_FAB2_LIB.BASEBOARD_FAB2(SCH_1):TP_CPU0_UPI2_RSVD_CG12     I3 @BASEBOARD_FAB2_LIB.BASEBOARD_FAB2(SCH_1):PAGE35
  DJ20 TP_CPU0_UPI2_RSVD_CF11 @BASEBOARD_FAB2_LIB.BASEBOARD_FAB2(SCH_1):TP_CPU0_UPI2_RSVD_CF11     I3 @BASEBOARD_FAB2_LIB.BASEBOARD_FAB2(SCH_1):PAGE35
  DK19 TP_CPU0_UPI2_RSVD_CD11 @BASEBOARD_FAB2_LIB.BASEBOARD_FAB2(SCH_1):TP_CPU0_UPI2_RSVD_CD11     I3 @BASEBOARD_FAB2_LIB.BASEBOARD_FAB2(SCH_1):PAGE35
  DN20 TP_CPU0_UPI2_RSVD_CB11 @BASEBOARD_FAB2_LIB.BASEBOARD_FAB2(SCH_1):TP_CPU0_UPI2_RSVD_CB11     I3 @BASEBOARD_FAB2_LIB.BASEBOARD_FAB2(SCH_1):PAGE35
  DP21 TP_CPU0_UPI2_RSVD_CA12 @BASEBOARD_FAB2_LIB.BASEBOARD_FAB2(SCH_1):TP_CPU0_UPI2_RSVD_CA12     I3 @BASEBOARD_FAB2_LIB.BASEBOARD_FAB2(SCH_1):PAGE35
  AY83 TP_CPU0_RSVD_255 @BASEBOARD_FAB2_LIB.BASEBOARD_FAB2(SCH_1):TP_CPU0_RSVD_255    I15 @BASEBOARD_FAB2_LIB.BASEBOARD_FAB2(SCH_1):PAGE36
  BA78 TP_CPU0_RSVD_171 @BASEBOARD_FAB2_LIB.BASEBOARD_FAB2(SCH_1):TP_CPU0_RSVD_171    I15 @BASEBOARD_FAB2_LIB.BASEBOARD_FAB2(SCH_1):PAGE36
  BA82 TP_CPU0_RSVD_170 @BASEBOARD_FAB2_LIB.BASEBOARD_FAB2(SCH_1):TP_CPU0_RSVD_170    I15 @BASEBOARD_FAB2_LIB.BASEBOARD_FAB2(SCH_1):PAGE36
  BB13 TP_CPU0_RSVD_169 @BASEBOARD_FAB2_LIB.BASEBOARD_FAB2(SCH_1):TP_CPU0_RSVD_169    I15 @BASEBOARD_FAB2_LIB.BASEBOARD_FAB2(SCH_1):PAGE36
  BB15 TP_CPU0_RSVD_168 @BASEBOARD_FAB2_LIB.BASEBOARD_FAB2(SCH_1):TP_CPU0_RSVD_168    I15 @BASEBOARD_FAB2_LIB.BASEBOARD_FAB2(SCH_1):PAGE36
  BB17 TP_CPU0_RSVD_167 @BASEBOARD_FAB2_LIB.BASEBOARD_FAB2(SCH_1):TP_CPU0_RSVD_167    I15 @BASEBOARD_FAB2_LIB.BASEBOARD_FAB2(SCH_1):PAGE36
  BB21 TP_CPU0_RSVD_166 @BASEBOARD_FAB2_LIB.BASEBOARD_FAB2(SCH_1):TP_CPU0_RSVD_166    I15 @BASEBOARD_FAB2_LIB.BASEBOARD_FAB2(SCH_1):PAGE36
  BB25 CLK_100M_CPU0_RC_REFCLK1_DN @BASEBOARD_FAB2_LIB.BASEBOARD_FAB2(SCH_1):CLK_100M_CPU0_RC_REFCLK1_DN    I15 @BASEBOARD_FAB2_LIB.BASEBOARD_FAB2(SCH_1):PAGE36
  BB65 TP_CPU0_RSVD_164 @BASEBOARD_FAB2_LIB.BASEBOARD_FAB2(SCH_1):TP_CPU0_RSVD_164    I15 @BASEBOARD_FAB2_LIB.BASEBOARD_FAB2(SCH_1):PAGE36
  BB67 TP_CPU0_RSVD_163 @BASEBOARD_FAB2_LIB.BASEBOARD_FAB2(SCH_1):TP_CPU0_RSVD_163    I15 @BASEBOARD_FAB2_LIB.BASEBOARD_FAB2(SCH_1):PAGE36
  BC14 TP_CPU0_RSVD_162 @BASEBOARD_FAB2_LIB.BASEBOARD_FAB2(SCH_1):TP_CPU0_RSVD_162    I15 @BASEBOARD_FAB2_LIB.BASEBOARD_FAB2(SCH_1):PAGE36
  BC18 TP_CPU0_RSVD_161 @BASEBOARD_FAB2_LIB.BASEBOARD_FAB2(SCH_1):TP_CPU0_RSVD_161    I15 @BASEBOARD_FAB2_LIB.BASEBOARD_FAB2(SCH_1):PAGE36
  BC20 TP_CPU0_RSVD_160 @BASEBOARD_FAB2_LIB.BASEBOARD_FAB2(SCH_1):TP_CPU0_RSVD_160    I15 @BASEBOARD_FAB2_LIB.BASEBOARD_FAB2(SCH_1):PAGE36
  BC22 TP_CPU0_RSVD_159 @BASEBOARD_FAB2_LIB.BASEBOARD_FAB2(SCH_1):TP_CPU0_RSVD_159    I15 @BASEBOARD_FAB2_LIB.BASEBOARD_FAB2(SCH_1):PAGE36
  BC64 TP_CPU0_RSVD_158 @BASEBOARD_FAB2_LIB.BASEBOARD_FAB2(SCH_1):TP_CPU0_RSVD_158    I15 @BASEBOARD_FAB2_LIB.BASEBOARD_FAB2(SCH_1):PAGE36
  BC66 TP_CPU0_RSVD_157 @BASEBOARD_FAB2_LIB.BASEBOARD_FAB2(SCH_1):TP_CPU0_RSVD_157    I15 @BASEBOARD_FAB2_LIB.BASEBOARD_FAB2(SCH_1):PAGE36
  BC68 TP_CPU0_RSVD_156 @BASEBOARD_FAB2_LIB.BASEBOARD_FAB2(SCH_1):TP_CPU0_RSVD_156    I15 @BASEBOARD_FAB2_LIB.BASEBOARD_FAB2(SCH_1):PAGE36
  BD17 TP_CPU0_RSVD_155 @BASEBOARD_FAB2_LIB.BASEBOARD_FAB2(SCH_1):TP_CPU0_RSVD_155    I15 @BASEBOARD_FAB2_LIB.BASEBOARD_FAB2(SCH_1):PAGE36
  BD19 TP_CPU0_RSVD_154 @BASEBOARD_FAB2_LIB.BASEBOARD_FAB2(SCH_1):TP_CPU0_RSVD_154    I15 @BASEBOARD_FAB2_LIB.BASEBOARD_FAB2(SCH_1):PAGE36
  BD25 CLK_100M_CPU0_RC_REFCLK1_DP @BASEBOARD_FAB2_LIB.BASEBOARD_FAB2(SCH_1):CLK_100M_CPU0_RC_REFCLK1_DP    I15 @BASEBOARD_FAB2_LIB.BASEBOARD_FAB2(SCH_1):PAGE36
  BD65 TP_CPU0_RSVD_152 @BASEBOARD_FAB2_LIB.BASEBOARD_FAB2(SCH_1):TP_CPU0_RSVD_152    I15 @BASEBOARD_FAB2_LIB.BASEBOARD_FAB2(SCH_1):PAGE36
  BD67 TP_CPU0_RSVD_151 @BASEBOARD_FAB2_LIB.BASEBOARD_FAB2(SCH_1):TP_CPU0_RSVD_151    I15 @BASEBOARD_FAB2_LIB.BASEBOARD_FAB2(SCH_1):PAGE36
  BD69 TP_CPU0_RSVD_150 @BASEBOARD_FAB2_LIB.BASEBOARD_FAB2(SCH_1):TP_CPU0_RSVD_150    I15 @BASEBOARD_FAB2_LIB.BASEBOARD_FAB2(SCH_1):PAGE36
  BE18 TP_CPU0_RSVD_149 @BASEBOARD_FAB2_LIB.BASEBOARD_FAB2(SCH_1):TP_CPU0_RSVD_149    I15 @BASEBOARD_FAB2_LIB.BASEBOARD_FAB2(SCH_1):PAGE36
  BE20 TP_CPU0_RSVD_148 @BASEBOARD_FAB2_LIB.BASEBOARD_FAB2(SCH_1):TP_CPU0_RSVD_148    I15 @BASEBOARD_FAB2_LIB.BASEBOARD_FAB2(SCH_1):PAGE36
  BE22 TP_CPU0_RSVD_147 @BASEBOARD_FAB2_LIB.BASEBOARD_FAB2(SCH_1):TP_CPU0_RSVD_147    I15 @BASEBOARD_FAB2_LIB.BASEBOARD_FAB2(SCH_1):PAGE36
  BF21 TP_CPU0_RSVD_146 @BASEBOARD_FAB2_LIB.BASEBOARD_FAB2(SCH_1):TP_CPU0_RSVD_146    I15 @BASEBOARD_FAB2_LIB.BASEBOARD_FAB2(SCH_1):PAGE36
  BG18 TP_CPU0_RSVD_145 @BASEBOARD_FAB2_LIB.BASEBOARD_FAB2(SCH_1):TP_CPU0_RSVD_145    I15 @BASEBOARD_FAB2_LIB.BASEBOARD_FAB2(SCH_1):PAGE36
  BG20 TP_CPU0_RSVD_144 @BASEBOARD_FAB2_LIB.BASEBOARD_FAB2(SCH_1):TP_CPU0_RSVD_144    I15 @BASEBOARD_FAB2_LIB.BASEBOARD_FAB2(SCH_1):PAGE36
  BH19 PVCCMCP_CPU0 @BASEBOARD_FAB2_LIB.BASEBOARD_FAB2(SCH_1):PVCCMCP_CPU0    I15 @BASEBOARD_FAB2_LIB.BASEBOARD_FAB2(SCH_1):PAGE36
  BJ16 PVCCMCP_CPU0 @BASEBOARD_FAB2_LIB.BASEBOARD_FAB2(SCH_1):PVCCMCP_CPU0    I15 @BASEBOARD_FAB2_LIB.BASEBOARD_FAB2(SCH_1):PAGE36
  BJ18 PVCCMCP_CPU0 @BASEBOARD_FAB2_LIB.BASEBOARD_FAB2(SCH_1):PVCCMCP_CPU0    I15 @BASEBOARD_FAB2_LIB.BASEBOARD_FAB2(SCH_1):PAGE36
  BJ20 PVCCMCP_CPU0 @BASEBOARD_FAB2_LIB.BASEBOARD_FAB2(SCH_1):PVCCMCP_CPU0    I15 @BASEBOARD_FAB2_LIB.BASEBOARD_FAB2(SCH_1):PAGE36
  BK17 PVCCMCP_CPU0 @BASEBOARD_FAB2_LIB.BASEBOARD_FAB2(SCH_1):PVCCMCP_CPU0    I15 @BASEBOARD_FAB2_LIB.BASEBOARD_FAB2(SCH_1):PAGE36
  BL18 PVCCMCP_CPU0 @BASEBOARD_FAB2_LIB.BASEBOARD_FAB2(SCH_1):PVCCMCP_CPU0    I15 @BASEBOARD_FAB2_LIB.BASEBOARD_FAB2(SCH_1):PAGE36
  BL20 PVCCMCP_CPU0 @BASEBOARD_FAB2_LIB.BASEBOARD_FAB2(SCH_1):PVCCMCP_CPU0    I15 @BASEBOARD_FAB2_LIB.BASEBOARD_FAB2(SCH_1):PAGE36
  BM17 PVCCMCP_CPU0 @BASEBOARD_FAB2_LIB.BASEBOARD_FAB2(SCH_1):PVCCMCP_CPU0    I15 @BASEBOARD_FAB2_LIB.BASEBOARD_FAB2(SCH_1):PAGE36
  BM19 PVCCMCP_CPU0 @BASEBOARD_FAB2_LIB.BASEBOARD_FAB2(SCH_1):PVCCMCP_CPU0    I15 @BASEBOARD_FAB2_LIB.BASEBOARD_FAB2(SCH_1):PAGE36
  BN18 PVCCMCP_CPU0 @BASEBOARD_FAB2_LIB.BASEBOARD_FAB2(SCH_1):PVCCMCP_CPU0    I15 @BASEBOARD_FAB2_LIB.BASEBOARD_FAB2(SCH_1):PAGE36
  BP17 PVCCMCP_CPU0 @BASEBOARD_FAB2_LIB.BASEBOARD_FAB2(SCH_1):PVCCMCP_CPU0    I15 @BASEBOARD_FAB2_LIB.BASEBOARD_FAB2(SCH_1):PAGE36
  BP21 PVCCMCP_CPU0 @BASEBOARD_FAB2_LIB.BASEBOARD_FAB2(SCH_1):PVCCMCP_CPU0    I15 @BASEBOARD_FAB2_LIB.BASEBOARD_FAB2(SCH_1):PAGE36
  BR22 PVCCMCP_CPU0 @BASEBOARD_FAB2_LIB.BASEBOARD_FAB2(SCH_1):PVCCMCP_CPU0    I15 @BASEBOARD_FAB2_LIB.BASEBOARD_FAB2(SCH_1):PAGE36
  BR24 PVCCMCP_CPU0 @BASEBOARD_FAB2_LIB.BASEBOARD_FAB2(SCH_1):PVCCMCP_CPU0    I15 @BASEBOARD_FAB2_LIB.BASEBOARD_FAB2(SCH_1):PAGE36
  BU18 PVCCMCP_CPU0 @BASEBOARD_FAB2_LIB.BASEBOARD_FAB2(SCH_1):PVCCMCP_CPU0    I15 @BASEBOARD_FAB2_LIB.BASEBOARD_FAB2(SCH_1):PAGE36
  BU20 PVCCMCP_CPU0 @BASEBOARD_FAB2_LIB.BASEBOARD_FAB2(SCH_1):PVCCMCP_CPU0    I15 @BASEBOARD_FAB2_LIB.BASEBOARD_FAB2(SCH_1):PAGE36
  BU22 PVCCMCP_CPU0 @BASEBOARD_FAB2_LIB.BASEBOARD_FAB2(SCH_1):PVCCMCP_CPU0    I15 @BASEBOARD_FAB2_LIB.BASEBOARD_FAB2(SCH_1):PAGE36
  BV19 PVCCMCP_CPU0 @BASEBOARD_FAB2_LIB.BASEBOARD_FAB2(SCH_1):PVCCMCP_CPU0    I15 @BASEBOARD_FAB2_LIB.BASEBOARD_FAB2(SCH_1):PAGE36
  BV21 PVCCMCP_CPU0 @BASEBOARD_FAB2_LIB.BASEBOARD_FAB2(SCH_1):PVCCMCP_CPU0    I15 @BASEBOARD_FAB2_LIB.BASEBOARD_FAB2(SCH_1):PAGE36
  BV23 TP_CPU0_RSVD_124 @BASEBOARD_FAB2_LIB.BASEBOARD_FAB2(SCH_1):TP_CPU0_RSVD_124    I15 @BASEBOARD_FAB2_LIB.BASEBOARD_FAB2(SCH_1):PAGE36
  BW10 TP_CPU0_RSVD_123 @BASEBOARD_FAB2_LIB.BASEBOARD_FAB2(SCH_1):TP_CPU0_RSVD_123    I15 @BASEBOARD_FAB2_LIB.BASEBOARD_FAB2(SCH_1):PAGE36
  BW20 PVCCMCP_CPU0 @BASEBOARD_FAB2_LIB.BASEBOARD_FAB2(SCH_1):PVCCMCP_CPU0    I15 @BASEBOARD_FAB2_LIB.BASEBOARD_FAB2(SCH_1):PAGE36
  BW22 TP_CPU0_RSVD_121 @BASEBOARD_FAB2_LIB.BASEBOARD_FAB2(SCH_1):TP_CPU0_RSVD_121    I15 @BASEBOARD_FAB2_LIB.BASEBOARD_FAB2(SCH_1):PAGE36
  BY19 PVCCMCP_CPU0 @BASEBOARD_FAB2_LIB.BASEBOARD_FAB2(SCH_1):PVCCMCP_CPU0    I15 @BASEBOARD_FAB2_LIB.BASEBOARD_FAB2(SCH_1):PAGE36
  BY25 TP_CPU0_RSVD_119 @BASEBOARD_FAB2_LIB.BASEBOARD_FAB2(SCH_1):TP_CPU0_RSVD_119    I15 @BASEBOARD_FAB2_LIB.BASEBOARD_FAB2(SCH_1):PAGE36
  CA22 PVCCMCP_CPU0 @BASEBOARD_FAB2_LIB.BASEBOARD_FAB2(SCH_1):PVCCMCP_CPU0    I15 @BASEBOARD_FAB2_LIB.BASEBOARD_FAB2(SCH_1):PAGE36
  CA24 TP_CPU0_RSVD_117 @BASEBOARD_FAB2_LIB.BASEBOARD_FAB2(SCH_1):TP_CPU0_RSVD_117    I15 @BASEBOARD_FAB2_LIB.BASEBOARD_FAB2(SCH_1):PAGE36
  CB19 PVCCMCP_CPU0 @BASEBOARD_FAB2_LIB.BASEBOARD_FAB2(SCH_1):PVCCMCP_CPU0    I15 @BASEBOARD_FAB2_LIB.BASEBOARD_FAB2(SCH_1):PAGE36
  CB21 PVCCMCP_CPU0 @BASEBOARD_FAB2_LIB.BASEBOARD_FAB2(SCH_1):PVCCMCP_CPU0    I15 @BASEBOARD_FAB2_LIB.BASEBOARD_FAB2(SCH_1):PAGE36
  CB25 TP_CPU0_RSVD_114 @BASEBOARD_FAB2_LIB.BASEBOARD_FAB2(SCH_1):TP_CPU0_RSVD_114    I15 @BASEBOARD_FAB2_LIB.BASEBOARD_FAB2(SCH_1):PAGE36
   CB5 TP_CPU0_RSVD_113 @BASEBOARD_FAB2_LIB.BASEBOARD_FAB2(SCH_1):TP_CPU0_RSVD_113    I15 @BASEBOARD_FAB2_LIB.BASEBOARD_FAB2(SCH_1):PAGE36
  CC20 PVCCMCP_CPU0 @BASEBOARD_FAB2_LIB.BASEBOARD_FAB2(SCH_1):PVCCMCP_CPU0    I15 @BASEBOARD_FAB2_LIB.BASEBOARD_FAB2(SCH_1):PAGE36
   CC6 TP_CPU0_RSVD_111 @BASEBOARD_FAB2_LIB.BASEBOARD_FAB2(SCH_1):TP_CPU0_RSVD_111    I15 @BASEBOARD_FAB2_LIB.BASEBOARD_FAB2(SCH_1):PAGE36
  CD19 PVCCMCP_CPU0 @BASEBOARD_FAB2_LIB.BASEBOARD_FAB2(SCH_1):PVCCMCP_CPU0    I15 @BASEBOARD_FAB2_LIB.BASEBOARD_FAB2(SCH_1):PAGE36
  CD21 PVCCMCP_CPU0 @BASEBOARD_FAB2_LIB.BASEBOARD_FAB2(SCH_1):PVCCMCP_CPU0    I15 @BASEBOARD_FAB2_LIB.BASEBOARD_FAB2(SCH_1):PAGE36
  CD25 TP_CPU0_RSVD_108 @BASEBOARD_FAB2_LIB.BASEBOARD_FAB2(SCH_1):TP_CPU0_RSVD_108    I15 @BASEBOARD_FAB2_LIB.BASEBOARD_FAB2(SCH_1):PAGE36
  CE22 PVCCMCP_CPU0 @BASEBOARD_FAB2_LIB.BASEBOARD_FAB2(SCH_1):PVCCMCP_CPU0    I15 @BASEBOARD_FAB2_LIB.BASEBOARD_FAB2(SCH_1):PAGE36
  CE78 TP_CPU0_RSVD_106 @BASEBOARD_FAB2_LIB.BASEBOARD_FAB2(SCH_1):TP_CPU0_RSVD_106    I15 @BASEBOARD_FAB2_LIB.BASEBOARD_FAB2(SCH_1):PAGE36
  CE80 TP_CPU0_RSVD_105 @BASEBOARD_FAB2_LIB.BASEBOARD_FAB2(SCH_1):TP_CPU0_RSVD_105    I15 @BASEBOARD_FAB2_LIB.BASEBOARD_FAB2(SCH_1):PAGE36
  CF19 PVCCMCP_CPU0 @BASEBOARD_FAB2_LIB.BASEBOARD_FAB2(SCH_1):PVCCMCP_CPU0    I15 @BASEBOARD_FAB2_LIB.BASEBOARD_FAB2(SCH_1):PAGE36
  CF21 PVCCMCP_CPU0 @BASEBOARD_FAB2_LIB.BASEBOARD_FAB2(SCH_1):PVCCMCP_CPU0    I15 @BASEBOARD_FAB2_LIB.BASEBOARD_FAB2(SCH_1):PAGE36
  CF23 PVCCMCP_CPU0 @BASEBOARD_FAB2_LIB.BASEBOARD_FAB2(SCH_1):PVCCMCP_CPU0    I15 @BASEBOARD_FAB2_LIB.BASEBOARD_FAB2(SCH_1):PAGE36
  CF79 TP_CPU0_RSVD_101 @BASEBOARD_FAB2_LIB.BASEBOARD_FAB2(SCH_1):TP_CPU0_RSVD_101    I15 @BASEBOARD_FAB2_LIB.BASEBOARD_FAB2(SCH_1):PAGE36
  CF81 TP_CPU0_RSVD_100 @BASEBOARD_FAB2_LIB.BASEBOARD_FAB2(SCH_1):TP_CPU0_RSVD_100    I15 @BASEBOARD_FAB2_LIB.BASEBOARD_FAB2(SCH_1):PAGE36
  CG10 TP_CPU0_RSVD_99 @BASEBOARD_FAB2_LIB.BASEBOARD_FAB2(SCH_1):TP_CPU0_RSVD_99    I15 @BASEBOARD_FAB2_LIB.BASEBOARD_FAB2(SCH_1):PAGE36
  CG20 PVCCMCP_CPU0 @BASEBOARD_FAB2_LIB.BASEBOARD_FAB2(SCH_1):PVCCMCP_CPU0    I15 @BASEBOARD_FAB2_LIB.BASEBOARD_FAB2(SCH_1):PAGE36
  CG24 TP_CPU0_RSVD_97 @BASEBOARD_FAB2_LIB.BASEBOARD_FAB2(SCH_1):TP_CPU0_RSVD_97    I15 @BASEBOARD_FAB2_LIB.BASEBOARD_FAB2(SCH_1):PAGE36
  CG26 PVCCMCP_CPU0 @BASEBOARD_FAB2_LIB.BASEBOARD_FAB2(SCH_1):PVCCMCP_CPU0    I15 @BASEBOARD_FAB2_LIB.BASEBOARD_FAB2(SCH_1):PAGE36
  CG78 TP_CPU0_RSVD_95 @BASEBOARD_FAB2_LIB.BASEBOARD_FAB2(SCH_1):TP_CPU0_RSVD_95    I15 @BASEBOARD_FAB2_LIB.BASEBOARD_FAB2(SCH_1):PAGE36
  CG82 TP_CPU0_RSVD_94 @BASEBOARD_FAB2_LIB.BASEBOARD_FAB2(SCH_1):TP_CPU0_RSVD_94    I15 @BASEBOARD_FAB2_LIB.BASEBOARD_FAB2(SCH_1):PAGE36
  CH21 PVCCMCP_CPU0 @BASEBOARD_FAB2_LIB.BASEBOARD_FAB2(SCH_1):PVCCMCP_CPU0    I15 @BASEBOARD_FAB2_LIB.BASEBOARD_FAB2(SCH_1):PAGE36
  CH23 PVCCMCP_CPU0 @BASEBOARD_FAB2_LIB.BASEBOARD_FAB2(SCH_1):PVCCMCP_CPU0    I15 @BASEBOARD_FAB2_LIB.BASEBOARD_FAB2(SCH_1):PAGE36
  CH25 TP_CPU0_RSVD_91 @BASEBOARD_FAB2_LIB.BASEBOARD_FAB2(SCH_1):TP_CPU0_RSVD_91    I16 @BASEBOARD_FAB2_LIB.BASEBOARD_FAB2(SCH_1):PAGE36
  CH77 TP_CPU0_RSVD_90 @BASEBOARD_FAB2_LIB.BASEBOARD_FAB2(SCH_1):TP_CPU0_RSVD_90    I16 @BASEBOARD_FAB2_LIB.BASEBOARD_FAB2(SCH_1):PAGE36
  CJ20 PVCCMCP_CPU0 @BASEBOARD_FAB2_LIB.BASEBOARD_FAB2(SCH_1):PVCCMCP_CPU0    I16 @BASEBOARD_FAB2_LIB.BASEBOARD_FAB2(SCH_1):PAGE36
  CJ22 PVCCMCP_CPU0 @BASEBOARD_FAB2_LIB.BASEBOARD_FAB2(SCH_1):PVCCMCP_CPU0    I16 @BASEBOARD_FAB2_LIB.BASEBOARD_FAB2(SCH_1):PAGE36
  CJ24 PVCCMCP_CPU0 @BASEBOARD_FAB2_LIB.BASEBOARD_FAB2(SCH_1):PVCCMCP_CPU0    I16 @BASEBOARD_FAB2_LIB.BASEBOARD_FAB2(SCH_1):PAGE36
  CJ26 PVCCMCP_CPU0 @BASEBOARD_FAB2_LIB.BASEBOARD_FAB2(SCH_1):PVCCMCP_CPU0    I16 @BASEBOARD_FAB2_LIB.BASEBOARD_FAB2(SCH_1):PAGE36
  CK19 TP_CPU0_RSVD_85 @BASEBOARD_FAB2_LIB.BASEBOARD_FAB2(SCH_1):TP_CPU0_RSVD_85    I16 @BASEBOARD_FAB2_LIB.BASEBOARD_FAB2(SCH_1):PAGE36
  CK23 PVCCMCP_CPU0 @BASEBOARD_FAB2_LIB.BASEBOARD_FAB2(SCH_1):PVCCMCP_CPU0    I16 @BASEBOARD_FAB2_LIB.BASEBOARD_FAB2(SCH_1):PAGE36
  CK25 PVCCMCP_CPU0 @BASEBOARD_FAB2_LIB.BASEBOARD_FAB2(SCH_1):PVCCMCP_CPU0    I16 @BASEBOARD_FAB2_LIB.BASEBOARD_FAB2(SCH_1):PAGE36
  CK77 TP_CPU0_RSVD_82 @BASEBOARD_FAB2_LIB.BASEBOARD_FAB2(SCH_1):TP_CPU0_RSVD_82    I16 @BASEBOARD_FAB2_LIB.BASEBOARD_FAB2(SCH_1):PAGE36
  CL24 PVCCMCP_CPU0 @BASEBOARD_FAB2_LIB.BASEBOARD_FAB2(SCH_1):PVCCMCP_CPU0    I16 @BASEBOARD_FAB2_LIB.BASEBOARD_FAB2(SCH_1):PAGE36
  AW22 TP_CPU0_TEST_10 @BASEBOARD_FAB2_LIB.BASEBOARD_FAB2(SCH_1):TP_CPU0_TEST_10    I16 @BASEBOARD_FAB2_LIB.BASEBOARD_FAB2(SCH_1):PAGE36
  AR16 TP_CPU0_TEST_6 @BASEBOARD_FAB2_LIB.BASEBOARD_FAB2(SCH_1):TP_CPU0_TEST_6    I16 @BASEBOARD_FAB2_LIB.BASEBOARD_FAB2(SCH_1):PAGE36
  AU18 TP_CPU0_TEST_7 @BASEBOARD_FAB2_LIB.BASEBOARD_FAB2(SCH_1):TP_CPU0_TEST_7    I16 @BASEBOARD_FAB2_LIB.BASEBOARD_FAB2(SCH_1):PAGE36
  AW16 TP_CPU0_TEST_8 @BASEBOARD_FAB2_LIB.BASEBOARD_FAB2(SCH_1):TP_CPU0_TEST_8    I16 @BASEBOARD_FAB2_LIB.BASEBOARD_FAB2(SCH_1):PAGE36
  AW20 TP_CPU0_TEST_9 @BASEBOARD_FAB2_LIB.BASEBOARD_FAB2(SCH_1):TP_CPU0_TEST_9    I16 @BASEBOARD_FAB2_LIB.BASEBOARD_FAB2(SCH_1):PAGE36
  AF43 PVCCIN_CPU0 @BASEBOARD_FAB2_LIB.BASEBOARD_FAB2(SCH_1):PVCCIN_CPU0   I310 @BASEBOARD_FAB2_LIB.BASEBOARD_FAB2(SCH_1):PAGE37
  AG38 PVCCIN_CPU0 @BASEBOARD_FAB2_LIB.BASEBOARD_FAB2(SCH_1):PVCCIN_CPU0   I310 @BASEBOARD_FAB2_LIB.BASEBOARD_FAB2(SCH_1):PAGE37
  AG40 PVCCIN_CPU0 @BASEBOARD_FAB2_LIB.BASEBOARD_FAB2(SCH_1):PVCCIN_CPU0   I310 @BASEBOARD_FAB2_LIB.BASEBOARD_FAB2(SCH_1):PAGE37
  AG42 PVCCIN_CPU0 @BASEBOARD_FAB2_LIB.BASEBOARD_FAB2(SCH_1):PVCCIN_CPU0   I310 @BASEBOARD_FAB2_LIB.BASEBOARD_FAB2(SCH_1):PAGE37
  AH37 PVCCIN_CPU0 @BASEBOARD_FAB2_LIB.BASEBOARD_FAB2(SCH_1):PVCCIN_CPU0   I310 @BASEBOARD_FAB2_LIB.BASEBOARD_FAB2(SCH_1):PAGE37
  AH39 PVCCIN_CPU0 @BASEBOARD_FAB2_LIB.BASEBOARD_FAB2(SCH_1):PVCCIN_CPU0   I310 @BASEBOARD_FAB2_LIB.BASEBOARD_FAB2(SCH_1):PAGE37
  AH41 PVCCIN_CPU0 @BASEBOARD_FAB2_LIB.BASEBOARD_FAB2(SCH_1):PVCCIN_CPU0   I310 @BASEBOARD_FAB2_LIB.BASEBOARD_FAB2(SCH_1):PAGE37
  AJ36 PVCCIN_CPU0 @BASEBOARD_FAB2_LIB.BASEBOARD_FAB2(SCH_1):PVCCIN_CPU0   I310 @BASEBOARD_FAB2_LIB.BASEBOARD_FAB2(SCH_1):PAGE37
  AK35 PVCCIN_CPU0 @BASEBOARD_FAB2_LIB.BASEBOARD_FAB2(SCH_1):PVCCIN_CPU0   I310 @BASEBOARD_FAB2_LIB.BASEBOARD_FAB2(SCH_1):PAGE37
  AK45 PVCCIN_CPU0 @BASEBOARD_FAB2_LIB.BASEBOARD_FAB2(SCH_1):PVCCIN_CPU0   I310 @BASEBOARD_FAB2_LIB.BASEBOARD_FAB2(SCH_1):PAGE37
  AK47 PVCCIN_CPU0 @BASEBOARD_FAB2_LIB.BASEBOARD_FAB2(SCH_1):PVCCIN_CPU0   I310 @BASEBOARD_FAB2_LIB.BASEBOARD_FAB2(SCH_1):PAGE37
  AK49 PVCCIN_CPU0 @BASEBOARD_FAB2_LIB.BASEBOARD_FAB2(SCH_1):PVCCIN_CPU0   I310 @BASEBOARD_FAB2_LIB.BASEBOARD_FAB2(SCH_1):PAGE37
  AK51 PVCCIN_CPU0 @BASEBOARD_FAB2_LIB.BASEBOARD_FAB2(SCH_1):PVCCIN_CPU0   I310 @BASEBOARD_FAB2_LIB.BASEBOARD_FAB2(SCH_1):PAGE37
  AK53 PVCCIN_CPU0 @BASEBOARD_FAB2_LIB.BASEBOARD_FAB2(SCH_1):PVCCIN_CPU0   I310 @BASEBOARD_FAB2_LIB.BASEBOARD_FAB2(SCH_1):PAGE37
  AL34 PVCCIN_CPU0 @BASEBOARD_FAB2_LIB.BASEBOARD_FAB2(SCH_1):PVCCIN_CPU0   I310 @BASEBOARD_FAB2_LIB.BASEBOARD_FAB2(SCH_1):PAGE37
  AL46 PVCCIN_CPU0 @BASEBOARD_FAB2_LIB.BASEBOARD_FAB2(SCH_1):PVCCIN_CPU0   I310 @BASEBOARD_FAB2_LIB.BASEBOARD_FAB2(SCH_1):PAGE37
  AL48 PVCCIN_CPU0 @BASEBOARD_FAB2_LIB.BASEBOARD_FAB2(SCH_1):PVCCIN_CPU0   I310 @BASEBOARD_FAB2_LIB.BASEBOARD_FAB2(SCH_1):PAGE37
  AL50 PVCCIN_CPU0 @BASEBOARD_FAB2_LIB.BASEBOARD_FAB2(SCH_1):PVCCIN_CPU0   I310 @BASEBOARD_FAB2_LIB.BASEBOARD_FAB2(SCH_1):PAGE37
  AL52 PVCCIN_CPU0 @BASEBOARD_FAB2_LIB.BASEBOARD_FAB2(SCH_1):PVCCIN_CPU0   I310 @BASEBOARD_FAB2_LIB.BASEBOARD_FAB2(SCH_1):PAGE37
  AL54 PVCCIN_CPU0 @BASEBOARD_FAB2_LIB.BASEBOARD_FAB2(SCH_1):PVCCIN_CPU0   I310 @BASEBOARD_FAB2_LIB.BASEBOARD_FAB2(SCH_1):PAGE37
  AM33 PVCCIN_CPU0 @BASEBOARD_FAB2_LIB.BASEBOARD_FAB2(SCH_1):PVCCIN_CPU0   I310 @BASEBOARD_FAB2_LIB.BASEBOARD_FAB2(SCH_1):PAGE37
  AM53 PVCCIN_CPU0 @BASEBOARD_FAB2_LIB.BASEBOARD_FAB2(SCH_1):PVCCIN_CPU0   I310 @BASEBOARD_FAB2_LIB.BASEBOARD_FAB2(SCH_1):PAGE37
  AM55 PVCCIN_CPU0 @BASEBOARD_FAB2_LIB.BASEBOARD_FAB2(SCH_1):PVCCIN_CPU0   I310 @BASEBOARD_FAB2_LIB.BASEBOARD_FAB2(SCH_1):PAGE37
  AN32 PVCCIN_CPU0 @BASEBOARD_FAB2_LIB.BASEBOARD_FAB2(SCH_1):PVCCIN_CPU0   I310 @BASEBOARD_FAB2_LIB.BASEBOARD_FAB2(SCH_1):PAGE37
  AN54 PVCCIN_CPU0 @BASEBOARD_FAB2_LIB.BASEBOARD_FAB2(SCH_1):PVCCIN_CPU0   I310 @BASEBOARD_FAB2_LIB.BASEBOARD_FAB2(SCH_1):PAGE37
  AN56 PVCCIN_CPU0 @BASEBOARD_FAB2_LIB.BASEBOARD_FAB2(SCH_1):PVCCIN_CPU0   I310 @BASEBOARD_FAB2_LIB.BASEBOARD_FAB2(SCH_1):PAGE37
  AP55 PVCCIN_CPU0 @BASEBOARD_FAB2_LIB.BASEBOARD_FAB2(SCH_1):PVCCIN_CPU0   I310 @BASEBOARD_FAB2_LIB.BASEBOARD_FAB2(SCH_1):PAGE37
  AP57 PVCCIN_CPU0 @BASEBOARD_FAB2_LIB.BASEBOARD_FAB2(SCH_1):PVCCIN_CPU0   I310 @BASEBOARD_FAB2_LIB.BASEBOARD_FAB2(SCH_1):PAGE37
  AR56 PVCCIN_CPU0 @BASEBOARD_FAB2_LIB.BASEBOARD_FAB2(SCH_1):PVCCIN_CPU0   I310 @BASEBOARD_FAB2_LIB.BASEBOARD_FAB2(SCH_1):PAGE37
  AR58 PVCCIN_CPU0 @BASEBOARD_FAB2_LIB.BASEBOARD_FAB2(SCH_1):PVCCIN_CPU0   I310 @BASEBOARD_FAB2_LIB.BASEBOARD_FAB2(SCH_1):PAGE37
  AT57 PVCCIN_CPU0 @BASEBOARD_FAB2_LIB.BASEBOARD_FAB2(SCH_1):PVCCIN_CPU0   I310 @BASEBOARD_FAB2_LIB.BASEBOARD_FAB2(SCH_1):PAGE37
  AT59 PVCCIN_CPU0 @BASEBOARD_FAB2_LIB.BASEBOARD_FAB2(SCH_1):PVCCIN_CPU0   I310 @BASEBOARD_FAB2_LIB.BASEBOARD_FAB2(SCH_1):PAGE37
  AU58 PVCCIN_CPU0 @BASEBOARD_FAB2_LIB.BASEBOARD_FAB2(SCH_1):PVCCIN_CPU0   I310 @BASEBOARD_FAB2_LIB.BASEBOARD_FAB2(SCH_1):PAGE37
  AU60 PVCCIN_CPU0 @BASEBOARD_FAB2_LIB.BASEBOARD_FAB2(SCH_1):PVCCIN_CPU0   I310 @BASEBOARD_FAB2_LIB.BASEBOARD_FAB2(SCH_1):PAGE37
  AV59 PVCCIN_CPU0 @BASEBOARD_FAB2_LIB.BASEBOARD_FAB2(SCH_1):PVCCIN_CPU0   I310 @BASEBOARD_FAB2_LIB.BASEBOARD_FAB2(SCH_1):PAGE37
  AV61 PVCCIN_CPU0 @BASEBOARD_FAB2_LIB.BASEBOARD_FAB2(SCH_1):PVCCIN_CPU0   I310 @BASEBOARD_FAB2_LIB.BASEBOARD_FAB2(SCH_1):PAGE37
  AW60 PVCCIN_CPU0 @BASEBOARD_FAB2_LIB.BASEBOARD_FAB2(SCH_1):PVCCIN_CPU0   I310 @BASEBOARD_FAB2_LIB.BASEBOARD_FAB2(SCH_1):PAGE37
  AY61 PVCCIN_CPU0 @BASEBOARD_FAB2_LIB.BASEBOARD_FAB2(SCH_1):PVCCIN_CPU0   I310 @BASEBOARD_FAB2_LIB.BASEBOARD_FAB2(SCH_1):PAGE37
  BA60 PVCCIN_CPU0 @BASEBOARD_FAB2_LIB.BASEBOARD_FAB2(SCH_1):PVCCIN_CPU0   I310 @BASEBOARD_FAB2_LIB.BASEBOARD_FAB2(SCH_1):PAGE37
  BB61 PVCCIN_CPU0 @BASEBOARD_FAB2_LIB.BASEBOARD_FAB2(SCH_1):PVCCIN_CPU0   I310 @BASEBOARD_FAB2_LIB.BASEBOARD_FAB2(SCH_1):PAGE37
  BB85 PVCCIN_CPU0 @BASEBOARD_FAB2_LIB.BASEBOARD_FAB2(SCH_1):PVCCIN_CPU0   I310 @BASEBOARD_FAB2_LIB.BASEBOARD_FAB2(SCH_1):PAGE37
  BC60 PVCCIN_CPU0 @BASEBOARD_FAB2_LIB.BASEBOARD_FAB2(SCH_1):PVCCIN_CPU0   I310 @BASEBOARD_FAB2_LIB.BASEBOARD_FAB2(SCH_1):PAGE37
  BC62 PVCCIN_CPU0 @BASEBOARD_FAB2_LIB.BASEBOARD_FAB2(SCH_1):PVCCIN_CPU0   I310 @BASEBOARD_FAB2_LIB.BASEBOARD_FAB2(SCH_1):PAGE37
  BC84 PVCCIN_CPU0 @BASEBOARD_FAB2_LIB.BASEBOARD_FAB2(SCH_1):PVCCIN_CPU0   I310 @BASEBOARD_FAB2_LIB.BASEBOARD_FAB2(SCH_1):PAGE37
  BD61 PVCCIN_CPU0 @BASEBOARD_FAB2_LIB.BASEBOARD_FAB2(SCH_1):PVCCIN_CPU0   I310 @BASEBOARD_FAB2_LIB.BASEBOARD_FAB2(SCH_1):PAGE37
  BD73 PVCCIN_CPU0 @BASEBOARD_FAB2_LIB.BASEBOARD_FAB2(SCH_1):PVCCIN_CPU0   I310 @BASEBOARD_FAB2_LIB.BASEBOARD_FAB2(SCH_1):PAGE37
  BD75 PVCCIN_CPU0 @BASEBOARD_FAB2_LIB.BASEBOARD_FAB2(SCH_1):PVCCIN_CPU0   I310 @BASEBOARD_FAB2_LIB.BASEBOARD_FAB2(SCH_1):PAGE37
  BD77 PVCCIN_CPU0 @BASEBOARD_FAB2_LIB.BASEBOARD_FAB2(SCH_1):PVCCIN_CPU0   I310 @BASEBOARD_FAB2_LIB.BASEBOARD_FAB2(SCH_1):PAGE37
  BD79 PVCCIN_CPU0 @BASEBOARD_FAB2_LIB.BASEBOARD_FAB2(SCH_1):PVCCIN_CPU0   I310 @BASEBOARD_FAB2_LIB.BASEBOARD_FAB2(SCH_1):PAGE37
  BD81 PVCCIN_CPU0 @BASEBOARD_FAB2_LIB.BASEBOARD_FAB2(SCH_1):PVCCIN_CPU0   I310 @BASEBOARD_FAB2_LIB.BASEBOARD_FAB2(SCH_1):PAGE37
  BD83 PVCCIN_CPU0 @BASEBOARD_FAB2_LIB.BASEBOARD_FAB2(SCH_1):PVCCIN_CPU0   I310 @BASEBOARD_FAB2_LIB.BASEBOARD_FAB2(SCH_1):PAGE37
  BD85 PVCCIN_CPU0 @BASEBOARD_FAB2_LIB.BASEBOARD_FAB2(SCH_1):PVCCIN_CPU0   I310 @BASEBOARD_FAB2_LIB.BASEBOARD_FAB2(SCH_1):PAGE37
  BE60 PVCCIN_CPU0 @BASEBOARD_FAB2_LIB.BASEBOARD_FAB2(SCH_1):PVCCIN_CPU0   I310 @BASEBOARD_FAB2_LIB.BASEBOARD_FAB2(SCH_1):PAGE37
  BE62 PVCCIN_CPU0 @BASEBOARD_FAB2_LIB.BASEBOARD_FAB2(SCH_1):PVCCIN_CPU0   I310 @BASEBOARD_FAB2_LIB.BASEBOARD_FAB2(SCH_1):PAGE37
  BE72 PVCCIN_CPU0 @BASEBOARD_FAB2_LIB.BASEBOARD_FAB2(SCH_1):PVCCIN_CPU0   I310 @BASEBOARD_FAB2_LIB.BASEBOARD_FAB2(SCH_1):PAGE37
  BE74 PVCCIN_CPU0 @BASEBOARD_FAB2_LIB.BASEBOARD_FAB2(SCH_1):PVCCIN_CPU0   I310 @BASEBOARD_FAB2_LIB.BASEBOARD_FAB2(SCH_1):PAGE37
  BE76 PVCCIN_CPU0 @BASEBOARD_FAB2_LIB.BASEBOARD_FAB2(SCH_1):PVCCIN_CPU0   I310 @BASEBOARD_FAB2_LIB.BASEBOARD_FAB2(SCH_1):PAGE37
  BE78 PVCCIN_CPU0 @BASEBOARD_FAB2_LIB.BASEBOARD_FAB2(SCH_1):PVCCIN_CPU0   I310 @BASEBOARD_FAB2_LIB.BASEBOARD_FAB2(SCH_1):PAGE37
  BE80 PVCCIN_CPU0 @BASEBOARD_FAB2_LIB.BASEBOARD_FAB2(SCH_1):PVCCIN_CPU0   I310 @BASEBOARD_FAB2_LIB.BASEBOARD_FAB2(SCH_1):PAGE37
  BE82 PVCCIN_CPU0 @BASEBOARD_FAB2_LIB.BASEBOARD_FAB2(SCH_1):PVCCIN_CPU0   I310 @BASEBOARD_FAB2_LIB.BASEBOARD_FAB2(SCH_1):PAGE37
  BE84 PVCCIN_CPU0 @BASEBOARD_FAB2_LIB.BASEBOARD_FAB2(SCH_1):PVCCIN_CPU0   I310 @BASEBOARD_FAB2_LIB.BASEBOARD_FAB2(SCH_1):PAGE37
  BF61 PVCCIN_CPU0 @BASEBOARD_FAB2_LIB.BASEBOARD_FAB2(SCH_1):PVCCIN_CPU0   I310 @BASEBOARD_FAB2_LIB.BASEBOARD_FAB2(SCH_1):PAGE37
  BF73 PVCCIN_CPU0 @BASEBOARD_FAB2_LIB.BASEBOARD_FAB2(SCH_1):PVCCIN_CPU0   I310 @BASEBOARD_FAB2_LIB.BASEBOARD_FAB2(SCH_1):PAGE37
  BF75 PVCCIN_CPU0 @BASEBOARD_FAB2_LIB.BASEBOARD_FAB2(SCH_1):PVCCIN_CPU0   I310 @BASEBOARD_FAB2_LIB.BASEBOARD_FAB2(SCH_1):PAGE37
  BF77 PVCCIN_CPU0 @BASEBOARD_FAB2_LIB.BASEBOARD_FAB2(SCH_1):PVCCIN_CPU0   I310 @BASEBOARD_FAB2_LIB.BASEBOARD_FAB2(SCH_1):PAGE37
  BF79 PVCCIN_CPU0 @BASEBOARD_FAB2_LIB.BASEBOARD_FAB2(SCH_1):PVCCIN_CPU0   I310 @BASEBOARD_FAB2_LIB.BASEBOARD_FAB2(SCH_1):PAGE37
  BF81 PVCCIN_CPU0 @BASEBOARD_FAB2_LIB.BASEBOARD_FAB2(SCH_1):PVCCIN_CPU0   I310 @BASEBOARD_FAB2_LIB.BASEBOARD_FAB2(SCH_1):PAGE37
  BF83 PVCCIN_CPU0 @BASEBOARD_FAB2_LIB.BASEBOARD_FAB2(SCH_1):PVCCIN_CPU0   I310 @BASEBOARD_FAB2_LIB.BASEBOARD_FAB2(SCH_1):PAGE37
  BF85 PVCCIN_CPU0 @BASEBOARD_FAB2_LIB.BASEBOARD_FAB2(SCH_1):PVCCIN_CPU0   I310 @BASEBOARD_FAB2_LIB.BASEBOARD_FAB2(SCH_1):PAGE37
  BG60 PVCCIN_CPU0 @BASEBOARD_FAB2_LIB.BASEBOARD_FAB2(SCH_1):PVCCIN_CPU0   I310 @BASEBOARD_FAB2_LIB.BASEBOARD_FAB2(SCH_1):PAGE37
  BG62 PVCCIN_CPU0 @BASEBOARD_FAB2_LIB.BASEBOARD_FAB2(SCH_1):PVCCIN_CPU0   I310 @BASEBOARD_FAB2_LIB.BASEBOARD_FAB2(SCH_1):PAGE37
  BG64 PVCCIN_CPU0 @BASEBOARD_FAB2_LIB.BASEBOARD_FAB2(SCH_1):PVCCIN_CPU0   I310 @BASEBOARD_FAB2_LIB.BASEBOARD_FAB2(SCH_1):PAGE37
  BG66 PVCCIN_CPU0 @BASEBOARD_FAB2_LIB.BASEBOARD_FAB2(SCH_1):PVCCIN_CPU0   I310 @BASEBOARD_FAB2_LIB.BASEBOARD_FAB2(SCH_1):PAGE37
  BG68 PVCCIN_CPU0 @BASEBOARD_FAB2_LIB.BASEBOARD_FAB2(SCH_1):PVCCIN_CPU0   I310 @BASEBOARD_FAB2_LIB.BASEBOARD_FAB2(SCH_1):PAGE37
  BG70 PVCCIN_CPU0 @BASEBOARD_FAB2_LIB.BASEBOARD_FAB2(SCH_1):PVCCIN_CPU0   I310 @BASEBOARD_FAB2_LIB.BASEBOARD_FAB2(SCH_1):PAGE37
  BG84 PVCCIN_CPU0 @BASEBOARD_FAB2_LIB.BASEBOARD_FAB2(SCH_1):PVCCIN_CPU0   I310 @BASEBOARD_FAB2_LIB.BASEBOARD_FAB2(SCH_1):PAGE37
  BH61 PVCCIN_CPU0 @BASEBOARD_FAB2_LIB.BASEBOARD_FAB2(SCH_1):PVCCIN_CPU0   I310 @BASEBOARD_FAB2_LIB.BASEBOARD_FAB2(SCH_1):PAGE37
  BH63 PVCCIN_CPU0 @BASEBOARD_FAB2_LIB.BASEBOARD_FAB2(SCH_1):PVCCIN_CPU0   I310 @BASEBOARD_FAB2_LIB.BASEBOARD_FAB2(SCH_1):PAGE37
  BH65 PVCCIN_CPU0 @BASEBOARD_FAB2_LIB.BASEBOARD_FAB2(SCH_1):PVCCIN_CPU0   I310 @BASEBOARD_FAB2_LIB.BASEBOARD_FAB2(SCH_1):PAGE37
  BH67 PVCCIN_CPU0 @BASEBOARD_FAB2_LIB.BASEBOARD_FAB2(SCH_1):PVCCIN_CPU0   I310 @BASEBOARD_FAB2_LIB.BASEBOARD_FAB2(SCH_1):PAGE37
  BH69 PVCCIN_CPU0 @BASEBOARD_FAB2_LIB.BASEBOARD_FAB2(SCH_1):PVCCIN_CPU0   I310 @BASEBOARD_FAB2_LIB.BASEBOARD_FAB2(SCH_1):PAGE37
  BH71 PVCCIN_CPU0 @BASEBOARD_FAB2_LIB.BASEBOARD_FAB2(SCH_1):PVCCIN_CPU0   I310 @BASEBOARD_FAB2_LIB.BASEBOARD_FAB2(SCH_1):PAGE37
  BH73 PVCCIN_CPU0 @BASEBOARD_FAB2_LIB.BASEBOARD_FAB2(SCH_1):PVCCIN_CPU0   I310 @BASEBOARD_FAB2_LIB.BASEBOARD_FAB2(SCH_1):PAGE37
  BH75 PVCCIN_CPU0 @BASEBOARD_FAB2_LIB.BASEBOARD_FAB2(SCH_1):PVCCIN_CPU0   I310 @BASEBOARD_FAB2_LIB.BASEBOARD_FAB2(SCH_1):PAGE37
  BH77 PVCCIN_CPU0 @BASEBOARD_FAB2_LIB.BASEBOARD_FAB2(SCH_1):PVCCIN_CPU0   I310 @BASEBOARD_FAB2_LIB.BASEBOARD_FAB2(SCH_1):PAGE37
  BH79 PVCCIN_CPU0 @BASEBOARD_FAB2_LIB.BASEBOARD_FAB2(SCH_1):PVCCIN_CPU0   I310 @BASEBOARD_FAB2_LIB.BASEBOARD_FAB2(SCH_1):PAGE37
  BH81 PVCCIN_CPU0 @BASEBOARD_FAB2_LIB.BASEBOARD_FAB2(SCH_1):PVCCIN_CPU0   I310 @BASEBOARD_FAB2_LIB.BASEBOARD_FAB2(SCH_1):PAGE37
  BH83 PVCCIN_CPU0 @BASEBOARD_FAB2_LIB.BASEBOARD_FAB2(SCH_1):PVCCIN_CPU0   I310 @BASEBOARD_FAB2_LIB.BASEBOARD_FAB2(SCH_1):PAGE37
  BJ60 PVCCIN_CPU0 @BASEBOARD_FAB2_LIB.BASEBOARD_FAB2(SCH_1):PVCCIN_CPU0   I310 @BASEBOARD_FAB2_LIB.BASEBOARD_FAB2(SCH_1):PAGE37
  BJ62 PVCCIN_CPU0 @BASEBOARD_FAB2_LIB.BASEBOARD_FAB2(SCH_1):PVCCIN_CPU0   I310 @BASEBOARD_FAB2_LIB.BASEBOARD_FAB2(SCH_1):PAGE37
  BJ64 PVCCIN_CPU0 @BASEBOARD_FAB2_LIB.BASEBOARD_FAB2(SCH_1):PVCCIN_CPU0   I310 @BASEBOARD_FAB2_LIB.BASEBOARD_FAB2(SCH_1):PAGE37
  BJ66 PVCCIN_CPU0 @BASEBOARD_FAB2_LIB.BASEBOARD_FAB2(SCH_1):PVCCIN_CPU0   I310 @BASEBOARD_FAB2_LIB.BASEBOARD_FAB2(SCH_1):PAGE37
  BJ68 PVCCIN_CPU0 @BASEBOARD_FAB2_LIB.BASEBOARD_FAB2(SCH_1):PVCCIN_CPU0   I310 @BASEBOARD_FAB2_LIB.BASEBOARD_FAB2(SCH_1):PAGE37
  BJ70 PVCCIN_CPU0 @BASEBOARD_FAB2_LIB.BASEBOARD_FAB2(SCH_1):PVCCIN_CPU0   I310 @BASEBOARD_FAB2_LIB.BASEBOARD_FAB2(SCH_1):PAGE37
  BJ72 PVCCIN_CPU0 @BASEBOARD_FAB2_LIB.BASEBOARD_FAB2(SCH_1):PVCCIN_CPU0   I310 @BASEBOARD_FAB2_LIB.BASEBOARD_FAB2(SCH_1):PAGE37
  BJ74 PVCCIN_CPU0 @BASEBOARD_FAB2_LIB.BASEBOARD_FAB2(SCH_1):PVCCIN_CPU0   I310 @BASEBOARD_FAB2_LIB.BASEBOARD_FAB2(SCH_1):PAGE37
  BJ76 PVCCIN_CPU0 @BASEBOARD_FAB2_LIB.BASEBOARD_FAB2(SCH_1):PVCCIN_CPU0   I310 @BASEBOARD_FAB2_LIB.BASEBOARD_FAB2(SCH_1):PAGE37
  BJ78 PVCCIN_CPU0 @BASEBOARD_FAB2_LIB.BASEBOARD_FAB2(SCH_1):PVCCIN_CPU0   I310 @BASEBOARD_FAB2_LIB.BASEBOARD_FAB2(SCH_1):PAGE37
  BJ80 PVCCIN_CPU0 @BASEBOARD_FAB2_LIB.BASEBOARD_FAB2(SCH_1):PVCCIN_CPU0   I310 @BASEBOARD_FAB2_LIB.BASEBOARD_FAB2(SCH_1):PAGE37
  BJ82 PVCCIN_CPU0 @BASEBOARD_FAB2_LIB.BASEBOARD_FAB2(SCH_1):PVCCIN_CPU0   I310 @BASEBOARD_FAB2_LIB.BASEBOARD_FAB2(SCH_1):PAGE37
  BJ84 PVCCIN_CPU0 @BASEBOARD_FAB2_LIB.BASEBOARD_FAB2(SCH_1):PVCCIN_CPU0   I310 @BASEBOARD_FAB2_LIB.BASEBOARD_FAB2(SCH_1):PAGE37
  BK61 PVCCIN_CPU0 @BASEBOARD_FAB2_LIB.BASEBOARD_FAB2(SCH_1):PVCCIN_CPU0   I310 @BASEBOARD_FAB2_LIB.BASEBOARD_FAB2(SCH_1):PAGE37
  BK63 PVCCIN_CPU0 @BASEBOARD_FAB2_LIB.BASEBOARD_FAB2(SCH_1):PVCCIN_CPU0   I310 @BASEBOARD_FAB2_LIB.BASEBOARD_FAB2(SCH_1):PAGE37
  BK65 PVCCIN_CPU0 @BASEBOARD_FAB2_LIB.BASEBOARD_FAB2(SCH_1):PVCCIN_CPU0   I310 @BASEBOARD_FAB2_LIB.BASEBOARD_FAB2(SCH_1):PAGE37
  BK67 PVCCIN_CPU0 @BASEBOARD_FAB2_LIB.BASEBOARD_FAB2(SCH_1):PVCCIN_CPU0   I310 @BASEBOARD_FAB2_LIB.BASEBOARD_FAB2(SCH_1):PAGE37
  BK69 PVCCIN_CPU0 @BASEBOARD_FAB2_LIB.BASEBOARD_FAB2(SCH_1):PVCCIN_CPU0   I310 @BASEBOARD_FAB2_LIB.BASEBOARD_FAB2(SCH_1):PAGE37
  BK71 PVCCIN_CPU0 @BASEBOARD_FAB2_LIB.BASEBOARD_FAB2(SCH_1):PVCCIN_CPU0   I310 @BASEBOARD_FAB2_LIB.BASEBOARD_FAB2(SCH_1):PAGE37
  BK73 PVCCIN_CPU0 @BASEBOARD_FAB2_LIB.BASEBOARD_FAB2(SCH_1):PVCCIN_CPU0   I310 @BASEBOARD_FAB2_LIB.BASEBOARD_FAB2(SCH_1):PAGE37
  BK75 PVCCIN_CPU0 @BASEBOARD_FAB2_LIB.BASEBOARD_FAB2(SCH_1):PVCCIN_CPU0   I310 @BASEBOARD_FAB2_LIB.BASEBOARD_FAB2(SCH_1):PAGE37
  BK77 PVCCIN_CPU0 @BASEBOARD_FAB2_LIB.BASEBOARD_FAB2(SCH_1):PVCCIN_CPU0   I310 @BASEBOARD_FAB2_LIB.BASEBOARD_FAB2(SCH_1):PAGE37
  BK79 PVCCIN_CPU0 @BASEBOARD_FAB2_LIB.BASEBOARD_FAB2(SCH_1):PVCCIN_CPU0   I310 @BASEBOARD_FAB2_LIB.BASEBOARD_FAB2(SCH_1):PAGE37
  BK81 PVCCIN_CPU0 @BASEBOARD_FAB2_LIB.BASEBOARD_FAB2(SCH_1):PVCCIN_CPU0   I310 @BASEBOARD_FAB2_LIB.BASEBOARD_FAB2(SCH_1):PAGE37
  BK83 PVCCIN_CPU0 @BASEBOARD_FAB2_LIB.BASEBOARD_FAB2(SCH_1):PVCCIN_CPU0   I310 @BASEBOARD_FAB2_LIB.BASEBOARD_FAB2(SCH_1):PAGE37
  BL60 PVCCIN_CPU0 @BASEBOARD_FAB2_LIB.BASEBOARD_FAB2(SCH_1):PVCCIN_CPU0   I310 @BASEBOARD_FAB2_LIB.BASEBOARD_FAB2(SCH_1):PAGE37
  BL62 PVCCIN_CPU0 @BASEBOARD_FAB2_LIB.BASEBOARD_FAB2(SCH_1):PVCCIN_CPU0   I310 @BASEBOARD_FAB2_LIB.BASEBOARD_FAB2(SCH_1):PAGE37
  BL84 PVCCIN_CPU0 @BASEBOARD_FAB2_LIB.BASEBOARD_FAB2(SCH_1):PVCCIN_CPU0   I310 @BASEBOARD_FAB2_LIB.BASEBOARD_FAB2(SCH_1):PAGE37
  BM61 PVCCIN_CPU0 @BASEBOARD_FAB2_LIB.BASEBOARD_FAB2(SCH_1):PVCCIN_CPU0   I310 @BASEBOARD_FAB2_LIB.BASEBOARD_FAB2(SCH_1):PAGE37
  BM63 PVCCIN_CPU0 @BASEBOARD_FAB2_LIB.BASEBOARD_FAB2(SCH_1):PVCCIN_CPU0   I310 @BASEBOARD_FAB2_LIB.BASEBOARD_FAB2(SCH_1):PAGE37
  BM65 PVCCIN_CPU0 @BASEBOARD_FAB2_LIB.BASEBOARD_FAB2(SCH_1):PVCCIN_CPU0   I310 @BASEBOARD_FAB2_LIB.BASEBOARD_FAB2(SCH_1):PAGE37
  BM67 PVCCIN_CPU0 @BASEBOARD_FAB2_LIB.BASEBOARD_FAB2(SCH_1):PVCCIN_CPU0   I310 @BASEBOARD_FAB2_LIB.BASEBOARD_FAB2(SCH_1):PAGE37
  BM69 PVCCIN_CPU0 @BASEBOARD_FAB2_LIB.BASEBOARD_FAB2(SCH_1):PVCCIN_CPU0   I310 @BASEBOARD_FAB2_LIB.BASEBOARD_FAB2(SCH_1):PAGE37
  BM71 PVCCIN_CPU0 @BASEBOARD_FAB2_LIB.BASEBOARD_FAB2(SCH_1):PVCCIN_CPU0   I310 @BASEBOARD_FAB2_LIB.BASEBOARD_FAB2(SCH_1):PAGE37
  BM73 PVCCIN_CPU0 @BASEBOARD_FAB2_LIB.BASEBOARD_FAB2(SCH_1):PVCCIN_CPU0   I310 @BASEBOARD_FAB2_LIB.BASEBOARD_FAB2(SCH_1):PAGE37
  BM75 PVCCIN_CPU0 @BASEBOARD_FAB2_LIB.BASEBOARD_FAB2(SCH_1):PVCCIN_CPU0   I310 @BASEBOARD_FAB2_LIB.BASEBOARD_FAB2(SCH_1):PAGE37
  BM77 PVCCIN_CPU0 @BASEBOARD_FAB2_LIB.BASEBOARD_FAB2(SCH_1):PVCCIN_CPU0   I310 @BASEBOARD_FAB2_LIB.BASEBOARD_FAB2(SCH_1):PAGE37
  BM79 PVCCIN_CPU0 @BASEBOARD_FAB2_LIB.BASEBOARD_FAB2(SCH_1):PVCCIN_CPU0   I310 @BASEBOARD_FAB2_LIB.BASEBOARD_FAB2(SCH_1):PAGE37
  BM81 PVCCIN_CPU0 @BASEBOARD_FAB2_LIB.BASEBOARD_FAB2(SCH_1):PVCCIN_CPU0   I310 @BASEBOARD_FAB2_LIB.BASEBOARD_FAB2(SCH_1):PAGE37
  BM83 PVCCIN_CPU0 @BASEBOARD_FAB2_LIB.BASEBOARD_FAB2(SCH_1):PVCCIN_CPU0   I310 @BASEBOARD_FAB2_LIB.BASEBOARD_FAB2(SCH_1):PAGE37
  BN60 PVCCIN_CPU0 @BASEBOARD_FAB2_LIB.BASEBOARD_FAB2(SCH_1):PVCCIN_CPU0   I310 @BASEBOARD_FAB2_LIB.BASEBOARD_FAB2(SCH_1):PAGE37
  BN62 PVCCIN_CPU0 @BASEBOARD_FAB2_LIB.BASEBOARD_FAB2(SCH_1):PVCCIN_CPU0   I310 @BASEBOARD_FAB2_LIB.BASEBOARD_FAB2(SCH_1):PAGE37
  BN64 PVCCIN_CPU0 @BASEBOARD_FAB2_LIB.BASEBOARD_FAB2(SCH_1):PVCCIN_CPU0   I310 @BASEBOARD_FAB2_LIB.BASEBOARD_FAB2(SCH_1):PAGE37
  BN66 PVCCIN_CPU0 @BASEBOARD_FAB2_LIB.BASEBOARD_FAB2(SCH_1):PVCCIN_CPU0   I310 @BASEBOARD_FAB2_LIB.BASEBOARD_FAB2(SCH_1):PAGE37
  BN68 PVCCIN_CPU0 @BASEBOARD_FAB2_LIB.BASEBOARD_FAB2(SCH_1):PVCCIN_CPU0   I310 @BASEBOARD_FAB2_LIB.BASEBOARD_FAB2(SCH_1):PAGE37
  BN70 PVCCIN_CPU0 @BASEBOARD_FAB2_LIB.BASEBOARD_FAB2(SCH_1):PVCCIN_CPU0   I310 @BASEBOARD_FAB2_LIB.BASEBOARD_FAB2(SCH_1):PAGE37
  BN72 PVCCIN_CPU0 @BASEBOARD_FAB2_LIB.BASEBOARD_FAB2(SCH_1):PVCCIN_CPU0   I310 @BASEBOARD_FAB2_LIB.BASEBOARD_FAB2(SCH_1):PAGE37
  BN74 PVCCIN_CPU0 @BASEBOARD_FAB2_LIB.BASEBOARD_FAB2(SCH_1):PVCCIN_CPU0   I310 @BASEBOARD_FAB2_LIB.BASEBOARD_FAB2(SCH_1):PAGE37
  BN76 PVCCIN_CPU0 @BASEBOARD_FAB2_LIB.BASEBOARD_FAB2(SCH_1):PVCCIN_CPU0   I310 @BASEBOARD_FAB2_LIB.BASEBOARD_FAB2(SCH_1):PAGE37
  BN78 PVCCIN_CPU0 @BASEBOARD_FAB2_LIB.BASEBOARD_FAB2(SCH_1):PVCCIN_CPU0   I310 @BASEBOARD_FAB2_LIB.BASEBOARD_FAB2(SCH_1):PAGE37
  BN80 PVCCIN_CPU0 @BASEBOARD_FAB2_LIB.BASEBOARD_FAB2(SCH_1):PVCCIN_CPU0   I311 @BASEBOARD_FAB2_LIB.BASEBOARD_FAB2(SCH_1):PAGE37
  BN82 PVCCIN_CPU0 @BASEBOARD_FAB2_LIB.BASEBOARD_FAB2(SCH_1):PVCCIN_CPU0   I311 @BASEBOARD_FAB2_LIB.BASEBOARD_FAB2(SCH_1):PAGE37
  BN84 PVCCIN_CPU0 @BASEBOARD_FAB2_LIB.BASEBOARD_FAB2(SCH_1):PVCCIN_CPU0   I311 @BASEBOARD_FAB2_LIB.BASEBOARD_FAB2(SCH_1):PAGE37
  BP61 PVCCIN_CPU0 @BASEBOARD_FAB2_LIB.BASEBOARD_FAB2(SCH_1):PVCCIN_CPU0   I311 @BASEBOARD_FAB2_LIB.BASEBOARD_FAB2(SCH_1):PAGE37
  BP63 PVCCIN_CPU0 @BASEBOARD_FAB2_LIB.BASEBOARD_FAB2(SCH_1):PVCCIN_CPU0   I311 @BASEBOARD_FAB2_LIB.BASEBOARD_FAB2(SCH_1):PAGE37
  BP65 PVCCIN_CPU0 @BASEBOARD_FAB2_LIB.BASEBOARD_FAB2(SCH_1):PVCCIN_CPU0   I311 @BASEBOARD_FAB2_LIB.BASEBOARD_FAB2(SCH_1):PAGE37
  BP67 PVCCIN_CPU0 @BASEBOARD_FAB2_LIB.BASEBOARD_FAB2(SCH_1):PVCCIN_CPU0   I311 @BASEBOARD_FAB2_LIB.BASEBOARD_FAB2(SCH_1):PAGE37
  BP69 PVCCIN_CPU0 @BASEBOARD_FAB2_LIB.BASEBOARD_FAB2(SCH_1):PVCCIN_CPU0   I311 @BASEBOARD_FAB2_LIB.BASEBOARD_FAB2(SCH_1):PAGE37
  BP71 PVCCIN_CPU0 @BASEBOARD_FAB2_LIB.BASEBOARD_FAB2(SCH_1):PVCCIN_CPU0   I311 @BASEBOARD_FAB2_LIB.BASEBOARD_FAB2(SCH_1):PAGE37
  BP73 PVCCIN_CPU0 @BASEBOARD_FAB2_LIB.BASEBOARD_FAB2(SCH_1):PVCCIN_CPU0   I311 @BASEBOARD_FAB2_LIB.BASEBOARD_FAB2(SCH_1):PAGE37
  BP75 PVCCIN_CPU0 @BASEBOARD_FAB2_LIB.BASEBOARD_FAB2(SCH_1):PVCCIN_CPU0   I311 @BASEBOARD_FAB2_LIB.BASEBOARD_FAB2(SCH_1):PAGE37
  BP77 PVCCIN_CPU0 @BASEBOARD_FAB2_LIB.BASEBOARD_FAB2(SCH_1):PVCCIN_CPU0   I311 @BASEBOARD_FAB2_LIB.BASEBOARD_FAB2(SCH_1):PAGE37
  BP79 PVCCIN_CPU0 @BASEBOARD_FAB2_LIB.BASEBOARD_FAB2(SCH_1):PVCCIN_CPU0   I311 @BASEBOARD_FAB2_LIB.BASEBOARD_FAB2(SCH_1):PAGE37
  BP81 PVCCIN_CPU0 @BASEBOARD_FAB2_LIB.BASEBOARD_FAB2(SCH_1):PVCCIN_CPU0   I311 @BASEBOARD_FAB2_LIB.BASEBOARD_FAB2(SCH_1):PAGE37
  BP83 PVCCIN_CPU0 @BASEBOARD_FAB2_LIB.BASEBOARD_FAB2(SCH_1):PVCCIN_CPU0   I311 @BASEBOARD_FAB2_LIB.BASEBOARD_FAB2(SCH_1):PAGE37
  BR60 PVCCIN_CPU0 @BASEBOARD_FAB2_LIB.BASEBOARD_FAB2(SCH_1):PVCCIN_CPU0   I311 @BASEBOARD_FAB2_LIB.BASEBOARD_FAB2(SCH_1):PAGE37
  BR62 PVCCIN_CPU0 @BASEBOARD_FAB2_LIB.BASEBOARD_FAB2(SCH_1):PVCCIN_CPU0   I311 @BASEBOARD_FAB2_LIB.BASEBOARD_FAB2(SCH_1):PAGE37
  BR84 PVCCIN_CPU0 @BASEBOARD_FAB2_LIB.BASEBOARD_FAB2(SCH_1):PVCCIN_CPU0   I311 @BASEBOARD_FAB2_LIB.BASEBOARD_FAB2(SCH_1):PAGE37
  BT61 PVCCIN_CPU0 @BASEBOARD_FAB2_LIB.BASEBOARD_FAB2(SCH_1):PVCCIN_CPU0   I311 @BASEBOARD_FAB2_LIB.BASEBOARD_FAB2(SCH_1):PAGE37
  BT63 PVCCIN_CPU0 @BASEBOARD_FAB2_LIB.BASEBOARD_FAB2(SCH_1):PVCCIN_CPU0   I311 @BASEBOARD_FAB2_LIB.BASEBOARD_FAB2(SCH_1):PAGE37
  BT65 PVCCIN_CPU0 @BASEBOARD_FAB2_LIB.BASEBOARD_FAB2(SCH_1):PVCCIN_CPU0   I311 @BASEBOARD_FAB2_LIB.BASEBOARD_FAB2(SCH_1):PAGE37
  BT67 PVCCIN_CPU0 @BASEBOARD_FAB2_LIB.BASEBOARD_FAB2(SCH_1):PVCCIN_CPU0   I311 @BASEBOARD_FAB2_LIB.BASEBOARD_FAB2(SCH_1):PAGE37
  BT69 PVCCIN_CPU0 @BASEBOARD_FAB2_LIB.BASEBOARD_FAB2(SCH_1):PVCCIN_CPU0   I311 @BASEBOARD_FAB2_LIB.BASEBOARD_FAB2(SCH_1):PAGE37
  BT71 PVCCIN_CPU0 @BASEBOARD_FAB2_LIB.BASEBOARD_FAB2(SCH_1):PVCCIN_CPU0   I311 @BASEBOARD_FAB2_LIB.BASEBOARD_FAB2(SCH_1):PAGE37
  BT73 PVCCIN_CPU0 @BASEBOARD_FAB2_LIB.BASEBOARD_FAB2(SCH_1):PVCCIN_CPU0   I311 @BASEBOARD_FAB2_LIB.BASEBOARD_FAB2(SCH_1):PAGE37
  BT75 PVCCIN_CPU0 @BASEBOARD_FAB2_LIB.BASEBOARD_FAB2(SCH_1):PVCCIN_CPU0   I311 @BASEBOARD_FAB2_LIB.BASEBOARD_FAB2(SCH_1):PAGE37
  BT77 PVCCIN_CPU0 @BASEBOARD_FAB2_LIB.BASEBOARD_FAB2(SCH_1):PVCCIN_CPU0   I311 @BASEBOARD_FAB2_LIB.BASEBOARD_FAB2(SCH_1):PAGE37
  BT79 PVCCIN_CPU0 @BASEBOARD_FAB2_LIB.BASEBOARD_FAB2(SCH_1):PVCCIN_CPU0   I311 @BASEBOARD_FAB2_LIB.BASEBOARD_FAB2(SCH_1):PAGE37
  BT81 PVCCIN_CPU0 @BASEBOARD_FAB2_LIB.BASEBOARD_FAB2(SCH_1):PVCCIN_CPU0   I311 @BASEBOARD_FAB2_LIB.BASEBOARD_FAB2(SCH_1):PAGE37
  BT83 PVCCIN_CPU0 @BASEBOARD_FAB2_LIB.BASEBOARD_FAB2(SCH_1):PVCCIN_CPU0   I311 @BASEBOARD_FAB2_LIB.BASEBOARD_FAB2(SCH_1):PAGE37
  BU60 PVCCIN_CPU0 @BASEBOARD_FAB2_LIB.BASEBOARD_FAB2(SCH_1):PVCCIN_CPU0   I311 @BASEBOARD_FAB2_LIB.BASEBOARD_FAB2(SCH_1):PAGE37
  BU62 PVCCIN_CPU0 @BASEBOARD_FAB2_LIB.BASEBOARD_FAB2(SCH_1):PVCCIN_CPU0   I311 @BASEBOARD_FAB2_LIB.BASEBOARD_FAB2(SCH_1):PAGE37
  BU64 PVCCIN_CPU0 @BASEBOARD_FAB2_LIB.BASEBOARD_FAB2(SCH_1):PVCCIN_CPU0   I311 @BASEBOARD_FAB2_LIB.BASEBOARD_FAB2(SCH_1):PAGE37
  BU66 PVCCIN_CPU0 @BASEBOARD_FAB2_LIB.BASEBOARD_FAB2(SCH_1):PVCCIN_CPU0   I311 @BASEBOARD_FAB2_LIB.BASEBOARD_FAB2(SCH_1):PAGE37
  BU68 PVCCIN_CPU0 @BASEBOARD_FAB2_LIB.BASEBOARD_FAB2(SCH_1):PVCCIN_CPU0   I311 @BASEBOARD_FAB2_LIB.BASEBOARD_FAB2(SCH_1):PAGE37
  BU70 PVCCIN_CPU0 @BASEBOARD_FAB2_LIB.BASEBOARD_FAB2(SCH_1):PVCCIN_CPU0   I311 @BASEBOARD_FAB2_LIB.BASEBOARD_FAB2(SCH_1):PAGE37
  BU72 PVCCIN_CPU0 @BASEBOARD_FAB2_LIB.BASEBOARD_FAB2(SCH_1):PVCCIN_CPU0   I311 @BASEBOARD_FAB2_LIB.BASEBOARD_FAB2(SCH_1):PAGE37
  BU74 PVCCIN_CPU0 @BASEBOARD_FAB2_LIB.BASEBOARD_FAB2(SCH_1):PVCCIN_CPU0   I311 @BASEBOARD_FAB2_LIB.BASEBOARD_FAB2(SCH_1):PAGE37
  BU76 PVCCIN_CPU0 @BASEBOARD_FAB2_LIB.BASEBOARD_FAB2(SCH_1):PVCCIN_CPU0   I311 @BASEBOARD_FAB2_LIB.BASEBOARD_FAB2(SCH_1):PAGE37
  BU78 PVCCIN_CPU0 @BASEBOARD_FAB2_LIB.BASEBOARD_FAB2(SCH_1):PVCCIN_CPU0   I311 @BASEBOARD_FAB2_LIB.BASEBOARD_FAB2(SCH_1):PAGE37
  BU80 PVCCIN_CPU0 @BASEBOARD_FAB2_LIB.BASEBOARD_FAB2(SCH_1):PVCCIN_CPU0   I311 @BASEBOARD_FAB2_LIB.BASEBOARD_FAB2(SCH_1):PAGE37
  BU82 PVCCIN_CPU0 @BASEBOARD_FAB2_LIB.BASEBOARD_FAB2(SCH_1):PVCCIN_CPU0   I311 @BASEBOARD_FAB2_LIB.BASEBOARD_FAB2(SCH_1):PAGE37
  BU84 PVCCIN_CPU0 @BASEBOARD_FAB2_LIB.BASEBOARD_FAB2(SCH_1):PVCCIN_CPU0   I311 @BASEBOARD_FAB2_LIB.BASEBOARD_FAB2(SCH_1):PAGE37
  BV61 PVCCIN_CPU0 @BASEBOARD_FAB2_LIB.BASEBOARD_FAB2(SCH_1):PVCCIN_CPU0   I311 @BASEBOARD_FAB2_LIB.BASEBOARD_FAB2(SCH_1):PAGE37
  BV63 PVCCIN_CPU0 @BASEBOARD_FAB2_LIB.BASEBOARD_FAB2(SCH_1):PVCCIN_CPU0   I311 @BASEBOARD_FAB2_LIB.BASEBOARD_FAB2(SCH_1):PAGE37
  BV65 PVCCIN_CPU0 @BASEBOARD_FAB2_LIB.BASEBOARD_FAB2(SCH_1):PVCCIN_CPU0   I311 @BASEBOARD_FAB2_LIB.BASEBOARD_FAB2(SCH_1):PAGE37
  BV67 PVCCIN_CPU0 @BASEBOARD_FAB2_LIB.BASEBOARD_FAB2(SCH_1):PVCCIN_CPU0   I311 @BASEBOARD_FAB2_LIB.BASEBOARD_FAB2(SCH_1):PAGE37
  BV69 PVCCIN_CPU0 @BASEBOARD_FAB2_LIB.BASEBOARD_FAB2(SCH_1):PVCCIN_CPU0   I311 @BASEBOARD_FAB2_LIB.BASEBOARD_FAB2(SCH_1):PAGE37
  BV71 PVCCIN_CPU0 @BASEBOARD_FAB2_LIB.BASEBOARD_FAB2(SCH_1):PVCCIN_CPU0   I311 @BASEBOARD_FAB2_LIB.BASEBOARD_FAB2(SCH_1):PAGE37
  BV73 PVCCIN_CPU0 @BASEBOARD_FAB2_LIB.BASEBOARD_FAB2(SCH_1):PVCCIN_CPU0   I311 @BASEBOARD_FAB2_LIB.BASEBOARD_FAB2(SCH_1):PAGE37
  BV75 PVCCIN_CPU0 @BASEBOARD_FAB2_LIB.BASEBOARD_FAB2(SCH_1):PVCCIN_CPU0   I311 @BASEBOARD_FAB2_LIB.BASEBOARD_FAB2(SCH_1):PAGE37
  BV77 PVCCIN_CPU0 @BASEBOARD_FAB2_LIB.BASEBOARD_FAB2(SCH_1):PVCCIN_CPU0   I311 @BASEBOARD_FAB2_LIB.BASEBOARD_FAB2(SCH_1):PAGE37
  BV79 PVCCIN_CPU0 @BASEBOARD_FAB2_LIB.BASEBOARD_FAB2(SCH_1):PVCCIN_CPU0   I311 @BASEBOARD_FAB2_LIB.BASEBOARD_FAB2(SCH_1):PAGE37
  BV81 PVCCIN_CPU0 @BASEBOARD_FAB2_LIB.BASEBOARD_FAB2(SCH_1):PVCCIN_CPU0   I311 @BASEBOARD_FAB2_LIB.BASEBOARD_FAB2(SCH_1):PAGE37
  BV83 PVCCIN_CPU0 @BASEBOARD_FAB2_LIB.BASEBOARD_FAB2(SCH_1):PVCCIN_CPU0   I311 @BASEBOARD_FAB2_LIB.BASEBOARD_FAB2(SCH_1):PAGE37
  BW60 PVCCIN_CPU0 @BASEBOARD_FAB2_LIB.BASEBOARD_FAB2(SCH_1):PVCCIN_CPU0   I311 @BASEBOARD_FAB2_LIB.BASEBOARD_FAB2(SCH_1):PAGE37
  BW62 PVCCIN_CPU0 @BASEBOARD_FAB2_LIB.BASEBOARD_FAB2(SCH_1):PVCCIN_CPU0   I311 @BASEBOARD_FAB2_LIB.BASEBOARD_FAB2(SCH_1):PAGE37
  BW64 PVCCIN_CPU0 @BASEBOARD_FAB2_LIB.BASEBOARD_FAB2(SCH_1):PVCCIN_CPU0   I311 @BASEBOARD_FAB2_LIB.BASEBOARD_FAB2(SCH_1):PAGE37
  BW66 PVCCIN_CPU0 @BASEBOARD_FAB2_LIB.BASEBOARD_FAB2(SCH_1):PVCCIN_CPU0   I311 @BASEBOARD_FAB2_LIB.BASEBOARD_FAB2(SCH_1):PAGE37
  BW68 PVCCIN_CPU0 @BASEBOARD_FAB2_LIB.BASEBOARD_FAB2(SCH_1):PVCCIN_CPU0   I311 @BASEBOARD_FAB2_LIB.BASEBOARD_FAB2(SCH_1):PAGE37
  BW70 PVCCIN_CPU0 @BASEBOARD_FAB2_LIB.BASEBOARD_FAB2(SCH_1):PVCCIN_CPU0   I311 @BASEBOARD_FAB2_LIB.BASEBOARD_FAB2(SCH_1):PAGE37
  BW84 PVCCIN_CPU0 @BASEBOARD_FAB2_LIB.BASEBOARD_FAB2(SCH_1):PVCCIN_CPU0   I311 @BASEBOARD_FAB2_LIB.BASEBOARD_FAB2(SCH_1):PAGE37
  BY61 PVCCIN_CPU0 @BASEBOARD_FAB2_LIB.BASEBOARD_FAB2(SCH_1):PVCCIN_CPU0   I311 @BASEBOARD_FAB2_LIB.BASEBOARD_FAB2(SCH_1):PAGE37
  BY73 PVCCIN_CPU0 @BASEBOARD_FAB2_LIB.BASEBOARD_FAB2(SCH_1):PVCCIN_CPU0   I311 @BASEBOARD_FAB2_LIB.BASEBOARD_FAB2(SCH_1):PAGE37
  BY75 PVCCIN_CPU0 @BASEBOARD_FAB2_LIB.BASEBOARD_FAB2(SCH_1):PVCCIN_CPU0   I311 @BASEBOARD_FAB2_LIB.BASEBOARD_FAB2(SCH_1):PAGE37
  BY77 PVCCIN_CPU0 @BASEBOARD_FAB2_LIB.BASEBOARD_FAB2(SCH_1):PVCCIN_CPU0   I311 @BASEBOARD_FAB2_LIB.BASEBOARD_FAB2(SCH_1):PAGE37
  BY79 PVCCIN_CPU0 @BASEBOARD_FAB2_LIB.BASEBOARD_FAB2(SCH_1):PVCCIN_CPU0   I311 @BASEBOARD_FAB2_LIB.BASEBOARD_FAB2(SCH_1):PAGE37
  BY81 PVCCIN_CPU0 @BASEBOARD_FAB2_LIB.BASEBOARD_FAB2(SCH_1):PVCCIN_CPU0   I311 @BASEBOARD_FAB2_LIB.BASEBOARD_FAB2(SCH_1):PAGE37
  BY83 PVCCIN_CPU0 @BASEBOARD_FAB2_LIB.BASEBOARD_FAB2(SCH_1):PVCCIN_CPU0   I311 @BASEBOARD_FAB2_LIB.BASEBOARD_FAB2(SCH_1):PAGE37
  CA60 PVCCIN_CPU0 @BASEBOARD_FAB2_LIB.BASEBOARD_FAB2(SCH_1):PVCCIN_CPU0   I311 @BASEBOARD_FAB2_LIB.BASEBOARD_FAB2(SCH_1):PAGE37
  CA62 PVCCIN_CPU0 @BASEBOARD_FAB2_LIB.BASEBOARD_FAB2(SCH_1):PVCCIN_CPU0   I311 @BASEBOARD_FAB2_LIB.BASEBOARD_FAB2(SCH_1):PAGE37
  CA72 PVCCIN_CPU0 @BASEBOARD_FAB2_LIB.BASEBOARD_FAB2(SCH_1):PVCCIN_CPU0   I311 @BASEBOARD_FAB2_LIB.BASEBOARD_FAB2(SCH_1):PAGE37
  CA74 PVCCIN_CPU0 @BASEBOARD_FAB2_LIB.BASEBOARD_FAB2(SCH_1):PVCCIN_CPU0   I311 @BASEBOARD_FAB2_LIB.BASEBOARD_FAB2(SCH_1):PAGE37
  CA76 PVCCIN_CPU0 @BASEBOARD_FAB2_LIB.BASEBOARD_FAB2(SCH_1):PVCCIN_CPU0   I311 @BASEBOARD_FAB2_LIB.BASEBOARD_FAB2(SCH_1):PAGE37
  CA78 PVCCIN_CPU0 @BASEBOARD_FAB2_LIB.BASEBOARD_FAB2(SCH_1):PVCCIN_CPU0   I311 @BASEBOARD_FAB2_LIB.BASEBOARD_FAB2(SCH_1):PAGE37
  CA80 PVCCIN_CPU0 @BASEBOARD_FAB2_LIB.BASEBOARD_FAB2(SCH_1):PVCCIN_CPU0   I311 @BASEBOARD_FAB2_LIB.BASEBOARD_FAB2(SCH_1):PAGE37
  CA82 PVCCIN_CPU0 @BASEBOARD_FAB2_LIB.BASEBOARD_FAB2(SCH_1):PVCCIN_CPU0   I311 @BASEBOARD_FAB2_LIB.BASEBOARD_FAB2(SCH_1):PAGE37
  CA84 PVCCIN_CPU0 @BASEBOARD_FAB2_LIB.BASEBOARD_FAB2(SCH_1):PVCCIN_CPU0   I311 @BASEBOARD_FAB2_LIB.BASEBOARD_FAB2(SCH_1):PAGE37
  CB61 PVCCIN_CPU0 @BASEBOARD_FAB2_LIB.BASEBOARD_FAB2(SCH_1):PVCCIN_CPU0   I311 @BASEBOARD_FAB2_LIB.BASEBOARD_FAB2(SCH_1):PAGE37
  CB73 PVCCIN_CPU0 @BASEBOARD_FAB2_LIB.BASEBOARD_FAB2(SCH_1):PVCCIN_CPU0   I311 @BASEBOARD_FAB2_LIB.BASEBOARD_FAB2(SCH_1):PAGE37
  CB75 PVCCIN_CPU0 @BASEBOARD_FAB2_LIB.BASEBOARD_FAB2(SCH_1):PVCCIN_CPU0   I311 @BASEBOARD_FAB2_LIB.BASEBOARD_FAB2(SCH_1):PAGE37
  CB77 PVCCIN_CPU0 @BASEBOARD_FAB2_LIB.BASEBOARD_FAB2(SCH_1):PVCCIN_CPU0   I311 @BASEBOARD_FAB2_LIB.BASEBOARD_FAB2(SCH_1):PAGE37
  CB79 PVCCIN_CPU0 @BASEBOARD_FAB2_LIB.BASEBOARD_FAB2(SCH_1):PVCCIN_CPU0   I311 @BASEBOARD_FAB2_LIB.BASEBOARD_FAB2(SCH_1):PAGE37
  CB81 PVCCIN_CPU0 @BASEBOARD_FAB2_LIB.BASEBOARD_FAB2(SCH_1):PVCCIN_CPU0   I311 @BASEBOARD_FAB2_LIB.BASEBOARD_FAB2(SCH_1):PAGE37
  CB83 PVCCIN_CPU0 @BASEBOARD_FAB2_LIB.BASEBOARD_FAB2(SCH_1):PVCCIN_CPU0   I311 @BASEBOARD_FAB2_LIB.BASEBOARD_FAB2(SCH_1):PAGE37
  CC60 PVCCIN_CPU0 @BASEBOARD_FAB2_LIB.BASEBOARD_FAB2(SCH_1):PVCCIN_CPU0   I311 @BASEBOARD_FAB2_LIB.BASEBOARD_FAB2(SCH_1):PAGE37
  CC62 PVCCIN_CPU0 @BASEBOARD_FAB2_LIB.BASEBOARD_FAB2(SCH_1):PVCCIN_CPU0   I311 @BASEBOARD_FAB2_LIB.BASEBOARD_FAB2(SCH_1):PAGE37
  CC84 PVCCIN_CPU0 @BASEBOARD_FAB2_LIB.BASEBOARD_FAB2(SCH_1):PVCCIN_CPU0   I311 @BASEBOARD_FAB2_LIB.BASEBOARD_FAB2(SCH_1):PAGE37
  CD61 PVCCIN_CPU0 @BASEBOARD_FAB2_LIB.BASEBOARD_FAB2(SCH_1):PVCCIN_CPU0   I311 @BASEBOARD_FAB2_LIB.BASEBOARD_FAB2(SCH_1):PAGE37
  CD83 PVCCIN_CPU0 @BASEBOARD_FAB2_LIB.BASEBOARD_FAB2(SCH_1):PVCCIN_CPU0   I311 @BASEBOARD_FAB2_LIB.BASEBOARD_FAB2(SCH_1):PAGE37
  CD85 PVCCIN_CPU0 @BASEBOARD_FAB2_LIB.BASEBOARD_FAB2(SCH_1):PVCCIN_CPU0   I311 @BASEBOARD_FAB2_LIB.BASEBOARD_FAB2(SCH_1):PAGE37
  CE60 PVCCIN_CPU0 @BASEBOARD_FAB2_LIB.BASEBOARD_FAB2(SCH_1):PVCCIN_CPU0   I311 @BASEBOARD_FAB2_LIB.BASEBOARD_FAB2(SCH_1):PAGE37
  CE84 PVCCIN_CPU0 @BASEBOARD_FAB2_LIB.BASEBOARD_FAB2(SCH_1):PVCCIN_CPU0   I311 @BASEBOARD_FAB2_LIB.BASEBOARD_FAB2(SCH_1):PAGE37
  CF61 PVCCIN_CPU0 @BASEBOARD_FAB2_LIB.BASEBOARD_FAB2(SCH_1):PVCCIN_CPU0   I311 @BASEBOARD_FAB2_LIB.BASEBOARD_FAB2(SCH_1):PAGE37
  CF85 PVCCIN_CPU0 @BASEBOARD_FAB2_LIB.BASEBOARD_FAB2(SCH_1):PVCCIN_CPU0   I311 @BASEBOARD_FAB2_LIB.BASEBOARD_FAB2(SCH_1):PAGE37
  CG60 PVCCIN_CPU0 @BASEBOARD_FAB2_LIB.BASEBOARD_FAB2(SCH_1):PVCCIN_CPU0   I311 @BASEBOARD_FAB2_LIB.BASEBOARD_FAB2(SCH_1):PAGE37
  CG84 PVCCIN_CPU0 @BASEBOARD_FAB2_LIB.BASEBOARD_FAB2(SCH_1):PVCCIN_CPU0   I311 @BASEBOARD_FAB2_LIB.BASEBOARD_FAB2(SCH_1):PAGE37
  CH61 PVCCIN_CPU0 @BASEBOARD_FAB2_LIB.BASEBOARD_FAB2(SCH_1):PVCCIN_CPU0   I311 @BASEBOARD_FAB2_LIB.BASEBOARD_FAB2(SCH_1):PAGE37
  CH85 PVCCIN_CPU0 @BASEBOARD_FAB2_LIB.BASEBOARD_FAB2(SCH_1):PVCCIN_CPU0   I311 @BASEBOARD_FAB2_LIB.BASEBOARD_FAB2(SCH_1):PAGE37
  CJ60 PVCCIN_CPU0 @BASEBOARD_FAB2_LIB.BASEBOARD_FAB2(SCH_1):PVCCIN_CPU0   I311 @BASEBOARD_FAB2_LIB.BASEBOARD_FAB2(SCH_1):PAGE37
  CK59 PVCCIN_CPU0 @BASEBOARD_FAB2_LIB.BASEBOARD_FAB2(SCH_1):PVCCIN_CPU0   I311 @BASEBOARD_FAB2_LIB.BASEBOARD_FAB2(SCH_1):PAGE37
  CK61 PVCCIN_CPU0 @BASEBOARD_FAB2_LIB.BASEBOARD_FAB2(SCH_1):PVCCIN_CPU0   I311 @BASEBOARD_FAB2_LIB.BASEBOARD_FAB2(SCH_1):PAGE37
  CL58 PVCCIN_CPU0 @BASEBOARD_FAB2_LIB.BASEBOARD_FAB2(SCH_1):PVCCIN_CPU0   I311 @BASEBOARD_FAB2_LIB.BASEBOARD_FAB2(SCH_1):PAGE37
  CL60 PVCCIN_CPU0 @BASEBOARD_FAB2_LIB.BASEBOARD_FAB2(SCH_1):PVCCIN_CPU0   I311 @BASEBOARD_FAB2_LIB.BASEBOARD_FAB2(SCH_1):PAGE37
  CM57 PVCCIN_CPU0 @BASEBOARD_FAB2_LIB.BASEBOARD_FAB2(SCH_1):PVCCIN_CPU0   I311 @BASEBOARD_FAB2_LIB.BASEBOARD_FAB2(SCH_1):PAGE37
  CM59 PVCCIN_CPU0 @BASEBOARD_FAB2_LIB.BASEBOARD_FAB2(SCH_1):PVCCIN_CPU0   I311 @BASEBOARD_FAB2_LIB.BASEBOARD_FAB2(SCH_1):PAGE37
  CN56 PVCCIN_CPU0 @BASEBOARD_FAB2_LIB.BASEBOARD_FAB2(SCH_1):PVCCIN_CPU0   I311 @BASEBOARD_FAB2_LIB.BASEBOARD_FAB2(SCH_1):PAGE37
  CN58 PVCCIN_CPU0 @BASEBOARD_FAB2_LIB.BASEBOARD_FAB2(SCH_1):PVCCIN_CPU0   I311 @BASEBOARD_FAB2_LIB.BASEBOARD_FAB2(SCH_1):PAGE37
  CP33 PVCCIN_CPU0 @BASEBOARD_FAB2_LIB.BASEBOARD_FAB2(SCH_1):PVCCIN_CPU0   I311 @BASEBOARD_FAB2_LIB.BASEBOARD_FAB2(SCH_1):PAGE37
  CP55 PVCCIN_CPU0 @BASEBOARD_FAB2_LIB.BASEBOARD_FAB2(SCH_1):PVCCIN_CPU0   I311 @BASEBOARD_FAB2_LIB.BASEBOARD_FAB2(SCH_1):PAGE37
  CP57 PVCCIN_CPU0 @BASEBOARD_FAB2_LIB.BASEBOARD_FAB2(SCH_1):PVCCIN_CPU0   I311 @BASEBOARD_FAB2_LIB.BASEBOARD_FAB2(SCH_1):PAGE37
  CR34 PVCCIN_CPU0 @BASEBOARD_FAB2_LIB.BASEBOARD_FAB2(SCH_1):PVCCIN_CPU0   I311 @BASEBOARD_FAB2_LIB.BASEBOARD_FAB2(SCH_1):PAGE37
  CR54 PVCCIN_CPU0 @BASEBOARD_FAB2_LIB.BASEBOARD_FAB2(SCH_1):PVCCIN_CPU0   I311 @BASEBOARD_FAB2_LIB.BASEBOARD_FAB2(SCH_1):PAGE37
  CR56 PVCCIN_CPU0 @BASEBOARD_FAB2_LIB.BASEBOARD_FAB2(SCH_1):PVCCIN_CPU0   I311 @BASEBOARD_FAB2_LIB.BASEBOARD_FAB2(SCH_1):PAGE37
  CT37 PVCCIN_CPU0 @BASEBOARD_FAB2_LIB.BASEBOARD_FAB2(SCH_1):PVCCIN_CPU0   I311 @BASEBOARD_FAB2_LIB.BASEBOARD_FAB2(SCH_1):PAGE37
  CT39 PVCCIN_CPU0 @BASEBOARD_FAB2_LIB.BASEBOARD_FAB2(SCH_1):PVCCIN_CPU0   I311 @BASEBOARD_FAB2_LIB.BASEBOARD_FAB2(SCH_1):PAGE37
  CT41 PVCCIN_CPU0 @BASEBOARD_FAB2_LIB.BASEBOARD_FAB2(SCH_1):PVCCIN_CPU0   I311 @BASEBOARD_FAB2_LIB.BASEBOARD_FAB2(SCH_1):PAGE37
  CT53 PVCCIN_CPU0 @BASEBOARD_FAB2_LIB.BASEBOARD_FAB2(SCH_1):PVCCIN_CPU0   I311 @BASEBOARD_FAB2_LIB.BASEBOARD_FAB2(SCH_1):PAGE37
  CT55 PVCCIN_CPU0 @BASEBOARD_FAB2_LIB.BASEBOARD_FAB2(SCH_1):PVCCIN_CPU0   I311 @BASEBOARD_FAB2_LIB.BASEBOARD_FAB2(SCH_1):PAGE37
  CU38 PVCCIN_CPU0 @BASEBOARD_FAB2_LIB.BASEBOARD_FAB2(SCH_1):PVCCIN_CPU0   I311 @BASEBOARD_FAB2_LIB.BASEBOARD_FAB2(SCH_1):PAGE37
  CU40 PVCCIN_CPU0 @BASEBOARD_FAB2_LIB.BASEBOARD_FAB2(SCH_1):PVCCIN_CPU0   I311 @BASEBOARD_FAB2_LIB.BASEBOARD_FAB2(SCH_1):PAGE37
  CU42 PVCCIN_CPU0 @BASEBOARD_FAB2_LIB.BASEBOARD_FAB2(SCH_1):PVCCIN_CPU0   I311 @BASEBOARD_FAB2_LIB.BASEBOARD_FAB2(SCH_1):PAGE37
  CU52 PVCCIN_CPU0 @BASEBOARD_FAB2_LIB.BASEBOARD_FAB2(SCH_1):PVCCIN_CPU0   I311 @BASEBOARD_FAB2_LIB.BASEBOARD_FAB2(SCH_1):PAGE37
  CU54 PVCCIN_CPU0 @BASEBOARD_FAB2_LIB.BASEBOARD_FAB2(SCH_1):PVCCIN_CPU0   I311 @BASEBOARD_FAB2_LIB.BASEBOARD_FAB2(SCH_1):PAGE37
  CV51 PVCCIN_CPU0 @BASEBOARD_FAB2_LIB.BASEBOARD_FAB2(SCH_1):PVCCIN_CPU0   I311 @BASEBOARD_FAB2_LIB.BASEBOARD_FAB2(SCH_1):PAGE37
  CW46 PVCCIN_CPU0 @BASEBOARD_FAB2_LIB.BASEBOARD_FAB2(SCH_1):PVCCIN_CPU0   I311 @BASEBOARD_FAB2_LIB.BASEBOARD_FAB2(SCH_1):PAGE37
  CW48 PVCCIN_CPU0 @BASEBOARD_FAB2_LIB.BASEBOARD_FAB2(SCH_1):PVCCIN_CPU0   I311 @BASEBOARD_FAB2_LIB.BASEBOARD_FAB2(SCH_1):PAGE37
  CW50 PVCCIN_CPU0 @BASEBOARD_FAB2_LIB.BASEBOARD_FAB2(SCH_1):PVCCIN_CPU0   I311 @BASEBOARD_FAB2_LIB.BASEBOARD_FAB2(SCH_1):PAGE37
  CY47 PVCCIN_CPU0 @BASEBOARD_FAB2_LIB.BASEBOARD_FAB2(SCH_1):PVCCIN_CPU0   I311 @BASEBOARD_FAB2_LIB.BASEBOARD_FAB2(SCH_1):PAGE37
  CY49 PVCCIN_CPU0 @BASEBOARD_FAB2_LIB.BASEBOARD_FAB2(SCH_1):PVCCIN_CPU0   I311 @BASEBOARD_FAB2_LIB.BASEBOARD_FAB2(SCH_1):PAGE37
  AV85 VSENSE_VCCINR2PMAX_CPU0 @BASEBOARD_FAB2_LIB.BASEBOARD_FAB2(SCH_1):VSENSE_VCCINR2PMAX_CPU0   I311 @BASEBOARD_FAB2_LIB.BASEBOARD_FAB2(SCH_1):PAGE37
  AW86 VSENSE_VCCINR2PMAX_CPU0 @BASEBOARD_FAB2_LIB.BASEBOARD_FAB2(SCH_1):VSENSE_VCCINR2PMAX_CPU0   I311 @BASEBOARD_FAB2_LIB.BASEBOARD_FAB2(SCH_1):PAGE37
  BA86 VSENSE_PVCCIN_CPU0_SKT_VSEN @BASEBOARD_FAB2_LIB.BASEBOARD_FAB2(SCH_1):VSENSE_PVCCIN_CPU0_SKT_VSEN   I311 @BASEBOARD_FAB2_LIB.BASEBOARD_FAB2(SCH_1):PAGE37
  AD41 VSENSE_PMAX_CPU0 @BASEBOARD_FAB2_LIB.BASEBOARD_FAB2(SCH_1):VSENSE_PMAX_CPU0   I311 @BASEBOARD_FAB2_LIB.BASEBOARD_FAB2(SCH_1):PAGE37
  AY85 VSENSE_PVCCIN_CPU0_SKT_VRTN @BASEBOARD_FAB2_LIB.BASEBOARD_FAB2(SCH_1):VSENSE_PVCCIN_CPU0_SKT_VRTN   I311 @BASEBOARD_FAB2_LIB.BASEBOARD_FAB2(SCH_1):PAGE37
   B47 PVDDQ_ABC @BASEBOARD_FAB2_LIB.BASEBOARD_FAB2(SCH_1):PVDDQ_ABC    I33 @BASEBOARD_FAB2_LIB.BASEBOARD_FAB2(SCH_1):PAGE38
   C46 PVDDQ_ABC @BASEBOARD_FAB2_LIB.BASEBOARD_FAB2(SCH_1):PVDDQ_ABC    I33 @BASEBOARD_FAB2_LIB.BASEBOARD_FAB2(SCH_1):PAGE38
   D45 PVDDQ_ABC @BASEBOARD_FAB2_LIB.BASEBOARD_FAB2(SCH_1):PVDDQ_ABC    I33 @BASEBOARD_FAB2_LIB.BASEBOARD_FAB2(SCH_1):PAGE38
  AF63 PVDDQ_ABC @BASEBOARD_FAB2_LIB.BASEBOARD_FAB2(SCH_1):PVDDQ_ABC    I33 @BASEBOARD_FAB2_LIB.BASEBOARD_FAB2(SCH_1):PAGE38
  AF61 PVDDQ_ABC @BASEBOARD_FAB2_LIB.BASEBOARD_FAB2(SCH_1):PVDDQ_ABC    I33 @BASEBOARD_FAB2_LIB.BASEBOARD_FAB2(SCH_1):PAGE38
  AF59 PVDDQ_ABC @BASEBOARD_FAB2_LIB.BASEBOARD_FAB2(SCH_1):PVDDQ_ABC    I33 @BASEBOARD_FAB2_LIB.BASEBOARD_FAB2(SCH_1):PAGE38
  AF57 PVDDQ_ABC @BASEBOARD_FAB2_LIB.BASEBOARD_FAB2(SCH_1):PVDDQ_ABC    I33 @BASEBOARD_FAB2_LIB.BASEBOARD_FAB2(SCH_1):PAGE38
  AF55 PVDDQ_ABC @BASEBOARD_FAB2_LIB.BASEBOARD_FAB2(SCH_1):PVDDQ_ABC    I33 @BASEBOARD_FAB2_LIB.BASEBOARD_FAB2(SCH_1):PAGE38
  AD45 PVDDQ_ABC @BASEBOARD_FAB2_LIB.BASEBOARD_FAB2(SCH_1):PVDDQ_ABC    I33 @BASEBOARD_FAB2_LIB.BASEBOARD_FAB2(SCH_1):PAGE38
   Y63 PVDDQ_ABC @BASEBOARD_FAB2_LIB.BASEBOARD_FAB2(SCH_1):PVDDQ_ABC    I33 @BASEBOARD_FAB2_LIB.BASEBOARD_FAB2(SCH_1):PAGE38
   Y61 PVDDQ_ABC @BASEBOARD_FAB2_LIB.BASEBOARD_FAB2(SCH_1):PVDDQ_ABC    I33 @BASEBOARD_FAB2_LIB.BASEBOARD_FAB2(SCH_1):PAGE38
   Y59 PVDDQ_ABC @BASEBOARD_FAB2_LIB.BASEBOARD_FAB2(SCH_1):PVDDQ_ABC    I33 @BASEBOARD_FAB2_LIB.BASEBOARD_FAB2(SCH_1):PAGE38
   Y57 PVDDQ_ABC @BASEBOARD_FAB2_LIB.BASEBOARD_FAB2(SCH_1):PVDDQ_ABC    I33 @BASEBOARD_FAB2_LIB.BASEBOARD_FAB2(SCH_1):PAGE38
   Y55 PVDDQ_ABC @BASEBOARD_FAB2_LIB.BASEBOARD_FAB2(SCH_1):PVDDQ_ABC    I33 @BASEBOARD_FAB2_LIB.BASEBOARD_FAB2(SCH_1):PAGE38
   Y53 PVDDQ_ABC @BASEBOARD_FAB2_LIB.BASEBOARD_FAB2(SCH_1):PVDDQ_ABC    I33 @BASEBOARD_FAB2_LIB.BASEBOARD_FAB2(SCH_1):PAGE38
   Y51 PVDDQ_ABC @BASEBOARD_FAB2_LIB.BASEBOARD_FAB2(SCH_1):PVDDQ_ABC    I33 @BASEBOARD_FAB2_LIB.BASEBOARD_FAB2(SCH_1):PAGE38
   Y49 PVDDQ_ABC @BASEBOARD_FAB2_LIB.BASEBOARD_FAB2(SCH_1):PVDDQ_ABC    I33 @BASEBOARD_FAB2_LIB.BASEBOARD_FAB2(SCH_1):PAGE38
   Y47 PVDDQ_ABC @BASEBOARD_FAB2_LIB.BASEBOARD_FAB2(SCH_1):PVDDQ_ABC    I33 @BASEBOARD_FAB2_LIB.BASEBOARD_FAB2(SCH_1):PAGE38
   Y45 PVDDQ_ABC @BASEBOARD_FAB2_LIB.BASEBOARD_FAB2(SCH_1):PVDDQ_ABC    I33 @BASEBOARD_FAB2_LIB.BASEBOARD_FAB2(SCH_1):PAGE38
   W64 PVDDQ_ABC @BASEBOARD_FAB2_LIB.BASEBOARD_FAB2(SCH_1):PVDDQ_ABC    I33 @BASEBOARD_FAB2_LIB.BASEBOARD_FAB2(SCH_1):PAGE38
   U62 PVDDQ_ABC @BASEBOARD_FAB2_LIB.BASEBOARD_FAB2(SCH_1):PVDDQ_ABC    I33 @BASEBOARD_FAB2_LIB.BASEBOARD_FAB2(SCH_1):PAGE38
   U60 PVDDQ_ABC @BASEBOARD_FAB2_LIB.BASEBOARD_FAB2(SCH_1):PVDDQ_ABC    I33 @BASEBOARD_FAB2_LIB.BASEBOARD_FAB2(SCH_1):PAGE38
   U58 PVDDQ_ABC @BASEBOARD_FAB2_LIB.BASEBOARD_FAB2(SCH_1):PVDDQ_ABC    I33 @BASEBOARD_FAB2_LIB.BASEBOARD_FAB2(SCH_1):PAGE38
   U56 PVDDQ_ABC @BASEBOARD_FAB2_LIB.BASEBOARD_FAB2(SCH_1):PVDDQ_ABC    I33 @BASEBOARD_FAB2_LIB.BASEBOARD_FAB2(SCH_1):PAGE38
   U54 PVDDQ_ABC @BASEBOARD_FAB2_LIB.BASEBOARD_FAB2(SCH_1):PVDDQ_ABC    I33 @BASEBOARD_FAB2_LIB.BASEBOARD_FAB2(SCH_1):PAGE38
   U52 PVDDQ_ABC @BASEBOARD_FAB2_LIB.BASEBOARD_FAB2(SCH_1):PVDDQ_ABC    I33 @BASEBOARD_FAB2_LIB.BASEBOARD_FAB2(SCH_1):PAGE38
   U50 PVDDQ_ABC @BASEBOARD_FAB2_LIB.BASEBOARD_FAB2(SCH_1):PVDDQ_ABC    I33 @BASEBOARD_FAB2_LIB.BASEBOARD_FAB2(SCH_1):PAGE38
   U48 PVDDQ_ABC @BASEBOARD_FAB2_LIB.BASEBOARD_FAB2(SCH_1):PVDDQ_ABC    I33 @BASEBOARD_FAB2_LIB.BASEBOARD_FAB2(SCH_1):PAGE38
   U46 PVDDQ_ABC @BASEBOARD_FAB2_LIB.BASEBOARD_FAB2(SCH_1):PVDDQ_ABC    I33 @BASEBOARD_FAB2_LIB.BASEBOARD_FAB2(SCH_1):PAGE38
   N64 PVDDQ_ABC @BASEBOARD_FAB2_LIB.BASEBOARD_FAB2(SCH_1):PVDDQ_ABC    I33 @BASEBOARD_FAB2_LIB.BASEBOARD_FAB2(SCH_1):PAGE38
   L62 PVDDQ_ABC @BASEBOARD_FAB2_LIB.BASEBOARD_FAB2(SCH_1):PVDDQ_ABC    I33 @BASEBOARD_FAB2_LIB.BASEBOARD_FAB2(SCH_1):PAGE38
   L60 PVDDQ_ABC @BASEBOARD_FAB2_LIB.BASEBOARD_FAB2(SCH_1):PVDDQ_ABC    I33 @BASEBOARD_FAB2_LIB.BASEBOARD_FAB2(SCH_1):PAGE38
   L58 PVDDQ_ABC @BASEBOARD_FAB2_LIB.BASEBOARD_FAB2(SCH_1):PVDDQ_ABC    I33 @BASEBOARD_FAB2_LIB.BASEBOARD_FAB2(SCH_1):PAGE38
   L56 PVDDQ_ABC @BASEBOARD_FAB2_LIB.BASEBOARD_FAB2(SCH_1):PVDDQ_ABC    I33 @BASEBOARD_FAB2_LIB.BASEBOARD_FAB2(SCH_1):PAGE38
   L54 PVDDQ_ABC @BASEBOARD_FAB2_LIB.BASEBOARD_FAB2(SCH_1):PVDDQ_ABC    I33 @BASEBOARD_FAB2_LIB.BASEBOARD_FAB2(SCH_1):PAGE38
   L52 PVDDQ_ABC @BASEBOARD_FAB2_LIB.BASEBOARD_FAB2(SCH_1):PVDDQ_ABC    I33 @BASEBOARD_FAB2_LIB.BASEBOARD_FAB2(SCH_1):PAGE38
   L50 PVDDQ_ABC @BASEBOARD_FAB2_LIB.BASEBOARD_FAB2(SCH_1):PVDDQ_ABC    I33 @BASEBOARD_FAB2_LIB.BASEBOARD_FAB2(SCH_1):PAGE38
   L48 PVDDQ_ABC @BASEBOARD_FAB2_LIB.BASEBOARD_FAB2(SCH_1):PVDDQ_ABC    I33 @BASEBOARD_FAB2_LIB.BASEBOARD_FAB2(SCH_1):PAGE38
   L46 PVDDQ_ABC @BASEBOARD_FAB2_LIB.BASEBOARD_FAB2(SCH_1):PVDDQ_ABC    I33 @BASEBOARD_FAB2_LIB.BASEBOARD_FAB2(SCH_1):PAGE38
   E64 PVDDQ_ABC @BASEBOARD_FAB2_LIB.BASEBOARD_FAB2(SCH_1):PVDDQ_ABC    I33 @BASEBOARD_FAB2_LIB.BASEBOARD_FAB2(SCH_1):PAGE38
   E62 PVDDQ_ABC @BASEBOARD_FAB2_LIB.BASEBOARD_FAB2(SCH_1):PVDDQ_ABC    I33 @BASEBOARD_FAB2_LIB.BASEBOARD_FAB2(SCH_1):PAGE38
   E60 PVDDQ_ABC @BASEBOARD_FAB2_LIB.BASEBOARD_FAB2(SCH_1):PVDDQ_ABC    I33 @BASEBOARD_FAB2_LIB.BASEBOARD_FAB2(SCH_1):PAGE38
   E58 PVDDQ_ABC @BASEBOARD_FAB2_LIB.BASEBOARD_FAB2(SCH_1):PVDDQ_ABC    I33 @BASEBOARD_FAB2_LIB.BASEBOARD_FAB2(SCH_1):PAGE38
   E56 PVDDQ_ABC @BASEBOARD_FAB2_LIB.BASEBOARD_FAB2(SCH_1):PVDDQ_ABC    I33 @BASEBOARD_FAB2_LIB.BASEBOARD_FAB2(SCH_1):PAGE38
   E54 PVDDQ_ABC @BASEBOARD_FAB2_LIB.BASEBOARD_FAB2(SCH_1):PVDDQ_ABC    I33 @BASEBOARD_FAB2_LIB.BASEBOARD_FAB2(SCH_1):PAGE38
   E52 PVDDQ_ABC @BASEBOARD_FAB2_LIB.BASEBOARD_FAB2(SCH_1):PVDDQ_ABC    I33 @BASEBOARD_FAB2_LIB.BASEBOARD_FAB2(SCH_1):PAGE38
   E50 PVDDQ_ABC @BASEBOARD_FAB2_LIB.BASEBOARD_FAB2(SCH_1):PVDDQ_ABC    I33 @BASEBOARD_FAB2_LIB.BASEBOARD_FAB2(SCH_1):PAGE38
   E48 PVDDQ_ABC @BASEBOARD_FAB2_LIB.BASEBOARD_FAB2(SCH_1):PVDDQ_ABC    I33 @BASEBOARD_FAB2_LIB.BASEBOARD_FAB2(SCH_1):PAGE38
   E46 PVDDQ_ABC @BASEBOARD_FAB2_LIB.BASEBOARD_FAB2(SCH_1):PVDDQ_ABC    I33 @BASEBOARD_FAB2_LIB.BASEBOARD_FAB2(SCH_1):PAGE38
   B59 PVDDQ_ABC @BASEBOARD_FAB2_LIB.BASEBOARD_FAB2(SCH_1):PVDDQ_ABC    I33 @BASEBOARD_FAB2_LIB.BASEBOARD_FAB2(SCH_1):PAGE38
   B53 PVDDQ_ABC @BASEBOARD_FAB2_LIB.BASEBOARD_FAB2(SCH_1):PVDDQ_ABC    I33 @BASEBOARD_FAB2_LIB.BASEBOARD_FAB2(SCH_1):PAGE38
   B49 PVDDQ_ABC @BASEBOARD_FAB2_LIB.BASEBOARD_FAB2(SCH_1):PVDDQ_ABC    I33 @BASEBOARD_FAB2_LIB.BASEBOARD_FAB2(SCH_1):PAGE38
  EE44 PVDDQ_DEF @BASEBOARD_FAB2_LIB.BASEBOARD_FAB2(SCH_1):PVDDQ_DEF    I33 @BASEBOARD_FAB2_LIB.BASEBOARD_FAB2(SCH_1):PAGE38
  EF45 PVDDQ_DEF @BASEBOARD_FAB2_LIB.BASEBOARD_FAB2(SCH_1):PVDDQ_DEF    I33 @BASEBOARD_FAB2_LIB.BASEBOARD_FAB2(SCH_1):PAGE38
  DB53 PVDDQ_DEF @BASEBOARD_FAB2_LIB.BASEBOARD_FAB2(SCH_1):PVDDQ_DEF    I33 @BASEBOARD_FAB2_LIB.BASEBOARD_FAB2(SCH_1):PAGE38
  DB55 PVDDQ_DEF @BASEBOARD_FAB2_LIB.BASEBOARD_FAB2(SCH_1):PVDDQ_DEF    I33 @BASEBOARD_FAB2_LIB.BASEBOARD_FAB2(SCH_1):PAGE38
  DB57 PVDDQ_DEF @BASEBOARD_FAB2_LIB.BASEBOARD_FAB2(SCH_1):PVDDQ_DEF    I33 @BASEBOARD_FAB2_LIB.BASEBOARD_FAB2(SCH_1):PAGE38
  DB59 PVDDQ_DEF @BASEBOARD_FAB2_LIB.BASEBOARD_FAB2(SCH_1):PVDDQ_DEF    I33 @BASEBOARD_FAB2_LIB.BASEBOARD_FAB2(SCH_1):PAGE38
  DB61 PVDDQ_DEF @BASEBOARD_FAB2_LIB.BASEBOARD_FAB2(SCH_1):PVDDQ_DEF    I33 @BASEBOARD_FAB2_LIB.BASEBOARD_FAB2(SCH_1):PAGE38
  DB63 PVDDQ_DEF @BASEBOARD_FAB2_LIB.BASEBOARD_FAB2(SCH_1):PVDDQ_DEF    I33 @BASEBOARD_FAB2_LIB.BASEBOARD_FAB2(SCH_1):PAGE38
  DD45 PVDDQ_DEF @BASEBOARD_FAB2_LIB.BASEBOARD_FAB2(SCH_1):PVDDQ_DEF    I33 @BASEBOARD_FAB2_LIB.BASEBOARD_FAB2(SCH_1):PAGE38
  DH45 PVDDQ_DEF @BASEBOARD_FAB2_LIB.BASEBOARD_FAB2(SCH_1):PVDDQ_DEF    I33 @BASEBOARD_FAB2_LIB.BASEBOARD_FAB2(SCH_1):PAGE38
  DH47 PVDDQ_DEF @BASEBOARD_FAB2_LIB.BASEBOARD_FAB2(SCH_1):PVDDQ_DEF    I33 @BASEBOARD_FAB2_LIB.BASEBOARD_FAB2(SCH_1):PAGE38
  DH49 PVDDQ_DEF @BASEBOARD_FAB2_LIB.BASEBOARD_FAB2(SCH_1):PVDDQ_DEF    I33 @BASEBOARD_FAB2_LIB.BASEBOARD_FAB2(SCH_1):PAGE38
  DH51 PVDDQ_DEF @BASEBOARD_FAB2_LIB.BASEBOARD_FAB2(SCH_1):PVDDQ_DEF    I33 @BASEBOARD_FAB2_LIB.BASEBOARD_FAB2(SCH_1):PAGE38
  DH53 PVDDQ_DEF @BASEBOARD_FAB2_LIB.BASEBOARD_FAB2(SCH_1):PVDDQ_DEF    I33 @BASEBOARD_FAB2_LIB.BASEBOARD_FAB2(SCH_1):PAGE38
  DH55 PVDDQ_DEF @BASEBOARD_FAB2_LIB.BASEBOARD_FAB2(SCH_1):PVDDQ_DEF    I33 @BASEBOARD_FAB2_LIB.BASEBOARD_FAB2(SCH_1):PAGE38
  DH57 PVDDQ_DEF @BASEBOARD_FAB2_LIB.BASEBOARD_FAB2(SCH_1):PVDDQ_DEF    I33 @BASEBOARD_FAB2_LIB.BASEBOARD_FAB2(SCH_1):PAGE38
  DH59 PVDDQ_DEF @BASEBOARD_FAB2_LIB.BASEBOARD_FAB2(SCH_1):PVDDQ_DEF    I33 @BASEBOARD_FAB2_LIB.BASEBOARD_FAB2(SCH_1):PAGE38
  DH61 PVDDQ_DEF @BASEBOARD_FAB2_LIB.BASEBOARD_FAB2(SCH_1):PVDDQ_DEF    I33 @BASEBOARD_FAB2_LIB.BASEBOARD_FAB2(SCH_1):PAGE38
  DH63 PVDDQ_DEF @BASEBOARD_FAB2_LIB.BASEBOARD_FAB2(SCH_1):PVDDQ_DEF    I33 @BASEBOARD_FAB2_LIB.BASEBOARD_FAB2(SCH_1):PAGE38
  DJ64 PVDDQ_DEF @BASEBOARD_FAB2_LIB.BASEBOARD_FAB2(SCH_1):PVDDQ_DEF    I33 @BASEBOARD_FAB2_LIB.BASEBOARD_FAB2(SCH_1):PAGE38
  DL46 PVDDQ_DEF @BASEBOARD_FAB2_LIB.BASEBOARD_FAB2(SCH_1):PVDDQ_DEF    I33 @BASEBOARD_FAB2_LIB.BASEBOARD_FAB2(SCH_1):PAGE38
  DL48 PVDDQ_DEF @BASEBOARD_FAB2_LIB.BASEBOARD_FAB2(SCH_1):PVDDQ_DEF    I33 @BASEBOARD_FAB2_LIB.BASEBOARD_FAB2(SCH_1):PAGE38
  DL50 PVDDQ_DEF @BASEBOARD_FAB2_LIB.BASEBOARD_FAB2(SCH_1):PVDDQ_DEF    I33 @BASEBOARD_FAB2_LIB.BASEBOARD_FAB2(SCH_1):PAGE38
  DL52 PVDDQ_DEF @BASEBOARD_FAB2_LIB.BASEBOARD_FAB2(SCH_1):PVDDQ_DEF    I33 @BASEBOARD_FAB2_LIB.BASEBOARD_FAB2(SCH_1):PAGE38
  DL54 PVDDQ_DEF @BASEBOARD_FAB2_LIB.BASEBOARD_FAB2(SCH_1):PVDDQ_DEF    I33 @BASEBOARD_FAB2_LIB.BASEBOARD_FAB2(SCH_1):PAGE38
  DL56 PVDDQ_DEF @BASEBOARD_FAB2_LIB.BASEBOARD_FAB2(SCH_1):PVDDQ_DEF    I33 @BASEBOARD_FAB2_LIB.BASEBOARD_FAB2(SCH_1):PAGE38
  DL58 PVDDQ_DEF @BASEBOARD_FAB2_LIB.BASEBOARD_FAB2(SCH_1):PVDDQ_DEF    I33 @BASEBOARD_FAB2_LIB.BASEBOARD_FAB2(SCH_1):PAGE38
  DL60 PVDDQ_DEF @BASEBOARD_FAB2_LIB.BASEBOARD_FAB2(SCH_1):PVDDQ_DEF    I33 @BASEBOARD_FAB2_LIB.BASEBOARD_FAB2(SCH_1):PAGE38
  DL62 PVDDQ_DEF @BASEBOARD_FAB2_LIB.BASEBOARD_FAB2(SCH_1):PVDDQ_DEF    I33 @BASEBOARD_FAB2_LIB.BASEBOARD_FAB2(SCH_1):PAGE38
  DU46 PVDDQ_DEF @BASEBOARD_FAB2_LIB.BASEBOARD_FAB2(SCH_1):PVDDQ_DEF    I33 @BASEBOARD_FAB2_LIB.BASEBOARD_FAB2(SCH_1):PAGE38
  DU48 PVDDQ_DEF @BASEBOARD_FAB2_LIB.BASEBOARD_FAB2(SCH_1):PVDDQ_DEF    I33 @BASEBOARD_FAB2_LIB.BASEBOARD_FAB2(SCH_1):PAGE38
  DU50 PVDDQ_DEF @BASEBOARD_FAB2_LIB.BASEBOARD_FAB2(SCH_1):PVDDQ_DEF    I33 @BASEBOARD_FAB2_LIB.BASEBOARD_FAB2(SCH_1):PAGE38
  DU52 PVDDQ_DEF @BASEBOARD_FAB2_LIB.BASEBOARD_FAB2(SCH_1):PVDDQ_DEF    I33 @BASEBOARD_FAB2_LIB.BASEBOARD_FAB2(SCH_1):PAGE38
  DU54 PVDDQ_DEF @BASEBOARD_FAB2_LIB.BASEBOARD_FAB2(SCH_1):PVDDQ_DEF    I33 @BASEBOARD_FAB2_LIB.BASEBOARD_FAB2(SCH_1):PAGE38
  DU56 PVDDQ_DEF @BASEBOARD_FAB2_LIB.BASEBOARD_FAB2(SCH_1):PVDDQ_DEF    I33 @BASEBOARD_FAB2_LIB.BASEBOARD_FAB2(SCH_1):PAGE38
  DU58 PVDDQ_DEF @BASEBOARD_FAB2_LIB.BASEBOARD_FAB2(SCH_1):PVDDQ_DEF    I33 @BASEBOARD_FAB2_LIB.BASEBOARD_FAB2(SCH_1):PAGE38
  DU60 PVDDQ_DEF @BASEBOARD_FAB2_LIB.BASEBOARD_FAB2(SCH_1):PVDDQ_DEF    I33 @BASEBOARD_FAB2_LIB.BASEBOARD_FAB2(SCH_1):PAGE38
  DU62 PVDDQ_DEF @BASEBOARD_FAB2_LIB.BASEBOARD_FAB2(SCH_1):PVDDQ_DEF    I33 @BASEBOARD_FAB2_LIB.BASEBOARD_FAB2(SCH_1):PAGE38
  DU64 PVDDQ_DEF @BASEBOARD_FAB2_LIB.BASEBOARD_FAB2(SCH_1):PVDDQ_DEF    I33 @BASEBOARD_FAB2_LIB.BASEBOARD_FAB2(SCH_1):PAGE38
  EC46 PVDDQ_DEF @BASEBOARD_FAB2_LIB.BASEBOARD_FAB2(SCH_1):PVDDQ_DEF    I33 @BASEBOARD_FAB2_LIB.BASEBOARD_FAB2(SCH_1):PAGE38
  EC48 PVDDQ_DEF @BASEBOARD_FAB2_LIB.BASEBOARD_FAB2(SCH_1):PVDDQ_DEF    I33 @BASEBOARD_FAB2_LIB.BASEBOARD_FAB2(SCH_1):PAGE38
  EC50 PVDDQ_DEF @BASEBOARD_FAB2_LIB.BASEBOARD_FAB2(SCH_1):PVDDQ_DEF    I33 @BASEBOARD_FAB2_LIB.BASEBOARD_FAB2(SCH_1):PAGE38
  EC52 PVDDQ_DEF @BASEBOARD_FAB2_LIB.BASEBOARD_FAB2(SCH_1):PVDDQ_DEF    I33 @BASEBOARD_FAB2_LIB.BASEBOARD_FAB2(SCH_1):PAGE38
  EC54 PVDDQ_DEF @BASEBOARD_FAB2_LIB.BASEBOARD_FAB2(SCH_1):PVDDQ_DEF    I33 @BASEBOARD_FAB2_LIB.BASEBOARD_FAB2(SCH_1):PAGE38
  EC56 PVDDQ_DEF @BASEBOARD_FAB2_LIB.BASEBOARD_FAB2(SCH_1):PVDDQ_DEF    I33 @BASEBOARD_FAB2_LIB.BASEBOARD_FAB2(SCH_1):PAGE38
  EC58 PVDDQ_DEF @BASEBOARD_FAB2_LIB.BASEBOARD_FAB2(SCH_1):PVDDQ_DEF    I33 @BASEBOARD_FAB2_LIB.BASEBOARD_FAB2(SCH_1):PAGE38
  EC60 PVDDQ_DEF @BASEBOARD_FAB2_LIB.BASEBOARD_FAB2(SCH_1):PVDDQ_DEF    I33 @BASEBOARD_FAB2_LIB.BASEBOARD_FAB2(SCH_1):PAGE38
  EC62 PVDDQ_DEF @BASEBOARD_FAB2_LIB.BASEBOARD_FAB2(SCH_1):PVDDQ_DEF    I33 @BASEBOARD_FAB2_LIB.BASEBOARD_FAB2(SCH_1):PAGE38
  EF49 PVDDQ_DEF @BASEBOARD_FAB2_LIB.BASEBOARD_FAB2(SCH_1):PVDDQ_DEF    I33 @BASEBOARD_FAB2_LIB.BASEBOARD_FAB2(SCH_1):PAGE38
  EF53 PVDDQ_DEF @BASEBOARD_FAB2_LIB.BASEBOARD_FAB2(SCH_1):PVDDQ_DEF    I33 @BASEBOARD_FAB2_LIB.BASEBOARD_FAB2(SCH_1):PAGE38
  EF59 PVDDQ_DEF @BASEBOARD_FAB2_LIB.BASEBOARD_FAB2(SCH_1):PVDDQ_DEF    I33 @BASEBOARD_FAB2_LIB.BASEBOARD_FAB2(SCH_1):PAGE38
  BY27 P1V8_MCP_CPU0 @BASEBOARD_FAB2_LIB.BASEBOARD_FAB2(SCH_1):P1V8_MCP_CPU0    I34 @BASEBOARD_FAB2_LIB.BASEBOARD_FAB2(SCH_1):PAGE38
  BV27 P1V8_MCP_CPU0 @BASEBOARD_FAB2_LIB.BASEBOARD_FAB2(SCH_1):P1V8_MCP_CPU0    I34 @BASEBOARD_FAB2_LIB.BASEBOARD_FAB2(SCH_1):PAGE38
  BU26 P1V8_MCP_CPU0 @BASEBOARD_FAB2_LIB.BASEBOARD_FAB2(SCH_1):P1V8_MCP_CPU0    I34 @BASEBOARD_FAB2_LIB.BASEBOARD_FAB2(SCH_1):PAGE38
  BT27 P1V8_MCP_CPU0 @BASEBOARD_FAB2_LIB.BASEBOARD_FAB2(SCH_1):P1V8_MCP_CPU0    I34 @BASEBOARD_FAB2_LIB.BASEBOARD_FAB2(SCH_1):PAGE38
  BM11 PVCCIOMCP_CPU0 @BASEBOARD_FAB2_LIB.BASEBOARD_FAB2(SCH_1):PVCCIOMCP_CPU0    I34 @BASEBOARD_FAB2_LIB.BASEBOARD_FAB2(SCH_1):PAGE38
  BN12 PVCCIOMCP_CPU0 @BASEBOARD_FAB2_LIB.BASEBOARD_FAB2(SCH_1):PVCCIOMCP_CPU0    I34 @BASEBOARD_FAB2_LIB.BASEBOARD_FAB2(SCH_1):PAGE38
  BN14 PVCCIOMCP_CPU0 @BASEBOARD_FAB2_LIB.BASEBOARD_FAB2(SCH_1):PVCCIOMCP_CPU0    I34 @BASEBOARD_FAB2_LIB.BASEBOARD_FAB2(SCH_1):PAGE38
  BP11 PVCCIOMCP_CPU0 @BASEBOARD_FAB2_LIB.BASEBOARD_FAB2(SCH_1):PVCCIOMCP_CPU0    I34 @BASEBOARD_FAB2_LIB.BASEBOARD_FAB2(SCH_1):PAGE38
  BP13 PVCCIOMCP_CPU0 @BASEBOARD_FAB2_LIB.BASEBOARD_FAB2(SCH_1):PVCCIOMCP_CPU0    I34 @BASEBOARD_FAB2_LIB.BASEBOARD_FAB2(SCH_1):PAGE38
  BP15 PVCCIOMCP_CPU0 @BASEBOARD_FAB2_LIB.BASEBOARD_FAB2(SCH_1):PVCCIOMCP_CPU0    I34 @BASEBOARD_FAB2_LIB.BASEBOARD_FAB2(SCH_1):PAGE38
  BR12 PVCCIOMCP_CPU0 @BASEBOARD_FAB2_LIB.BASEBOARD_FAB2(SCH_1):PVCCIOMCP_CPU0    I34 @BASEBOARD_FAB2_LIB.BASEBOARD_FAB2(SCH_1):PAGE38
  BR14 PVCCIOMCP_CPU0 @BASEBOARD_FAB2_LIB.BASEBOARD_FAB2(SCH_1):PVCCIOMCP_CPU0    I34 @BASEBOARD_FAB2_LIB.BASEBOARD_FAB2(SCH_1):PAGE38
  BT11 PVCCIOMCP_CPU0 @BASEBOARD_FAB2_LIB.BASEBOARD_FAB2(SCH_1):PVCCIOMCP_CPU0    I34 @BASEBOARD_FAB2_LIB.BASEBOARD_FAB2(SCH_1):PAGE38
  BT13 PVCCIOMCP_CPU0 @BASEBOARD_FAB2_LIB.BASEBOARD_FAB2(SCH_1):PVCCIOMCP_CPU0    I34 @BASEBOARD_FAB2_LIB.BASEBOARD_FAB2(SCH_1):PAGE38
  BT15 PVCCIOMCP_CPU0 @BASEBOARD_FAB2_LIB.BASEBOARD_FAB2(SCH_1):PVCCIOMCP_CPU0    I34 @BASEBOARD_FAB2_LIB.BASEBOARD_FAB2(SCH_1):PAGE38
  BU12 PVCCIOMCP_CPU0 @BASEBOARD_FAB2_LIB.BASEBOARD_FAB2(SCH_1):PVCCIOMCP_CPU0    I34 @BASEBOARD_FAB2_LIB.BASEBOARD_FAB2(SCH_1):PAGE38
  BU14 PVCCIOMCP_CPU0 @BASEBOARD_FAB2_LIB.BASEBOARD_FAB2(SCH_1):PVCCIOMCP_CPU0    I34 @BASEBOARD_FAB2_LIB.BASEBOARD_FAB2(SCH_1):PAGE38
  BV11 PVCCIOMCP_CPU0 @BASEBOARD_FAB2_LIB.BASEBOARD_FAB2(SCH_1):PVCCIOMCP_CPU0    I34 @BASEBOARD_FAB2_LIB.BASEBOARD_FAB2(SCH_1):PAGE38
  BV13 PVCCIOMCP_CPU0 @BASEBOARD_FAB2_LIB.BASEBOARD_FAB2(SCH_1):PVCCIOMCP_CPU0    I34 @BASEBOARD_FAB2_LIB.BASEBOARD_FAB2(SCH_1):PAGE38
  BV15 PVCCIOMCP_CPU0 @BASEBOARD_FAB2_LIB.BASEBOARD_FAB2(SCH_1):PVCCIOMCP_CPU0    I34 @BASEBOARD_FAB2_LIB.BASEBOARD_FAB2(SCH_1):PAGE38
  BD13 PVCCMCP_CPU0 @BASEBOARD_FAB2_LIB.BASEBOARD_FAB2(SCH_1):PVCCMCP_CPU0    I34 @BASEBOARD_FAB2_LIB.BASEBOARD_FAB2(SCH_1):PAGE38
  BE12 PVCCMCP_CPU0 @BASEBOARD_FAB2_LIB.BASEBOARD_FAB2(SCH_1):PVCCMCP_CPU0    I34 @BASEBOARD_FAB2_LIB.BASEBOARD_FAB2(SCH_1):PAGE38
  BE14 PVCCMCP_CPU0 @BASEBOARD_FAB2_LIB.BASEBOARD_FAB2(SCH_1):PVCCMCP_CPU0    I34 @BASEBOARD_FAB2_LIB.BASEBOARD_FAB2(SCH_1):PAGE38
  BF11 PVCCMCP_CPU0 @BASEBOARD_FAB2_LIB.BASEBOARD_FAB2(SCH_1):PVCCMCP_CPU0    I34 @BASEBOARD_FAB2_LIB.BASEBOARD_FAB2(SCH_1):PAGE38
  BF13 PVCCMCP_CPU0 @BASEBOARD_FAB2_LIB.BASEBOARD_FAB2(SCH_1):PVCCMCP_CPU0    I34 @BASEBOARD_FAB2_LIB.BASEBOARD_FAB2(SCH_1):PAGE38
  BG12 PVCCMCP_CPU0 @BASEBOARD_FAB2_LIB.BASEBOARD_FAB2(SCH_1):PVCCMCP_CPU0    I34 @BASEBOARD_FAB2_LIB.BASEBOARD_FAB2(SCH_1):PAGE38
  BG14 PVCCMCP_CPU0 @BASEBOARD_FAB2_LIB.BASEBOARD_FAB2(SCH_1):PVCCMCP_CPU0    I34 @BASEBOARD_FAB2_LIB.BASEBOARD_FAB2(SCH_1):PAGE38
  BH13 PVCCMCP_CPU0 @BASEBOARD_FAB2_LIB.BASEBOARD_FAB2(SCH_1):PVCCMCP_CPU0    I34 @BASEBOARD_FAB2_LIB.BASEBOARD_FAB2(SCH_1):PAGE38
  BJ12 PVCCMCP_CPU0 @BASEBOARD_FAB2_LIB.BASEBOARD_FAB2(SCH_1):PVCCMCP_CPU0    I34 @BASEBOARD_FAB2_LIB.BASEBOARD_FAB2(SCH_1):PAGE38
  BJ14 PVCCMCP_CPU0 @BASEBOARD_FAB2_LIB.BASEBOARD_FAB2(SCH_1):PVCCMCP_CPU0    I34 @BASEBOARD_FAB2_LIB.BASEBOARD_FAB2(SCH_1):PAGE38
  BK13 PVCCMCP_CPU0 @BASEBOARD_FAB2_LIB.BASEBOARD_FAB2(SCH_1):PVCCMCP_CPU0    I34 @BASEBOARD_FAB2_LIB.BASEBOARD_FAB2(SCH_1):PAGE38
  BK15 PVCCMCP_CPU0 @BASEBOARD_FAB2_LIB.BASEBOARD_FAB2(SCH_1):PVCCMCP_CPU0    I34 @BASEBOARD_FAB2_LIB.BASEBOARD_FAB2(SCH_1):PAGE38
  BL14 PVCCMCP_CPU0 @BASEBOARD_FAB2_LIB.BASEBOARD_FAB2(SCH_1):PVCCMCP_CPU0    I34 @BASEBOARD_FAB2_LIB.BASEBOARD_FAB2(SCH_1):PAGE38
    A8 PVPP_ABC @BASEBOARD_FAB2_LIB.BASEBOARD_FAB2(SCH_1):PVPP_ABC    I34 @BASEBOARD_FAB2_LIB.BASEBOARD_FAB2(SCH_1):PAGE38
   A10 PVPP_ABC @BASEBOARD_FAB2_LIB.BASEBOARD_FAB2(SCH_1):PVPP_ABC    I34 @BASEBOARD_FAB2_LIB.BASEBOARD_FAB2(SCH_1):PAGE38
   A12 PVPP_ABC @BASEBOARD_FAB2_LIB.BASEBOARD_FAB2(SCH_1):PVPP_ABC    I34 @BASEBOARD_FAB2_LIB.BASEBOARD_FAB2(SCH_1):PAGE38
   B11 PVPP_ABC @BASEBOARD_FAB2_LIB.BASEBOARD_FAB2(SCH_1):PVPP_ABC    I34 @BASEBOARD_FAB2_LIB.BASEBOARD_FAB2(SCH_1):PAGE38
  CY55 P3V3_STBY @BASEBOARD_FAB2_LIB.BASEBOARD_FAB2(SCH_1):P3V3_STBY    I34 @BASEBOARD_FAB2_LIB.BASEBOARD_FAB2(SCH_1):PAGE38
  AR28 PVCCIO_CPU0 @BASEBOARD_FAB2_LIB.BASEBOARD_FAB2(SCH_1):PVCCIO_CPU0    I34 @BASEBOARD_FAB2_LIB.BASEBOARD_FAB2(SCH_1):PAGE38
  AL28 PVCCIO_CPU0 @BASEBOARD_FAB2_LIB.BASEBOARD_FAB2(SCH_1):PVCCIO_CPU0    I34 @BASEBOARD_FAB2_LIB.BASEBOARD_FAB2(SCH_1):PAGE38
  AM29 PVCCIO_CPU0 @BASEBOARD_FAB2_LIB.BASEBOARD_FAB2(SCH_1):PVCCIO_CPU0    I34 @BASEBOARD_FAB2_LIB.BASEBOARD_FAB2(SCH_1):PAGE38
  AG34 PVCCIO_CPU0 @BASEBOARD_FAB2_LIB.BASEBOARD_FAB2(SCH_1):PVCCIO_CPU0    I34 @BASEBOARD_FAB2_LIB.BASEBOARD_FAB2(SCH_1):PAGE38
  AE34 PVCCIO_CPU0 @BASEBOARD_FAB2_LIB.BASEBOARD_FAB2(SCH_1):PVCCIO_CPU0    I34 @BASEBOARD_FAB2_LIB.BASEBOARD_FAB2(SCH_1):PAGE38
  AD35 PVCCIO_CPU0 @BASEBOARD_FAB2_LIB.BASEBOARD_FAB2(SCH_1):PVCCIO_CPU0    I34 @BASEBOARD_FAB2_LIB.BASEBOARD_FAB2(SCH_1):PAGE38
  AF35 PVCCIO_CPU0 @BASEBOARD_FAB2_LIB.BASEBOARD_FAB2(SCH_1):PVCCIO_CPU0    I34 @BASEBOARD_FAB2_LIB.BASEBOARD_FAB2(SCH_1):PAGE38
  AC36 PVCCIO_CPU0 @BASEBOARD_FAB2_LIB.BASEBOARD_FAB2(SCH_1):PVCCIO_CPU0    I34 @BASEBOARD_FAB2_LIB.BASEBOARD_FAB2(SCH_1):PAGE38
  AD37 PVCCIO_CPU0 @BASEBOARD_FAB2_LIB.BASEBOARD_FAB2(SCH_1):PVCCIO_CPU0    I34 @BASEBOARD_FAB2_LIB.BASEBOARD_FAB2(SCH_1):PAGE38
  AE36 PVCCIO_CPU0 @BASEBOARD_FAB2_LIB.BASEBOARD_FAB2(SCH_1):PVCCIO_CPU0    I34 @BASEBOARD_FAB2_LIB.BASEBOARD_FAB2(SCH_1):PAGE38
  BF27 PVCCIO_CPU0 @BASEBOARD_FAB2_LIB.BASEBOARD_FAB2(SCH_1):PVCCIO_CPU0    I34 @BASEBOARD_FAB2_LIB.BASEBOARD_FAB2(SCH_1):PAGE38
  BG26 PVCCIO_CPU0 @BASEBOARD_FAB2_LIB.BASEBOARD_FAB2(SCH_1):PVCCIO_CPU0    I34 @BASEBOARD_FAB2_LIB.BASEBOARD_FAB2(SCH_1):PAGE38
  BH25 PVCCIO_CPU0 @BASEBOARD_FAB2_LIB.BASEBOARD_FAB2(SCH_1):PVCCIO_CPU0    I34 @BASEBOARD_FAB2_LIB.BASEBOARD_FAB2(SCH_1):PAGE38
  BH27 PVCCIO_CPU0 @BASEBOARD_FAB2_LIB.BASEBOARD_FAB2(SCH_1):PVCCIO_CPU0    I34 @BASEBOARD_FAB2_LIB.BASEBOARD_FAB2(SCH_1):PAGE38
  BJ26 PVCCIO_CPU0 @BASEBOARD_FAB2_LIB.BASEBOARD_FAB2(SCH_1):PVCCIO_CPU0    I34 @BASEBOARD_FAB2_LIB.BASEBOARD_FAB2(SCH_1):PAGE38
  BK25 PVCCIO_CPU0 @BASEBOARD_FAB2_LIB.BASEBOARD_FAB2(SCH_1):PVCCIO_CPU0    I34 @BASEBOARD_FAB2_LIB.BASEBOARD_FAB2(SCH_1):PAGE38
  BK27 PVCCIO_CPU0 @BASEBOARD_FAB2_LIB.BASEBOARD_FAB2(SCH_1):PVCCIO_CPU0    I34 @BASEBOARD_FAB2_LIB.BASEBOARD_FAB2(SCH_1):PAGE38
  BL26 PVCCIO_CPU0 @BASEBOARD_FAB2_LIB.BASEBOARD_FAB2(SCH_1):PVCCIO_CPU0    I34 @BASEBOARD_FAB2_LIB.BASEBOARD_FAB2(SCH_1):PAGE38
  BM27 PVCCIO_CPU0 @BASEBOARD_FAB2_LIB.BASEBOARD_FAB2(SCH_1):PVCCIO_CPU0    I34 @BASEBOARD_FAB2_LIB.BASEBOARD_FAB2(SCH_1):PAGE38
  CH27 PVCCIO_CPU0 @BASEBOARD_FAB2_LIB.BASEBOARD_FAB2(SCH_1):PVCCIO_CPU0    I34 @BASEBOARD_FAB2_LIB.BASEBOARD_FAB2(SCH_1):PAGE38
  CJ28 PVCCIO_CPU0 @BASEBOARD_FAB2_LIB.BASEBOARD_FAB2(SCH_1):PVCCIO_CPU0    I34 @BASEBOARD_FAB2_LIB.BASEBOARD_FAB2(SCH_1):PAGE38
  CC26 PVCCIO_CPU0 @BASEBOARD_FAB2_LIB.BASEBOARD_FAB2(SCH_1):PVCCIO_CPU0    I34 @BASEBOARD_FAB2_LIB.BASEBOARD_FAB2(SCH_1):PAGE38
  CD27 PVCCIO_CPU0 @BASEBOARD_FAB2_LIB.BASEBOARD_FAB2(SCH_1):PVCCIO_CPU0    I34 @BASEBOARD_FAB2_LIB.BASEBOARD_FAB2(SCH_1):PAGE38
  CF27 PVCCIO_CPU0 @BASEBOARD_FAB2_LIB.BASEBOARD_FAB2(SCH_1):PVCCIO_CPU0    I34 @BASEBOARD_FAB2_LIB.BASEBOARD_FAB2(SCH_1):PAGE38
  AV27 PVCCIO_CPU0 @BASEBOARD_FAB2_LIB.BASEBOARD_FAB2(SCH_1):PVCCIO_CPU0    I34 @BASEBOARD_FAB2_LIB.BASEBOARD_FAB2(SCH_1):PAGE38
  AW26 PVCCIO_CPU0 @BASEBOARD_FAB2_LIB.BASEBOARD_FAB2(SCH_1):PVCCIO_CPU0    I34 @BASEBOARD_FAB2_LIB.BASEBOARD_FAB2(SCH_1):PAGE38
  AY27 PVCCIO_CPU0 @BASEBOARD_FAB2_LIB.BASEBOARD_FAB2(SCH_1):PVCCIO_CPU0    I34 @BASEBOARD_FAB2_LIB.BASEBOARD_FAB2(SCH_1):PAGE38
  BA26 PVCCIO_CPU0 @BASEBOARD_FAB2_LIB.BASEBOARD_FAB2(SCH_1):PVCCIO_CPU0    I34 @BASEBOARD_FAB2_LIB.BASEBOARD_FAB2(SCH_1):PAGE38
  BB27 PVCCIO_CPU0 @BASEBOARD_FAB2_LIB.BASEBOARD_FAB2(SCH_1):PVCCIO_CPU0    I34 @BASEBOARD_FAB2_LIB.BASEBOARD_FAB2(SCH_1):PAGE38
  BC26 PVCCIO_CPU0 @BASEBOARD_FAB2_LIB.BASEBOARD_FAB2(SCH_1):PVCCIO_CPU0    I34 @BASEBOARD_FAB2_LIB.BASEBOARD_FAB2(SCH_1):PAGE38
   W10 PVCCIO_CPU0 @BASEBOARD_FAB2_LIB.BASEBOARD_FAB2(SCH_1):PVCCIO_CPU0    I34 @BASEBOARD_FAB2_LIB.BASEBOARD_FAB2(SCH_1):PAGE38
   N18 PVCCIO_CPU0 @BASEBOARD_FAB2_LIB.BASEBOARD_FAB2(SCH_1):PVCCIO_CPU0    I34 @BASEBOARD_FAB2_LIB.BASEBOARD_FAB2(SCH_1):PAGE38
    M9 PVCCIO_CPU0 @BASEBOARD_FAB2_LIB.BASEBOARD_FAB2(SCH_1):PVCCIO_CPU0    I34 @BASEBOARD_FAB2_LIB.BASEBOARD_FAB2(SCH_1):PAGE38
    M7 PVCCIO_CPU0 @BASEBOARD_FAB2_LIB.BASEBOARD_FAB2(SCH_1):PVCCIO_CPU0    I34 @BASEBOARD_FAB2_LIB.BASEBOARD_FAB2(SCH_1):PAGE38
   K15 PVCCIO_CPU0 @BASEBOARD_FAB2_LIB.BASEBOARD_FAB2(SCH_1):PVCCIO_CPU0    I34 @BASEBOARD_FAB2_LIB.BASEBOARD_FAB2(SCH_1):PAGE38
    J2 PVCCIO_CPU0 @BASEBOARD_FAB2_LIB.BASEBOARD_FAB2(SCH_1):PVCCIO_CPU0    I34 @BASEBOARD_FAB2_LIB.BASEBOARD_FAB2(SCH_1):PAGE38
  EB15 PVCCIO_CPU0 @BASEBOARD_FAB2_LIB.BASEBOARD_FAB2(SCH_1):PVCCIO_CPU0    I34 @BASEBOARD_FAB2_LIB.BASEBOARD_FAB2(SCH_1):PAGE38
  EA12 PVCCIO_CPU0 @BASEBOARD_FAB2_LIB.BASEBOARD_FAB2(SCH_1):PVCCIO_CPU0    I34 @BASEBOARD_FAB2_LIB.BASEBOARD_FAB2(SCH_1):PAGE38
  DU20 PVCCIO_CPU0 @BASEBOARD_FAB2_LIB.BASEBOARD_FAB2(SCH_1):PVCCIO_CPU0    I34 @BASEBOARD_FAB2_LIB.BASEBOARD_FAB2(SCH_1):PAGE38
   DR2 PVCCIO_CPU0 @BASEBOARD_FAB2_LIB.BASEBOARD_FAB2(SCH_1):PVCCIO_CPU0    I34 @BASEBOARD_FAB2_LIB.BASEBOARD_FAB2(SCH_1):PAGE38
  DR10 PVCCIO_CPU0 @BASEBOARD_FAB2_LIB.BASEBOARD_FAB2(SCH_1):PVCCIO_CPU0    I34 @BASEBOARD_FAB2_LIB.BASEBOARD_FAB2(SCH_1):PAGE38
  DP19 PVCCIO_CPU0 @BASEBOARD_FAB2_LIB.BASEBOARD_FAB2(SCH_1):PVCCIO_CPU0    I34 @BASEBOARD_FAB2_LIB.BASEBOARD_FAB2(SCH_1):PAGE38
   DN8 PVCCIO_CPU0 @BASEBOARD_FAB2_LIB.BASEBOARD_FAB2(SCH_1):PVCCIO_CPU0    I34 @BASEBOARD_FAB2_LIB.BASEBOARD_FAB2(SCH_1):PAGE38
  DM17 PVCCIO_CPU0 @BASEBOARD_FAB2_LIB.BASEBOARD_FAB2(SCH_1):PVCCIO_CPU0    I34 @BASEBOARD_FAB2_LIB.BASEBOARD_FAB2(SCH_1):PAGE38
  DJ16 PVCCIO_CPU0 @BASEBOARD_FAB2_LIB.BASEBOARD_FAB2(SCH_1):PVCCIO_CPU0    I34 @BASEBOARD_FAB2_LIB.BASEBOARD_FAB2(SCH_1):PAGE38
   H13 PVCCIO_CPU0 @BASEBOARD_FAB2_LIB.BASEBOARD_FAB2(SCH_1):PVCCIO_CPU0    I34 @BASEBOARD_FAB2_LIB.BASEBOARD_FAB2(SCH_1):PAGE38
   J10 PVCCIO_CPU0 @BASEBOARD_FAB2_LIB.BASEBOARD_FAB2(SCH_1):PVCCIO_CPU0    I34 @BASEBOARD_FAB2_LIB.BASEBOARD_FAB2(SCH_1):PAGE38
   L14 PVCCIO_CPU0 @BASEBOARD_FAB2_LIB.BASEBOARD_FAB2(SCH_1):PVCCIO_CPU0    I34 @BASEBOARD_FAB2_LIB.BASEBOARD_FAB2(SCH_1):PAGE38
   L16 PVCCIO_CPU0 @BASEBOARD_FAB2_LIB.BASEBOARD_FAB2(SCH_1):PVCCIO_CPU0    I34 @BASEBOARD_FAB2_LIB.BASEBOARD_FAB2(SCH_1):PAGE38
   DH7 PVCCIO_CPU0 @BASEBOARD_FAB2_LIB.BASEBOARD_FAB2(SCH_1):PVCCIO_CPU0    I34 @BASEBOARD_FAB2_LIB.BASEBOARD_FAB2(SCH_1):PAGE38
   DG8 PVCCIO_CPU0 @BASEBOARD_FAB2_LIB.BASEBOARD_FAB2(SCH_1):PVCCIO_CPU0    I34 @BASEBOARD_FAB2_LIB.BASEBOARD_FAB2(SCH_1):PAGE38
   M11 PVCCIO_CPU0 @BASEBOARD_FAB2_LIB.BASEBOARD_FAB2(SCH_1):PVCCIO_CPU0    I34 @BASEBOARD_FAB2_LIB.BASEBOARD_FAB2(SCH_1):PAGE38
   M21 PVCCIO_CPU0 @BASEBOARD_FAB2_LIB.BASEBOARD_FAB2(SCH_1):PVCCIO_CPU0    I34 @BASEBOARD_FAB2_LIB.BASEBOARD_FAB2(SCH_1):PAGE38
    P5 PVCCIO_CPU0 @BASEBOARD_FAB2_LIB.BASEBOARD_FAB2(SCH_1):PVCCIO_CPU0    I34 @BASEBOARD_FAB2_LIB.BASEBOARD_FAB2(SCH_1):PAGE38
    T3 PVCCIO_CPU0 @BASEBOARD_FAB2_LIB.BASEBOARD_FAB2(SCH_1):PVCCIO_CPU0    I34 @BASEBOARD_FAB2_LIB.BASEBOARD_FAB2(SCH_1):PAGE38
   U14 PVCCIO_CPU0 @BASEBOARD_FAB2_LIB.BASEBOARD_FAB2(SCH_1):PVCCIO_CPU0    I34 @BASEBOARD_FAB2_LIB.BASEBOARD_FAB2(SCH_1):PAGE38
  DF21 PVCCIO_CPU0 @BASEBOARD_FAB2_LIB.BASEBOARD_FAB2(SCH_1):PVCCIO_CPU0    I34 @BASEBOARD_FAB2_LIB.BASEBOARD_FAB2(SCH_1):PAGE38
    W4 PVCCIO_CPU0 @BASEBOARD_FAB2_LIB.BASEBOARD_FAB2(SCH_1):PVCCIO_CPU0    I34 @BASEBOARD_FAB2_LIB.BASEBOARD_FAB2(SCH_1):PAGE38
    W6 PVCCIO_CPU0 @BASEBOARD_FAB2_LIB.BASEBOARD_FAB2(SCH_1):PVCCIO_CPU0    I34 @BASEBOARD_FAB2_LIB.BASEBOARD_FAB2(SCH_1):PAGE38
  AA10 PVCCIO_CPU0 @BASEBOARD_FAB2_LIB.BASEBOARD_FAB2(SCH_1):PVCCIO_CPU0    I34 @BASEBOARD_FAB2_LIB.BASEBOARD_FAB2(SCH_1):PAGE38
  AC20 PVCCIO_CPU0 @BASEBOARD_FAB2_LIB.BASEBOARD_FAB2(SCH_1):PVCCIO_CPU0    I34 @BASEBOARD_FAB2_LIB.BASEBOARD_FAB2(SCH_1):PAGE38
   AC4 PVCCIO_CPU0 @BASEBOARD_FAB2_LIB.BASEBOARD_FAB2(SCH_1):PVCCIO_CPU0    I34 @BASEBOARD_FAB2_LIB.BASEBOARD_FAB2(SCH_1):PAGE38
   AH9 PVCCIO_CPU0 @BASEBOARD_FAB2_LIB.BASEBOARD_FAB2(SCH_1):PVCCIO_CPU0    I34 @BASEBOARD_FAB2_LIB.BASEBOARD_FAB2(SCH_1):PAGE38
  DF13 PVCCIO_CPU0 @BASEBOARD_FAB2_LIB.BASEBOARD_FAB2(SCH_1):PVCCIO_CPU0    I34 @BASEBOARD_FAB2_LIB.BASEBOARD_FAB2(SCH_1):PAGE38
  AN10 PVCCIO_CPU0 @BASEBOARD_FAB2_LIB.BASEBOARD_FAB2(SCH_1):PVCCIO_CPU0    I34 @BASEBOARD_FAB2_LIB.BASEBOARD_FAB2(SCH_1):PAGE38
   DD7 PVCCIO_CPU0 @BASEBOARD_FAB2_LIB.BASEBOARD_FAB2(SCH_1):PVCCIO_CPU0    I34 @BASEBOARD_FAB2_LIB.BASEBOARD_FAB2(SCH_1):PAGE38
  AT11 PVCCIO_CPU0 @BASEBOARD_FAB2_LIB.BASEBOARD_FAB2(SCH_1):PVCCIO_CPU0    I34 @BASEBOARD_FAB2_LIB.BASEBOARD_FAB2(SCH_1):PAGE38
   AW6 PVCCIO_CPU0 @BASEBOARD_FAB2_LIB.BASEBOARD_FAB2(SCH_1):PVCCIO_CPU0    I34 @BASEBOARD_FAB2_LIB.BASEBOARD_FAB2(SCH_1):PAGE38
  AY11 PVCCIO_CPU0 @BASEBOARD_FAB2_LIB.BASEBOARD_FAB2(SCH_1):PVCCIO_CPU0    I34 @BASEBOARD_FAB2_LIB.BASEBOARD_FAB2(SCH_1):PAGE38
  BA24 PVCCIO_CPU0 @BASEBOARD_FAB2_LIB.BASEBOARD_FAB2(SCH_1):PVCCIO_CPU0    I34 @BASEBOARD_FAB2_LIB.BASEBOARD_FAB2(SCH_1):PAGE38
   BB5 PVCCIO_CPU0 @BASEBOARD_FAB2_LIB.BASEBOARD_FAB2(SCH_1):PVCCIO_CPU0    I34 @BASEBOARD_FAB2_LIB.BASEBOARD_FAB2(SCH_1):PAGE38
  DA14 PVCCIO_CPU0 @BASEBOARD_FAB2_LIB.BASEBOARD_FAB2(SCH_1):PVCCIO_CPU0    I34 @BASEBOARD_FAB2_LIB.BASEBOARD_FAB2(SCH_1):PAGE38
  BF23 PVCCIO_CPU0 @BASEBOARD_FAB2_LIB.BASEBOARD_FAB2(SCH_1):PVCCIO_CPU0    I34 @BASEBOARD_FAB2_LIB.BASEBOARD_FAB2(SCH_1):PAGE38
  BJ24 PVCCIO_CPU0 @BASEBOARD_FAB2_LIB.BASEBOARD_FAB2(SCH_1):PVCCIO_CPU0    I34 @BASEBOARD_FAB2_LIB.BASEBOARD_FAB2(SCH_1):PAGE38
  BP25 PVCCIO_CPU0 @BASEBOARD_FAB2_LIB.BASEBOARD_FAB2(SCH_1):PVCCIO_CPU0    I34 @BASEBOARD_FAB2_LIB.BASEBOARD_FAB2(SCH_1):PAGE38
  CB13 PVCCIO_CPU0 @BASEBOARD_FAB2_LIB.BASEBOARD_FAB2(SCH_1):PVCCIO_CPU0    I34 @BASEBOARD_FAB2_LIB.BASEBOARD_FAB2(SCH_1):PAGE38
  CB17 PVCCIO_CPU0 @BASEBOARD_FAB2_LIB.BASEBOARD_FAB2(SCH_1):PVCCIO_CPU0    I34 @BASEBOARD_FAB2_LIB.BASEBOARD_FAB2(SCH_1):PAGE38
   CD9 PVCCIO_CPU0 @BASEBOARD_FAB2_LIB.BASEBOARD_FAB2(SCH_1):PVCCIO_CPU0    I34 @BASEBOARD_FAB2_LIB.BASEBOARD_FAB2(SCH_1):PAGE38
  CE18 PVCCIO_CPU0 @BASEBOARD_FAB2_LIB.BASEBOARD_FAB2(SCH_1):PVCCIO_CPU0    I34 @BASEBOARD_FAB2_LIB.BASEBOARD_FAB2(SCH_1):PAGE38
    D7 PVCCIO_CPU0 @BASEBOARD_FAB2_LIB.BASEBOARD_FAB2(SCH_1):PVCCIO_CPU0    I34 @BASEBOARD_FAB2_LIB.BASEBOARD_FAB2(SCH_1):PAGE38
   CH9 PVCCIO_CPU0 @BASEBOARD_FAB2_LIB.BASEBOARD_FAB2(SCH_1):PVCCIO_CPU0    I34 @BASEBOARD_FAB2_LIB.BASEBOARD_FAB2(SCH_1):PAGE38
   CV7 PVCCIO_CPU0 @BASEBOARD_FAB2_LIB.BASEBOARD_FAB2(SCH_1):PVCCIO_CPU0    I34 @BASEBOARD_FAB2_LIB.BASEBOARD_FAB2(SCH_1):PAGE38
   CK5 PVCCIO_CPU0 @BASEBOARD_FAB2_LIB.BASEBOARD_FAB2(SCH_1):PVCCIO_CPU0    I34 @BASEBOARD_FAB2_LIB.BASEBOARD_FAB2(SCH_1):PAGE38
  CL12 PVCCIO_CPU0 @BASEBOARD_FAB2_LIB.BASEBOARD_FAB2(SCH_1):PVCCIO_CPU0    I34 @BASEBOARD_FAB2_LIB.BASEBOARD_FAB2(SCH_1):PAGE38
  CM15 PVCCIO_CPU0 @BASEBOARD_FAB2_LIB.BASEBOARD_FAB2(SCH_1):PVCCIO_CPU0    I34 @BASEBOARD_FAB2_LIB.BASEBOARD_FAB2(SCH_1):PAGE38
  CB65 PVSA_CPU0 @BASEBOARD_FAB2_LIB.BASEBOARD_FAB2(SCH_1):PVSA_CPU0    I34 @BASEBOARD_FAB2_LIB.BASEBOARD_FAB2(SCH_1):PAGE38
  CB67 PVSA_CPU0 @BASEBOARD_FAB2_LIB.BASEBOARD_FAB2(SCH_1):PVSA_CPU0    I34 @BASEBOARD_FAB2_LIB.BASEBOARD_FAB2(SCH_1):PAGE38
  CB69 PVSA_CPU0 @BASEBOARD_FAB2_LIB.BASEBOARD_FAB2(SCH_1):PVSA_CPU0    I34 @BASEBOARD_FAB2_LIB.BASEBOARD_FAB2(SCH_1):PAGE38
  CC66 PVSA_CPU0 @BASEBOARD_FAB2_LIB.BASEBOARD_FAB2(SCH_1):PVSA_CPU0    I34 @BASEBOARD_FAB2_LIB.BASEBOARD_FAB2(SCH_1):PAGE38
  CC68 PVSA_CPU0 @BASEBOARD_FAB2_LIB.BASEBOARD_FAB2(SCH_1):PVSA_CPU0    I34 @BASEBOARD_FAB2_LIB.BASEBOARD_FAB2(SCH_1):PAGE38
  CC70 PVSA_CPU0 @BASEBOARD_FAB2_LIB.BASEBOARD_FAB2(SCH_1):PVSA_CPU0    I34 @BASEBOARD_FAB2_LIB.BASEBOARD_FAB2(SCH_1):PAGE38
  CD65 PVSA_CPU0 @BASEBOARD_FAB2_LIB.BASEBOARD_FAB2(SCH_1):PVSA_CPU0    I34 @BASEBOARD_FAB2_LIB.BASEBOARD_FAB2(SCH_1):PAGE38
  CD67 PVSA_CPU0 @BASEBOARD_FAB2_LIB.BASEBOARD_FAB2(SCH_1):PVSA_CPU0    I34 @BASEBOARD_FAB2_LIB.BASEBOARD_FAB2(SCH_1):PAGE38
  CD69 PVSA_CPU0 @BASEBOARD_FAB2_LIB.BASEBOARD_FAB2(SCH_1):PVSA_CPU0    I34 @BASEBOARD_FAB2_LIB.BASEBOARD_FAB2(SCH_1):PAGE38
  CD71 PVSA_CPU0 @BASEBOARD_FAB2_LIB.BASEBOARD_FAB2(SCH_1):PVSA_CPU0    I34 @BASEBOARD_FAB2_LIB.BASEBOARD_FAB2(SCH_1):PAGE38
  CE64 PVSA_CPU0 @BASEBOARD_FAB2_LIB.BASEBOARD_FAB2(SCH_1):PVSA_CPU0    I34 @BASEBOARD_FAB2_LIB.BASEBOARD_FAB2(SCH_1):PAGE38
  CE66 PVSA_CPU0 @BASEBOARD_FAB2_LIB.BASEBOARD_FAB2(SCH_1):PVSA_CPU0    I34 @BASEBOARD_FAB2_LIB.BASEBOARD_FAB2(SCH_1):PAGE38
  CE68 PVSA_CPU0 @BASEBOARD_FAB2_LIB.BASEBOARD_FAB2(SCH_1):PVSA_CPU0    I34 @BASEBOARD_FAB2_LIB.BASEBOARD_FAB2(SCH_1):PAGE38
  CE72 PVSA_CPU0 @BASEBOARD_FAB2_LIB.BASEBOARD_FAB2(SCH_1):PVSA_CPU0    I34 @BASEBOARD_FAB2_LIB.BASEBOARD_FAB2(SCH_1):PAGE38
  CE74 PVSA_CPU0 @BASEBOARD_FAB2_LIB.BASEBOARD_FAB2(SCH_1):PVSA_CPU0    I34 @BASEBOARD_FAB2_LIB.BASEBOARD_FAB2(SCH_1):PAGE38
  CF65 PVSA_CPU0 @BASEBOARD_FAB2_LIB.BASEBOARD_FAB2(SCH_1):PVSA_CPU0    I34 @BASEBOARD_FAB2_LIB.BASEBOARD_FAB2(SCH_1):PAGE38
  CF67 PVSA_CPU0 @BASEBOARD_FAB2_LIB.BASEBOARD_FAB2(SCH_1):PVSA_CPU0    I34 @BASEBOARD_FAB2_LIB.BASEBOARD_FAB2(SCH_1):PAGE38
  CF73 PVSA_CPU0 @BASEBOARD_FAB2_LIB.BASEBOARD_FAB2(SCH_1):PVSA_CPU0    I34 @BASEBOARD_FAB2_LIB.BASEBOARD_FAB2(SCH_1):PAGE38
  CF75 PVSA_CPU0 @BASEBOARD_FAB2_LIB.BASEBOARD_FAB2(SCH_1):PVSA_CPU0    I34 @BASEBOARD_FAB2_LIB.BASEBOARD_FAB2(SCH_1):PAGE38
  CG64 PVSA_CPU0 @BASEBOARD_FAB2_LIB.BASEBOARD_FAB2(SCH_1):PVSA_CPU0    I34 @BASEBOARD_FAB2_LIB.BASEBOARD_FAB2(SCH_1):PAGE38
  CG66 PVSA_CPU0 @BASEBOARD_FAB2_LIB.BASEBOARD_FAB2(SCH_1):PVSA_CPU0    I34 @BASEBOARD_FAB2_LIB.BASEBOARD_FAB2(SCH_1):PAGE38
  CG74 PVSA_CPU0 @BASEBOARD_FAB2_LIB.BASEBOARD_FAB2(SCH_1):PVSA_CPU0    I34 @BASEBOARD_FAB2_LIB.BASEBOARD_FAB2(SCH_1):PAGE38
  CH65 PVSA_CPU0 @BASEBOARD_FAB2_LIB.BASEBOARD_FAB2(SCH_1):PVSA_CPU0    I34 @BASEBOARD_FAB2_LIB.BASEBOARD_FAB2(SCH_1):PAGE38
  CH75 PVSA_CPU0 @BASEBOARD_FAB2_LIB.BASEBOARD_FAB2(SCH_1):PVSA_CPU0    I34 @BASEBOARD_FAB2_LIB.BASEBOARD_FAB2(SCH_1):PAGE38
  CJ64 PVSA_CPU0 @BASEBOARD_FAB2_LIB.BASEBOARD_FAB2(SCH_1):PVSA_CPU0    I34 @BASEBOARD_FAB2_LIB.BASEBOARD_FAB2(SCH_1):PAGE38
  CJ66 PVSA_CPU0 @BASEBOARD_FAB2_LIB.BASEBOARD_FAB2(SCH_1):PVSA_CPU0    I34 @BASEBOARD_FAB2_LIB.BASEBOARD_FAB2(SCH_1):PAGE38
  BT17 VSENSE_PVCCIOMCP_CPU0_SKT_VSEN @BASEBOARD_FAB2_LIB.BASEBOARD_FAB2(SCH_1):VSENSE_PVCCIOMCP_CPU0_SKT_VSEN   I127 @BASEBOARD_FAB2_LIB.BASEBOARD_FAB2(SCH_1):PAGE39
  BU16 VSENSE_PVCCIOMCP_CPU0_SKT_VRTN @BASEBOARD_FAB2_LIB.BASEBOARD_FAB2(SCH_1):VSENSE_PVCCIOMCP_CPU0_SKT_VRTN   I127 @BASEBOARD_FAB2_LIB.BASEBOARD_FAB2(SCH_1):PAGE39
  BN16 VSENSE_PVCCMCP_CPU0_SKT_VSEN @BASEBOARD_FAB2_LIB.BASEBOARD_FAB2(SCH_1):VSENSE_PVCCMCP_CPU0_SKT_VSEN   I127 @BASEBOARD_FAB2_LIB.BASEBOARD_FAB2(SCH_1):PAGE39
  BL16 VSENSE_PVCCMCP_CPU0_SKT_VRTN @BASEBOARD_FAB2_LIB.BASEBOARD_FAB2(SCH_1):VSENSE_PVCCMCP_CPU0_SKT_VRTN   I127 @BASEBOARD_FAB2_LIB.BASEBOARD_FAB2(SCH_1):PAGE39
  CL26 PVCCMCP_CPU0 @BASEBOARD_FAB2_LIB.BASEBOARD_FAB2(SCH_1):PVCCMCP_CPU0   I127 @BASEBOARD_FAB2_LIB.BASEBOARD_FAB2(SCH_1):PAGE39
  CM23 PVCCMCP_CPU0 @BASEBOARD_FAB2_LIB.BASEBOARD_FAB2(SCH_1):PVCCMCP_CPU0   I127 @BASEBOARD_FAB2_LIB.BASEBOARD_FAB2(SCH_1):PAGE39
  CM25 PVCCMCP_CPU0 @BASEBOARD_FAB2_LIB.BASEBOARD_FAB2(SCH_1):PVCCMCP_CPU0   I127 @BASEBOARD_FAB2_LIB.BASEBOARD_FAB2(SCH_1):PAGE39
  CN22 TP_CPU0_KTI2_AMONV @BASEBOARD_FAB2_LIB.BASEBOARD_FAB2(SCH_1):TP_CPU0_KTI2_AMONV   I127 @BASEBOARD_FAB2_LIB.BASEBOARD_FAB2(SCH_1):PAGE39
  CN24 PVCCMCP_CPU0 @BASEBOARD_FAB2_LIB.BASEBOARD_FAB2(SCH_1):PVCCMCP_CPU0   I127 @BASEBOARD_FAB2_LIB.BASEBOARD_FAB2(SCH_1):PAGE39
  CN28 PD_CPU0_MCP01_DMON @BASEBOARD_FAB2_LIB.BASEBOARD_FAB2(SCH_1):PD_CPU0_MCP01_DMON   I127 @BASEBOARD_FAB2_LIB.BASEBOARD_FAB2(SCH_1):PAGE39
  CP23 PVCCMCP_CPU0 @BASEBOARD_FAB2_LIB.BASEBOARD_FAB2(SCH_1):PVCCMCP_CPU0   I127 @BASEBOARD_FAB2_LIB.BASEBOARD_FAB2(SCH_1):PAGE39
  CP31 TP_CPU0_RSVD_73 @BASEBOARD_FAB2_LIB.BASEBOARD_FAB2(SCH_1):TP_CPU0_RSVD_73   I127 @BASEBOARD_FAB2_LIB.BASEBOARD_FAB2(SCH_1):PAGE39
  CR60 TP_CPU0_RSVD_72 @BASEBOARD_FAB2_LIB.BASEBOARD_FAB2(SCH_1):TP_CPU0_RSVD_72   I127 @BASEBOARD_FAB2_LIB.BASEBOARD_FAB2(SCH_1):PAGE39
  CT23 PVCCMCP_CPU0 @BASEBOARD_FAB2_LIB.BASEBOARD_FAB2(SCH_1):PVCCMCP_CPU0   I127 @BASEBOARD_FAB2_LIB.BASEBOARD_FAB2(SCH_1):PAGE39
   CT5 TP_CPU0_RSVD_70 @BASEBOARD_FAB2_LIB.BASEBOARD_FAB2(SCH_1):TP_CPU0_RSVD_70   I127 @BASEBOARD_FAB2_LIB.BASEBOARD_FAB2(SCH_1):PAGE39
  CT69 TP_CPU0_RSVD_69 @BASEBOARD_FAB2_LIB.BASEBOARD_FAB2(SCH_1):TP_CPU0_RSVD_69   I127 @BASEBOARD_FAB2_LIB.BASEBOARD_FAB2(SCH_1):PAGE39
  CU24 PVCCMCP_CPU0 @BASEBOARD_FAB2_LIB.BASEBOARD_FAB2(SCH_1):PVCCMCP_CPU0   I127 @BASEBOARD_FAB2_LIB.BASEBOARD_FAB2(SCH_1):PAGE39
   CU6 TP_CPU0_RSVD_67 @BASEBOARD_FAB2_LIB.BASEBOARD_FAB2(SCH_1):TP_CPU0_RSVD_67   I127 @BASEBOARD_FAB2_LIB.BASEBOARD_FAB2(SCH_1):PAGE39
  CU60 TP_CPU0_RSVD_66 @BASEBOARD_FAB2_LIB.BASEBOARD_FAB2(SCH_1):TP_CPU0_RSVD_66   I127 @BASEBOARD_FAB2_LIB.BASEBOARD_FAB2(SCH_1):PAGE39
  CV23 PVCCMCP_CPU0 @BASEBOARD_FAB2_LIB.BASEBOARD_FAB2(SCH_1):PVCCMCP_CPU0   I127 @BASEBOARD_FAB2_LIB.BASEBOARD_FAB2(SCH_1):PAGE39
  CV69 TP_CPU0_RSVD_64 @BASEBOARD_FAB2_LIB.BASEBOARD_FAB2(SCH_1):TP_CPU0_RSVD_64   I127 @BASEBOARD_FAB2_LIB.BASEBOARD_FAB2(SCH_1):PAGE39
  CW22 TP_CPU0_KTI2_DFX_DN @BASEBOARD_FAB2_LIB.BASEBOARD_FAB2(SCH_1):TP_CPU0_KTI2_DFX_DN   I127 @BASEBOARD_FAB2_LIB.BASEBOARD_FAB2(SCH_1):PAGE39
  CW24 PVCCMCP_CPU0 @BASEBOARD_FAB2_LIB.BASEBOARD_FAB2(SCH_1):PVCCMCP_CPU0   I127 @BASEBOARD_FAB2_LIB.BASEBOARD_FAB2(SCH_1):PAGE39
  CW60 TP_CPU0_RSVD_61 @BASEBOARD_FAB2_LIB.BASEBOARD_FAB2(SCH_1):TP_CPU0_RSVD_61   I127 @BASEBOARD_FAB2_LIB.BASEBOARD_FAB2(SCH_1):PAGE39
  CW62 TP_CPU0_RSVD_60 @BASEBOARD_FAB2_LIB.BASEBOARD_FAB2(SCH_1):TP_CPU0_RSVD_60   I127 @BASEBOARD_FAB2_LIB.BASEBOARD_FAB2(SCH_1):PAGE39
  CY23 TP_CPU0_RSVD_59 @BASEBOARD_FAB2_LIB.BASEBOARD_FAB2(SCH_1):TP_CPU0_RSVD_59   I127 @BASEBOARD_FAB2_LIB.BASEBOARD_FAB2(SCH_1):PAGE39
  CY25 PVCCMCP_CPU0 @BASEBOARD_FAB2_LIB.BASEBOARD_FAB2(SCH_1):PVCCMCP_CPU0   I127 @BASEBOARD_FAB2_LIB.BASEBOARD_FAB2(SCH_1):PAGE39
  CY39 TP_CPU0_RSVD_57 @BASEBOARD_FAB2_LIB.BASEBOARD_FAB2(SCH_1):TP_CPU0_RSVD_57   I127 @BASEBOARD_FAB2_LIB.BASEBOARD_FAB2(SCH_1):PAGE39
  CY53 TP_CPU0_RSVD_56 @BASEBOARD_FAB2_LIB.BASEBOARD_FAB2(SCH_1):TP_CPU0_RSVD_56   I127 @BASEBOARD_FAB2_LIB.BASEBOARD_FAB2(SCH_1):PAGE39
  CY57 TP_CPU0_RSVD_55 @BASEBOARD_FAB2_LIB.BASEBOARD_FAB2(SCH_1):TP_CPU0_RSVD_55   I127 @BASEBOARD_FAB2_LIB.BASEBOARD_FAB2(SCH_1):PAGE39
  CY63 TP_CPU0_RSVD_54 @BASEBOARD_FAB2_LIB.BASEBOARD_FAB2(SCH_1):TP_CPU0_RSVD_54   I127 @BASEBOARD_FAB2_LIB.BASEBOARD_FAB2(SCH_1):PAGE39
  CY73 TP_CPU0_RSVD_53 @BASEBOARD_FAB2_LIB.BASEBOARD_FAB2(SCH_1):TP_CPU0_RSVD_53   I127 @BASEBOARD_FAB2_LIB.BASEBOARD_FAB2(SCH_1):PAGE39
  DA24 PVCCMCP_CPU0 @BASEBOARD_FAB2_LIB.BASEBOARD_FAB2(SCH_1):PVCCMCP_CPU0   I127 @BASEBOARD_FAB2_LIB.BASEBOARD_FAB2(SCH_1):PAGE39
  DA40 TP_CPU0_RSVD_51 @BASEBOARD_FAB2_LIB.BASEBOARD_FAB2(SCH_1):TP_CPU0_RSVD_51   I127 @BASEBOARD_FAB2_LIB.BASEBOARD_FAB2(SCH_1):PAGE39
  DA52 TP_CPU0_RSVD_50 @BASEBOARD_FAB2_LIB.BASEBOARD_FAB2(SCH_1):TP_CPU0_RSVD_50   I127 @BASEBOARD_FAB2_LIB.BASEBOARD_FAB2(SCH_1):PAGE39
  DA54 TP_CPU0_RSVD_49 @BASEBOARD_FAB2_LIB.BASEBOARD_FAB2(SCH_1):TP_CPU0_RSVD_49   I127 @BASEBOARD_FAB2_LIB.BASEBOARD_FAB2(SCH_1):PAGE39
  DA56 TP_CPU0_RSVD_48 @BASEBOARD_FAB2_LIB.BASEBOARD_FAB2(SCH_1):TP_CPU0_RSVD_48   I127 @BASEBOARD_FAB2_LIB.BASEBOARD_FAB2(SCH_1):PAGE39
  DC46 TP_CPU0_RSVD_47 @BASEBOARD_FAB2_LIB.BASEBOARD_FAB2(SCH_1):TP_CPU0_RSVD_47   I127 @BASEBOARD_FAB2_LIB.BASEBOARD_FAB2(SCH_1):PAGE39
  DC52 TP_CPU0_RSVD_46 @BASEBOARD_FAB2_LIB.BASEBOARD_FAB2(SCH_1):TP_CPU0_RSVD_46   I127 @BASEBOARD_FAB2_LIB.BASEBOARD_FAB2(SCH_1):PAGE39
  DD51 TP_CPU0_RSVD_45 @BASEBOARD_FAB2_LIB.BASEBOARD_FAB2(SCH_1):TP_CPU0_RSVD_45   I127 @BASEBOARD_FAB2_LIB.BASEBOARD_FAB2(SCH_1):PAGE39
  DG36 TP_CPU0_RSVD_44 @BASEBOARD_FAB2_LIB.BASEBOARD_FAB2(SCH_1):TP_CPU0_RSVD_44   I127 @BASEBOARD_FAB2_LIB.BASEBOARD_FAB2(SCH_1):PAGE39
  DG64 TP_CPU0_RSVD_43 @BASEBOARD_FAB2_LIB.BASEBOARD_FAB2(SCH_1):TP_CPU0_RSVD_43   I127 @BASEBOARD_FAB2_LIB.BASEBOARD_FAB2(SCH_1):PAGE39
  DH65 TP_CPU0_RSVD_42 @BASEBOARD_FAB2_LIB.BASEBOARD_FAB2(SCH_1):TP_CPU0_RSVD_42   I127 @BASEBOARD_FAB2_LIB.BASEBOARD_FAB2(SCH_1):PAGE39
  DJ36 TP_CPU0_RSVD_41 @BASEBOARD_FAB2_LIB.BASEBOARD_FAB2(SCH_1):TP_CPU0_RSVD_41   I127 @BASEBOARD_FAB2_LIB.BASEBOARD_FAB2(SCH_1):PAGE39
  DJ66 TP_CPU0_RSVD_40 @BASEBOARD_FAB2_LIB.BASEBOARD_FAB2(SCH_1):TP_CPU0_RSVD_40   I127 @BASEBOARD_FAB2_LIB.BASEBOARD_FAB2(SCH_1):PAGE39
  DK15 TP_CPU0_RSVD_39 @BASEBOARD_FAB2_LIB.BASEBOARD_FAB2(SCH_1):TP_CPU0_RSVD_39   I127 @BASEBOARD_FAB2_LIB.BASEBOARD_FAB2(SCH_1):PAGE39
  DK37 TP_CPU0_RSVD_38 @BASEBOARD_FAB2_LIB.BASEBOARD_FAB2(SCH_1):TP_CPU0_RSVD_38   I127 @BASEBOARD_FAB2_LIB.BASEBOARD_FAB2(SCH_1):PAGE39
  DK65 TP_CPU0_RSVD_37 @BASEBOARD_FAB2_LIB.BASEBOARD_FAB2(SCH_1):TP_CPU0_RSVD_37   I127 @BASEBOARD_FAB2_LIB.BASEBOARD_FAB2(SCH_1):PAGE39
  DK67 TP_CPU0_RSVD_36 @BASEBOARD_FAB2_LIB.BASEBOARD_FAB2(SCH_1):TP_CPU0_RSVD_36   I127 @BASEBOARD_FAB2_LIB.BASEBOARD_FAB2(SCH_1):PAGE39
  DL38 TP_CPU0_RSVD_35 @BASEBOARD_FAB2_LIB.BASEBOARD_FAB2(SCH_1):TP_CPU0_RSVD_35   I127 @BASEBOARD_FAB2_LIB.BASEBOARD_FAB2(SCH_1):PAGE39
  DL66 TP_CPU0_RSVD_34 @BASEBOARD_FAB2_LIB.BASEBOARD_FAB2(SCH_1):TP_CPU0_RSVD_34   I127 @BASEBOARD_FAB2_LIB.BASEBOARD_FAB2(SCH_1):PAGE39
  DM67 TP_CPU0_RSVD_33 @BASEBOARD_FAB2_LIB.BASEBOARD_FAB2(SCH_1):TP_CPU0_RSVD_33   I127 @BASEBOARD_FAB2_LIB.BASEBOARD_FAB2(SCH_1):PAGE39
  DN62 TP_CPU0_RSVD_32 @BASEBOARD_FAB2_LIB.BASEBOARD_FAB2(SCH_1):TP_CPU0_RSVD_32   I127 @BASEBOARD_FAB2_LIB.BASEBOARD_FAB2(SCH_1):PAGE39
  DN66 TP_CPU0_RSVD_31 @BASEBOARD_FAB2_LIB.BASEBOARD_FAB2(SCH_1):TP_CPU0_RSVD_31   I127 @BASEBOARD_FAB2_LIB.BASEBOARD_FAB2(SCH_1):PAGE39
  DP17 TP_CPU0_RSVD_30 @BASEBOARD_FAB2_LIB.BASEBOARD_FAB2(SCH_1):TP_CPU0_RSVD_30   I127 @BASEBOARD_FAB2_LIB.BASEBOARD_FAB2(SCH_1):PAGE39
  DP65 TP_CPU0_RSVD_29 @BASEBOARD_FAB2_LIB.BASEBOARD_FAB2(SCH_1):TP_CPU0_RSVD_29   I127 @BASEBOARD_FAB2_LIB.BASEBOARD_FAB2(SCH_1):PAGE39
  DR44 TP_CPU0_RSVD_28 @BASEBOARD_FAB2_LIB.BASEBOARD_FAB2(SCH_1):TP_CPU0_RSVD_28   I127 @BASEBOARD_FAB2_LIB.BASEBOARD_FAB2(SCH_1):PAGE39
  DT71 TP_CPU0_RSVD_27 @BASEBOARD_FAB2_LIB.BASEBOARD_FAB2(SCH_1):TP_CPU0_RSVD_27   I127 @BASEBOARD_FAB2_LIB.BASEBOARD_FAB2(SCH_1):PAGE39
  DU44 TP_CPU0_RSVD_26 @BASEBOARD_FAB2_LIB.BASEBOARD_FAB2(SCH_1):TP_CPU0_RSVD_26   I127 @BASEBOARD_FAB2_LIB.BASEBOARD_FAB2(SCH_1):PAGE39
  DV61 TP_CPU0_RSVD_25 @BASEBOARD_FAB2_LIB.BASEBOARD_FAB2(SCH_1):TP_CPU0_RSVD_25   I127 @BASEBOARD_FAB2_LIB.BASEBOARD_FAB2(SCH_1):PAGE39
  DV71 TP_CPU0_RSVD_24 @BASEBOARD_FAB2_LIB.BASEBOARD_FAB2(SCH_1):TP_CPU0_RSVD_24   I127 @BASEBOARD_FAB2_LIB.BASEBOARD_FAB2(SCH_1):PAGE39
  DW44 TP_CPU0_RSVD_23 @BASEBOARD_FAB2_LIB.BASEBOARD_FAB2(SCH_1):TP_CPU0_RSVD_23   I127 @BASEBOARD_FAB2_LIB.BASEBOARD_FAB2(SCH_1):PAGE39
  DW46 TP_CPU0_RSVD_22 @BASEBOARD_FAB2_LIB.BASEBOARD_FAB2(SCH_1):TP_CPU0_RSVD_22   I127 @BASEBOARD_FAB2_LIB.BASEBOARD_FAB2(SCH_1):PAGE39
   DY3 TP_CPU0_RSVD_21 @BASEBOARD_FAB2_LIB.BASEBOARD_FAB2(SCH_1):TP_CPU0_RSVD_21   I127 @BASEBOARD_FAB2_LIB.BASEBOARD_FAB2(SCH_1):PAGE39
   EA4 TP_CPU0_RSVD_20 @BASEBOARD_FAB2_LIB.BASEBOARD_FAB2(SCH_1):TP_CPU0_RSVD_20   I127 @BASEBOARD_FAB2_LIB.BASEBOARD_FAB2(SCH_1):PAGE39
  EA44 TP_CPU0_RSVD_19 @BASEBOARD_FAB2_LIB.BASEBOARD_FAB2(SCH_1):TP_CPU0_RSVD_19   I127 @BASEBOARD_FAB2_LIB.BASEBOARD_FAB2(SCH_1):PAGE39
   EB3 TP_CPU0_RSVD_18 @BASEBOARD_FAB2_LIB.BASEBOARD_FAB2(SCH_1):TP_CPU0_RSVD_18   I127 @BASEBOARD_FAB2_LIB.BASEBOARD_FAB2(SCH_1):PAGE39
   EB5 TP_CPU0_RSVD_17 @BASEBOARD_FAB2_LIB.BASEBOARD_FAB2(SCH_1):TP_CPU0_RSVD_17   I127 @BASEBOARD_FAB2_LIB.BASEBOARD_FAB2(SCH_1):PAGE39
  EB85 TP_CPU0_RSVD_16 @BASEBOARD_FAB2_LIB.BASEBOARD_FAB2(SCH_1):TP_CPU0_RSVD_16   I127 @BASEBOARD_FAB2_LIB.BASEBOARD_FAB2(SCH_1):PAGE39
  EC16 TP_CPU0_RSVD_15 @BASEBOARD_FAB2_LIB.BASEBOARD_FAB2(SCH_1):TP_CPU0_RSVD_15   I127 @BASEBOARD_FAB2_LIB.BASEBOARD_FAB2(SCH_1):PAGE39
   EC4 TP_CPU0_RSVD_14 @BASEBOARD_FAB2_LIB.BASEBOARD_FAB2(SCH_1):TP_CPU0_RSVD_14   I127 @BASEBOARD_FAB2_LIB.BASEBOARD_FAB2(SCH_1):PAGE39
  EC44 TP_CPU0_RSVD_13 @BASEBOARD_FAB2_LIB.BASEBOARD_FAB2(SCH_1):TP_CPU0_RSVD_13   I127 @BASEBOARD_FAB2_LIB.BASEBOARD_FAB2(SCH_1):PAGE39
  EC84 TP_CPU0_RSVD_12 @BASEBOARD_FAB2_LIB.BASEBOARD_FAB2(SCH_1):TP_CPU0_RSVD_12   I127 @BASEBOARD_FAB2_LIB.BASEBOARD_FAB2(SCH_1):PAGE39
  ED45 TP_CPU0_RSVD_11 @BASEBOARD_FAB2_LIB.BASEBOARD_FAB2(SCH_1):TP_CPU0_RSVD_11   I127 @BASEBOARD_FAB2_LIB.BASEBOARD_FAB2(SCH_1):PAGE39
   ED5 TP_CPU0_RSVD_10 @BASEBOARD_FAB2_LIB.BASEBOARD_FAB2(SCH_1):TP_CPU0_RSVD_10   I127 @BASEBOARD_FAB2_LIB.BASEBOARD_FAB2(SCH_1):PAGE39
  ED83 TP_CPU0_RSVD_9 @BASEBOARD_FAB2_LIB.BASEBOARD_FAB2(SCH_1):TP_CPU0_RSVD_9   I127 @BASEBOARD_FAB2_LIB.BASEBOARD_FAB2(SCH_1):PAGE39
  EE16 TP_CPU0_RSVD_8 @BASEBOARD_FAB2_LIB.BASEBOARD_FAB2(SCH_1):TP_CPU0_RSVD_8   I127 @BASEBOARD_FAB2_LIB.BASEBOARD_FAB2(SCH_1):PAGE39
  EE46 TP_CPU0_RSVD_7 @BASEBOARD_FAB2_LIB.BASEBOARD_FAB2(SCH_1):TP_CPU0_RSVD_7   I127 @BASEBOARD_FAB2_LIB.BASEBOARD_FAB2(SCH_1):PAGE39
   EE6 TP_CPU0_RSVD_6 @BASEBOARD_FAB2_LIB.BASEBOARD_FAB2(SCH_1):TP_CPU0_RSVD_6   I127 @BASEBOARD_FAB2_LIB.BASEBOARD_FAB2(SCH_1):PAGE39
  EE82 TP_CPU0_RSVD_5 @BASEBOARD_FAB2_LIB.BASEBOARD_FAB2(SCH_1):TP_CPU0_RSVD_5   I127 @BASEBOARD_FAB2_LIB.BASEBOARD_FAB2(SCH_1):PAGE39
  EE84 TP_CPU0_RSVD_4 @BASEBOARD_FAB2_LIB.BASEBOARD_FAB2(SCH_1):TP_CPU0_RSVD_4   I127 @BASEBOARD_FAB2_LIB.BASEBOARD_FAB2(SCH_1):PAGE39
  EF47 TP_CPU0_RSVD_3 @BASEBOARD_FAB2_LIB.BASEBOARD_FAB2(SCH_1):TP_CPU0_RSVD_3   I127 @BASEBOARD_FAB2_LIB.BASEBOARD_FAB2(SCH_1):PAGE39
  EF77 TP_CPU0_RSVD_2 @BASEBOARD_FAB2_LIB.BASEBOARD_FAB2(SCH_1):TP_CPU0_RSVD_2   I127 @BASEBOARD_FAB2_LIB.BASEBOARD_FAB2(SCH_1):PAGE39
  EF81 TP_CPU0_RSVD_1 @BASEBOARD_FAB2_LIB.BASEBOARD_FAB2(SCH_1):TP_CPU0_RSVD_1   I127 @BASEBOARD_FAB2_LIB.BASEBOARD_FAB2(SCH_1):PAGE39
  EF83 TP_CPU0_RSVD_0 @BASEBOARD_FAB2_LIB.BASEBOARD_FAB2(SCH_1):TP_CPU0_RSVD_0   I127 @BASEBOARD_FAB2_LIB.BASEBOARD_FAB2(SCH_1):PAGE39
   CN6 PVCCIO_CPU0 @BASEBOARD_FAB2_LIB.BASEBOARD_FAB2(SCH_1):PVCCIO_CPU0   I127 @BASEBOARD_FAB2_LIB.BASEBOARD_FAB2(SCH_1):PAGE39
  CU12 PVCCIO_CPU0 @BASEBOARD_FAB2_LIB.BASEBOARD_FAB2(SCH_1):PVCCIO_CPU0   I127 @BASEBOARD_FAB2_LIB.BASEBOARD_FAB2(SCH_1):PAGE39
  CV21 PVCCIO_CPU0 @BASEBOARD_FAB2_LIB.BASEBOARD_FAB2(SCH_1):PVCCIO_CPU0   I127 @BASEBOARD_FAB2_LIB.BASEBOARD_FAB2(SCH_1):PAGE39
  CU18 PVCCIO_CPU0 @BASEBOARD_FAB2_LIB.BASEBOARD_FAB2(SCH_1):PVCCIO_CPU0   I127 @BASEBOARD_FAB2_LIB.BASEBOARD_FAB2(SCH_1):PAGE39
  CY17 PVCCIO_CPU0 @BASEBOARD_FAB2_LIB.BASEBOARD_FAB2(SCH_1):PVCCIO_CPU0   I127 @BASEBOARD_FAB2_LIB.BASEBOARD_FAB2(SCH_1):PAGE39
  DC18 PVCCIO_CPU0 @BASEBOARD_FAB2_LIB.BASEBOARD_FAB2(SCH_1):PVCCIO_CPU0   I127 @BASEBOARD_FAB2_LIB.BASEBOARD_FAB2(SCH_1):PAGE39
  DE14 PVCCIO_CPU0 @BASEBOARD_FAB2_LIB.BASEBOARD_FAB2(SCH_1):PVCCIO_CPU0   I127 @BASEBOARD_FAB2_LIB.BASEBOARD_FAB2(SCH_1):PAGE39
  CP13 PVCCIO_CPU0 @BASEBOARD_FAB2_LIB.BASEBOARD_FAB2(SCH_1):PVCCIO_CPU0   I127 @BASEBOARD_FAB2_LIB.BASEBOARD_FAB2(SCH_1):PAGE39
  CL20 PVCCIO_CPU0 @BASEBOARD_FAB2_LIB.BASEBOARD_FAB2(SCH_1):PVCCIO_CPU0   I127 @BASEBOARD_FAB2_LIB.BASEBOARD_FAB2(SCH_1):PAGE39
  CG14 PVCCIO_CPU0 @BASEBOARD_FAB2_LIB.BASEBOARD_FAB2(SCH_1):PVCCIO_CPU0   I127 @BASEBOARD_FAB2_LIB.BASEBOARD_FAB2(SCH_1):PAGE39
   CF5 PVCCIO_CPU0 @BASEBOARD_FAB2_LIB.BASEBOARD_FAB2(SCH_1):PVCCIO_CPU0   I127 @BASEBOARD_FAB2_LIB.BASEBOARD_FAB2(SCH_1):PAGE39
  DK21 PVCCIO_CPU0 @BASEBOARD_FAB2_LIB.BASEBOARD_FAB2(SCH_1):PVCCIO_CPU0   I127 @BASEBOARD_FAB2_LIB.BASEBOARD_FAB2(SCH_1):PAGE39
  BE24 PVCCIO_CPU0 @BASEBOARD_FAB2_LIB.BASEBOARD_FAB2(SCH_1):PVCCIO_CPU0   I127 @BASEBOARD_FAB2_LIB.BASEBOARD_FAB2(SCH_1):PAGE39
   AT7 PVCCIO_CPU0 @BASEBOARD_FAB2_LIB.BASEBOARD_FAB2(SCH_1):PVCCIO_CPU0   I127 @BASEBOARD_FAB2_LIB.BASEBOARD_FAB2(SCH_1):PAGE39
   AT5 PVCCIO_CPU0 @BASEBOARD_FAB2_LIB.BASEBOARD_FAB2(SCH_1):PVCCIO_CPU0   I127 @BASEBOARD_FAB2_LIB.BASEBOARD_FAB2(SCH_1):PAGE39
   AM5 PVCCIO_CPU0 @BASEBOARD_FAB2_LIB.BASEBOARD_FAB2(SCH_1):PVCCIO_CPU0   I127 @BASEBOARD_FAB2_LIB.BASEBOARD_FAB2(SCH_1):PAGE39
  DV11 PVCCIO_CPU0 @BASEBOARD_FAB2_LIB.BASEBOARD_FAB2(SCH_1):PVCCIO_CPU0   I127 @BASEBOARD_FAB2_LIB.BASEBOARD_FAB2(SCH_1):PAGE39
   AF5 PVCCIO_CPU0 @BASEBOARD_FAB2_LIB.BASEBOARD_FAB2(SCH_1):PVCCIO_CPU0   I127 @BASEBOARD_FAB2_LIB.BASEBOARD_FAB2(SCH_1):PAGE39
  AE10 PVCCIO_CPU0 @BASEBOARD_FAB2_LIB.BASEBOARD_FAB2(SCH_1):PVCCIO_CPU0   I127 @BASEBOARD_FAB2_LIB.BASEBOARD_FAB2(SCH_1):PAGE39
  EE10 PVCCIO_CPU0 @BASEBOARD_FAB2_LIB.BASEBOARD_FAB2(SCH_1):PVCCIO_CPU0   I127 @BASEBOARD_FAB2_LIB.BASEBOARD_FAB2(SCH_1):PAGE39
   BH5 VSENSE_PVCCIO_CPU0_SKT_VSEN @BASEBOARD_FAB2_LIB.BASEBOARD_FAB2(SCH_1):VSENSE_PVCCIO_CPU0_SKT_VSEN   I127 @BASEBOARD_FAB2_LIB.BASEBOARD_FAB2(SCH_1):PAGE39
  CE76 VSENSE_PVSA_CPU0_SKT_VSEN @BASEBOARD_FAB2_LIB.BASEBOARD_FAB2(SCH_1):VSENSE_PVSA_CPU0_SKT_VSEN   I127 @BASEBOARD_FAB2_LIB.BASEBOARD_FAB2(SCH_1):PAGE39
   BF5 VSENSE_PVCCIO_CPU0_SKT_VRTN @BASEBOARD_FAB2_LIB.BASEBOARD_FAB2(SCH_1):VSENSE_PVCCIO_CPU0_SKT_VRTN   I127 @BASEBOARD_FAB2_LIB.BASEBOARD_FAB2(SCH_1):PAGE39
  CG76 VSENSE_PVSA_CPU0_SKT_VRTN @BASEBOARD_FAB2_LIB.BASEBOARD_FAB2(SCH_1):VSENSE_PVSA_CPU0_SKT_VRTN   I127 @BASEBOARD_FAB2_LIB.BASEBOARD_FAB2(SCH_1):PAGE39
    B9    GND @BASEBOARD_FAB2_LIB.BASEBOARD_FAB2(SCH_1):GND    I20 @BASEBOARD_FAB2_LIB.BASEBOARD_FAB2(SCH_1):PAGE40
   A42    GND @BASEBOARD_FAB2_LIB.BASEBOARD_FAB2(SCH_1):GND    I20 @BASEBOARD_FAB2_LIB.BASEBOARD_FAB2(SCH_1):PAGE40
   B43    GND @BASEBOARD_FAB2_LIB.BASEBOARD_FAB2(SCH_1):GND    I20 @BASEBOARD_FAB2_LIB.BASEBOARD_FAB2(SCH_1):PAGE40
    B5    GND @BASEBOARD_FAB2_LIB.BASEBOARD_FAB2(SCH_1):GND    I20 @BASEBOARD_FAB2_LIB.BASEBOARD_FAB2(SCH_1):PAGE40
   B79    GND @BASEBOARD_FAB2_LIB.BASEBOARD_FAB2(SCH_1):GND    I20 @BASEBOARD_FAB2_LIB.BASEBOARD_FAB2(SCH_1):PAGE40
    C4    GND @BASEBOARD_FAB2_LIB.BASEBOARD_FAB2(SCH_1):GND    I20 @BASEBOARD_FAB2_LIB.BASEBOARD_FAB2(SCH_1):PAGE40
   C80    GND @BASEBOARD_FAB2_LIB.BASEBOARD_FAB2(SCH_1):GND    I20 @BASEBOARD_FAB2_LIB.BASEBOARD_FAB2(SCH_1):PAGE40
    D3    GND @BASEBOARD_FAB2_LIB.BASEBOARD_FAB2(SCH_1):GND    I20 @BASEBOARD_FAB2_LIB.BASEBOARD_FAB2(SCH_1):PAGE40
   D81    GND @BASEBOARD_FAB2_LIB.BASEBOARD_FAB2(SCH_1):GND    I20 @BASEBOARD_FAB2_LIB.BASEBOARD_FAB2(SCH_1):PAGE40
   E82    GND @BASEBOARD_FAB2_LIB.BASEBOARD_FAB2(SCH_1):GND    I20 @BASEBOARD_FAB2_LIB.BASEBOARD_FAB2(SCH_1):PAGE40
   J86    GND @BASEBOARD_FAB2_LIB.BASEBOARD_FAB2(SCH_1):GND    I20 @BASEBOARD_FAB2_LIB.BASEBOARD_FAB2(SCH_1):PAGE40
  DY85    GND @BASEBOARD_FAB2_LIB.BASEBOARD_FAB2(SCH_1):GND    I20 @BASEBOARD_FAB2_LIB.BASEBOARD_FAB2(SCH_1):PAGE40
  EA84    GND @BASEBOARD_FAB2_LIB.BASEBOARD_FAB2(SCH_1):GND    I20 @BASEBOARD_FAB2_LIB.BASEBOARD_FAB2(SCH_1):PAGE40
  EB83    GND @BASEBOARD_FAB2_LIB.BASEBOARD_FAB2(SCH_1):GND    I20 @BASEBOARD_FAB2_LIB.BASEBOARD_FAB2(SCH_1):PAGE40
   DW2    GND @BASEBOARD_FAB2_LIB.BASEBOARD_FAB2(SCH_1):GND    I20 @BASEBOARD_FAB2_LIB.BASEBOARD_FAB2(SCH_1):PAGE40
  EC42    GND @BASEBOARD_FAB2_LIB.BASEBOARD_FAB2(SCH_1):GND    I20 @BASEBOARD_FAB2_LIB.BASEBOARD_FAB2(SCH_1):PAGE40
   EC6    GND @BASEBOARD_FAB2_LIB.BASEBOARD_FAB2(SCH_1):GND    I20 @BASEBOARD_FAB2_LIB.BASEBOARD_FAB2(SCH_1):PAGE40
  EC82    GND @BASEBOARD_FAB2_LIB.BASEBOARD_FAB2(SCH_1):GND    I20 @BASEBOARD_FAB2_LIB.BASEBOARD_FAB2(SCH_1):PAGE40
  ED41    GND @BASEBOARD_FAB2_LIB.BASEBOARD_FAB2(SCH_1):GND    I20 @BASEBOARD_FAB2_LIB.BASEBOARD_FAB2(SCH_1):PAGE40
   ED7    GND @BASEBOARD_FAB2_LIB.BASEBOARD_FAB2(SCH_1):GND    I20 @BASEBOARD_FAB2_LIB.BASEBOARD_FAB2(SCH_1):PAGE40
  ED81    GND @BASEBOARD_FAB2_LIB.BASEBOARD_FAB2(SCH_1):GND    I20 @BASEBOARD_FAB2_LIB.BASEBOARD_FAB2(SCH_1):PAGE40
  EE40    GND @BASEBOARD_FAB2_LIB.BASEBOARD_FAB2(SCH_1):GND    I20 @BASEBOARD_FAB2_LIB.BASEBOARD_FAB2(SCH_1):PAGE40
   EE8    GND @BASEBOARD_FAB2_LIB.BASEBOARD_FAB2(SCH_1):GND    I20 @BASEBOARD_FAB2_LIB.BASEBOARD_FAB2(SCH_1):PAGE40
  EE80    GND @BASEBOARD_FAB2_LIB.BASEBOARD_FAB2(SCH_1):GND    I20 @BASEBOARD_FAB2_LIB.BASEBOARD_FAB2(SCH_1):PAGE40
  ED69    GND @BASEBOARD_FAB2_LIB.BASEBOARD_FAB2(SCH_1):GND    I20 @BASEBOARD_FAB2_LIB.BASEBOARD_FAB2(SCH_1):PAGE40
   E66    GND @BASEBOARD_FAB2_LIB.BASEBOARD_FAB2(SCH_1):GND    I20 @BASEBOARD_FAB2_LIB.BASEBOARD_FAB2(SCH_1):PAGE40
   V11    GND @BASEBOARD_FAB2_LIB.BASEBOARD_FAB2(SCH_1):GND    I20 @BASEBOARD_FAB2_LIB.BASEBOARD_FAB2(SCH_1):PAGE40
    L8    GND @BASEBOARD_FAB2_LIB.BASEBOARD_FAB2(SCH_1):GND    I20 @BASEBOARD_FAB2_LIB.BASEBOARD_FAB2(SCH_1):PAGE40
  EA14    GND @BASEBOARD_FAB2_LIB.BASEBOARD_FAB2(SCH_1):GND    I20 @BASEBOARD_FAB2_LIB.BASEBOARD_FAB2(SCH_1):PAGE40
  DY63    GND @BASEBOARD_FAB2_LIB.BASEBOARD_FAB2(SCH_1):GND    I20 @BASEBOARD_FAB2_LIB.BASEBOARD_FAB2(SCH_1):PAGE40
  DY61    GND @BASEBOARD_FAB2_LIB.BASEBOARD_FAB2(SCH_1):GND    I20 @BASEBOARD_FAB2_LIB.BASEBOARD_FAB2(SCH_1):PAGE40
  DY59    GND @BASEBOARD_FAB2_LIB.BASEBOARD_FAB2(SCH_1):GND    I20 @BASEBOARD_FAB2_LIB.BASEBOARD_FAB2(SCH_1):PAGE40
  DY57    GND @BASEBOARD_FAB2_LIB.BASEBOARD_FAB2(SCH_1):GND    I20 @BASEBOARD_FAB2_LIB.BASEBOARD_FAB2(SCH_1):PAGE40
  DY55    GND @BASEBOARD_FAB2_LIB.BASEBOARD_FAB2(SCH_1):GND    I20 @BASEBOARD_FAB2_LIB.BASEBOARD_FAB2(SCH_1):PAGE40
  DY53    GND @BASEBOARD_FAB2_LIB.BASEBOARD_FAB2(SCH_1):GND    I20 @BASEBOARD_FAB2_LIB.BASEBOARD_FAB2(SCH_1):PAGE40
  DY51    GND @BASEBOARD_FAB2_LIB.BASEBOARD_FAB2(SCH_1):GND    I20 @BASEBOARD_FAB2_LIB.BASEBOARD_FAB2(SCH_1):PAGE40
  DY49    GND @BASEBOARD_FAB2_LIB.BASEBOARD_FAB2(SCH_1):GND    I20 @BASEBOARD_FAB2_LIB.BASEBOARD_FAB2(SCH_1):PAGE40
  DY47    GND @BASEBOARD_FAB2_LIB.BASEBOARD_FAB2(SCH_1):GND    I20 @BASEBOARD_FAB2_LIB.BASEBOARD_FAB2(SCH_1):PAGE40
  DY45    GND @BASEBOARD_FAB2_LIB.BASEBOARD_FAB2(SCH_1):GND    I20 @BASEBOARD_FAB2_LIB.BASEBOARD_FAB2(SCH_1):PAGE40
  DV19    GND @BASEBOARD_FAB2_LIB.BASEBOARD_FAB2(SCH_1):GND    I20 @BASEBOARD_FAB2_LIB.BASEBOARD_FAB2(SCH_1):PAGE40
   DP9    GND @BASEBOARD_FAB2_LIB.BASEBOARD_FAB2(SCH_1):GND    I20 @BASEBOARD_FAB2_LIB.BASEBOARD_FAB2(SCH_1):PAGE40
  DP63    GND @BASEBOARD_FAB2_LIB.BASEBOARD_FAB2(SCH_1):GND    I20 @BASEBOARD_FAB2_LIB.BASEBOARD_FAB2(SCH_1):PAGE40
  DP61    GND @BASEBOARD_FAB2_LIB.BASEBOARD_FAB2(SCH_1):GND    I20 @BASEBOARD_FAB2_LIB.BASEBOARD_FAB2(SCH_1):PAGE40
  DP59    GND @BASEBOARD_FAB2_LIB.BASEBOARD_FAB2(SCH_1):GND    I20 @BASEBOARD_FAB2_LIB.BASEBOARD_FAB2(SCH_1):PAGE40
  DP57    GND @BASEBOARD_FAB2_LIB.BASEBOARD_FAB2(SCH_1):GND    I20 @BASEBOARD_FAB2_LIB.BASEBOARD_FAB2(SCH_1):PAGE40
  DP55    GND @BASEBOARD_FAB2_LIB.BASEBOARD_FAB2(SCH_1):GND    I20 @BASEBOARD_FAB2_LIB.BASEBOARD_FAB2(SCH_1):PAGE40
  DP53    GND @BASEBOARD_FAB2_LIB.BASEBOARD_FAB2(SCH_1):GND    I20 @BASEBOARD_FAB2_LIB.BASEBOARD_FAB2(SCH_1):PAGE40
  DP51    GND @BASEBOARD_FAB2_LIB.BASEBOARD_FAB2(SCH_1):GND    I20 @BASEBOARD_FAB2_LIB.BASEBOARD_FAB2(SCH_1):PAGE40
  DP49    GND @BASEBOARD_FAB2_LIB.BASEBOARD_FAB2(SCH_1):GND    I20 @BASEBOARD_FAB2_LIB.BASEBOARD_FAB2(SCH_1):PAGE40
  DP47    GND @BASEBOARD_FAB2_LIB.BASEBOARD_FAB2(SCH_1):GND    I20 @BASEBOARD_FAB2_LIB.BASEBOARD_FAB2(SCH_1):PAGE40
  DP45    GND @BASEBOARD_FAB2_LIB.BASEBOARD_FAB2(SCH_1):GND    I20 @BASEBOARD_FAB2_LIB.BASEBOARD_FAB2(SCH_1):PAGE40
  DN18    GND @BASEBOARD_FAB2_LIB.BASEBOARD_FAB2(SCH_1):GND    I20 @BASEBOARD_FAB2_LIB.BASEBOARD_FAB2(SCH_1):PAGE40
   DL8    GND @BASEBOARD_FAB2_LIB.BASEBOARD_FAB2(SCH_1):GND    I20 @BASEBOARD_FAB2_LIB.BASEBOARD_FAB2(SCH_1):PAGE40
  DE62    GND @BASEBOARD_FAB2_LIB.BASEBOARD_FAB2(SCH_1):GND    I20 @BASEBOARD_FAB2_LIB.BASEBOARD_FAB2(SCH_1):PAGE40
  DE60    GND @BASEBOARD_FAB2_LIB.BASEBOARD_FAB2(SCH_1):GND    I20 @BASEBOARD_FAB2_LIB.BASEBOARD_FAB2(SCH_1):PAGE40
  DE58    GND @BASEBOARD_FAB2_LIB.BASEBOARD_FAB2(SCH_1):GND    I20 @BASEBOARD_FAB2_LIB.BASEBOARD_FAB2(SCH_1):PAGE40
  DE56    GND @BASEBOARD_FAB2_LIB.BASEBOARD_FAB2(SCH_1):GND    I20 @BASEBOARD_FAB2_LIB.BASEBOARD_FAB2(SCH_1):PAGE40
  DE54    GND @BASEBOARD_FAB2_LIB.BASEBOARD_FAB2(SCH_1):GND    I20 @BASEBOARD_FAB2_LIB.BASEBOARD_FAB2(SCH_1):PAGE40
  DE52    GND @BASEBOARD_FAB2_LIB.BASEBOARD_FAB2(SCH_1):GND    I20 @BASEBOARD_FAB2_LIB.BASEBOARD_FAB2(SCH_1):PAGE40
  DE50    GND @BASEBOARD_FAB2_LIB.BASEBOARD_FAB2(SCH_1):GND    I20 @BASEBOARD_FAB2_LIB.BASEBOARD_FAB2(SCH_1):PAGE40
  DE48    GND @BASEBOARD_FAB2_LIB.BASEBOARD_FAB2(SCH_1):GND    I20 @BASEBOARD_FAB2_LIB.BASEBOARD_FAB2(SCH_1):PAGE40
   CW6    GND @BASEBOARD_FAB2_LIB.BASEBOARD_FAB2(SCH_1):GND    I20 @BASEBOARD_FAB2_LIB.BASEBOARD_FAB2(SCH_1):PAGE40
   CG6    GND @BASEBOARD_FAB2_LIB.BASEBOARD_FAB2(SCH_1):GND    I20 @BASEBOARD_FAB2_LIB.BASEBOARD_FAB2(SCH_1):PAGE40
   AR6    GND @BASEBOARD_FAB2_LIB.BASEBOARD_FAB2(SCH_1):GND    I20 @BASEBOARD_FAB2_LIB.BASEBOARD_FAB2(SCH_1):PAGE40
   AJ4    GND @BASEBOARD_FAB2_LIB.BASEBOARD_FAB2(SCH_1):GND    I20 @BASEBOARD_FAB2_LIB.BASEBOARD_FAB2(SCH_1):PAGE40
  AC62    GND @BASEBOARD_FAB2_LIB.BASEBOARD_FAB2(SCH_1):GND    I20 @BASEBOARD_FAB2_LIB.BASEBOARD_FAB2(SCH_1):PAGE40
  AC60    GND @BASEBOARD_FAB2_LIB.BASEBOARD_FAB2(SCH_1):GND    I20 @BASEBOARD_FAB2_LIB.BASEBOARD_FAB2(SCH_1):PAGE40
  AC58    GND @BASEBOARD_FAB2_LIB.BASEBOARD_FAB2(SCH_1):GND    I20 @BASEBOARD_FAB2_LIB.BASEBOARD_FAB2(SCH_1):PAGE40
   A26    GND @BASEBOARD_FAB2_LIB.BASEBOARD_FAB2(SCH_1):GND    I20 @BASEBOARD_FAB2_LIB.BASEBOARD_FAB2(SCH_1):PAGE40
   A30    GND @BASEBOARD_FAB2_LIB.BASEBOARD_FAB2(SCH_1):GND    I20 @BASEBOARD_FAB2_LIB.BASEBOARD_FAB2(SCH_1):PAGE40
   A32    GND @BASEBOARD_FAB2_LIB.BASEBOARD_FAB2(SCH_1):GND    I20 @BASEBOARD_FAB2_LIB.BASEBOARD_FAB2(SCH_1):PAGE40
   A36    GND @BASEBOARD_FAB2_LIB.BASEBOARD_FAB2(SCH_1):GND    I20 @BASEBOARD_FAB2_LIB.BASEBOARD_FAB2(SCH_1):PAGE40
   A38    GND @BASEBOARD_FAB2_LIB.BASEBOARD_FAB2(SCH_1):GND    I20 @BASEBOARD_FAB2_LIB.BASEBOARD_FAB2(SCH_1):PAGE40
   B25    GND @BASEBOARD_FAB2_LIB.BASEBOARD_FAB2(SCH_1):GND    I20 @BASEBOARD_FAB2_LIB.BASEBOARD_FAB2(SCH_1):PAGE40
   B31    GND @BASEBOARD_FAB2_LIB.BASEBOARD_FAB2(SCH_1):GND    I20 @BASEBOARD_FAB2_LIB.BASEBOARD_FAB2(SCH_1):PAGE40
   B37    GND @BASEBOARD_FAB2_LIB.BASEBOARD_FAB2(SCH_1):GND    I20 @BASEBOARD_FAB2_LIB.BASEBOARD_FAB2(SCH_1):PAGE40
   B71    GND @BASEBOARD_FAB2_LIB.BASEBOARD_FAB2(SCH_1):GND    I20 @BASEBOARD_FAB2_LIB.BASEBOARD_FAB2(SCH_1):PAGE40
   B75    GND @BASEBOARD_FAB2_LIB.BASEBOARD_FAB2(SCH_1):GND    I20 @BASEBOARD_FAB2_LIB.BASEBOARD_FAB2(SCH_1):PAGE40
    C8    GND @BASEBOARD_FAB2_LIB.BASEBOARD_FAB2(SCH_1):GND    I20 @BASEBOARD_FAB2_LIB.BASEBOARD_FAB2(SCH_1):PAGE40
   C10    GND @BASEBOARD_FAB2_LIB.BASEBOARD_FAB2(SCH_1):GND    I20 @BASEBOARD_FAB2_LIB.BASEBOARD_FAB2(SCH_1):PAGE40
   C12    GND @BASEBOARD_FAB2_LIB.BASEBOARD_FAB2(SCH_1):GND    I20 @BASEBOARD_FAB2_LIB.BASEBOARD_FAB2(SCH_1):PAGE40
   C14    GND @BASEBOARD_FAB2_LIB.BASEBOARD_FAB2(SCH_1):GND    I20 @BASEBOARD_FAB2_LIB.BASEBOARD_FAB2(SCH_1):PAGE40
   C16    GND @BASEBOARD_FAB2_LIB.BASEBOARD_FAB2(SCH_1):GND    I20 @BASEBOARD_FAB2_LIB.BASEBOARD_FAB2(SCH_1):PAGE40
   C76    GND @BASEBOARD_FAB2_LIB.BASEBOARD_FAB2(SCH_1):GND    I20 @BASEBOARD_FAB2_LIB.BASEBOARD_FAB2(SCH_1):PAGE40
   C78    GND @BASEBOARD_FAB2_LIB.BASEBOARD_FAB2(SCH_1):GND    I20 @BASEBOARD_FAB2_LIB.BASEBOARD_FAB2(SCH_1):PAGE40
  CM27    GND @BASEBOARD_FAB2_LIB.BASEBOARD_FAB2(SCH_1):GND    I20 @BASEBOARD_FAB2_LIB.BASEBOARD_FAB2(SCH_1):PAGE40
   D11    GND @BASEBOARD_FAB2_LIB.BASEBOARD_FAB2(SCH_1):GND    I20 @BASEBOARD_FAB2_LIB.BASEBOARD_FAB2(SCH_1):PAGE40
   D13    GND @BASEBOARD_FAB2_LIB.BASEBOARD_FAB2(SCH_1):GND    I20 @BASEBOARD_FAB2_LIB.BASEBOARD_FAB2(SCH_1):PAGE40
   D25    GND @BASEBOARD_FAB2_LIB.BASEBOARD_FAB2(SCH_1):GND    I20 @BASEBOARD_FAB2_LIB.BASEBOARD_FAB2(SCH_1):PAGE40
   D27    GND @BASEBOARD_FAB2_LIB.BASEBOARD_FAB2(SCH_1):GND    I20 @BASEBOARD_FAB2_LIB.BASEBOARD_FAB2(SCH_1):PAGE40
   D29    GND @BASEBOARD_FAB2_LIB.BASEBOARD_FAB2(SCH_1):GND    I20 @BASEBOARD_FAB2_LIB.BASEBOARD_FAB2(SCH_1):PAGE40
   D31    GND @BASEBOARD_FAB2_LIB.BASEBOARD_FAB2(SCH_1):GND    I20 @BASEBOARD_FAB2_LIB.BASEBOARD_FAB2(SCH_1):PAGE40
   D33    GND @BASEBOARD_FAB2_LIB.BASEBOARD_FAB2(SCH_1):GND    I20 @BASEBOARD_FAB2_LIB.BASEBOARD_FAB2(SCH_1):PAGE40
   D35    GND @BASEBOARD_FAB2_LIB.BASEBOARD_FAB2(SCH_1):GND    I20 @BASEBOARD_FAB2_LIB.BASEBOARD_FAB2(SCH_1):PAGE40
   D37    GND @BASEBOARD_FAB2_LIB.BASEBOARD_FAB2(SCH_1):GND    I20 @BASEBOARD_FAB2_LIB.BASEBOARD_FAB2(SCH_1):PAGE40
   D39    GND @BASEBOARD_FAB2_LIB.BASEBOARD_FAB2(SCH_1):GND    I20 @BASEBOARD_FAB2_LIB.BASEBOARD_FAB2(SCH_1):PAGE40
   D41    GND @BASEBOARD_FAB2_LIB.BASEBOARD_FAB2(SCH_1):GND    I20 @BASEBOARD_FAB2_LIB.BASEBOARD_FAB2(SCH_1):PAGE40
   D43    GND @BASEBOARD_FAB2_LIB.BASEBOARD_FAB2(SCH_1):GND    I20 @BASEBOARD_FAB2_LIB.BASEBOARD_FAB2(SCH_1):PAGE40
   D77    GND @BASEBOARD_FAB2_LIB.BASEBOARD_FAB2(SCH_1):GND    I20 @BASEBOARD_FAB2_LIB.BASEBOARD_FAB2(SCH_1):PAGE40
    E6    GND @BASEBOARD_FAB2_LIB.BASEBOARD_FAB2(SCH_1):GND    I20 @BASEBOARD_FAB2_LIB.BASEBOARD_FAB2(SCH_1):PAGE40
    E8    GND @BASEBOARD_FAB2_LIB.BASEBOARD_FAB2(SCH_1):GND    I20 @BASEBOARD_FAB2_LIB.BASEBOARD_FAB2(SCH_1):PAGE40
   E16    GND @BASEBOARD_FAB2_LIB.BASEBOARD_FAB2(SCH_1):GND    I20 @BASEBOARD_FAB2_LIB.BASEBOARD_FAB2(SCH_1):PAGE40
   E18    GND @BASEBOARD_FAB2_LIB.BASEBOARD_FAB2(SCH_1):GND    I20 @BASEBOARD_FAB2_LIB.BASEBOARD_FAB2(SCH_1):PAGE40
   E20    GND @BASEBOARD_FAB2_LIB.BASEBOARD_FAB2(SCH_1):GND    I20 @BASEBOARD_FAB2_LIB.BASEBOARD_FAB2(SCH_1):PAGE40
   E22    GND @BASEBOARD_FAB2_LIB.BASEBOARD_FAB2(SCH_1):GND    I20 @BASEBOARD_FAB2_LIB.BASEBOARD_FAB2(SCH_1):PAGE40
   E72    GND @BASEBOARD_FAB2_LIB.BASEBOARD_FAB2(SCH_1):GND    I20 @BASEBOARD_FAB2_LIB.BASEBOARD_FAB2(SCH_1):PAGE40
   E74    GND @BASEBOARD_FAB2_LIB.BASEBOARD_FAB2(SCH_1):GND    I20 @BASEBOARD_FAB2_LIB.BASEBOARD_FAB2(SCH_1):PAGE40
   E76    GND @BASEBOARD_FAB2_LIB.BASEBOARD_FAB2(SCH_1):GND    I20 @BASEBOARD_FAB2_LIB.BASEBOARD_FAB2(SCH_1):PAGE40
    F5    GND @BASEBOARD_FAB2_LIB.BASEBOARD_FAB2(SCH_1):GND    I20 @BASEBOARD_FAB2_LIB.BASEBOARD_FAB2(SCH_1):PAGE40
   F17    GND @BASEBOARD_FAB2_LIB.BASEBOARD_FAB2(SCH_1):GND    I20 @BASEBOARD_FAB2_LIB.BASEBOARD_FAB2(SCH_1):PAGE40
   F19    GND @BASEBOARD_FAB2_LIB.BASEBOARD_FAB2(SCH_1):GND    I20 @BASEBOARD_FAB2_LIB.BASEBOARD_FAB2(SCH_1):PAGE40
   F25    GND @BASEBOARD_FAB2_LIB.BASEBOARD_FAB2(SCH_1):GND    I20 @BASEBOARD_FAB2_LIB.BASEBOARD_FAB2(SCH_1):PAGE40
   F31    GND @BASEBOARD_FAB2_LIB.BASEBOARD_FAB2(SCH_1):GND    I20 @BASEBOARD_FAB2_LIB.BASEBOARD_FAB2(SCH_1):PAGE40
   F37    GND @BASEBOARD_FAB2_LIB.BASEBOARD_FAB2(SCH_1):GND    I20 @BASEBOARD_FAB2_LIB.BASEBOARD_FAB2(SCH_1):PAGE40
   F43    GND @BASEBOARD_FAB2_LIB.BASEBOARD_FAB2(SCH_1):GND    I20 @BASEBOARD_FAB2_LIB.BASEBOARD_FAB2(SCH_1):PAGE40
   F67    GND @BASEBOARD_FAB2_LIB.BASEBOARD_FAB2(SCH_1):GND    I20 @BASEBOARD_FAB2_LIB.BASEBOARD_FAB2(SCH_1):PAGE40
   F69    GND @BASEBOARD_FAB2_LIB.BASEBOARD_FAB2(SCH_1):GND    I20 @BASEBOARD_FAB2_LIB.BASEBOARD_FAB2(SCH_1):PAGE40
    G4    GND @BASEBOARD_FAB2_LIB.BASEBOARD_FAB2(SCH_1):GND    I20 @BASEBOARD_FAB2_LIB.BASEBOARD_FAB2(SCH_1):PAGE40
    G8    GND @BASEBOARD_FAB2_LIB.BASEBOARD_FAB2(SCH_1):GND    I20 @BASEBOARD_FAB2_LIB.BASEBOARD_FAB2(SCH_1):PAGE40
   G22    GND @BASEBOARD_FAB2_LIB.BASEBOARD_FAB2(SCH_1):GND    I20 @BASEBOARD_FAB2_LIB.BASEBOARD_FAB2(SCH_1):PAGE40
   G24    GND @BASEBOARD_FAB2_LIB.BASEBOARD_FAB2(SCH_1):GND    I20 @BASEBOARD_FAB2_LIB.BASEBOARD_FAB2(SCH_1):PAGE40
   G26    GND @BASEBOARD_FAB2_LIB.BASEBOARD_FAB2(SCH_1):GND    I20 @BASEBOARD_FAB2_LIB.BASEBOARD_FAB2(SCH_1):PAGE40
   G30    GND @BASEBOARD_FAB2_LIB.BASEBOARD_FAB2(SCH_1):GND    I20 @BASEBOARD_FAB2_LIB.BASEBOARD_FAB2(SCH_1):PAGE40
   G32    GND @BASEBOARD_FAB2_LIB.BASEBOARD_FAB2(SCH_1):GND    I20 @BASEBOARD_FAB2_LIB.BASEBOARD_FAB2(SCH_1):PAGE40
   G36    GND @BASEBOARD_FAB2_LIB.BASEBOARD_FAB2(SCH_1):GND    I20 @BASEBOARD_FAB2_LIB.BASEBOARD_FAB2(SCH_1):PAGE40
   G38    GND @BASEBOARD_FAB2_LIB.BASEBOARD_FAB2(SCH_1):GND    I20 @BASEBOARD_FAB2_LIB.BASEBOARD_FAB2(SCH_1):PAGE40
   G42    GND @BASEBOARD_FAB2_LIB.BASEBOARD_FAB2(SCH_1):GND    I20 @BASEBOARD_FAB2_LIB.BASEBOARD_FAB2(SCH_1):PAGE40
   G66    GND @BASEBOARD_FAB2_LIB.BASEBOARD_FAB2(SCH_1):GND    I20 @BASEBOARD_FAB2_LIB.BASEBOARD_FAB2(SCH_1):PAGE40
   G70    GND @BASEBOARD_FAB2_LIB.BASEBOARD_FAB2(SCH_1):GND    I20 @BASEBOARD_FAB2_LIB.BASEBOARD_FAB2(SCH_1):PAGE40
   G76    GND @BASEBOARD_FAB2_LIB.BASEBOARD_FAB2(SCH_1):GND    I20 @BASEBOARD_FAB2_LIB.BASEBOARD_FAB2(SCH_1):PAGE40
   G78    GND @BASEBOARD_FAB2_LIB.BASEBOARD_FAB2(SCH_1):GND    I20 @BASEBOARD_FAB2_LIB.BASEBOARD_FAB2(SCH_1):PAGE40
   G80    GND @BASEBOARD_FAB2_LIB.BASEBOARD_FAB2(SCH_1):GND    I20 @BASEBOARD_FAB2_LIB.BASEBOARD_FAB2(SCH_1):PAGE40
   G82    GND @BASEBOARD_FAB2_LIB.BASEBOARD_FAB2(SCH_1):GND    I20 @BASEBOARD_FAB2_LIB.BASEBOARD_FAB2(SCH_1):PAGE40
    H3    GND @BASEBOARD_FAB2_LIB.BASEBOARD_FAB2(SCH_1):GND    I20 @BASEBOARD_FAB2_LIB.BASEBOARD_FAB2(SCH_1):PAGE40
   H11    GND @BASEBOARD_FAB2_LIB.BASEBOARD_FAB2(SCH_1):GND    I20 @BASEBOARD_FAB2_LIB.BASEBOARD_FAB2(SCH_1):PAGE40
   H25    GND @BASEBOARD_FAB2_LIB.BASEBOARD_FAB2(SCH_1):GND    I20 @BASEBOARD_FAB2_LIB.BASEBOARD_FAB2(SCH_1):PAGE40
   H27    GND @BASEBOARD_FAB2_LIB.BASEBOARD_FAB2(SCH_1):GND    I20 @BASEBOARD_FAB2_LIB.BASEBOARD_FAB2(SCH_1):PAGE40
   H29    GND @BASEBOARD_FAB2_LIB.BASEBOARD_FAB2(SCH_1):GND    I20 @BASEBOARD_FAB2_LIB.BASEBOARD_FAB2(SCH_1):PAGE40
   H31    GND @BASEBOARD_FAB2_LIB.BASEBOARD_FAB2(SCH_1):GND    I20 @BASEBOARD_FAB2_LIB.BASEBOARD_FAB2(SCH_1):PAGE40
   H33    GND @BASEBOARD_FAB2_LIB.BASEBOARD_FAB2(SCH_1):GND    I20 @BASEBOARD_FAB2_LIB.BASEBOARD_FAB2(SCH_1):PAGE40
   H35    GND @BASEBOARD_FAB2_LIB.BASEBOARD_FAB2(SCH_1):GND    I20 @BASEBOARD_FAB2_LIB.BASEBOARD_FAB2(SCH_1):PAGE40
   H37    GND @BASEBOARD_FAB2_LIB.BASEBOARD_FAB2(SCH_1):GND    I20 @BASEBOARD_FAB2_LIB.BASEBOARD_FAB2(SCH_1):PAGE40
   H39    GND @BASEBOARD_FAB2_LIB.BASEBOARD_FAB2(SCH_1):GND    I20 @BASEBOARD_FAB2_LIB.BASEBOARD_FAB2(SCH_1):PAGE40
   H41    GND @BASEBOARD_FAB2_LIB.BASEBOARD_FAB2(SCH_1):GND    I20 @BASEBOARD_FAB2_LIB.BASEBOARD_FAB2(SCH_1):PAGE40
   H65    GND @BASEBOARD_FAB2_LIB.BASEBOARD_FAB2(SCH_1):GND    I20 @BASEBOARD_FAB2_LIB.BASEBOARD_FAB2(SCH_1):PAGE40
   H71    GND @BASEBOARD_FAB2_LIB.BASEBOARD_FAB2(SCH_1):GND    I20 @BASEBOARD_FAB2_LIB.BASEBOARD_FAB2(SCH_1):PAGE40
   H75    GND @BASEBOARD_FAB2_LIB.BASEBOARD_FAB2(SCH_1):GND    I20 @BASEBOARD_FAB2_LIB.BASEBOARD_FAB2(SCH_1):PAGE40
  DN44    GND @BASEBOARD_FAB2_LIB.BASEBOARD_FAB2(SCH_1):GND    I20 @BASEBOARD_FAB2_LIB.BASEBOARD_FAB2(SCH_1):PAGE40
    J4    GND @BASEBOARD_FAB2_LIB.BASEBOARD_FAB2(SCH_1):GND    I20 @BASEBOARD_FAB2_LIB.BASEBOARD_FAB2(SCH_1):PAGE40
   J12    GND @BASEBOARD_FAB2_LIB.BASEBOARD_FAB2(SCH_1):GND    I20 @BASEBOARD_FAB2_LIB.BASEBOARD_FAB2(SCH_1):PAGE40
   J14    GND @BASEBOARD_FAB2_LIB.BASEBOARD_FAB2(SCH_1):GND    I20 @BASEBOARD_FAB2_LIB.BASEBOARD_FAB2(SCH_1):PAGE40
   J22    GND @BASEBOARD_FAB2_LIB.BASEBOARD_FAB2(SCH_1):GND    I20 @BASEBOARD_FAB2_LIB.BASEBOARD_FAB2(SCH_1):PAGE40
   J26    GND @BASEBOARD_FAB2_LIB.BASEBOARD_FAB2(SCH_1):GND    I20 @BASEBOARD_FAB2_LIB.BASEBOARD_FAB2(SCH_1):PAGE40
   J28    GND @BASEBOARD_FAB2_LIB.BASEBOARD_FAB2(SCH_1):GND    I20 @BASEBOARD_FAB2_LIB.BASEBOARD_FAB2(SCH_1):PAGE40
   J32    GND @BASEBOARD_FAB2_LIB.BASEBOARD_FAB2(SCH_1):GND    I20 @BASEBOARD_FAB2_LIB.BASEBOARD_FAB2(SCH_1):PAGE40
   J34    GND @BASEBOARD_FAB2_LIB.BASEBOARD_FAB2(SCH_1):GND    I20 @BASEBOARD_FAB2_LIB.BASEBOARD_FAB2(SCH_1):PAGE40
   J38    GND @BASEBOARD_FAB2_LIB.BASEBOARD_FAB2(SCH_1):GND    I20 @BASEBOARD_FAB2_LIB.BASEBOARD_FAB2(SCH_1):PAGE40
   J40    GND @BASEBOARD_FAB2_LIB.BASEBOARD_FAB2(SCH_1):GND    I20 @BASEBOARD_FAB2_LIB.BASEBOARD_FAB2(SCH_1):PAGE40
   J72    GND @BASEBOARD_FAB2_LIB.BASEBOARD_FAB2(SCH_1):GND    I20 @BASEBOARD_FAB2_LIB.BASEBOARD_FAB2(SCH_1):PAGE40
   J74    GND @BASEBOARD_FAB2_LIB.BASEBOARD_FAB2(SCH_1):GND    I20 @BASEBOARD_FAB2_LIB.BASEBOARD_FAB2(SCH_1):PAGE40
   J76    GND @BASEBOARD_FAB2_LIB.BASEBOARD_FAB2(SCH_1):GND    I21 @BASEBOARD_FAB2_LIB.BASEBOARD_FAB2(SCH_1):PAGE40
   J82    GND @BASEBOARD_FAB2_LIB.BASEBOARD_FAB2(SCH_1):GND    I21 @BASEBOARD_FAB2_LIB.BASEBOARD_FAB2(SCH_1):PAGE40
   J84    GND @BASEBOARD_FAB2_LIB.BASEBOARD_FAB2(SCH_1):GND    I21 @BASEBOARD_FAB2_LIB.BASEBOARD_FAB2(SCH_1):PAGE40
    K1    GND @BASEBOARD_FAB2_LIB.BASEBOARD_FAB2(SCH_1):GND    I21 @BASEBOARD_FAB2_LIB.BASEBOARD_FAB2(SCH_1):PAGE40
   K11    GND @BASEBOARD_FAB2_LIB.BASEBOARD_FAB2(SCH_1):GND    I21 @BASEBOARD_FAB2_LIB.BASEBOARD_FAB2(SCH_1):PAGE40
   K13    GND @BASEBOARD_FAB2_LIB.BASEBOARD_FAB2(SCH_1):GND    I21 @BASEBOARD_FAB2_LIB.BASEBOARD_FAB2(SCH_1):PAGE40
   K17    GND @BASEBOARD_FAB2_LIB.BASEBOARD_FAB2(SCH_1):GND    I21 @BASEBOARD_FAB2_LIB.BASEBOARD_FAB2(SCH_1):PAGE40
   DB7    GND @BASEBOARD_FAB2_LIB.BASEBOARD_FAB2(SCH_1):GND    I21 @BASEBOARD_FAB2_LIB.BASEBOARD_FAB2(SCH_1):PAGE40
   K27    GND @BASEBOARD_FAB2_LIB.BASEBOARD_FAB2(SCH_1):GND    I21 @BASEBOARD_FAB2_LIB.BASEBOARD_FAB2(SCH_1):PAGE40
   K33    GND @BASEBOARD_FAB2_LIB.BASEBOARD_FAB2(SCH_1):GND    I21 @BASEBOARD_FAB2_LIB.BASEBOARD_FAB2(SCH_1):PAGE40
   K39    GND @BASEBOARD_FAB2_LIB.BASEBOARD_FAB2(SCH_1):GND    I21 @BASEBOARD_FAB2_LIB.BASEBOARD_FAB2(SCH_1):PAGE40
   K65    GND @BASEBOARD_FAB2_LIB.BASEBOARD_FAB2(SCH_1):GND    I21 @BASEBOARD_FAB2_LIB.BASEBOARD_FAB2(SCH_1):PAGE40
   K67    GND @BASEBOARD_FAB2_LIB.BASEBOARD_FAB2(SCH_1):GND    I21 @BASEBOARD_FAB2_LIB.BASEBOARD_FAB2(SCH_1):PAGE40
   K69    GND @BASEBOARD_FAB2_LIB.BASEBOARD_FAB2(SCH_1):GND    I21 @BASEBOARD_FAB2_LIB.BASEBOARD_FAB2(SCH_1):PAGE40
   K71    GND @BASEBOARD_FAB2_LIB.BASEBOARD_FAB2(SCH_1):GND    I21 @BASEBOARD_FAB2_LIB.BASEBOARD_FAB2(SCH_1):PAGE40
   K73    GND @BASEBOARD_FAB2_LIB.BASEBOARD_FAB2(SCH_1):GND    I21 @BASEBOARD_FAB2_LIB.BASEBOARD_FAB2(SCH_1):PAGE40
   K77    GND @BASEBOARD_FAB2_LIB.BASEBOARD_FAB2(SCH_1):GND    I21 @BASEBOARD_FAB2_LIB.BASEBOARD_FAB2(SCH_1):PAGE40
   K81    GND @BASEBOARD_FAB2_LIB.BASEBOARD_FAB2(SCH_1):GND    I21 @BASEBOARD_FAB2_LIB.BASEBOARD_FAB2(SCH_1):PAGE40
   K83    GND @BASEBOARD_FAB2_LIB.BASEBOARD_FAB2(SCH_1):GND    I21 @BASEBOARD_FAB2_LIB.BASEBOARD_FAB2(SCH_1):PAGE40
   K85    GND @BASEBOARD_FAB2_LIB.BASEBOARD_FAB2(SCH_1):GND    I21 @BASEBOARD_FAB2_LIB.BASEBOARD_FAB2(SCH_1):PAGE40
   L10    GND @BASEBOARD_FAB2_LIB.BASEBOARD_FAB2(SCH_1):GND    I21 @BASEBOARD_FAB2_LIB.BASEBOARD_FAB2(SCH_1):PAGE40
    L2    GND @BASEBOARD_FAB2_LIB.BASEBOARD_FAB2(SCH_1):GND    I21 @BASEBOARD_FAB2_LIB.BASEBOARD_FAB2(SCH_1):PAGE40
    L6    GND @BASEBOARD_FAB2_LIB.BASEBOARD_FAB2(SCH_1):GND    I21 @BASEBOARD_FAB2_LIB.BASEBOARD_FAB2(SCH_1):PAGE40
   L20    GND @BASEBOARD_FAB2_LIB.BASEBOARD_FAB2(SCH_1):GND    I21 @BASEBOARD_FAB2_LIB.BASEBOARD_FAB2(SCH_1):PAGE40
   L22    GND @BASEBOARD_FAB2_LIB.BASEBOARD_FAB2(SCH_1):GND    I21 @BASEBOARD_FAB2_LIB.BASEBOARD_FAB2(SCH_1):PAGE40
   L72    GND @BASEBOARD_FAB2_LIB.BASEBOARD_FAB2(SCH_1):GND    I21 @BASEBOARD_FAB2_LIB.BASEBOARD_FAB2(SCH_1):PAGE40
   L78    GND @BASEBOARD_FAB2_LIB.BASEBOARD_FAB2(SCH_1):GND    I21 @BASEBOARD_FAB2_LIB.BASEBOARD_FAB2(SCH_1):PAGE40
   L80    GND @BASEBOARD_FAB2_LIB.BASEBOARD_FAB2(SCH_1):GND    I21 @BASEBOARD_FAB2_LIB.BASEBOARD_FAB2(SCH_1):PAGE40
   L82    GND @BASEBOARD_FAB2_LIB.BASEBOARD_FAB2(SCH_1):GND    I21 @BASEBOARD_FAB2_LIB.BASEBOARD_FAB2(SCH_1):PAGE40
   BT9    GND @BASEBOARD_FAB2_LIB.BASEBOARD_FAB2(SCH_1):GND    I21 @BASEBOARD_FAB2_LIB.BASEBOARD_FAB2(SCH_1):PAGE40
   CT7    GND @BASEBOARD_FAB2_LIB.BASEBOARD_FAB2(SCH_1):GND    I21 @BASEBOARD_FAB2_LIB.BASEBOARD_FAB2(SCH_1):PAGE40
   M15    GND @BASEBOARD_FAB2_LIB.BASEBOARD_FAB2(SCH_1):GND    I21 @BASEBOARD_FAB2_LIB.BASEBOARD_FAB2(SCH_1):PAGE40
   M17    GND @BASEBOARD_FAB2_LIB.BASEBOARD_FAB2(SCH_1):GND    I21 @BASEBOARD_FAB2_LIB.BASEBOARD_FAB2(SCH_1):PAGE40
   M19    GND @BASEBOARD_FAB2_LIB.BASEBOARD_FAB2(SCH_1):GND    I21 @BASEBOARD_FAB2_LIB.BASEBOARD_FAB2(SCH_1):PAGE40
   M23    GND @BASEBOARD_FAB2_LIB.BASEBOARD_FAB2(SCH_1):GND    I21 @BASEBOARD_FAB2_LIB.BASEBOARD_FAB2(SCH_1):PAGE40
   M25    GND @BASEBOARD_FAB2_LIB.BASEBOARD_FAB2(SCH_1):GND    I21 @BASEBOARD_FAB2_LIB.BASEBOARD_FAB2(SCH_1):PAGE40
   M27    GND @BASEBOARD_FAB2_LIB.BASEBOARD_FAB2(SCH_1):GND    I21 @BASEBOARD_FAB2_LIB.BASEBOARD_FAB2(SCH_1):PAGE40
   M29    GND @BASEBOARD_FAB2_LIB.BASEBOARD_FAB2(SCH_1):GND    I21 @BASEBOARD_FAB2_LIB.BASEBOARD_FAB2(SCH_1):PAGE40
   M31    GND @BASEBOARD_FAB2_LIB.BASEBOARD_FAB2(SCH_1):GND    I21 @BASEBOARD_FAB2_LIB.BASEBOARD_FAB2(SCH_1):PAGE40
   M33    GND @BASEBOARD_FAB2_LIB.BASEBOARD_FAB2(SCH_1):GND    I21 @BASEBOARD_FAB2_LIB.BASEBOARD_FAB2(SCH_1):PAGE40
   M35    GND @BASEBOARD_FAB2_LIB.BASEBOARD_FAB2(SCH_1):GND    I21 @BASEBOARD_FAB2_LIB.BASEBOARD_FAB2(SCH_1):PAGE40
   M37    GND @BASEBOARD_FAB2_LIB.BASEBOARD_FAB2(SCH_1):GND    I21 @BASEBOARD_FAB2_LIB.BASEBOARD_FAB2(SCH_1):PAGE40
   M39    GND @BASEBOARD_FAB2_LIB.BASEBOARD_FAB2(SCH_1):GND    I21 @BASEBOARD_FAB2_LIB.BASEBOARD_FAB2(SCH_1):PAGE40
   M41    GND @BASEBOARD_FAB2_LIB.BASEBOARD_FAB2(SCH_1):GND    I21 @BASEBOARD_FAB2_LIB.BASEBOARD_FAB2(SCH_1):PAGE40
   M43    GND @BASEBOARD_FAB2_LIB.BASEBOARD_FAB2(SCH_1):GND    I21 @BASEBOARD_FAB2_LIB.BASEBOARD_FAB2(SCH_1):PAGE40
   M65    GND @BASEBOARD_FAB2_LIB.BASEBOARD_FAB2(SCH_1):GND    I21 @BASEBOARD_FAB2_LIB.BASEBOARD_FAB2(SCH_1):PAGE40
   M71    GND @BASEBOARD_FAB2_LIB.BASEBOARD_FAB2(SCH_1):GND    I21 @BASEBOARD_FAB2_LIB.BASEBOARD_FAB2(SCH_1):PAGE40
   M79    GND @BASEBOARD_FAB2_LIB.BASEBOARD_FAB2(SCH_1):GND    I21 @BASEBOARD_FAB2_LIB.BASEBOARD_FAB2(SCH_1):PAGE40
   M83    GND @BASEBOARD_FAB2_LIB.BASEBOARD_FAB2(SCH_1):GND    I21 @BASEBOARD_FAB2_LIB.BASEBOARD_FAB2(SCH_1):PAGE40
   M85    GND @BASEBOARD_FAB2_LIB.BASEBOARD_FAB2(SCH_1):GND    I21 @BASEBOARD_FAB2_LIB.BASEBOARD_FAB2(SCH_1):PAGE40
  DM19    GND @BASEBOARD_FAB2_LIB.BASEBOARD_FAB2(SCH_1):GND    I21 @BASEBOARD_FAB2_LIB.BASEBOARD_FAB2(SCH_1):PAGE40
   N20    GND @BASEBOARD_FAB2_LIB.BASEBOARD_FAB2(SCH_1):GND    I21 @BASEBOARD_FAB2_LIB.BASEBOARD_FAB2(SCH_1):PAGE40
   N22    GND @BASEBOARD_FAB2_LIB.BASEBOARD_FAB2(SCH_1):GND    I21 @BASEBOARD_FAB2_LIB.BASEBOARD_FAB2(SCH_1):PAGE40
    N6    GND @BASEBOARD_FAB2_LIB.BASEBOARD_FAB2(SCH_1):GND    I21 @BASEBOARD_FAB2_LIB.BASEBOARD_FAB2(SCH_1):PAGE40
   N66    GND @BASEBOARD_FAB2_LIB.BASEBOARD_FAB2(SCH_1):GND    I21 @BASEBOARD_FAB2_LIB.BASEBOARD_FAB2(SCH_1):PAGE40
   N70    GND @BASEBOARD_FAB2_LIB.BASEBOARD_FAB2(SCH_1):GND    I21 @BASEBOARD_FAB2_LIB.BASEBOARD_FAB2(SCH_1):PAGE40
   N72    GND @BASEBOARD_FAB2_LIB.BASEBOARD_FAB2(SCH_1):GND    I21 @BASEBOARD_FAB2_LIB.BASEBOARD_FAB2(SCH_1):PAGE40
   N74    GND @BASEBOARD_FAB2_LIB.BASEBOARD_FAB2(SCH_1):GND    I21 @BASEBOARD_FAB2_LIB.BASEBOARD_FAB2(SCH_1):PAGE40
   N76    GND @BASEBOARD_FAB2_LIB.BASEBOARD_FAB2(SCH_1):GND    I21 @BASEBOARD_FAB2_LIB.BASEBOARD_FAB2(SCH_1):PAGE40
   N78    GND @BASEBOARD_FAB2_LIB.BASEBOARD_FAB2(SCH_1):GND    I21 @BASEBOARD_FAB2_LIB.BASEBOARD_FAB2(SCH_1):PAGE40
    N4    GND @BASEBOARD_FAB2_LIB.BASEBOARD_FAB2(SCH_1):GND    I21 @BASEBOARD_FAB2_LIB.BASEBOARD_FAB2(SCH_1):PAGE40
    N8    GND @BASEBOARD_FAB2_LIB.BASEBOARD_FAB2(SCH_1):GND    I21 @BASEBOARD_FAB2_LIB.BASEBOARD_FAB2(SCH_1):PAGE40
   P11    GND @BASEBOARD_FAB2_LIB.BASEBOARD_FAB2(SCH_1):GND    I21 @BASEBOARD_FAB2_LIB.BASEBOARD_FAB2(SCH_1):PAGE40
   P15    GND @BASEBOARD_FAB2_LIB.BASEBOARD_FAB2(SCH_1):GND    I21 @BASEBOARD_FAB2_LIB.BASEBOARD_FAB2(SCH_1):PAGE40
   P27    GND @BASEBOARD_FAB2_LIB.BASEBOARD_FAB2(SCH_1):GND    I21 @BASEBOARD_FAB2_LIB.BASEBOARD_FAB2(SCH_1):PAGE40
   P33    GND @BASEBOARD_FAB2_LIB.BASEBOARD_FAB2(SCH_1):GND    I21 @BASEBOARD_FAB2_LIB.BASEBOARD_FAB2(SCH_1):PAGE40
   P39    GND @BASEBOARD_FAB2_LIB.BASEBOARD_FAB2(SCH_1):GND    I21 @BASEBOARD_FAB2_LIB.BASEBOARD_FAB2(SCH_1):PAGE40
   P67    GND @BASEBOARD_FAB2_LIB.BASEBOARD_FAB2(SCH_1):GND    I21 @BASEBOARD_FAB2_LIB.BASEBOARD_FAB2(SCH_1):PAGE40
   P69    GND @BASEBOARD_FAB2_LIB.BASEBOARD_FAB2(SCH_1):GND    I21 @BASEBOARD_FAB2_LIB.BASEBOARD_FAB2(SCH_1):PAGE40
   P71    GND @BASEBOARD_FAB2_LIB.BASEBOARD_FAB2(SCH_1):GND    I21 @BASEBOARD_FAB2_LIB.BASEBOARD_FAB2(SCH_1):PAGE40
   P81    GND @BASEBOARD_FAB2_LIB.BASEBOARD_FAB2(SCH_1):GND    I21 @BASEBOARD_FAB2_LIB.BASEBOARD_FAB2(SCH_1):PAGE40
   P83    GND @BASEBOARD_FAB2_LIB.BASEBOARD_FAB2(SCH_1):GND    I21 @BASEBOARD_FAB2_LIB.BASEBOARD_FAB2(SCH_1):PAGE40
   R14    GND @BASEBOARD_FAB2_LIB.BASEBOARD_FAB2(SCH_1):GND    I21 @BASEBOARD_FAB2_LIB.BASEBOARD_FAB2(SCH_1):PAGE40
   R18    GND @BASEBOARD_FAB2_LIB.BASEBOARD_FAB2(SCH_1):GND    I21 @BASEBOARD_FAB2_LIB.BASEBOARD_FAB2(SCH_1):PAGE40
    R2    GND @BASEBOARD_FAB2_LIB.BASEBOARD_FAB2(SCH_1):GND    I21 @BASEBOARD_FAB2_LIB.BASEBOARD_FAB2(SCH_1):PAGE40
    R4    GND @BASEBOARD_FAB2_LIB.BASEBOARD_FAB2(SCH_1):GND    I21 @BASEBOARD_FAB2_LIB.BASEBOARD_FAB2(SCH_1):PAGE40
   R22    GND @BASEBOARD_FAB2_LIB.BASEBOARD_FAB2(SCH_1):GND    I21 @BASEBOARD_FAB2_LIB.BASEBOARD_FAB2(SCH_1):PAGE40
   R26    GND @BASEBOARD_FAB2_LIB.BASEBOARD_FAB2(SCH_1):GND    I21 @BASEBOARD_FAB2_LIB.BASEBOARD_FAB2(SCH_1):PAGE40
   R28    GND @BASEBOARD_FAB2_LIB.BASEBOARD_FAB2(SCH_1):GND    I21 @BASEBOARD_FAB2_LIB.BASEBOARD_FAB2(SCH_1):PAGE40
   R32    GND @BASEBOARD_FAB2_LIB.BASEBOARD_FAB2(SCH_1):GND    I21 @BASEBOARD_FAB2_LIB.BASEBOARD_FAB2(SCH_1):PAGE40
   R34    GND @BASEBOARD_FAB2_LIB.BASEBOARD_FAB2(SCH_1):GND    I21 @BASEBOARD_FAB2_LIB.BASEBOARD_FAB2(SCH_1):PAGE40
   R38    GND @BASEBOARD_FAB2_LIB.BASEBOARD_FAB2(SCH_1):GND    I21 @BASEBOARD_FAB2_LIB.BASEBOARD_FAB2(SCH_1):PAGE40
   R40    GND @BASEBOARD_FAB2_LIB.BASEBOARD_FAB2(SCH_1):GND    I21 @BASEBOARD_FAB2_LIB.BASEBOARD_FAB2(SCH_1):PAGE40
   R68    GND @BASEBOARD_FAB2_LIB.BASEBOARD_FAB2(SCH_1):GND    I21 @BASEBOARD_FAB2_LIB.BASEBOARD_FAB2(SCH_1):PAGE40
   R72    GND @BASEBOARD_FAB2_LIB.BASEBOARD_FAB2(SCH_1):GND    I21 @BASEBOARD_FAB2_LIB.BASEBOARD_FAB2(SCH_1):PAGE40
   R78    GND @BASEBOARD_FAB2_LIB.BASEBOARD_FAB2(SCH_1):GND    I21 @BASEBOARD_FAB2_LIB.BASEBOARD_FAB2(SCH_1):PAGE40
   R86    GND @BASEBOARD_FAB2_LIB.BASEBOARD_FAB2(SCH_1):GND    I21 @BASEBOARD_FAB2_LIB.BASEBOARD_FAB2(SCH_1):PAGE40
   T13    GND @BASEBOARD_FAB2_LIB.BASEBOARD_FAB2(SCH_1):GND    I21 @BASEBOARD_FAB2_LIB.BASEBOARD_FAB2(SCH_1):PAGE40
   T17    GND @BASEBOARD_FAB2_LIB.BASEBOARD_FAB2(SCH_1):GND    I21 @BASEBOARD_FAB2_LIB.BASEBOARD_FAB2(SCH_1):PAGE40
   T25    GND @BASEBOARD_FAB2_LIB.BASEBOARD_FAB2(SCH_1):GND    I21 @BASEBOARD_FAB2_LIB.BASEBOARD_FAB2(SCH_1):PAGE40
   T29    GND @BASEBOARD_FAB2_LIB.BASEBOARD_FAB2(SCH_1):GND    I21 @BASEBOARD_FAB2_LIB.BASEBOARD_FAB2(SCH_1):PAGE40
   T31    GND @BASEBOARD_FAB2_LIB.BASEBOARD_FAB2(SCH_1):GND    I21 @BASEBOARD_FAB2_LIB.BASEBOARD_FAB2(SCH_1):PAGE40
   T35    GND @BASEBOARD_FAB2_LIB.BASEBOARD_FAB2(SCH_1):GND    I21 @BASEBOARD_FAB2_LIB.BASEBOARD_FAB2(SCH_1):PAGE40
   T37    GND @BASEBOARD_FAB2_LIB.BASEBOARD_FAB2(SCH_1):GND    I21 @BASEBOARD_FAB2_LIB.BASEBOARD_FAB2(SCH_1):PAGE40
   T41    GND @BASEBOARD_FAB2_LIB.BASEBOARD_FAB2(SCH_1):GND    I21 @BASEBOARD_FAB2_LIB.BASEBOARD_FAB2(SCH_1):PAGE40
   T65    GND @BASEBOARD_FAB2_LIB.BASEBOARD_FAB2(SCH_1):GND    I21 @BASEBOARD_FAB2_LIB.BASEBOARD_FAB2(SCH_1):PAGE40
   T73    GND @BASEBOARD_FAB2_LIB.BASEBOARD_FAB2(SCH_1):GND    I21 @BASEBOARD_FAB2_LIB.BASEBOARD_FAB2(SCH_1):PAGE40
   T77    GND @BASEBOARD_FAB2_LIB.BASEBOARD_FAB2(SCH_1):GND    I21 @BASEBOARD_FAB2_LIB.BASEBOARD_FAB2(SCH_1):PAGE40
   T83    GND @BASEBOARD_FAB2_LIB.BASEBOARD_FAB2(SCH_1):GND    I21 @BASEBOARD_FAB2_LIB.BASEBOARD_FAB2(SCH_1):PAGE40
   T85    GND @BASEBOARD_FAB2_LIB.BASEBOARD_FAB2(SCH_1):GND    I21 @BASEBOARD_FAB2_LIB.BASEBOARD_FAB2(SCH_1):PAGE40
    U2    GND @BASEBOARD_FAB2_LIB.BASEBOARD_FAB2(SCH_1):GND    I21 @BASEBOARD_FAB2_LIB.BASEBOARD_FAB2(SCH_1):PAGE40
    U4    GND @BASEBOARD_FAB2_LIB.BASEBOARD_FAB2(SCH_1):GND    I21 @BASEBOARD_FAB2_LIB.BASEBOARD_FAB2(SCH_1):PAGE40
    U6    GND @BASEBOARD_FAB2_LIB.BASEBOARD_FAB2(SCH_1):GND    I21 @BASEBOARD_FAB2_LIB.BASEBOARD_FAB2(SCH_1):PAGE40
   U20    GND @BASEBOARD_FAB2_LIB.BASEBOARD_FAB2(SCH_1):GND    I21 @BASEBOARD_FAB2_LIB.BASEBOARD_FAB2(SCH_1):PAGE40
   U22    GND @BASEBOARD_FAB2_LIB.BASEBOARD_FAB2(SCH_1):GND    I21 @BASEBOARD_FAB2_LIB.BASEBOARD_FAB2(SCH_1):PAGE40
   U24    GND @BASEBOARD_FAB2_LIB.BASEBOARD_FAB2(SCH_1):GND    I21 @BASEBOARD_FAB2_LIB.BASEBOARD_FAB2(SCH_1):PAGE40
   U30    GND @BASEBOARD_FAB2_LIB.BASEBOARD_FAB2(SCH_1):GND    I21 @BASEBOARD_FAB2_LIB.BASEBOARD_FAB2(SCH_1):PAGE40
   U36    GND @BASEBOARD_FAB2_LIB.BASEBOARD_FAB2(SCH_1):GND    I21 @BASEBOARD_FAB2_LIB.BASEBOARD_FAB2(SCH_1):PAGE40
   U42    GND @BASEBOARD_FAB2_LIB.BASEBOARD_FAB2(SCH_1):GND    I21 @BASEBOARD_FAB2_LIB.BASEBOARD_FAB2(SCH_1):PAGE40
   U68    GND @BASEBOARD_FAB2_LIB.BASEBOARD_FAB2(SCH_1):GND    I21 @BASEBOARD_FAB2_LIB.BASEBOARD_FAB2(SCH_1):PAGE40
   U70    GND @BASEBOARD_FAB2_LIB.BASEBOARD_FAB2(SCH_1):GND    I21 @BASEBOARD_FAB2_LIB.BASEBOARD_FAB2(SCH_1):PAGE40
   U74    GND @BASEBOARD_FAB2_LIB.BASEBOARD_FAB2(SCH_1):GND    I21 @BASEBOARD_FAB2_LIB.BASEBOARD_FAB2(SCH_1):PAGE40
   U76    GND @BASEBOARD_FAB2_LIB.BASEBOARD_FAB2(SCH_1):GND    I21 @BASEBOARD_FAB2_LIB.BASEBOARD_FAB2(SCH_1):PAGE40
   U78    GND @BASEBOARD_FAB2_LIB.BASEBOARD_FAB2(SCH_1):GND    I21 @BASEBOARD_FAB2_LIB.BASEBOARD_FAB2(SCH_1):PAGE40
   U80    GND @BASEBOARD_FAB2_LIB.BASEBOARD_FAB2(SCH_1):GND    I21 @BASEBOARD_FAB2_LIB.BASEBOARD_FAB2(SCH_1):PAGE40
   U86    GND @BASEBOARD_FAB2_LIB.BASEBOARD_FAB2(SCH_1):GND    I21 @BASEBOARD_FAB2_LIB.BASEBOARD_FAB2(SCH_1):PAGE40
    V1    GND @BASEBOARD_FAB2_LIB.BASEBOARD_FAB2(SCH_1):GND    I21 @BASEBOARD_FAB2_LIB.BASEBOARD_FAB2(SCH_1):PAGE40
    V5    GND @BASEBOARD_FAB2_LIB.BASEBOARD_FAB2(SCH_1):GND    I21 @BASEBOARD_FAB2_LIB.BASEBOARD_FAB2(SCH_1):PAGE40
    V9    GND @BASEBOARD_FAB2_LIB.BASEBOARD_FAB2(SCH_1):GND    I21 @BASEBOARD_FAB2_LIB.BASEBOARD_FAB2(SCH_1):PAGE40
   V13    GND @BASEBOARD_FAB2_LIB.BASEBOARD_FAB2(SCH_1):GND    I21 @BASEBOARD_FAB2_LIB.BASEBOARD_FAB2(SCH_1):PAGE40
   V15    GND @BASEBOARD_FAB2_LIB.BASEBOARD_FAB2(SCH_1):GND    I21 @BASEBOARD_FAB2_LIB.BASEBOARD_FAB2(SCH_1):PAGE40
   V21    GND @BASEBOARD_FAB2_LIB.BASEBOARD_FAB2(SCH_1):GND    I21 @BASEBOARD_FAB2_LIB.BASEBOARD_FAB2(SCH_1):PAGE40
   V23    GND @BASEBOARD_FAB2_LIB.BASEBOARD_FAB2(SCH_1):GND    I21 @BASEBOARD_FAB2_LIB.BASEBOARD_FAB2(SCH_1):PAGE40
   V43    GND @BASEBOARD_FAB2_LIB.BASEBOARD_FAB2(SCH_1):GND    I21 @BASEBOARD_FAB2_LIB.BASEBOARD_FAB2(SCH_1):PAGE40
   V73    GND @BASEBOARD_FAB2_LIB.BASEBOARD_FAB2(SCH_1):GND    I21 @BASEBOARD_FAB2_LIB.BASEBOARD_FAB2(SCH_1):PAGE40
   V75    GND @BASEBOARD_FAB2_LIB.BASEBOARD_FAB2(SCH_1):GND    I21 @BASEBOARD_FAB2_LIB.BASEBOARD_FAB2(SCH_1):PAGE40
   V77    GND @BASEBOARD_FAB2_LIB.BASEBOARD_FAB2(SCH_1):GND    I21 @BASEBOARD_FAB2_LIB.BASEBOARD_FAB2(SCH_1):PAGE40
   V83    GND @BASEBOARD_FAB2_LIB.BASEBOARD_FAB2(SCH_1):GND    I21 @BASEBOARD_FAB2_LIB.BASEBOARD_FAB2(SCH_1):PAGE40
    W8    GND @BASEBOARD_FAB2_LIB.BASEBOARD_FAB2(SCH_1):GND    I21 @BASEBOARD_FAB2_LIB.BASEBOARD_FAB2(SCH_1):PAGE40
  AC56    GND @BASEBOARD_FAB2_LIB.BASEBOARD_FAB2(SCH_1):GND    I21 @BASEBOARD_FAB2_LIB.BASEBOARD_FAB2(SCH_1):PAGE40
   W12    GND @BASEBOARD_FAB2_LIB.BASEBOARD_FAB2(SCH_1):GND    I21 @BASEBOARD_FAB2_LIB.BASEBOARD_FAB2(SCH_1):PAGE40
   W22    GND @BASEBOARD_FAB2_LIB.BASEBOARD_FAB2(SCH_1):GND    I21 @BASEBOARD_FAB2_LIB.BASEBOARD_FAB2(SCH_1):PAGE40
   W24    GND @BASEBOARD_FAB2_LIB.BASEBOARD_FAB2(SCH_1):GND    I21 @BASEBOARD_FAB2_LIB.BASEBOARD_FAB2(SCH_1):PAGE40
   W26    GND @BASEBOARD_FAB2_LIB.BASEBOARD_FAB2(SCH_1):GND    I21 @BASEBOARD_FAB2_LIB.BASEBOARD_FAB2(SCH_1):PAGE40
   W28    GND @BASEBOARD_FAB2_LIB.BASEBOARD_FAB2(SCH_1):GND    I21 @BASEBOARD_FAB2_LIB.BASEBOARD_FAB2(SCH_1):PAGE40
   W30    GND @BASEBOARD_FAB2_LIB.BASEBOARD_FAB2(SCH_1):GND    I21 @BASEBOARD_FAB2_LIB.BASEBOARD_FAB2(SCH_1):PAGE40
   W32    GND @BASEBOARD_FAB2_LIB.BASEBOARD_FAB2(SCH_1):GND    I21 @BASEBOARD_FAB2_LIB.BASEBOARD_FAB2(SCH_1):PAGE40
   W34    GND @BASEBOARD_FAB2_LIB.BASEBOARD_FAB2(SCH_1):GND    I21 @BASEBOARD_FAB2_LIB.BASEBOARD_FAB2(SCH_1):PAGE40
   W36    GND @BASEBOARD_FAB2_LIB.BASEBOARD_FAB2(SCH_1):GND    I21 @BASEBOARD_FAB2_LIB.BASEBOARD_FAB2(SCH_1):PAGE40
   W38    GND @BASEBOARD_FAB2_LIB.BASEBOARD_FAB2(SCH_1):GND    I21 @BASEBOARD_FAB2_LIB.BASEBOARD_FAB2(SCH_1):PAGE40
   W40    GND @BASEBOARD_FAB2_LIB.BASEBOARD_FAB2(SCH_1):GND    I21 @BASEBOARD_FAB2_LIB.BASEBOARD_FAB2(SCH_1):PAGE40
   W42    GND @BASEBOARD_FAB2_LIB.BASEBOARD_FAB2(SCH_1):GND    I21 @BASEBOARD_FAB2_LIB.BASEBOARD_FAB2(SCH_1):PAGE40
   W68    GND @BASEBOARD_FAB2_LIB.BASEBOARD_FAB2(SCH_1):GND    I21 @BASEBOARD_FAB2_LIB.BASEBOARD_FAB2(SCH_1):PAGE40
   W74    GND @BASEBOARD_FAB2_LIB.BASEBOARD_FAB2(SCH_1):GND    I21 @BASEBOARD_FAB2_LIB.BASEBOARD_FAB2(SCH_1):PAGE40
   W78    GND @BASEBOARD_FAB2_LIB.BASEBOARD_FAB2(SCH_1):GND    I21 @BASEBOARD_FAB2_LIB.BASEBOARD_FAB2(SCH_1):PAGE40
   W82    GND @BASEBOARD_FAB2_LIB.BASEBOARD_FAB2(SCH_1):GND    I21 @BASEBOARD_FAB2_LIB.BASEBOARD_FAB2(SCH_1):PAGE40
   Y15    GND @BASEBOARD_FAB2_LIB.BASEBOARD_FAB2(SCH_1):GND    I21 @BASEBOARD_FAB2_LIB.BASEBOARD_FAB2(SCH_1):PAGE40
   Y17    GND @BASEBOARD_FAB2_LIB.BASEBOARD_FAB2(SCH_1):GND    I21 @BASEBOARD_FAB2_LIB.BASEBOARD_FAB2(SCH_1):PAGE40
    Y5    GND @BASEBOARD_FAB2_LIB.BASEBOARD_FAB2(SCH_1):GND    I21 @BASEBOARD_FAB2_LIB.BASEBOARD_FAB2(SCH_1):PAGE40
   Y67    GND @BASEBOARD_FAB2_LIB.BASEBOARD_FAB2(SCH_1):GND    I21 @BASEBOARD_FAB2_LIB.BASEBOARD_FAB2(SCH_1):PAGE40
    Y7    GND @BASEBOARD_FAB2_LIB.BASEBOARD_FAB2(SCH_1):GND    I21 @BASEBOARD_FAB2_LIB.BASEBOARD_FAB2(SCH_1):PAGE40
    Y9    GND @BASEBOARD_FAB2_LIB.BASEBOARD_FAB2(SCH_1):GND    I21 @BASEBOARD_FAB2_LIB.BASEBOARD_FAB2(SCH_1):PAGE40
   Y71    GND @BASEBOARD_FAB2_LIB.BASEBOARD_FAB2(SCH_1):GND    I21 @BASEBOARD_FAB2_LIB.BASEBOARD_FAB2(SCH_1):PAGE40
   Y73    GND @BASEBOARD_FAB2_LIB.BASEBOARD_FAB2(SCH_1):GND    I21 @BASEBOARD_FAB2_LIB.BASEBOARD_FAB2(SCH_1):PAGE40
   Y79    GND @BASEBOARD_FAB2_LIB.BASEBOARD_FAB2(SCH_1):GND    I21 @BASEBOARD_FAB2_LIB.BASEBOARD_FAB2(SCH_1):PAGE40
   Y81    GND @BASEBOARD_FAB2_LIB.BASEBOARD_FAB2(SCH_1):GND    I21 @BASEBOARD_FAB2_LIB.BASEBOARD_FAB2(SCH_1):PAGE40
   Y83    GND @BASEBOARD_FAB2_LIB.BASEBOARD_FAB2(SCH_1):GND    I21 @BASEBOARD_FAB2_LIB.BASEBOARD_FAB2(SCH_1):PAGE40
   Y85    GND @BASEBOARD_FAB2_LIB.BASEBOARD_FAB2(SCH_1):GND    I21 @BASEBOARD_FAB2_LIB.BASEBOARD_FAB2(SCH_1):PAGE40
   AA4    GND @BASEBOARD_FAB2_LIB.BASEBOARD_FAB2(SCH_1):GND    I21 @BASEBOARD_FAB2_LIB.BASEBOARD_FAB2(SCH_1):PAGE40
  AA16    GND @BASEBOARD_FAB2_LIB.BASEBOARD_FAB2(SCH_1):GND    I21 @BASEBOARD_FAB2_LIB.BASEBOARD_FAB2(SCH_1):PAGE40
  AA18    GND @BASEBOARD_FAB2_LIB.BASEBOARD_FAB2(SCH_1):GND    I22 @BASEBOARD_FAB2_LIB.BASEBOARD_FAB2(SCH_1):PAGE40
  AA22    GND @BASEBOARD_FAB2_LIB.BASEBOARD_FAB2(SCH_1):GND    I22 @BASEBOARD_FAB2_LIB.BASEBOARD_FAB2(SCH_1):PAGE40
  AA24    GND @BASEBOARD_FAB2_LIB.BASEBOARD_FAB2(SCH_1):GND    I22 @BASEBOARD_FAB2_LIB.BASEBOARD_FAB2(SCH_1):PAGE40
  AA30    GND @BASEBOARD_FAB2_LIB.BASEBOARD_FAB2(SCH_1):GND    I22 @BASEBOARD_FAB2_LIB.BASEBOARD_FAB2(SCH_1):PAGE40
  AA36    GND @BASEBOARD_FAB2_LIB.BASEBOARD_FAB2(SCH_1):GND    I22 @BASEBOARD_FAB2_LIB.BASEBOARD_FAB2(SCH_1):PAGE40
  AA42    GND @BASEBOARD_FAB2_LIB.BASEBOARD_FAB2(SCH_1):GND    I22 @BASEBOARD_FAB2_LIB.BASEBOARD_FAB2(SCH_1):PAGE40
  AA64    GND @BASEBOARD_FAB2_LIB.BASEBOARD_FAB2(SCH_1):GND    I22 @BASEBOARD_FAB2_LIB.BASEBOARD_FAB2(SCH_1):PAGE40
  AA66    GND @BASEBOARD_FAB2_LIB.BASEBOARD_FAB2(SCH_1):GND    I22 @BASEBOARD_FAB2_LIB.BASEBOARD_FAB2(SCH_1):PAGE40
  AA68    GND @BASEBOARD_FAB2_LIB.BASEBOARD_FAB2(SCH_1):GND    I22 @BASEBOARD_FAB2_LIB.BASEBOARD_FAB2(SCH_1):PAGE40
  AA76    GND @BASEBOARD_FAB2_LIB.BASEBOARD_FAB2(SCH_1):GND    I22 @BASEBOARD_FAB2_LIB.BASEBOARD_FAB2(SCH_1):PAGE40
  AA78    GND @BASEBOARD_FAB2_LIB.BASEBOARD_FAB2(SCH_1):GND    I22 @BASEBOARD_FAB2_LIB.BASEBOARD_FAB2(SCH_1):PAGE40
  AA80    GND @BASEBOARD_FAB2_LIB.BASEBOARD_FAB2(SCH_1):GND    I22 @BASEBOARD_FAB2_LIB.BASEBOARD_FAB2(SCH_1):PAGE40
  AA82    GND @BASEBOARD_FAB2_LIB.BASEBOARD_FAB2(SCH_1):GND    I22 @BASEBOARD_FAB2_LIB.BASEBOARD_FAB2(SCH_1):PAGE40
   AB1    GND @BASEBOARD_FAB2_LIB.BASEBOARD_FAB2(SCH_1):GND    I22 @BASEBOARD_FAB2_LIB.BASEBOARD_FAB2(SCH_1):PAGE40
   AB5    GND @BASEBOARD_FAB2_LIB.BASEBOARD_FAB2(SCH_1):GND    I22 @BASEBOARD_FAB2_LIB.BASEBOARD_FAB2(SCH_1):PAGE40
  AB11    GND @BASEBOARD_FAB2_LIB.BASEBOARD_FAB2(SCH_1):GND    I22 @BASEBOARD_FAB2_LIB.BASEBOARD_FAB2(SCH_1):PAGE40
  AB21    GND @BASEBOARD_FAB2_LIB.BASEBOARD_FAB2(SCH_1):GND    I22 @BASEBOARD_FAB2_LIB.BASEBOARD_FAB2(SCH_1):PAGE40
  AB23    GND @BASEBOARD_FAB2_LIB.BASEBOARD_FAB2(SCH_1):GND    I22 @BASEBOARD_FAB2_LIB.BASEBOARD_FAB2(SCH_1):PAGE40
  AB25    GND @BASEBOARD_FAB2_LIB.BASEBOARD_FAB2(SCH_1):GND    I22 @BASEBOARD_FAB2_LIB.BASEBOARD_FAB2(SCH_1):PAGE40
  AB29    GND @BASEBOARD_FAB2_LIB.BASEBOARD_FAB2(SCH_1):GND    I22 @BASEBOARD_FAB2_LIB.BASEBOARD_FAB2(SCH_1):PAGE40
  AB31    GND @BASEBOARD_FAB2_LIB.BASEBOARD_FAB2(SCH_1):GND    I22 @BASEBOARD_FAB2_LIB.BASEBOARD_FAB2(SCH_1):PAGE40
  AB35    GND @BASEBOARD_FAB2_LIB.BASEBOARD_FAB2(SCH_1):GND    I22 @BASEBOARD_FAB2_LIB.BASEBOARD_FAB2(SCH_1):PAGE40
  AB37    GND @BASEBOARD_FAB2_LIB.BASEBOARD_FAB2(SCH_1):GND    I22 @BASEBOARD_FAB2_LIB.BASEBOARD_FAB2(SCH_1):PAGE40
  AB41    GND @BASEBOARD_FAB2_LIB.BASEBOARD_FAB2(SCH_1):GND    I22 @BASEBOARD_FAB2_LIB.BASEBOARD_FAB2(SCH_1):PAGE40
  AB65    GND @BASEBOARD_FAB2_LIB.BASEBOARD_FAB2(SCH_1):GND    I22 @BASEBOARD_FAB2_LIB.BASEBOARD_FAB2(SCH_1):PAGE40
  AB69    GND @BASEBOARD_FAB2_LIB.BASEBOARD_FAB2(SCH_1):GND    I22 @BASEBOARD_FAB2_LIB.BASEBOARD_FAB2(SCH_1):PAGE40
  AB73    GND @BASEBOARD_FAB2_LIB.BASEBOARD_FAB2(SCH_1):GND    I22 @BASEBOARD_FAB2_LIB.BASEBOARD_FAB2(SCH_1):PAGE40
  AB79    GND @BASEBOARD_FAB2_LIB.BASEBOARD_FAB2(SCH_1):GND    I22 @BASEBOARD_FAB2_LIB.BASEBOARD_FAB2(SCH_1):PAGE40
  AB83    GND @BASEBOARD_FAB2_LIB.BASEBOARD_FAB2(SCH_1):GND    I22 @BASEBOARD_FAB2_LIB.BASEBOARD_FAB2(SCH_1):PAGE40
  AB85    GND @BASEBOARD_FAB2_LIB.BASEBOARD_FAB2(SCH_1):GND    I22 @BASEBOARD_FAB2_LIB.BASEBOARD_FAB2(SCH_1):PAGE40
  AC18    GND @BASEBOARD_FAB2_LIB.BASEBOARD_FAB2(SCH_1):GND    I22 @BASEBOARD_FAB2_LIB.BASEBOARD_FAB2(SCH_1):PAGE40
  AC22    GND @BASEBOARD_FAB2_LIB.BASEBOARD_FAB2(SCH_1):GND    I22 @BASEBOARD_FAB2_LIB.BASEBOARD_FAB2(SCH_1):PAGE40
  AC26    GND @BASEBOARD_FAB2_LIB.BASEBOARD_FAB2(SCH_1):GND    I22 @BASEBOARD_FAB2_LIB.BASEBOARD_FAB2(SCH_1):PAGE40
  AC28    GND @BASEBOARD_FAB2_LIB.BASEBOARD_FAB2(SCH_1):GND    I22 @BASEBOARD_FAB2_LIB.BASEBOARD_FAB2(SCH_1):PAGE40
  AC32    GND @BASEBOARD_FAB2_LIB.BASEBOARD_FAB2(SCH_1):GND    I22 @BASEBOARD_FAB2_LIB.BASEBOARD_FAB2(SCH_1):PAGE40
  AC34    GND @BASEBOARD_FAB2_LIB.BASEBOARD_FAB2(SCH_1):GND    I22 @BASEBOARD_FAB2_LIB.BASEBOARD_FAB2(SCH_1):PAGE40
  AC38    GND @BASEBOARD_FAB2_LIB.BASEBOARD_FAB2(SCH_1):GND    I22 @BASEBOARD_FAB2_LIB.BASEBOARD_FAB2(SCH_1):PAGE40
  AC40    GND @BASEBOARD_FAB2_LIB.BASEBOARD_FAB2(SCH_1):GND    I22 @BASEBOARD_FAB2_LIB.BASEBOARD_FAB2(SCH_1):PAGE40
  AC64    GND @BASEBOARD_FAB2_LIB.BASEBOARD_FAB2(SCH_1):GND    I22 @BASEBOARD_FAB2_LIB.BASEBOARD_FAB2(SCH_1):PAGE40
  AC70    GND @BASEBOARD_FAB2_LIB.BASEBOARD_FAB2(SCH_1):GND    I22 @BASEBOARD_FAB2_LIB.BASEBOARD_FAB2(SCH_1):PAGE40
  AC72    GND @BASEBOARD_FAB2_LIB.BASEBOARD_FAB2(SCH_1):GND    I22 @BASEBOARD_FAB2_LIB.BASEBOARD_FAB2(SCH_1):PAGE40
  AC78    GND @BASEBOARD_FAB2_LIB.BASEBOARD_FAB2(SCH_1):GND    I22 @BASEBOARD_FAB2_LIB.BASEBOARD_FAB2(SCH_1):PAGE40
  AC84    GND @BASEBOARD_FAB2_LIB.BASEBOARD_FAB2(SCH_1):GND    I22 @BASEBOARD_FAB2_LIB.BASEBOARD_FAB2(SCH_1):PAGE40
  AC86    GND @BASEBOARD_FAB2_LIB.BASEBOARD_FAB2(SCH_1):GND    I22 @BASEBOARD_FAB2_LIB.BASEBOARD_FAB2(SCH_1):PAGE40
   AD3    GND @BASEBOARD_FAB2_LIB.BASEBOARD_FAB2(SCH_1):GND    I22 @BASEBOARD_FAB2_LIB.BASEBOARD_FAB2(SCH_1):PAGE40
   AD7    GND @BASEBOARD_FAB2_LIB.BASEBOARD_FAB2(SCH_1):GND    I22 @BASEBOARD_FAB2_LIB.BASEBOARD_FAB2(SCH_1):PAGE40
   AD9    GND @BASEBOARD_FAB2_LIB.BASEBOARD_FAB2(SCH_1):GND    I22 @BASEBOARD_FAB2_LIB.BASEBOARD_FAB2(SCH_1):PAGE40
  AD11    GND @BASEBOARD_FAB2_LIB.BASEBOARD_FAB2(SCH_1):GND    I22 @BASEBOARD_FAB2_LIB.BASEBOARD_FAB2(SCH_1):PAGE40
  AD13    GND @BASEBOARD_FAB2_LIB.BASEBOARD_FAB2(SCH_1):GND    I22 @BASEBOARD_FAB2_LIB.BASEBOARD_FAB2(SCH_1):PAGE40
  AD15    GND @BASEBOARD_FAB2_LIB.BASEBOARD_FAB2(SCH_1):GND    I22 @BASEBOARD_FAB2_LIB.BASEBOARD_FAB2(SCH_1):PAGE40
  AD19    GND @BASEBOARD_FAB2_LIB.BASEBOARD_FAB2(SCH_1):GND    I22 @BASEBOARD_FAB2_LIB.BASEBOARD_FAB2(SCH_1):PAGE40
  AD21    GND @BASEBOARD_FAB2_LIB.BASEBOARD_FAB2(SCH_1):GND    I22 @BASEBOARD_FAB2_LIB.BASEBOARD_FAB2(SCH_1):PAGE40
  AD27    GND @BASEBOARD_FAB2_LIB.BASEBOARD_FAB2(SCH_1):GND    I22 @BASEBOARD_FAB2_LIB.BASEBOARD_FAB2(SCH_1):PAGE40
  AD33    GND @BASEBOARD_FAB2_LIB.BASEBOARD_FAB2(SCH_1):GND    I22 @BASEBOARD_FAB2_LIB.BASEBOARD_FAB2(SCH_1):PAGE40
  AD39    GND @BASEBOARD_FAB2_LIB.BASEBOARD_FAB2(SCH_1):GND    I22 @BASEBOARD_FAB2_LIB.BASEBOARD_FAB2(SCH_1):PAGE40
  AD43    GND @BASEBOARD_FAB2_LIB.BASEBOARD_FAB2(SCH_1):GND    I22 @BASEBOARD_FAB2_LIB.BASEBOARD_FAB2(SCH_1):PAGE40
  AD71    GND @BASEBOARD_FAB2_LIB.BASEBOARD_FAB2(SCH_1):GND    I22 @BASEBOARD_FAB2_LIB.BASEBOARD_FAB2(SCH_1):PAGE40
  AD73    GND @BASEBOARD_FAB2_LIB.BASEBOARD_FAB2(SCH_1):GND    I22 @BASEBOARD_FAB2_LIB.BASEBOARD_FAB2(SCH_1):PAGE40
  AD75    GND @BASEBOARD_FAB2_LIB.BASEBOARD_FAB2(SCH_1):GND    I22 @BASEBOARD_FAB2_LIB.BASEBOARD_FAB2(SCH_1):PAGE40
  AD81    GND @BASEBOARD_FAB2_LIB.BASEBOARD_FAB2(SCH_1):GND    I22 @BASEBOARD_FAB2_LIB.BASEBOARD_FAB2(SCH_1):PAGE40
  AD83    GND @BASEBOARD_FAB2_LIB.BASEBOARD_FAB2(SCH_1):GND    I22 @BASEBOARD_FAB2_LIB.BASEBOARD_FAB2(SCH_1):PAGE40
  AD85    GND @BASEBOARD_FAB2_LIB.BASEBOARD_FAB2(SCH_1):GND    I22 @BASEBOARD_FAB2_LIB.BASEBOARD_FAB2(SCH_1):PAGE40
   AE4    GND @BASEBOARD_FAB2_LIB.BASEBOARD_FAB2(SCH_1):GND    I22 @BASEBOARD_FAB2_LIB.BASEBOARD_FAB2(SCH_1):PAGE40
   AE8    GND @BASEBOARD_FAB2_LIB.BASEBOARD_FAB2(SCH_1):GND    I22 @BASEBOARD_FAB2_LIB.BASEBOARD_FAB2(SCH_1):PAGE40
  AC54    GND @BASEBOARD_FAB2_LIB.BASEBOARD_FAB2(SCH_1):GND    I22 @BASEBOARD_FAB2_LIB.BASEBOARD_FAB2(SCH_1):PAGE40
  AE16    GND @BASEBOARD_FAB2_LIB.BASEBOARD_FAB2(SCH_1):GND    I22 @BASEBOARD_FAB2_LIB.BASEBOARD_FAB2(SCH_1):PAGE40
  AE38    GND @BASEBOARD_FAB2_LIB.BASEBOARD_FAB2(SCH_1):GND    I22 @BASEBOARD_FAB2_LIB.BASEBOARD_FAB2(SCH_1):PAGE40
  AE40    GND @BASEBOARD_FAB2_LIB.BASEBOARD_FAB2(SCH_1):GND    I22 @BASEBOARD_FAB2_LIB.BASEBOARD_FAB2(SCH_1):PAGE40
  AE42    GND @BASEBOARD_FAB2_LIB.BASEBOARD_FAB2(SCH_1):GND    I22 @BASEBOARD_FAB2_LIB.BASEBOARD_FAB2(SCH_1):PAGE40
  AE64    GND @BASEBOARD_FAB2_LIB.BASEBOARD_FAB2(SCH_1):GND    I22 @BASEBOARD_FAB2_LIB.BASEBOARD_FAB2(SCH_1):PAGE40
  AE66    GND @BASEBOARD_FAB2_LIB.BASEBOARD_FAB2(SCH_1):GND    I22 @BASEBOARD_FAB2_LIB.BASEBOARD_FAB2(SCH_1):PAGE40
  AE68    GND @BASEBOARD_FAB2_LIB.BASEBOARD_FAB2(SCH_1):GND    I22 @BASEBOARD_FAB2_LIB.BASEBOARD_FAB2(SCH_1):PAGE40
  AE70    GND @BASEBOARD_FAB2_LIB.BASEBOARD_FAB2(SCH_1):GND    I22 @BASEBOARD_FAB2_LIB.BASEBOARD_FAB2(SCH_1):PAGE40
  AE78    GND @BASEBOARD_FAB2_LIB.BASEBOARD_FAB2(SCH_1):GND    I22 @BASEBOARD_FAB2_LIB.BASEBOARD_FAB2(SCH_1):PAGE40
   AF1    GND @BASEBOARD_FAB2_LIB.BASEBOARD_FAB2(SCH_1):GND    I22 @BASEBOARD_FAB2_LIB.BASEBOARD_FAB2(SCH_1):PAGE40
  AC52    GND @BASEBOARD_FAB2_LIB.BASEBOARD_FAB2(SCH_1):GND    I22 @BASEBOARD_FAB2_LIB.BASEBOARD_FAB2(SCH_1):PAGE40
   AF9    GND @BASEBOARD_FAB2_LIB.BASEBOARD_FAB2(SCH_1):GND    I22 @BASEBOARD_FAB2_LIB.BASEBOARD_FAB2(SCH_1):PAGE40
  AF21    GND @BASEBOARD_FAB2_LIB.BASEBOARD_FAB2(SCH_1):GND    I22 @BASEBOARD_FAB2_LIB.BASEBOARD_FAB2(SCH_1):PAGE40
  AF23    GND @BASEBOARD_FAB2_LIB.BASEBOARD_FAB2(SCH_1):GND    I22 @BASEBOARD_FAB2_LIB.BASEBOARD_FAB2(SCH_1):PAGE40
  AF25    GND @BASEBOARD_FAB2_LIB.BASEBOARD_FAB2(SCH_1):GND    I22 @BASEBOARD_FAB2_LIB.BASEBOARD_FAB2(SCH_1):PAGE40
  AF27    GND @BASEBOARD_FAB2_LIB.BASEBOARD_FAB2(SCH_1):GND    I22 @BASEBOARD_FAB2_LIB.BASEBOARD_FAB2(SCH_1):PAGE40
  AF29    GND @BASEBOARD_FAB2_LIB.BASEBOARD_FAB2(SCH_1):GND    I22 @BASEBOARD_FAB2_LIB.BASEBOARD_FAB2(SCH_1):PAGE40
  AF31    GND @BASEBOARD_FAB2_LIB.BASEBOARD_FAB2(SCH_1):GND    I22 @BASEBOARD_FAB2_LIB.BASEBOARD_FAB2(SCH_1):PAGE40
  AF33    GND @BASEBOARD_FAB2_LIB.BASEBOARD_FAB2(SCH_1):GND    I22 @BASEBOARD_FAB2_LIB.BASEBOARD_FAB2(SCH_1):PAGE40
  AF37    GND @BASEBOARD_FAB2_LIB.BASEBOARD_FAB2(SCH_1):GND    I22 @BASEBOARD_FAB2_LIB.BASEBOARD_FAB2(SCH_1):PAGE40
  AF39    GND @BASEBOARD_FAB2_LIB.BASEBOARD_FAB2(SCH_1):GND    I22 @BASEBOARD_FAB2_LIB.BASEBOARD_FAB2(SCH_1):PAGE40
  AF41    GND @BASEBOARD_FAB2_LIB.BASEBOARD_FAB2(SCH_1):GND    I22 @BASEBOARD_FAB2_LIB.BASEBOARD_FAB2(SCH_1):PAGE40
  AF73    GND @BASEBOARD_FAB2_LIB.BASEBOARD_FAB2(SCH_1):GND    I22 @BASEBOARD_FAB2_LIB.BASEBOARD_FAB2(SCH_1):PAGE40
  AF77    GND @BASEBOARD_FAB2_LIB.BASEBOARD_FAB2(SCH_1):GND    I22 @BASEBOARD_FAB2_LIB.BASEBOARD_FAB2(SCH_1):PAGE40
  AF83    GND @BASEBOARD_FAB2_LIB.BASEBOARD_FAB2(SCH_1):GND    I22 @BASEBOARD_FAB2_LIB.BASEBOARD_FAB2(SCH_1):PAGE40
  AF85    GND @BASEBOARD_FAB2_LIB.BASEBOARD_FAB2(SCH_1):GND    I22 @BASEBOARD_FAB2_LIB.BASEBOARD_FAB2(SCH_1):PAGE40
  AG12    GND @BASEBOARD_FAB2_LIB.BASEBOARD_FAB2(SCH_1):GND    I22 @BASEBOARD_FAB2_LIB.BASEBOARD_FAB2(SCH_1):PAGE40
  AG14    GND @BASEBOARD_FAB2_LIB.BASEBOARD_FAB2(SCH_1):GND    I22 @BASEBOARD_FAB2_LIB.BASEBOARD_FAB2(SCH_1):PAGE40
  AG18    GND @BASEBOARD_FAB2_LIB.BASEBOARD_FAB2(SCH_1):GND    I22 @BASEBOARD_FAB2_LIB.BASEBOARD_FAB2(SCH_1):PAGE40
  AG36    GND @BASEBOARD_FAB2_LIB.BASEBOARD_FAB2(SCH_1):GND    I22 @BASEBOARD_FAB2_LIB.BASEBOARD_FAB2(SCH_1):PAGE40
  AG64    GND @BASEBOARD_FAB2_LIB.BASEBOARD_FAB2(SCH_1):GND    I22 @BASEBOARD_FAB2_LIB.BASEBOARD_FAB2(SCH_1):PAGE40
  AG70    GND @BASEBOARD_FAB2_LIB.BASEBOARD_FAB2(SCH_1):GND    I22 @BASEBOARD_FAB2_LIB.BASEBOARD_FAB2(SCH_1):PAGE40
  AG74    GND @BASEBOARD_FAB2_LIB.BASEBOARD_FAB2(SCH_1):GND    I22 @BASEBOARD_FAB2_LIB.BASEBOARD_FAB2(SCH_1):PAGE40
  AG76    GND @BASEBOARD_FAB2_LIB.BASEBOARD_FAB2(SCH_1):GND    I22 @BASEBOARD_FAB2_LIB.BASEBOARD_FAB2(SCH_1):PAGE40
  AG78    GND @BASEBOARD_FAB2_LIB.BASEBOARD_FAB2(SCH_1):GND    I22 @BASEBOARD_FAB2_LIB.BASEBOARD_FAB2(SCH_1):PAGE40
  AG80    GND @BASEBOARD_FAB2_LIB.BASEBOARD_FAB2(SCH_1):GND    I22 @BASEBOARD_FAB2_LIB.BASEBOARD_FAB2(SCH_1):PAGE40
   AH1    GND @BASEBOARD_FAB2_LIB.BASEBOARD_FAB2(SCH_1):GND    I22 @BASEBOARD_FAB2_LIB.BASEBOARD_FAB2(SCH_1):PAGE40
   AH5    GND @BASEBOARD_FAB2_LIB.BASEBOARD_FAB2(SCH_1):GND    I22 @BASEBOARD_FAB2_LIB.BASEBOARD_FAB2(SCH_1):PAGE40
  AH21    GND @BASEBOARD_FAB2_LIB.BASEBOARD_FAB2(SCH_1):GND    I22 @BASEBOARD_FAB2_LIB.BASEBOARD_FAB2(SCH_1):PAGE40
  AH27    GND @BASEBOARD_FAB2_LIB.BASEBOARD_FAB2(SCH_1):GND    I22 @BASEBOARD_FAB2_LIB.BASEBOARD_FAB2(SCH_1):PAGE40
  AH33    GND @BASEBOARD_FAB2_LIB.BASEBOARD_FAB2(SCH_1):GND    I22 @BASEBOARD_FAB2_LIB.BASEBOARD_FAB2(SCH_1):PAGE40
  AH35    GND @BASEBOARD_FAB2_LIB.BASEBOARD_FAB2(SCH_1):GND    I22 @BASEBOARD_FAB2_LIB.BASEBOARD_FAB2(SCH_1):PAGE40
  AH45    GND @BASEBOARD_FAB2_LIB.BASEBOARD_FAB2(SCH_1):GND    I22 @BASEBOARD_FAB2_LIB.BASEBOARD_FAB2(SCH_1):PAGE40
  AH47    GND @BASEBOARD_FAB2_LIB.BASEBOARD_FAB2(SCH_1):GND    I22 @BASEBOARD_FAB2_LIB.BASEBOARD_FAB2(SCH_1):PAGE40
  AH49    GND @BASEBOARD_FAB2_LIB.BASEBOARD_FAB2(SCH_1):GND    I22 @BASEBOARD_FAB2_LIB.BASEBOARD_FAB2(SCH_1):PAGE40
  AH51    GND @BASEBOARD_FAB2_LIB.BASEBOARD_FAB2(SCH_1):GND    I22 @BASEBOARD_FAB2_LIB.BASEBOARD_FAB2(SCH_1):PAGE40
  AH53    GND @BASEBOARD_FAB2_LIB.BASEBOARD_FAB2(SCH_1):GND    I22 @BASEBOARD_FAB2_LIB.BASEBOARD_FAB2(SCH_1):PAGE40
  AH59    GND @BASEBOARD_FAB2_LIB.BASEBOARD_FAB2(SCH_1):GND    I22 @BASEBOARD_FAB2_LIB.BASEBOARD_FAB2(SCH_1):PAGE40
  AH61    GND @BASEBOARD_FAB2_LIB.BASEBOARD_FAB2(SCH_1):GND    I22 @BASEBOARD_FAB2_LIB.BASEBOARD_FAB2(SCH_1):PAGE40
  AH65    GND @BASEBOARD_FAB2_LIB.BASEBOARD_FAB2(SCH_1):GND    I22 @BASEBOARD_FAB2_LIB.BASEBOARD_FAB2(SCH_1):PAGE40
  AH69    GND @BASEBOARD_FAB2_LIB.BASEBOARD_FAB2(SCH_1):GND    I22 @BASEBOARD_FAB2_LIB.BASEBOARD_FAB2(SCH_1):PAGE40
  AH75    GND @BASEBOARD_FAB2_LIB.BASEBOARD_FAB2(SCH_1):GND    I22 @BASEBOARD_FAB2_LIB.BASEBOARD_FAB2(SCH_1):PAGE40
  AH77    GND @BASEBOARD_FAB2_LIB.BASEBOARD_FAB2(SCH_1):GND    I22 @BASEBOARD_FAB2_LIB.BASEBOARD_FAB2(SCH_1):PAGE40
  AH83    GND @BASEBOARD_FAB2_LIB.BASEBOARD_FAB2(SCH_1):GND    I22 @BASEBOARD_FAB2_LIB.BASEBOARD_FAB2(SCH_1):PAGE40
   AJ8    GND @BASEBOARD_FAB2_LIB.BASEBOARD_FAB2(SCH_1):GND    I22 @BASEBOARD_FAB2_LIB.BASEBOARD_FAB2(SCH_1):PAGE40
  AJ22    GND @BASEBOARD_FAB2_LIB.BASEBOARD_FAB2(SCH_1):GND    I22 @BASEBOARD_FAB2_LIB.BASEBOARD_FAB2(SCH_1):PAGE40
  AJ26    GND @BASEBOARD_FAB2_LIB.BASEBOARD_FAB2(SCH_1):GND    I22 @BASEBOARD_FAB2_LIB.BASEBOARD_FAB2(SCH_1):PAGE40
  AJ28    GND @BASEBOARD_FAB2_LIB.BASEBOARD_FAB2(SCH_1):GND    I22 @BASEBOARD_FAB2_LIB.BASEBOARD_FAB2(SCH_1):PAGE40
  AJ32    GND @BASEBOARD_FAB2_LIB.BASEBOARD_FAB2(SCH_1):GND    I22 @BASEBOARD_FAB2_LIB.BASEBOARD_FAB2(SCH_1):PAGE40
  AJ34    GND @BASEBOARD_FAB2_LIB.BASEBOARD_FAB2(SCH_1):GND    I22 @BASEBOARD_FAB2_LIB.BASEBOARD_FAB2(SCH_1):PAGE40
  AJ46    GND @BASEBOARD_FAB2_LIB.BASEBOARD_FAB2(SCH_1):GND    I22 @BASEBOARD_FAB2_LIB.BASEBOARD_FAB2(SCH_1):PAGE40
  AJ48    GND @BASEBOARD_FAB2_LIB.BASEBOARD_FAB2(SCH_1):GND    I22 @BASEBOARD_FAB2_LIB.BASEBOARD_FAB2(SCH_1):PAGE40
  AJ50    GND @BASEBOARD_FAB2_LIB.BASEBOARD_FAB2(SCH_1):GND    I22 @BASEBOARD_FAB2_LIB.BASEBOARD_FAB2(SCH_1):PAGE40
  AJ52    GND @BASEBOARD_FAB2_LIB.BASEBOARD_FAB2(SCH_1):GND    I22 @BASEBOARD_FAB2_LIB.BASEBOARD_FAB2(SCH_1):PAGE40
  AJ54    GND @BASEBOARD_FAB2_LIB.BASEBOARD_FAB2(SCH_1):GND    I22 @BASEBOARD_FAB2_LIB.BASEBOARD_FAB2(SCH_1):PAGE40
  AJ66    GND @BASEBOARD_FAB2_LIB.BASEBOARD_FAB2(SCH_1):GND    I22 @BASEBOARD_FAB2_LIB.BASEBOARD_FAB2(SCH_1):PAGE40
  AJ68    GND @BASEBOARD_FAB2_LIB.BASEBOARD_FAB2(SCH_1):GND    I22 @BASEBOARD_FAB2_LIB.BASEBOARD_FAB2(SCH_1):PAGE40
  AJ74    GND @BASEBOARD_FAB2_LIB.BASEBOARD_FAB2(SCH_1):GND    I22 @BASEBOARD_FAB2_LIB.BASEBOARD_FAB2(SCH_1):PAGE40
  AJ78    GND @BASEBOARD_FAB2_LIB.BASEBOARD_FAB2(SCH_1):GND    I22 @BASEBOARD_FAB2_LIB.BASEBOARD_FAB2(SCH_1):PAGE40
  AJ82    GND @BASEBOARD_FAB2_LIB.BASEBOARD_FAB2(SCH_1):GND    I22 @BASEBOARD_FAB2_LIB.BASEBOARD_FAB2(SCH_1):PAGE40
  AJ86    GND @BASEBOARD_FAB2_LIB.BASEBOARD_FAB2(SCH_1):GND    I22 @BASEBOARD_FAB2_LIB.BASEBOARD_FAB2(SCH_1):PAGE40
   AK9    GND @BASEBOARD_FAB2_LIB.BASEBOARD_FAB2(SCH_1):GND    I22 @BASEBOARD_FAB2_LIB.BASEBOARD_FAB2(SCH_1):PAGE40
  AK13    GND @BASEBOARD_FAB2_LIB.BASEBOARD_FAB2(SCH_1):GND    I22 @BASEBOARD_FAB2_LIB.BASEBOARD_FAB2(SCH_1):PAGE40
  AK19    GND @BASEBOARD_FAB2_LIB.BASEBOARD_FAB2(SCH_1):GND    I22 @BASEBOARD_FAB2_LIB.BASEBOARD_FAB2(SCH_1):PAGE40
  AK23    GND @BASEBOARD_FAB2_LIB.BASEBOARD_FAB2(SCH_1):GND    I22 @BASEBOARD_FAB2_LIB.BASEBOARD_FAB2(SCH_1):PAGE40
  AK25    GND @BASEBOARD_FAB2_LIB.BASEBOARD_FAB2(SCH_1):GND    I22 @BASEBOARD_FAB2_LIB.BASEBOARD_FAB2(SCH_1):PAGE40
  AK29    GND @BASEBOARD_FAB2_LIB.BASEBOARD_FAB2(SCH_1):GND    I22 @BASEBOARD_FAB2_LIB.BASEBOARD_FAB2(SCH_1):PAGE40
  AK31    GND @BASEBOARD_FAB2_LIB.BASEBOARD_FAB2(SCH_1):GND    I22 @BASEBOARD_FAB2_LIB.BASEBOARD_FAB2(SCH_1):PAGE40
  AK33    GND @BASEBOARD_FAB2_LIB.BASEBOARD_FAB2(SCH_1):GND    I22 @BASEBOARD_FAB2_LIB.BASEBOARD_FAB2(SCH_1):PAGE40
  AK55    GND @BASEBOARD_FAB2_LIB.BASEBOARD_FAB2(SCH_1):GND    I22 @BASEBOARD_FAB2_LIB.BASEBOARD_FAB2(SCH_1):PAGE40
  AK65    GND @BASEBOARD_FAB2_LIB.BASEBOARD_FAB2(SCH_1):GND    I22 @BASEBOARD_FAB2_LIB.BASEBOARD_FAB2(SCH_1):PAGE40
  AK67    GND @BASEBOARD_FAB2_LIB.BASEBOARD_FAB2(SCH_1):GND    I22 @BASEBOARD_FAB2_LIB.BASEBOARD_FAB2(SCH_1):PAGE40
  AK73    GND @BASEBOARD_FAB2_LIB.BASEBOARD_FAB2(SCH_1):GND    I22 @BASEBOARD_FAB2_LIB.BASEBOARD_FAB2(SCH_1):PAGE40
  AK79    GND @BASEBOARD_FAB2_LIB.BASEBOARD_FAB2(SCH_1):GND    I22 @BASEBOARD_FAB2_LIB.BASEBOARD_FAB2(SCH_1):PAGE40
  AK81    GND @BASEBOARD_FAB2_LIB.BASEBOARD_FAB2(SCH_1):GND    I22 @BASEBOARD_FAB2_LIB.BASEBOARD_FAB2(SCH_1):PAGE40
  AK83    GND @BASEBOARD_FAB2_LIB.BASEBOARD_FAB2(SCH_1):GND    I22 @BASEBOARD_FAB2_LIB.BASEBOARD_FAB2(SCH_1):PAGE40
  AK85    GND @BASEBOARD_FAB2_LIB.BASEBOARD_FAB2(SCH_1):GND    I22 @BASEBOARD_FAB2_LIB.BASEBOARD_FAB2(SCH_1):PAGE40
   AL4    GND @BASEBOARD_FAB2_LIB.BASEBOARD_FAB2(SCH_1):GND    I22 @BASEBOARD_FAB2_LIB.BASEBOARD_FAB2(SCH_1):PAGE40
  AL10    GND @BASEBOARD_FAB2_LIB.BASEBOARD_FAB2(SCH_1):GND    I22 @BASEBOARD_FAB2_LIB.BASEBOARD_FAB2(SCH_1):PAGE40
  AL24    GND @BASEBOARD_FAB2_LIB.BASEBOARD_FAB2(SCH_1):GND    I22 @BASEBOARD_FAB2_LIB.BASEBOARD_FAB2(SCH_1):PAGE40
  AL30    GND @BASEBOARD_FAB2_LIB.BASEBOARD_FAB2(SCH_1):GND    I22 @BASEBOARD_FAB2_LIB.BASEBOARD_FAB2(SCH_1):PAGE40
  AL32    GND @BASEBOARD_FAB2_LIB.BASEBOARD_FAB2(SCH_1):GND    I22 @BASEBOARD_FAB2_LIB.BASEBOARD_FAB2(SCH_1):PAGE40
  AL56    GND @BASEBOARD_FAB2_LIB.BASEBOARD_FAB2(SCH_1):GND    I22 @BASEBOARD_FAB2_LIB.BASEBOARD_FAB2(SCH_1):PAGE40
  AL64    GND @BASEBOARD_FAB2_LIB.BASEBOARD_FAB2(SCH_1):GND    I22 @BASEBOARD_FAB2_LIB.BASEBOARD_FAB2(SCH_1):PAGE40
  AL68    GND @BASEBOARD_FAB2_LIB.BASEBOARD_FAB2(SCH_1):GND    I22 @BASEBOARD_FAB2_LIB.BASEBOARD_FAB2(SCH_1):PAGE40
  AL76    GND @BASEBOARD_FAB2_LIB.BASEBOARD_FAB2(SCH_1):GND    I23 @BASEBOARD_FAB2_LIB.BASEBOARD_FAB2(SCH_1):PAGE40
  AL78    GND @BASEBOARD_FAB2_LIB.BASEBOARD_FAB2(SCH_1):GND    I23 @BASEBOARD_FAB2_LIB.BASEBOARD_FAB2(SCH_1):PAGE40
  AL80    GND @BASEBOARD_FAB2_LIB.BASEBOARD_FAB2(SCH_1):GND    I23 @BASEBOARD_FAB2_LIB.BASEBOARD_FAB2(SCH_1):PAGE40
  AL82    GND @BASEBOARD_FAB2_LIB.BASEBOARD_FAB2(SCH_1):GND    I23 @BASEBOARD_FAB2_LIB.BASEBOARD_FAB2(SCH_1):PAGE40
  AL86    GND @BASEBOARD_FAB2_LIB.BASEBOARD_FAB2(SCH_1):GND    I23 @BASEBOARD_FAB2_LIB.BASEBOARD_FAB2(SCH_1):PAGE40
   AM1    GND @BASEBOARD_FAB2_LIB.BASEBOARD_FAB2(SCH_1):GND    I23 @BASEBOARD_FAB2_LIB.BASEBOARD_FAB2(SCH_1):PAGE40
  AC50    GND @BASEBOARD_FAB2_LIB.BASEBOARD_FAB2(SCH_1):GND    I23 @BASEBOARD_FAB2_LIB.BASEBOARD_FAB2(SCH_1):PAGE40
  AM31    GND @BASEBOARD_FAB2_LIB.BASEBOARD_FAB2(SCH_1):GND    I23 @BASEBOARD_FAB2_LIB.BASEBOARD_FAB2(SCH_1):PAGE40
  AM57    GND @BASEBOARD_FAB2_LIB.BASEBOARD_FAB2(SCH_1):GND    I23 @BASEBOARD_FAB2_LIB.BASEBOARD_FAB2(SCH_1):PAGE40
  AM63    GND @BASEBOARD_FAB2_LIB.BASEBOARD_FAB2(SCH_1):GND    I23 @BASEBOARD_FAB2_LIB.BASEBOARD_FAB2(SCH_1):PAGE40
  AM69    GND @BASEBOARD_FAB2_LIB.BASEBOARD_FAB2(SCH_1):GND    I23 @BASEBOARD_FAB2_LIB.BASEBOARD_FAB2(SCH_1):PAGE40
  AM73    GND @BASEBOARD_FAB2_LIB.BASEBOARD_FAB2(SCH_1):GND    I23 @BASEBOARD_FAB2_LIB.BASEBOARD_FAB2(SCH_1):PAGE40
  AM79    GND @BASEBOARD_FAB2_LIB.BASEBOARD_FAB2(SCH_1):GND    I23 @BASEBOARD_FAB2_LIB.BASEBOARD_FAB2(SCH_1):PAGE40
  AM83    GND @BASEBOARD_FAB2_LIB.BASEBOARD_FAB2(SCH_1):GND    I23 @BASEBOARD_FAB2_LIB.BASEBOARD_FAB2(SCH_1):PAGE40
   AN2    GND @BASEBOARD_FAB2_LIB.BASEBOARD_FAB2(SCH_1):GND    I23 @BASEBOARD_FAB2_LIB.BASEBOARD_FAB2(SCH_1):PAGE40
   AN6    GND @BASEBOARD_FAB2_LIB.BASEBOARD_FAB2(SCH_1):GND    I23 @BASEBOARD_FAB2_LIB.BASEBOARD_FAB2(SCH_1):PAGE40
  AN28    GND @BASEBOARD_FAB2_LIB.BASEBOARD_FAB2(SCH_1):GND    I23 @BASEBOARD_FAB2_LIB.BASEBOARD_FAB2(SCH_1):PAGE40
  AN58    GND @BASEBOARD_FAB2_LIB.BASEBOARD_FAB2(SCH_1):GND    I23 @BASEBOARD_FAB2_LIB.BASEBOARD_FAB2(SCH_1):PAGE40
  AN78    GND @BASEBOARD_FAB2_LIB.BASEBOARD_FAB2(SCH_1):GND    I23 @BASEBOARD_FAB2_LIB.BASEBOARD_FAB2(SCH_1):PAGE40
   AP5    GND @BASEBOARD_FAB2_LIB.BASEBOARD_FAB2(SCH_1):GND    I23 @BASEBOARD_FAB2_LIB.BASEBOARD_FAB2(SCH_1):PAGE40
   AP9    GND @BASEBOARD_FAB2_LIB.BASEBOARD_FAB2(SCH_1):GND    I23 @BASEBOARD_FAB2_LIB.BASEBOARD_FAB2(SCH_1):PAGE40
  AP13    GND @BASEBOARD_FAB2_LIB.BASEBOARD_FAB2(SCH_1):GND    I23 @BASEBOARD_FAB2_LIB.BASEBOARD_FAB2(SCH_1):PAGE40
  AP19    GND @BASEBOARD_FAB2_LIB.BASEBOARD_FAB2(SCH_1):GND    I23 @BASEBOARD_FAB2_LIB.BASEBOARD_FAB2(SCH_1):PAGE40
  AP31    GND @BASEBOARD_FAB2_LIB.BASEBOARD_FAB2(SCH_1):GND    I23 @BASEBOARD_FAB2_LIB.BASEBOARD_FAB2(SCH_1):PAGE40
  AP59    GND @BASEBOARD_FAB2_LIB.BASEBOARD_FAB2(SCH_1):GND    I23 @BASEBOARD_FAB2_LIB.BASEBOARD_FAB2(SCH_1):PAGE40
  AP63    GND @BASEBOARD_FAB2_LIB.BASEBOARD_FAB2(SCH_1):GND    I23 @BASEBOARD_FAB2_LIB.BASEBOARD_FAB2(SCH_1):PAGE40
  AP65    GND @BASEBOARD_FAB2_LIB.BASEBOARD_FAB2(SCH_1):GND    I23 @BASEBOARD_FAB2_LIB.BASEBOARD_FAB2(SCH_1):PAGE40
  AP67    GND @BASEBOARD_FAB2_LIB.BASEBOARD_FAB2(SCH_1):GND    I23 @BASEBOARD_FAB2_LIB.BASEBOARD_FAB2(SCH_1):PAGE40
  AP69    GND @BASEBOARD_FAB2_LIB.BASEBOARD_FAB2(SCH_1):GND    I23 @BASEBOARD_FAB2_LIB.BASEBOARD_FAB2(SCH_1):PAGE40
  AP73    GND @BASEBOARD_FAB2_LIB.BASEBOARD_FAB2(SCH_1):GND    I23 @BASEBOARD_FAB2_LIB.BASEBOARD_FAB2(SCH_1):PAGE40
  AP75    GND @BASEBOARD_FAB2_LIB.BASEBOARD_FAB2(SCH_1):GND    I23 @BASEBOARD_FAB2_LIB.BASEBOARD_FAB2(SCH_1):PAGE40
  AP81    GND @BASEBOARD_FAB2_LIB.BASEBOARD_FAB2(SCH_1):GND    I23 @BASEBOARD_FAB2_LIB.BASEBOARD_FAB2(SCH_1):PAGE40
  AP83    GND @BASEBOARD_FAB2_LIB.BASEBOARD_FAB2(SCH_1):GND    I23 @BASEBOARD_FAB2_LIB.BASEBOARD_FAB2(SCH_1):PAGE40
  AP85    GND @BASEBOARD_FAB2_LIB.BASEBOARD_FAB2(SCH_1):GND    I23 @BASEBOARD_FAB2_LIB.BASEBOARD_FAB2(SCH_1):PAGE40
  AR10    GND @BASEBOARD_FAB2_LIB.BASEBOARD_FAB2(SCH_1):GND    I23 @BASEBOARD_FAB2_LIB.BASEBOARD_FAB2(SCH_1):PAGE40
  AR24    GND @BASEBOARD_FAB2_LIB.BASEBOARD_FAB2(SCH_1):GND    I23 @BASEBOARD_FAB2_LIB.BASEBOARD_FAB2(SCH_1):PAGE40
  AR30    GND @BASEBOARD_FAB2_LIB.BASEBOARD_FAB2(SCH_1):GND    I23 @BASEBOARD_FAB2_LIB.BASEBOARD_FAB2(SCH_1):PAGE40
  AR60    GND @BASEBOARD_FAB2_LIB.BASEBOARD_FAB2(SCH_1):GND    I23 @BASEBOARD_FAB2_LIB.BASEBOARD_FAB2(SCH_1):PAGE40
  AR72    GND @BASEBOARD_FAB2_LIB.BASEBOARD_FAB2(SCH_1):GND    I23 @BASEBOARD_FAB2_LIB.BASEBOARD_FAB2(SCH_1):PAGE40
  AR78    GND @BASEBOARD_FAB2_LIB.BASEBOARD_FAB2(SCH_1):GND    I23 @BASEBOARD_FAB2_LIB.BASEBOARD_FAB2(SCH_1):PAGE40
  AC48    GND @BASEBOARD_FAB2_LIB.BASEBOARD_FAB2(SCH_1):GND    I23 @BASEBOARD_FAB2_LIB.BASEBOARD_FAB2(SCH_1):PAGE40
   P63    GND @BASEBOARD_FAB2_LIB.BASEBOARD_FAB2(SCH_1):GND    I23 @BASEBOARD_FAB2_LIB.BASEBOARD_FAB2(SCH_1):PAGE40
  AT15    GND @BASEBOARD_FAB2_LIB.BASEBOARD_FAB2(SCH_1):GND    I23 @BASEBOARD_FAB2_LIB.BASEBOARD_FAB2(SCH_1):PAGE40
  AT17    GND @BASEBOARD_FAB2_LIB.BASEBOARD_FAB2(SCH_1):GND    I23 @BASEBOARD_FAB2_LIB.BASEBOARD_FAB2(SCH_1):PAGE40
  AT21    GND @BASEBOARD_FAB2_LIB.BASEBOARD_FAB2(SCH_1):GND    I23 @BASEBOARD_FAB2_LIB.BASEBOARD_FAB2(SCH_1):PAGE40
  AT27    GND @BASEBOARD_FAB2_LIB.BASEBOARD_FAB2(SCH_1):GND    I23 @BASEBOARD_FAB2_LIB.BASEBOARD_FAB2(SCH_1):PAGE40
  AT61    GND @BASEBOARD_FAB2_LIB.BASEBOARD_FAB2(SCH_1):GND    I23 @BASEBOARD_FAB2_LIB.BASEBOARD_FAB2(SCH_1):PAGE40
  AT63    GND @BASEBOARD_FAB2_LIB.BASEBOARD_FAB2(SCH_1):GND    I23 @BASEBOARD_FAB2_LIB.BASEBOARD_FAB2(SCH_1):PAGE40
  AT69    GND @BASEBOARD_FAB2_LIB.BASEBOARD_FAB2(SCH_1):GND    I23 @BASEBOARD_FAB2_LIB.BASEBOARD_FAB2(SCH_1):PAGE40
  AT73    GND @BASEBOARD_FAB2_LIB.BASEBOARD_FAB2(SCH_1):GND    I23 @BASEBOARD_FAB2_LIB.BASEBOARD_FAB2(SCH_1):PAGE40
  AT77    GND @BASEBOARD_FAB2_LIB.BASEBOARD_FAB2(SCH_1):GND    I23 @BASEBOARD_FAB2_LIB.BASEBOARD_FAB2(SCH_1):PAGE40
  AT83    GND @BASEBOARD_FAB2_LIB.BASEBOARD_FAB2(SCH_1):GND    I23 @BASEBOARD_FAB2_LIB.BASEBOARD_FAB2(SCH_1):PAGE40
  AT85    GND @BASEBOARD_FAB2_LIB.BASEBOARD_FAB2(SCH_1):GND    I23 @BASEBOARD_FAB2_LIB.BASEBOARD_FAB2(SCH_1):PAGE40
   AU2    GND @BASEBOARD_FAB2_LIB.BASEBOARD_FAB2(SCH_1):GND    I23 @BASEBOARD_FAB2_LIB.BASEBOARD_FAB2(SCH_1):PAGE40
   AU6    GND @BASEBOARD_FAB2_LIB.BASEBOARD_FAB2(SCH_1):GND    I23 @BASEBOARD_FAB2_LIB.BASEBOARD_FAB2(SCH_1):PAGE40
  AU26    GND @BASEBOARD_FAB2_LIB.BASEBOARD_FAB2(SCH_1):GND    I23 @BASEBOARD_FAB2_LIB.BASEBOARD_FAB2(SCH_1):PAGE40
  AU28    GND @BASEBOARD_FAB2_LIB.BASEBOARD_FAB2(SCH_1):GND    I23 @BASEBOARD_FAB2_LIB.BASEBOARD_FAB2(SCH_1):PAGE40
  AU62    GND @BASEBOARD_FAB2_LIB.BASEBOARD_FAB2(SCH_1):GND    I23 @BASEBOARD_FAB2_LIB.BASEBOARD_FAB2(SCH_1):PAGE40
  AU64    GND @BASEBOARD_FAB2_LIB.BASEBOARD_FAB2(SCH_1):GND    I23 @BASEBOARD_FAB2_LIB.BASEBOARD_FAB2(SCH_1):PAGE40
  AU68    GND @BASEBOARD_FAB2_LIB.BASEBOARD_FAB2(SCH_1):GND    I23 @BASEBOARD_FAB2_LIB.BASEBOARD_FAB2(SCH_1):PAGE40
  AU74    GND @BASEBOARD_FAB2_LIB.BASEBOARD_FAB2(SCH_1):GND    I23 @BASEBOARD_FAB2_LIB.BASEBOARD_FAB2(SCH_1):PAGE40
  AU76    GND @BASEBOARD_FAB2_LIB.BASEBOARD_FAB2(SCH_1):GND    I23 @BASEBOARD_FAB2_LIB.BASEBOARD_FAB2(SCH_1):PAGE40
  AU78    GND @BASEBOARD_FAB2_LIB.BASEBOARD_FAB2(SCH_1):GND    I23 @BASEBOARD_FAB2_LIB.BASEBOARD_FAB2(SCH_1):PAGE40
  AU80    GND @BASEBOARD_FAB2_LIB.BASEBOARD_FAB2(SCH_1):GND    I23 @BASEBOARD_FAB2_LIB.BASEBOARD_FAB2(SCH_1):PAGE40
  AU84    GND @BASEBOARD_FAB2_LIB.BASEBOARD_FAB2(SCH_1):GND    I23 @BASEBOARD_FAB2_LIB.BASEBOARD_FAB2(SCH_1):PAGE40
  AU86    GND @BASEBOARD_FAB2_LIB.BASEBOARD_FAB2(SCH_1):GND    I23 @BASEBOARD_FAB2_LIB.BASEBOARD_FAB2(SCH_1):PAGE40
   AV1    GND @BASEBOARD_FAB2_LIB.BASEBOARD_FAB2(SCH_1):GND    I23 @BASEBOARD_FAB2_LIB.BASEBOARD_FAB2(SCH_1):PAGE40
   AV3    GND @BASEBOARD_FAB2_LIB.BASEBOARD_FAB2(SCH_1):GND    I23 @BASEBOARD_FAB2_LIB.BASEBOARD_FAB2(SCH_1):PAGE40
   AV7    GND @BASEBOARD_FAB2_LIB.BASEBOARD_FAB2(SCH_1):GND    I23 @BASEBOARD_FAB2_LIB.BASEBOARD_FAB2(SCH_1):PAGE40
  AV11    GND @BASEBOARD_FAB2_LIB.BASEBOARD_FAB2(SCH_1):GND    I23 @BASEBOARD_FAB2_LIB.BASEBOARD_FAB2(SCH_1):PAGE40
  AV13    GND @BASEBOARD_FAB2_LIB.BASEBOARD_FAB2(SCH_1):GND    I23 @BASEBOARD_FAB2_LIB.BASEBOARD_FAB2(SCH_1):PAGE40
  AV19    GND @BASEBOARD_FAB2_LIB.BASEBOARD_FAB2(SCH_1):GND    I23 @BASEBOARD_FAB2_LIB.BASEBOARD_FAB2(SCH_1):PAGE40
  AV23    GND @BASEBOARD_FAB2_LIB.BASEBOARD_FAB2(SCH_1):GND    I23 @BASEBOARD_FAB2_LIB.BASEBOARD_FAB2(SCH_1):PAGE40
  AV25    GND @BASEBOARD_FAB2_LIB.BASEBOARD_FAB2(SCH_1):GND    I23 @BASEBOARD_FAB2_LIB.BASEBOARD_FAB2(SCH_1):PAGE40
  AV63    GND @BASEBOARD_FAB2_LIB.BASEBOARD_FAB2(SCH_1):GND    I23 @BASEBOARD_FAB2_LIB.BASEBOARD_FAB2(SCH_1):PAGE40
  AV65    GND @BASEBOARD_FAB2_LIB.BASEBOARD_FAB2(SCH_1):GND    I23 @BASEBOARD_FAB2_LIB.BASEBOARD_FAB2(SCH_1):PAGE40
  AV67    GND @BASEBOARD_FAB2_LIB.BASEBOARD_FAB2(SCH_1):GND    I23 @BASEBOARD_FAB2_LIB.BASEBOARD_FAB2(SCH_1):PAGE40
  AV75    GND @BASEBOARD_FAB2_LIB.BASEBOARD_FAB2(SCH_1):GND    I23 @BASEBOARD_FAB2_LIB.BASEBOARD_FAB2(SCH_1):PAGE40
  AV83    GND @BASEBOARD_FAB2_LIB.BASEBOARD_FAB2(SCH_1):GND    I23 @BASEBOARD_FAB2_LIB.BASEBOARD_FAB2(SCH_1):PAGE40
   AW2    GND @BASEBOARD_FAB2_LIB.BASEBOARD_FAB2(SCH_1):GND    I23 @BASEBOARD_FAB2_LIB.BASEBOARD_FAB2(SCH_1):PAGE40
  AW10    GND @BASEBOARD_FAB2_LIB.BASEBOARD_FAB2(SCH_1):GND    I23 @BASEBOARD_FAB2_LIB.BASEBOARD_FAB2(SCH_1):PAGE40
  AW62    GND @BASEBOARD_FAB2_LIB.BASEBOARD_FAB2(SCH_1):GND    I23 @BASEBOARD_FAB2_LIB.BASEBOARD_FAB2(SCH_1):PAGE40
  AW66    GND @BASEBOARD_FAB2_LIB.BASEBOARD_FAB2(SCH_1):GND    I23 @BASEBOARD_FAB2_LIB.BASEBOARD_FAB2(SCH_1):PAGE40
  AW68    GND @BASEBOARD_FAB2_LIB.BASEBOARD_FAB2(SCH_1):GND    I23 @BASEBOARD_FAB2_LIB.BASEBOARD_FAB2(SCH_1):PAGE40
  AW70    GND @BASEBOARD_FAB2_LIB.BASEBOARD_FAB2(SCH_1):GND    I23 @BASEBOARD_FAB2_LIB.BASEBOARD_FAB2(SCH_1):PAGE40
  AW72    GND @BASEBOARD_FAB2_LIB.BASEBOARD_FAB2(SCH_1):GND    I23 @BASEBOARD_FAB2_LIB.BASEBOARD_FAB2(SCH_1):PAGE40
  AW74    GND @BASEBOARD_FAB2_LIB.BASEBOARD_FAB2(SCH_1):GND    I23 @BASEBOARD_FAB2_LIB.BASEBOARD_FAB2(SCH_1):PAGE40
  AW78    GND @BASEBOARD_FAB2_LIB.BASEBOARD_FAB2(SCH_1):GND    I23 @BASEBOARD_FAB2_LIB.BASEBOARD_FAB2(SCH_1):PAGE40
  AW82    GND @BASEBOARD_FAB2_LIB.BASEBOARD_FAB2(SCH_1):GND    I23 @BASEBOARD_FAB2_LIB.BASEBOARD_FAB2(SCH_1):PAGE40
  AW84    GND @BASEBOARD_FAB2_LIB.BASEBOARD_FAB2(SCH_1):GND    I23 @BASEBOARD_FAB2_LIB.BASEBOARD_FAB2(SCH_1):PAGE40
   AY5    GND @BASEBOARD_FAB2_LIB.BASEBOARD_FAB2(SCH_1):GND    I23 @BASEBOARD_FAB2_LIB.BASEBOARD_FAB2(SCH_1):PAGE40
  AY15    GND @BASEBOARD_FAB2_LIB.BASEBOARD_FAB2(SCH_1):GND    I23 @BASEBOARD_FAB2_LIB.BASEBOARD_FAB2(SCH_1):PAGE40
  AY17    GND @BASEBOARD_FAB2_LIB.BASEBOARD_FAB2(SCH_1):GND    I23 @BASEBOARD_FAB2_LIB.BASEBOARD_FAB2(SCH_1):PAGE40
  AY21    GND @BASEBOARD_FAB2_LIB.BASEBOARD_FAB2(SCH_1):GND    I23 @BASEBOARD_FAB2_LIB.BASEBOARD_FAB2(SCH_1):PAGE40
  AY23    GND @BASEBOARD_FAB2_LIB.BASEBOARD_FAB2(SCH_1):GND    I23 @BASEBOARD_FAB2_LIB.BASEBOARD_FAB2(SCH_1):PAGE40
  AY25    GND @BASEBOARD_FAB2_LIB.BASEBOARD_FAB2(SCH_1):GND    I23 @BASEBOARD_FAB2_LIB.BASEBOARD_FAB2(SCH_1):PAGE40
  AY63    GND @BASEBOARD_FAB2_LIB.BASEBOARD_FAB2(SCH_1):GND    I23 @BASEBOARD_FAB2_LIB.BASEBOARD_FAB2(SCH_1):PAGE40
  AY79    GND @BASEBOARD_FAB2_LIB.BASEBOARD_FAB2(SCH_1):GND    I23 @BASEBOARD_FAB2_LIB.BASEBOARD_FAB2(SCH_1):PAGE40
  AY81    GND @BASEBOARD_FAB2_LIB.BASEBOARD_FAB2(SCH_1):GND    I23 @BASEBOARD_FAB2_LIB.BASEBOARD_FAB2(SCH_1):PAGE40
   BA2    GND @BASEBOARD_FAB2_LIB.BASEBOARD_FAB2(SCH_1):GND    I23 @BASEBOARD_FAB2_LIB.BASEBOARD_FAB2(SCH_1):PAGE40
   BA6    GND @BASEBOARD_FAB2_LIB.BASEBOARD_FAB2(SCH_1):GND    I23 @BASEBOARD_FAB2_LIB.BASEBOARD_FAB2(SCH_1):PAGE40
  BA12    GND @BASEBOARD_FAB2_LIB.BASEBOARD_FAB2(SCH_1):GND    I23 @BASEBOARD_FAB2_LIB.BASEBOARD_FAB2(SCH_1):PAGE40
  BA62    GND @BASEBOARD_FAB2_LIB.BASEBOARD_FAB2(SCH_1):GND    I23 @BASEBOARD_FAB2_LIB.BASEBOARD_FAB2(SCH_1):PAGE40
  BA68    GND @BASEBOARD_FAB2_LIB.BASEBOARD_FAB2(SCH_1):GND    I23 @BASEBOARD_FAB2_LIB.BASEBOARD_FAB2(SCH_1):PAGE40
  BA74    GND @BASEBOARD_FAB2_LIB.BASEBOARD_FAB2(SCH_1):GND    I23 @BASEBOARD_FAB2_LIB.BASEBOARD_FAB2(SCH_1):PAGE40
  BA80    GND @BASEBOARD_FAB2_LIB.BASEBOARD_FAB2(SCH_1):GND    I23 @BASEBOARD_FAB2_LIB.BASEBOARD_FAB2(SCH_1):PAGE40
  BA84    GND @BASEBOARD_FAB2_LIB.BASEBOARD_FAB2(SCH_1):GND    I23 @BASEBOARD_FAB2_LIB.BASEBOARD_FAB2(SCH_1):PAGE40
  BB19    GND @BASEBOARD_FAB2_LIB.BASEBOARD_FAB2(SCH_1):GND    I23 @BASEBOARD_FAB2_LIB.BASEBOARD_FAB2(SCH_1):PAGE40
  BB23    GND @BASEBOARD_FAB2_LIB.BASEBOARD_FAB2(SCH_1):GND    I23 @BASEBOARD_FAB2_LIB.BASEBOARD_FAB2(SCH_1):PAGE40
  BB63    GND @BASEBOARD_FAB2_LIB.BASEBOARD_FAB2(SCH_1):GND    I23 @BASEBOARD_FAB2_LIB.BASEBOARD_FAB2(SCH_1):PAGE40
  BB69    GND @BASEBOARD_FAB2_LIB.BASEBOARD_FAB2(SCH_1):GND    I23 @BASEBOARD_FAB2_LIB.BASEBOARD_FAB2(SCH_1):PAGE40
  BB73    GND @BASEBOARD_FAB2_LIB.BASEBOARD_FAB2(SCH_1):GND    I23 @BASEBOARD_FAB2_LIB.BASEBOARD_FAB2(SCH_1):PAGE40
  BB75    GND @BASEBOARD_FAB2_LIB.BASEBOARD_FAB2(SCH_1):GND    I23 @BASEBOARD_FAB2_LIB.BASEBOARD_FAB2(SCH_1):PAGE40
  BB77    GND @BASEBOARD_FAB2_LIB.BASEBOARD_FAB2(SCH_1):GND    I23 @BASEBOARD_FAB2_LIB.BASEBOARD_FAB2(SCH_1):PAGE40
  BB79    GND @BASEBOARD_FAB2_LIB.BASEBOARD_FAB2(SCH_1):GND    I23 @BASEBOARD_FAB2_LIB.BASEBOARD_FAB2(SCH_1):PAGE40
  BB81    GND @BASEBOARD_FAB2_LIB.BASEBOARD_FAB2(SCH_1):GND    I23 @BASEBOARD_FAB2_LIB.BASEBOARD_FAB2(SCH_1):PAGE40
  BB83    GND @BASEBOARD_FAB2_LIB.BASEBOARD_FAB2(SCH_1):GND    I23 @BASEBOARD_FAB2_LIB.BASEBOARD_FAB2(SCH_1):PAGE40
   BC4    GND @BASEBOARD_FAB2_LIB.BASEBOARD_FAB2(SCH_1):GND    I23 @BASEBOARD_FAB2_LIB.BASEBOARD_FAB2(SCH_1):PAGE40
   BC8    GND @BASEBOARD_FAB2_LIB.BASEBOARD_FAB2(SCH_1):GND    I23 @BASEBOARD_FAB2_LIB.BASEBOARD_FAB2(SCH_1):PAGE40
  BC12    GND @BASEBOARD_FAB2_LIB.BASEBOARD_FAB2(SCH_1):GND    I23 @BASEBOARD_FAB2_LIB.BASEBOARD_FAB2(SCH_1):PAGE40
  BC16    GND @BASEBOARD_FAB2_LIB.BASEBOARD_FAB2(SCH_1):GND    I23 @BASEBOARD_FAB2_LIB.BASEBOARD_FAB2(SCH_1):PAGE40
  BC70    GND @BASEBOARD_FAB2_LIB.BASEBOARD_FAB2(SCH_1):GND    I23 @BASEBOARD_FAB2_LIB.BASEBOARD_FAB2(SCH_1):PAGE40
  BC72    GND @BASEBOARD_FAB2_LIB.BASEBOARD_FAB2(SCH_1):GND    I23 @BASEBOARD_FAB2_LIB.BASEBOARD_FAB2(SCH_1):PAGE40
  BC74    GND @BASEBOARD_FAB2_LIB.BASEBOARD_FAB2(SCH_1):GND    I23 @BASEBOARD_FAB2_LIB.BASEBOARD_FAB2(SCH_1):PAGE40
  BC76    GND @BASEBOARD_FAB2_LIB.BASEBOARD_FAB2(SCH_1):GND    I23 @BASEBOARD_FAB2_LIB.BASEBOARD_FAB2(SCH_1):PAGE40
  BC78    GND @BASEBOARD_FAB2_LIB.BASEBOARD_FAB2(SCH_1):GND    I23 @BASEBOARD_FAB2_LIB.BASEBOARD_FAB2(SCH_1):PAGE40
  BC80    GND @BASEBOARD_FAB2_LIB.BASEBOARD_FAB2(SCH_1):GND    I23 @BASEBOARD_FAB2_LIB.BASEBOARD_FAB2(SCH_1):PAGE40
  BC82    GND @BASEBOARD_FAB2_LIB.BASEBOARD_FAB2(SCH_1):GND    I23 @BASEBOARD_FAB2_LIB.BASEBOARD_FAB2(SCH_1):PAGE40
   BD5    GND @BASEBOARD_FAB2_LIB.BASEBOARD_FAB2(SCH_1):GND    I23 @BASEBOARD_FAB2_LIB.BASEBOARD_FAB2(SCH_1):PAGE40
  BD11    GND @BASEBOARD_FAB2_LIB.BASEBOARD_FAB2(SCH_1):GND    I23 @BASEBOARD_FAB2_LIB.BASEBOARD_FAB2(SCH_1):PAGE40
  BD15    GND @BASEBOARD_FAB2_LIB.BASEBOARD_FAB2(SCH_1):GND    I23 @BASEBOARD_FAB2_LIB.BASEBOARD_FAB2(SCH_1):PAGE40
  BD21    GND @BASEBOARD_FAB2_LIB.BASEBOARD_FAB2(SCH_1):GND    I23 @BASEBOARD_FAB2_LIB.BASEBOARD_FAB2(SCH_1):PAGE40
  BD27    GND @BASEBOARD_FAB2_LIB.BASEBOARD_FAB2(SCH_1):GND    I23 @BASEBOARD_FAB2_LIB.BASEBOARD_FAB2(SCH_1):PAGE40
  BD63    GND @BASEBOARD_FAB2_LIB.BASEBOARD_FAB2(SCH_1):GND    I23 @BASEBOARD_FAB2_LIB.BASEBOARD_FAB2(SCH_1):PAGE40
  BD71    GND @BASEBOARD_FAB2_LIB.BASEBOARD_FAB2(SCH_1):GND    I23 @BASEBOARD_FAB2_LIB.BASEBOARD_FAB2(SCH_1):PAGE40
   BE4    GND @BASEBOARD_FAB2_LIB.BASEBOARD_FAB2(SCH_1):GND    I23 @BASEBOARD_FAB2_LIB.BASEBOARD_FAB2(SCH_1):PAGE40
   BE6    GND @BASEBOARD_FAB2_LIB.BASEBOARD_FAB2(SCH_1):GND    I23 @BASEBOARD_FAB2_LIB.BASEBOARD_FAB2(SCH_1):PAGE40
   BE8    GND @BASEBOARD_FAB2_LIB.BASEBOARD_FAB2(SCH_1):GND    I23 @BASEBOARD_FAB2_LIB.BASEBOARD_FAB2(SCH_1):PAGE40
  BE10    GND @BASEBOARD_FAB2_LIB.BASEBOARD_FAB2(SCH_1):GND    I23 @BASEBOARD_FAB2_LIB.BASEBOARD_FAB2(SCH_1):PAGE40
  BE26    GND @BASEBOARD_FAB2_LIB.BASEBOARD_FAB2(SCH_1):GND    I23 @BASEBOARD_FAB2_LIB.BASEBOARD_FAB2(SCH_1):PAGE40
  BE64    GND @BASEBOARD_FAB2_LIB.BASEBOARD_FAB2(SCH_1):GND    I23 @BASEBOARD_FAB2_LIB.BASEBOARD_FAB2(SCH_1):PAGE40
  BE66    GND @BASEBOARD_FAB2_LIB.BASEBOARD_FAB2(SCH_1):GND    I23 @BASEBOARD_FAB2_LIB.BASEBOARD_FAB2(SCH_1):PAGE40
  BE68    GND @BASEBOARD_FAB2_LIB.BASEBOARD_FAB2(SCH_1):GND    I23 @BASEBOARD_FAB2_LIB.BASEBOARD_FAB2(SCH_1):PAGE40
  BE70    GND @BASEBOARD_FAB2_LIB.BASEBOARD_FAB2(SCH_1):GND    I23 @BASEBOARD_FAB2_LIB.BASEBOARD_FAB2(SCH_1):PAGE40
   BF9    GND @BASEBOARD_FAB2_LIB.BASEBOARD_FAB2(SCH_1):GND    I23 @BASEBOARD_FAB2_LIB.BASEBOARD_FAB2(SCH_1):PAGE40
  BF15    GND @BASEBOARD_FAB2_LIB.BASEBOARD_FAB2(SCH_1):GND    I23 @BASEBOARD_FAB2_LIB.BASEBOARD_FAB2(SCH_1):PAGE40
  BF17    GND @BASEBOARD_FAB2_LIB.BASEBOARD_FAB2(SCH_1):GND    I23 @BASEBOARD_FAB2_LIB.BASEBOARD_FAB2(SCH_1):PAGE40
  BF19    GND @BASEBOARD_FAB2_LIB.BASEBOARD_FAB2(SCH_1):GND    I23 @BASEBOARD_FAB2_LIB.BASEBOARD_FAB2(SCH_1):PAGE40
  BF25    GND @BASEBOARD_FAB2_LIB.BASEBOARD_FAB2(SCH_1):GND    I23 @BASEBOARD_FAB2_LIB.BASEBOARD_FAB2(SCH_1):PAGE40
  BF63    GND @BASEBOARD_FAB2_LIB.BASEBOARD_FAB2(SCH_1):GND    I23 @BASEBOARD_FAB2_LIB.BASEBOARD_FAB2(SCH_1):PAGE40
  BF65    GND @BASEBOARD_FAB2_LIB.BASEBOARD_FAB2(SCH_1):GND    I23 @BASEBOARD_FAB2_LIB.BASEBOARD_FAB2(SCH_1):PAGE40
  BF67    GND @BASEBOARD_FAB2_LIB.BASEBOARD_FAB2(SCH_1):GND    I23 @BASEBOARD_FAB2_LIB.BASEBOARD_FAB2(SCH_1):PAGE40
  BF69    GND @BASEBOARD_FAB2_LIB.BASEBOARD_FAB2(SCH_1):GND    I23 @BASEBOARD_FAB2_LIB.BASEBOARD_FAB2(SCH_1):PAGE40
  BF71    GND @BASEBOARD_FAB2_LIB.BASEBOARD_FAB2(SCH_1):GND    I23 @BASEBOARD_FAB2_LIB.BASEBOARD_FAB2(SCH_1):PAGE40
   BG6    GND @BASEBOARD_FAB2_LIB.BASEBOARD_FAB2(SCH_1):GND    I23 @BASEBOARD_FAB2_LIB.BASEBOARD_FAB2(SCH_1):PAGE40
   BG8    GND @BASEBOARD_FAB2_LIB.BASEBOARD_FAB2(SCH_1):GND    I23 @BASEBOARD_FAB2_LIB.BASEBOARD_FAB2(SCH_1):PAGE40
  BG10    GND @BASEBOARD_FAB2_LIB.BASEBOARD_FAB2(SCH_1):GND    I23 @BASEBOARD_FAB2_LIB.BASEBOARD_FAB2(SCH_1):PAGE40
  BG22    GND @BASEBOARD_FAB2_LIB.BASEBOARD_FAB2(SCH_1):GND    I23 @BASEBOARD_FAB2_LIB.BASEBOARD_FAB2(SCH_1):PAGE40
  BG24    GND @BASEBOARD_FAB2_LIB.BASEBOARD_FAB2(SCH_1):GND    I23 @BASEBOARD_FAB2_LIB.BASEBOARD_FAB2(SCH_1):PAGE40
  BG72    GND @BASEBOARD_FAB2_LIB.BASEBOARD_FAB2(SCH_1):GND    I23 @BASEBOARD_FAB2_LIB.BASEBOARD_FAB2(SCH_1):PAGE40
  BG74    GND @BASEBOARD_FAB2_LIB.BASEBOARD_FAB2(SCH_1):GND   I283 @BASEBOARD_FAB2_LIB.BASEBOARD_FAB2(SCH_1):PAGE41
  BG76    GND @BASEBOARD_FAB2_LIB.BASEBOARD_FAB2(SCH_1):GND   I283 @BASEBOARD_FAB2_LIB.BASEBOARD_FAB2(SCH_1):PAGE41
  BG78    GND @BASEBOARD_FAB2_LIB.BASEBOARD_FAB2(SCH_1):GND   I283 @BASEBOARD_FAB2_LIB.BASEBOARD_FAB2(SCH_1):PAGE41
  BG80    GND @BASEBOARD_FAB2_LIB.BASEBOARD_FAB2(SCH_1):GND   I283 @BASEBOARD_FAB2_LIB.BASEBOARD_FAB2(SCH_1):PAGE41
  BG82    GND @BASEBOARD_FAB2_LIB.BASEBOARD_FAB2(SCH_1):GND   I283 @BASEBOARD_FAB2_LIB.BASEBOARD_FAB2(SCH_1):PAGE41
   BH7    GND @BASEBOARD_FAB2_LIB.BASEBOARD_FAB2(SCH_1):GND   I283 @BASEBOARD_FAB2_LIB.BASEBOARD_FAB2(SCH_1):PAGE41
   BH9    GND @BASEBOARD_FAB2_LIB.BASEBOARD_FAB2(SCH_1):GND   I283 @BASEBOARD_FAB2_LIB.BASEBOARD_FAB2(SCH_1):PAGE41
  BH11    GND @BASEBOARD_FAB2_LIB.BASEBOARD_FAB2(SCH_1):GND   I283 @BASEBOARD_FAB2_LIB.BASEBOARD_FAB2(SCH_1):PAGE41
  BH15    GND @BASEBOARD_FAB2_LIB.BASEBOARD_FAB2(SCH_1):GND   I283 @BASEBOARD_FAB2_LIB.BASEBOARD_FAB2(SCH_1):PAGE41
  BH21    GND @BASEBOARD_FAB2_LIB.BASEBOARD_FAB2(SCH_1):GND   I283 @BASEBOARD_FAB2_LIB.BASEBOARD_FAB2(SCH_1):PAGE41
   BJ4    GND @BASEBOARD_FAB2_LIB.BASEBOARD_FAB2(SCH_1):GND   I283 @BASEBOARD_FAB2_LIB.BASEBOARD_FAB2(SCH_1):PAGE41
   BJ6    GND @BASEBOARD_FAB2_LIB.BASEBOARD_FAB2(SCH_1):GND   I283 @BASEBOARD_FAB2_LIB.BASEBOARD_FAB2(SCH_1):PAGE41
   BK3    GND @BASEBOARD_FAB2_LIB.BASEBOARD_FAB2(SCH_1):GND   I283 @BASEBOARD_FAB2_LIB.BASEBOARD_FAB2(SCH_1):PAGE41
   BK7    GND @BASEBOARD_FAB2_LIB.BASEBOARD_FAB2(SCH_1):GND   I283 @BASEBOARD_FAB2_LIB.BASEBOARD_FAB2(SCH_1):PAGE41
  BK11    GND @BASEBOARD_FAB2_LIB.BASEBOARD_FAB2(SCH_1):GND   I283 @BASEBOARD_FAB2_LIB.BASEBOARD_FAB2(SCH_1):PAGE41
  BK19    GND @BASEBOARD_FAB2_LIB.BASEBOARD_FAB2(SCH_1):GND   I283 @BASEBOARD_FAB2_LIB.BASEBOARD_FAB2(SCH_1):PAGE41
   BL6    GND @BASEBOARD_FAB2_LIB.BASEBOARD_FAB2(SCH_1):GND   I283 @BASEBOARD_FAB2_LIB.BASEBOARD_FAB2(SCH_1):PAGE41
  BL10    GND @BASEBOARD_FAB2_LIB.BASEBOARD_FAB2(SCH_1):GND   I283 @BASEBOARD_FAB2_LIB.BASEBOARD_FAB2(SCH_1):PAGE41
  BL12    GND @BASEBOARD_FAB2_LIB.BASEBOARD_FAB2(SCH_1):GND   I283 @BASEBOARD_FAB2_LIB.BASEBOARD_FAB2(SCH_1):PAGE41
   P61    GND @BASEBOARD_FAB2_LIB.BASEBOARD_FAB2(SCH_1):GND   I283 @BASEBOARD_FAB2_LIB.BASEBOARD_FAB2(SCH_1):PAGE41
  BL22    GND @BASEBOARD_FAB2_LIB.BASEBOARD_FAB2(SCH_1):GND   I283 @BASEBOARD_FAB2_LIB.BASEBOARD_FAB2(SCH_1):PAGE41
  BL24    GND @BASEBOARD_FAB2_LIB.BASEBOARD_FAB2(SCH_1):GND   I283 @BASEBOARD_FAB2_LIB.BASEBOARD_FAB2(SCH_1):PAGE41
  BL64    GND @BASEBOARD_FAB2_LIB.BASEBOARD_FAB2(SCH_1):GND   I283 @BASEBOARD_FAB2_LIB.BASEBOARD_FAB2(SCH_1):PAGE41
  BL66    GND @BASEBOARD_FAB2_LIB.BASEBOARD_FAB2(SCH_1):GND   I283 @BASEBOARD_FAB2_LIB.BASEBOARD_FAB2(SCH_1):PAGE41
  BL68    GND @BASEBOARD_FAB2_LIB.BASEBOARD_FAB2(SCH_1):GND   I283 @BASEBOARD_FAB2_LIB.BASEBOARD_FAB2(SCH_1):PAGE41
  BL70    GND @BASEBOARD_FAB2_LIB.BASEBOARD_FAB2(SCH_1):GND   I283 @BASEBOARD_FAB2_LIB.BASEBOARD_FAB2(SCH_1):PAGE41
  BL72    GND @BASEBOARD_FAB2_LIB.BASEBOARD_FAB2(SCH_1):GND   I283 @BASEBOARD_FAB2_LIB.BASEBOARD_FAB2(SCH_1):PAGE41
  BL74    GND @BASEBOARD_FAB2_LIB.BASEBOARD_FAB2(SCH_1):GND   I283 @BASEBOARD_FAB2_LIB.BASEBOARD_FAB2(SCH_1):PAGE41
  BL76    GND @BASEBOARD_FAB2_LIB.BASEBOARD_FAB2(SCH_1):GND   I283 @BASEBOARD_FAB2_LIB.BASEBOARD_FAB2(SCH_1):PAGE41
  BL78    GND @BASEBOARD_FAB2_LIB.BASEBOARD_FAB2(SCH_1):GND   I283 @BASEBOARD_FAB2_LIB.BASEBOARD_FAB2(SCH_1):PAGE41
  BL80    GND @BASEBOARD_FAB2_LIB.BASEBOARD_FAB2(SCH_1):GND   I283 @BASEBOARD_FAB2_LIB.BASEBOARD_FAB2(SCH_1):PAGE41
  BL82    GND @BASEBOARD_FAB2_LIB.BASEBOARD_FAB2(SCH_1):GND   I283 @BASEBOARD_FAB2_LIB.BASEBOARD_FAB2(SCH_1):PAGE41
   BM9    GND @BASEBOARD_FAB2_LIB.BASEBOARD_FAB2(SCH_1):GND   I283 @BASEBOARD_FAB2_LIB.BASEBOARD_FAB2(SCH_1):PAGE41
  BM13    GND @BASEBOARD_FAB2_LIB.BASEBOARD_FAB2(SCH_1):GND   I283 @BASEBOARD_FAB2_LIB.BASEBOARD_FAB2(SCH_1):PAGE41
  BM15    GND @BASEBOARD_FAB2_LIB.BASEBOARD_FAB2(SCH_1):GND   I283 @BASEBOARD_FAB2_LIB.BASEBOARD_FAB2(SCH_1):PAGE41
   P59    GND @BASEBOARD_FAB2_LIB.BASEBOARD_FAB2(SCH_1):GND   I283 @BASEBOARD_FAB2_LIB.BASEBOARD_FAB2(SCH_1):PAGE41
  BM25    GND @BASEBOARD_FAB2_LIB.BASEBOARD_FAB2(SCH_1):GND   I283 @BASEBOARD_FAB2_LIB.BASEBOARD_FAB2(SCH_1):PAGE41
   BN6    GND @BASEBOARD_FAB2_LIB.BASEBOARD_FAB2(SCH_1):GND   I283 @BASEBOARD_FAB2_LIB.BASEBOARD_FAB2(SCH_1):PAGE41
  BN10    GND @BASEBOARD_FAB2_LIB.BASEBOARD_FAB2(SCH_1):GND   I283 @BASEBOARD_FAB2_LIB.BASEBOARD_FAB2(SCH_1):PAGE41
  BN20    GND @BASEBOARD_FAB2_LIB.BASEBOARD_FAB2(SCH_1):GND   I283 @BASEBOARD_FAB2_LIB.BASEBOARD_FAB2(SCH_1):PAGE41
  BN26    GND @BASEBOARD_FAB2_LIB.BASEBOARD_FAB2(SCH_1):GND   I283 @BASEBOARD_FAB2_LIB.BASEBOARD_FAB2(SCH_1):PAGE41
   BP3    GND @BASEBOARD_FAB2_LIB.BASEBOARD_FAB2(SCH_1):GND   I283 @BASEBOARD_FAB2_LIB.BASEBOARD_FAB2(SCH_1):PAGE41
  BP27    GND @BASEBOARD_FAB2_LIB.BASEBOARD_FAB2(SCH_1):GND   I283 @BASEBOARD_FAB2_LIB.BASEBOARD_FAB2(SCH_1):PAGE41
   BR6    GND @BASEBOARD_FAB2_LIB.BASEBOARD_FAB2(SCH_1):GND   I283 @BASEBOARD_FAB2_LIB.BASEBOARD_FAB2(SCH_1):PAGE41
  BR10    GND @BASEBOARD_FAB2_LIB.BASEBOARD_FAB2(SCH_1):GND   I283 @BASEBOARD_FAB2_LIB.BASEBOARD_FAB2(SCH_1):PAGE41
  BR16    GND @BASEBOARD_FAB2_LIB.BASEBOARD_FAB2(SCH_1):GND   I283 @BASEBOARD_FAB2_LIB.BASEBOARD_FAB2(SCH_1):PAGE41
   P57    GND @BASEBOARD_FAB2_LIB.BASEBOARD_FAB2(SCH_1):GND   I283 @BASEBOARD_FAB2_LIB.BASEBOARD_FAB2(SCH_1):PAGE41
  BR64    GND @BASEBOARD_FAB2_LIB.BASEBOARD_FAB2(SCH_1):GND   I283 @BASEBOARD_FAB2_LIB.BASEBOARD_FAB2(SCH_1):PAGE41
  BR66    GND @BASEBOARD_FAB2_LIB.BASEBOARD_FAB2(SCH_1):GND   I283 @BASEBOARD_FAB2_LIB.BASEBOARD_FAB2(SCH_1):PAGE41
  BR68    GND @BASEBOARD_FAB2_LIB.BASEBOARD_FAB2(SCH_1):GND   I283 @BASEBOARD_FAB2_LIB.BASEBOARD_FAB2(SCH_1):PAGE41
  BR70    GND @BASEBOARD_FAB2_LIB.BASEBOARD_FAB2(SCH_1):GND   I283 @BASEBOARD_FAB2_LIB.BASEBOARD_FAB2(SCH_1):PAGE41
  BR72    GND @BASEBOARD_FAB2_LIB.BASEBOARD_FAB2(SCH_1):GND   I283 @BASEBOARD_FAB2_LIB.BASEBOARD_FAB2(SCH_1):PAGE41
  BR74    GND @BASEBOARD_FAB2_LIB.BASEBOARD_FAB2(SCH_1):GND   I283 @BASEBOARD_FAB2_LIB.BASEBOARD_FAB2(SCH_1):PAGE41
  BR76    GND @BASEBOARD_FAB2_LIB.BASEBOARD_FAB2(SCH_1):GND   I283 @BASEBOARD_FAB2_LIB.BASEBOARD_FAB2(SCH_1):PAGE41
  BR78    GND @BASEBOARD_FAB2_LIB.BASEBOARD_FAB2(SCH_1):GND   I283 @BASEBOARD_FAB2_LIB.BASEBOARD_FAB2(SCH_1):PAGE41
  BR80    GND @BASEBOARD_FAB2_LIB.BASEBOARD_FAB2(SCH_1):GND   I283 @BASEBOARD_FAB2_LIB.BASEBOARD_FAB2(SCH_1):PAGE41
  BR82    GND @BASEBOARD_FAB2_LIB.BASEBOARD_FAB2(SCH_1):GND   I283 @BASEBOARD_FAB2_LIB.BASEBOARD_FAB2(SCH_1):PAGE41
   BT3    GND @BASEBOARD_FAB2_LIB.BASEBOARD_FAB2(SCH_1):GND   I283 @BASEBOARD_FAB2_LIB.BASEBOARD_FAB2(SCH_1):PAGE41
   BT5    GND @BASEBOARD_FAB2_LIB.BASEBOARD_FAB2(SCH_1):GND   I283 @BASEBOARD_FAB2_LIB.BASEBOARD_FAB2(SCH_1):PAGE41
  BT21    GND @BASEBOARD_FAB2_LIB.BASEBOARD_FAB2(SCH_1):GND   I283 @BASEBOARD_FAB2_LIB.BASEBOARD_FAB2(SCH_1):PAGE41
  BT23    GND @BASEBOARD_FAB2_LIB.BASEBOARD_FAB2(SCH_1):GND   I283 @BASEBOARD_FAB2_LIB.BASEBOARD_FAB2(SCH_1):PAGE41
  BT25    GND @BASEBOARD_FAB2_LIB.BASEBOARD_FAB2(SCH_1):GND   I283 @BASEBOARD_FAB2_LIB.BASEBOARD_FAB2(SCH_1):PAGE41
   BU8    GND @BASEBOARD_FAB2_LIB.BASEBOARD_FAB2(SCH_1):GND   I283 @BASEBOARD_FAB2_LIB.BASEBOARD_FAB2(SCH_1):PAGE41
   BV5    GND @BASEBOARD_FAB2_LIB.BASEBOARD_FAB2(SCH_1):GND   I283 @BASEBOARD_FAB2_LIB.BASEBOARD_FAB2(SCH_1):PAGE41
  BU10    GND @BASEBOARD_FAB2_LIB.BASEBOARD_FAB2(SCH_1):GND   I283 @BASEBOARD_FAB2_LIB.BASEBOARD_FAB2(SCH_1):PAGE41
  BV17    GND @BASEBOARD_FAB2_LIB.BASEBOARD_FAB2(SCH_1):GND   I283 @BASEBOARD_FAB2_LIB.BASEBOARD_FAB2(SCH_1):PAGE41
  BV25    GND @BASEBOARD_FAB2_LIB.BASEBOARD_FAB2(SCH_1):GND   I283 @BASEBOARD_FAB2_LIB.BASEBOARD_FAB2(SCH_1):PAGE41
   BW6    GND @BASEBOARD_FAB2_LIB.BASEBOARD_FAB2(SCH_1):GND   I283 @BASEBOARD_FAB2_LIB.BASEBOARD_FAB2(SCH_1):PAGE41
   P55    GND @BASEBOARD_FAB2_LIB.BASEBOARD_FAB2(SCH_1):GND   I283 @BASEBOARD_FAB2_LIB.BASEBOARD_FAB2(SCH_1):PAGE41
  BW12    GND @BASEBOARD_FAB2_LIB.BASEBOARD_FAB2(SCH_1):GND   I283 @BASEBOARD_FAB2_LIB.BASEBOARD_FAB2(SCH_1):PAGE41
  BW14    GND @BASEBOARD_FAB2_LIB.BASEBOARD_FAB2(SCH_1):GND   I283 @BASEBOARD_FAB2_LIB.BASEBOARD_FAB2(SCH_1):PAGE41
  BW16    GND @BASEBOARD_FAB2_LIB.BASEBOARD_FAB2(SCH_1):GND   I283 @BASEBOARD_FAB2_LIB.BASEBOARD_FAB2(SCH_1):PAGE41
  BW18    GND @BASEBOARD_FAB2_LIB.BASEBOARD_FAB2(SCH_1):GND   I283 @BASEBOARD_FAB2_LIB.BASEBOARD_FAB2(SCH_1):PAGE41
  BW26    GND @BASEBOARD_FAB2_LIB.BASEBOARD_FAB2(SCH_1):GND   I283 @BASEBOARD_FAB2_LIB.BASEBOARD_FAB2(SCH_1):PAGE41
  BW72    GND @BASEBOARD_FAB2_LIB.BASEBOARD_FAB2(SCH_1):GND   I283 @BASEBOARD_FAB2_LIB.BASEBOARD_FAB2(SCH_1):PAGE41
  BW74    GND @BASEBOARD_FAB2_LIB.BASEBOARD_FAB2(SCH_1):GND   I283 @BASEBOARD_FAB2_LIB.BASEBOARD_FAB2(SCH_1):PAGE41
  BW76    GND @BASEBOARD_FAB2_LIB.BASEBOARD_FAB2(SCH_1):GND   I283 @BASEBOARD_FAB2_LIB.BASEBOARD_FAB2(SCH_1):PAGE41
  BW78    GND @BASEBOARD_FAB2_LIB.BASEBOARD_FAB2(SCH_1):GND   I283 @BASEBOARD_FAB2_LIB.BASEBOARD_FAB2(SCH_1):PAGE41
  BW80    GND @BASEBOARD_FAB2_LIB.BASEBOARD_FAB2(SCH_1):GND   I283 @BASEBOARD_FAB2_LIB.BASEBOARD_FAB2(SCH_1):PAGE41
  BW82    GND @BASEBOARD_FAB2_LIB.BASEBOARD_FAB2(SCH_1):GND   I283 @BASEBOARD_FAB2_LIB.BASEBOARD_FAB2(SCH_1):PAGE41
  BY11    GND @BASEBOARD_FAB2_LIB.BASEBOARD_FAB2(SCH_1):GND   I283 @BASEBOARD_FAB2_LIB.BASEBOARD_FAB2(SCH_1):PAGE41
  BY13    GND @BASEBOARD_FAB2_LIB.BASEBOARD_FAB2(SCH_1):GND   I283 @BASEBOARD_FAB2_LIB.BASEBOARD_FAB2(SCH_1):PAGE41
  BY23    GND @BASEBOARD_FAB2_LIB.BASEBOARD_FAB2(SCH_1):GND   I283 @BASEBOARD_FAB2_LIB.BASEBOARD_FAB2(SCH_1):PAGE41
  BY63    GND @BASEBOARD_FAB2_LIB.BASEBOARD_FAB2(SCH_1):GND   I283 @BASEBOARD_FAB2_LIB.BASEBOARD_FAB2(SCH_1):PAGE41
  BY65    GND @BASEBOARD_FAB2_LIB.BASEBOARD_FAB2(SCH_1):GND   I283 @BASEBOARD_FAB2_LIB.BASEBOARD_FAB2(SCH_1):PAGE41
  BY67    GND @BASEBOARD_FAB2_LIB.BASEBOARD_FAB2(SCH_1):GND   I283 @BASEBOARD_FAB2_LIB.BASEBOARD_FAB2(SCH_1):PAGE41
  BY69    GND @BASEBOARD_FAB2_LIB.BASEBOARD_FAB2(SCH_1):GND   I283 @BASEBOARD_FAB2_LIB.BASEBOARD_FAB2(SCH_1):PAGE41
  BY71    GND @BASEBOARD_FAB2_LIB.BASEBOARD_FAB2(SCH_1):GND   I283 @BASEBOARD_FAB2_LIB.BASEBOARD_FAB2(SCH_1):PAGE41
   CA2    GND @BASEBOARD_FAB2_LIB.BASEBOARD_FAB2(SCH_1):GND   I283 @BASEBOARD_FAB2_LIB.BASEBOARD_FAB2(SCH_1):PAGE41
   CA6    GND @BASEBOARD_FAB2_LIB.BASEBOARD_FAB2(SCH_1):GND   I283 @BASEBOARD_FAB2_LIB.BASEBOARD_FAB2(SCH_1):PAGE41
   CA8    GND @BASEBOARD_FAB2_LIB.BASEBOARD_FAB2(SCH_1):GND   I283 @BASEBOARD_FAB2_LIB.BASEBOARD_FAB2(SCH_1):PAGE41
  CA10    GND @BASEBOARD_FAB2_LIB.BASEBOARD_FAB2(SCH_1):GND   I283 @BASEBOARD_FAB2_LIB.BASEBOARD_FAB2(SCH_1):PAGE41
  CA14    GND @BASEBOARD_FAB2_LIB.BASEBOARD_FAB2(SCH_1):GND   I283 @BASEBOARD_FAB2_LIB.BASEBOARD_FAB2(SCH_1):PAGE41
  CA18    GND @BASEBOARD_FAB2_LIB.BASEBOARD_FAB2(SCH_1):GND   I283 @BASEBOARD_FAB2_LIB.BASEBOARD_FAB2(SCH_1):PAGE41
  CA26    GND @BASEBOARD_FAB2_LIB.BASEBOARD_FAB2(SCH_1):GND   I283 @BASEBOARD_FAB2_LIB.BASEBOARD_FAB2(SCH_1):PAGE41
  CA64    GND @BASEBOARD_FAB2_LIB.BASEBOARD_FAB2(SCH_1):GND   I283 @BASEBOARD_FAB2_LIB.BASEBOARD_FAB2(SCH_1):PAGE41
  CA66    GND @BASEBOARD_FAB2_LIB.BASEBOARD_FAB2(SCH_1):GND   I283 @BASEBOARD_FAB2_LIB.BASEBOARD_FAB2(SCH_1):PAGE41
  CA68    GND @BASEBOARD_FAB2_LIB.BASEBOARD_FAB2(SCH_1):GND   I283 @BASEBOARD_FAB2_LIB.BASEBOARD_FAB2(SCH_1):PAGE41
  CA70    GND @BASEBOARD_FAB2_LIB.BASEBOARD_FAB2(SCH_1):GND   I283 @BASEBOARD_FAB2_LIB.BASEBOARD_FAB2(SCH_1):PAGE41
   CB7    GND @BASEBOARD_FAB2_LIB.BASEBOARD_FAB2(SCH_1):GND   I283 @BASEBOARD_FAB2_LIB.BASEBOARD_FAB2(SCH_1):PAGE41
   CB9    GND @BASEBOARD_FAB2_LIB.BASEBOARD_FAB2(SCH_1):GND   I283 @BASEBOARD_FAB2_LIB.BASEBOARD_FAB2(SCH_1):PAGE41
  CB27    GND @BASEBOARD_FAB2_LIB.BASEBOARD_FAB2(SCH_1):GND   I283 @BASEBOARD_FAB2_LIB.BASEBOARD_FAB2(SCH_1):PAGE41
  CB63    GND @BASEBOARD_FAB2_LIB.BASEBOARD_FAB2(SCH_1):GND   I283 @BASEBOARD_FAB2_LIB.BASEBOARD_FAB2(SCH_1):PAGE41
  CB71    GND @BASEBOARD_FAB2_LIB.BASEBOARD_FAB2(SCH_1):GND   I283 @BASEBOARD_FAB2_LIB.BASEBOARD_FAB2(SCH_1):PAGE41
   CC4    GND @BASEBOARD_FAB2_LIB.BASEBOARD_FAB2(SCH_1):GND   I283 @BASEBOARD_FAB2_LIB.BASEBOARD_FAB2(SCH_1):PAGE41
  CC16    GND @BASEBOARD_FAB2_LIB.BASEBOARD_FAB2(SCH_1):GND   I283 @BASEBOARD_FAB2_LIB.BASEBOARD_FAB2(SCH_1):PAGE41
  CC18    GND @BASEBOARD_FAB2_LIB.BASEBOARD_FAB2(SCH_1):GND   I283 @BASEBOARD_FAB2_LIB.BASEBOARD_FAB2(SCH_1):PAGE41
  CC24    GND @BASEBOARD_FAB2_LIB.BASEBOARD_FAB2(SCH_1):GND   I283 @BASEBOARD_FAB2_LIB.BASEBOARD_FAB2(SCH_1):PAGE41
  CC64    GND @BASEBOARD_FAB2_LIB.BASEBOARD_FAB2(SCH_1):GND   I283 @BASEBOARD_FAB2_LIB.BASEBOARD_FAB2(SCH_1):PAGE41
  CC72    GND @BASEBOARD_FAB2_LIB.BASEBOARD_FAB2(SCH_1):GND   I283 @BASEBOARD_FAB2_LIB.BASEBOARD_FAB2(SCH_1):PAGE41
  CC74    GND @BASEBOARD_FAB2_LIB.BASEBOARD_FAB2(SCH_1):GND   I283 @BASEBOARD_FAB2_LIB.BASEBOARD_FAB2(SCH_1):PAGE41
  CC76    GND @BASEBOARD_FAB2_LIB.BASEBOARD_FAB2(SCH_1):GND   I283 @BASEBOARD_FAB2_LIB.BASEBOARD_FAB2(SCH_1):PAGE41
  CC78    GND @BASEBOARD_FAB2_LIB.BASEBOARD_FAB2(SCH_1):GND   I283 @BASEBOARD_FAB2_LIB.BASEBOARD_FAB2(SCH_1):PAGE41
  CC80    GND @BASEBOARD_FAB2_LIB.BASEBOARD_FAB2(SCH_1):GND   I283 @BASEBOARD_FAB2_LIB.BASEBOARD_FAB2(SCH_1):PAGE41
  CC82    GND @BASEBOARD_FAB2_LIB.BASEBOARD_FAB2(SCH_1):GND   I283 @BASEBOARD_FAB2_LIB.BASEBOARD_FAB2(SCH_1):PAGE41
   CD5    GND @BASEBOARD_FAB2_LIB.BASEBOARD_FAB2(SCH_1):GND   I283 @BASEBOARD_FAB2_LIB.BASEBOARD_FAB2(SCH_1):PAGE41
  CD13    GND @BASEBOARD_FAB2_LIB.BASEBOARD_FAB2(SCH_1):GND   I283 @BASEBOARD_FAB2_LIB.BASEBOARD_FAB2(SCH_1):PAGE41
  CD63    GND @BASEBOARD_FAB2_LIB.BASEBOARD_FAB2(SCH_1):GND   I283 @BASEBOARD_FAB2_LIB.BASEBOARD_FAB2(SCH_1):PAGE41
  CD73    GND @BASEBOARD_FAB2_LIB.BASEBOARD_FAB2(SCH_1):GND   I283 @BASEBOARD_FAB2_LIB.BASEBOARD_FAB2(SCH_1):PAGE41
  CD75    GND @BASEBOARD_FAB2_LIB.BASEBOARD_FAB2(SCH_1):GND   I283 @BASEBOARD_FAB2_LIB.BASEBOARD_FAB2(SCH_1):PAGE41
  CD77    GND @BASEBOARD_FAB2_LIB.BASEBOARD_FAB2(SCH_1):GND   I283 @BASEBOARD_FAB2_LIB.BASEBOARD_FAB2(SCH_1):PAGE41
  CD79    GND @BASEBOARD_FAB2_LIB.BASEBOARD_FAB2(SCH_1):GND   I283 @BASEBOARD_FAB2_LIB.BASEBOARD_FAB2(SCH_1):PAGE41
  CD81    GND @BASEBOARD_FAB2_LIB.BASEBOARD_FAB2(SCH_1):GND   I283 @BASEBOARD_FAB2_LIB.BASEBOARD_FAB2(SCH_1):PAGE41
  CE10    GND @BASEBOARD_FAB2_LIB.BASEBOARD_FAB2(SCH_1):GND   I283 @BASEBOARD_FAB2_LIB.BASEBOARD_FAB2(SCH_1):PAGE41
  CE14    GND @BASEBOARD_FAB2_LIB.BASEBOARD_FAB2(SCH_1):GND   I283 @BASEBOARD_FAB2_LIB.BASEBOARD_FAB2(SCH_1):PAGE41
  CE20    GND @BASEBOARD_FAB2_LIB.BASEBOARD_FAB2(SCH_1):GND   I283 @BASEBOARD_FAB2_LIB.BASEBOARD_FAB2(SCH_1):PAGE41
  CE26    GND @BASEBOARD_FAB2_LIB.BASEBOARD_FAB2(SCH_1):GND   I283 @BASEBOARD_FAB2_LIB.BASEBOARD_FAB2(SCH_1):PAGE41
  CE62    GND @BASEBOARD_FAB2_LIB.BASEBOARD_FAB2(SCH_1):GND   I283 @BASEBOARD_FAB2_LIB.BASEBOARD_FAB2(SCH_1):PAGE41
  CE70    GND @BASEBOARD_FAB2_LIB.BASEBOARD_FAB2(SCH_1):GND   I283 @BASEBOARD_FAB2_LIB.BASEBOARD_FAB2(SCH_1):PAGE41
  CE82    GND @BASEBOARD_FAB2_LIB.BASEBOARD_FAB2(SCH_1):GND   I283 @BASEBOARD_FAB2_LIB.BASEBOARD_FAB2(SCH_1):PAGE41
   P53    GND @BASEBOARD_FAB2_LIB.BASEBOARD_FAB2(SCH_1):GND   I283 @BASEBOARD_FAB2_LIB.BASEBOARD_FAB2(SCH_1):PAGE41
   CF9    GND @BASEBOARD_FAB2_LIB.BASEBOARD_FAB2(SCH_1):GND   I283 @BASEBOARD_FAB2_LIB.BASEBOARD_FAB2(SCH_1):PAGE41
  CF63    GND @BASEBOARD_FAB2_LIB.BASEBOARD_FAB2(SCH_1):GND   I283 @BASEBOARD_FAB2_LIB.BASEBOARD_FAB2(SCH_1):PAGE41
  CF69    GND @BASEBOARD_FAB2_LIB.BASEBOARD_FAB2(SCH_1):GND   I283 @BASEBOARD_FAB2_LIB.BASEBOARD_FAB2(SCH_1):PAGE41
  CF71    GND @BASEBOARD_FAB2_LIB.BASEBOARD_FAB2(SCH_1):GND   I283 @BASEBOARD_FAB2_LIB.BASEBOARD_FAB2(SCH_1):PAGE41
  CF77    GND @BASEBOARD_FAB2_LIB.BASEBOARD_FAB2(SCH_1):GND   I283 @BASEBOARD_FAB2_LIB.BASEBOARD_FAB2(SCH_1):PAGE41
  CF83    GND @BASEBOARD_FAB2_LIB.BASEBOARD_FAB2(SCH_1):GND   I283 @BASEBOARD_FAB2_LIB.BASEBOARD_FAB2(SCH_1):PAGE41
   P51    GND @BASEBOARD_FAB2_LIB.BASEBOARD_FAB2(SCH_1):GND   I283 @BASEBOARD_FAB2_LIB.BASEBOARD_FAB2(SCH_1):PAGE41
  CG18    GND @BASEBOARD_FAB2_LIB.BASEBOARD_FAB2(SCH_1):GND   I283 @BASEBOARD_FAB2_LIB.BASEBOARD_FAB2(SCH_1):PAGE41
  CG22    GND @BASEBOARD_FAB2_LIB.BASEBOARD_FAB2(SCH_1):GND   I283 @BASEBOARD_FAB2_LIB.BASEBOARD_FAB2(SCH_1):PAGE41
  CG62    GND @BASEBOARD_FAB2_LIB.BASEBOARD_FAB2(SCH_1):GND   I283 @BASEBOARD_FAB2_LIB.BASEBOARD_FAB2(SCH_1):PAGE41
  CG68    GND @BASEBOARD_FAB2_LIB.BASEBOARD_FAB2(SCH_1):GND   I283 @BASEBOARD_FAB2_LIB.BASEBOARD_FAB2(SCH_1):PAGE41
  CG72    GND @BASEBOARD_FAB2_LIB.BASEBOARD_FAB2(SCH_1):GND   I283 @BASEBOARD_FAB2_LIB.BASEBOARD_FAB2(SCH_1):PAGE41
  CG80    GND @BASEBOARD_FAB2_LIB.BASEBOARD_FAB2(SCH_1):GND   I283 @BASEBOARD_FAB2_LIB.BASEBOARD_FAB2(SCH_1):PAGE41
   CH1    GND @BASEBOARD_FAB2_LIB.BASEBOARD_FAB2(SCH_1):GND   I283 @BASEBOARD_FAB2_LIB.BASEBOARD_FAB2(SCH_1):PAGE41
   CH3    GND @BASEBOARD_FAB2_LIB.BASEBOARD_FAB2(SCH_1):GND   I283 @BASEBOARD_FAB2_LIB.BASEBOARD_FAB2(SCH_1):PAGE41
  CH15    GND @BASEBOARD_FAB2_LIB.BASEBOARD_FAB2(SCH_1):GND   I283 @BASEBOARD_FAB2_LIB.BASEBOARD_FAB2(SCH_1):PAGE41
  CH19    GND @BASEBOARD_FAB2_LIB.BASEBOARD_FAB2(SCH_1):GND   I283 @BASEBOARD_FAB2_LIB.BASEBOARD_FAB2(SCH_1):PAGE41
  CH63    GND @BASEBOARD_FAB2_LIB.BASEBOARD_FAB2(SCH_1):GND   I283 @BASEBOARD_FAB2_LIB.BASEBOARD_FAB2(SCH_1):PAGE41
  CH67    GND @BASEBOARD_FAB2_LIB.BASEBOARD_FAB2(SCH_1):GND   I283 @BASEBOARD_FAB2_LIB.BASEBOARD_FAB2(SCH_1):PAGE41
  CH73    GND @BASEBOARD_FAB2_LIB.BASEBOARD_FAB2(SCH_1):GND   I283 @BASEBOARD_FAB2_LIB.BASEBOARD_FAB2(SCH_1):PAGE41
  CH79    GND @BASEBOARD_FAB2_LIB.BASEBOARD_FAB2(SCH_1):GND   I283 @BASEBOARD_FAB2_LIB.BASEBOARD_FAB2(SCH_1):PAGE41
  CH81    GND @BASEBOARD_FAB2_LIB.BASEBOARD_FAB2(SCH_1):GND   I283 @BASEBOARD_FAB2_LIB.BASEBOARD_FAB2(SCH_1):PAGE41
  CH83    GND @BASEBOARD_FAB2_LIB.BASEBOARD_FAB2(SCH_1):GND   I283 @BASEBOARD_FAB2_LIB.BASEBOARD_FAB2(SCH_1):PAGE41
   CJ2    GND @BASEBOARD_FAB2_LIB.BASEBOARD_FAB2(SCH_1):GND   I283 @BASEBOARD_FAB2_LIB.BASEBOARD_FAB2(SCH_1):PAGE41
   CJ6    GND @BASEBOARD_FAB2_LIB.BASEBOARD_FAB2(SCH_1):GND   I283 @BASEBOARD_FAB2_LIB.BASEBOARD_FAB2(SCH_1):PAGE41
   CJ8    GND @BASEBOARD_FAB2_LIB.BASEBOARD_FAB2(SCH_1):GND   I283 @BASEBOARD_FAB2_LIB.BASEBOARD_FAB2(SCH_1):PAGE41
  CJ10    GND @BASEBOARD_FAB2_LIB.BASEBOARD_FAB2(SCH_1):GND   I283 @BASEBOARD_FAB2_LIB.BASEBOARD_FAB2(SCH_1):PAGE41
  CJ12    GND @BASEBOARD_FAB2_LIB.BASEBOARD_FAB2(SCH_1):GND   I283 @BASEBOARD_FAB2_LIB.BASEBOARD_FAB2(SCH_1):PAGE41
   P49    GND @BASEBOARD_FAB2_LIB.BASEBOARD_FAB2(SCH_1):GND   I283 @BASEBOARD_FAB2_LIB.BASEBOARD_FAB2(SCH_1):PAGE41
   P47    GND @BASEBOARD_FAB2_LIB.BASEBOARD_FAB2(SCH_1):GND   I284 @BASEBOARD_FAB2_LIB.BASEBOARD_FAB2(SCH_1):PAGE41
  CJ62    GND @BASEBOARD_FAB2_LIB.BASEBOARD_FAB2(SCH_1):GND   I284 @BASEBOARD_FAB2_LIB.BASEBOARD_FAB2(SCH_1):PAGE41
  CJ74    GND @BASEBOARD_FAB2_LIB.BASEBOARD_FAB2(SCH_1):GND   I284 @BASEBOARD_FAB2_LIB.BASEBOARD_FAB2(SCH_1):PAGE41
  CJ76    GND @BASEBOARD_FAB2_LIB.BASEBOARD_FAB2(SCH_1):GND   I284 @BASEBOARD_FAB2_LIB.BASEBOARD_FAB2(SCH_1):PAGE41
  CJ78    GND @BASEBOARD_FAB2_LIB.BASEBOARD_FAB2(SCH_1):GND   I284 @BASEBOARD_FAB2_LIB.BASEBOARD_FAB2(SCH_1):PAGE41
  CJ82    GND @BASEBOARD_FAB2_LIB.BASEBOARD_FAB2(SCH_1):GND   I284 @BASEBOARD_FAB2_LIB.BASEBOARD_FAB2(SCH_1):PAGE41
  CJ84    GND @BASEBOARD_FAB2_LIB.BASEBOARD_FAB2(SCH_1):GND   I284 @BASEBOARD_FAB2_LIB.BASEBOARD_FAB2(SCH_1):PAGE41
  CJ86    GND @BASEBOARD_FAB2_LIB.BASEBOARD_FAB2(SCH_1):GND   I284 @BASEBOARD_FAB2_LIB.BASEBOARD_FAB2(SCH_1):PAGE41
  CK11    GND @BASEBOARD_FAB2_LIB.BASEBOARD_FAB2(SCH_1):GND   I284 @BASEBOARD_FAB2_LIB.BASEBOARD_FAB2(SCH_1):PAGE41
  CK15    GND @BASEBOARD_FAB2_LIB.BASEBOARD_FAB2(SCH_1):GND   I284 @BASEBOARD_FAB2_LIB.BASEBOARD_FAB2(SCH_1):PAGE41
  CK21    GND @BASEBOARD_FAB2_LIB.BASEBOARD_FAB2(SCH_1):GND   I284 @BASEBOARD_FAB2_LIB.BASEBOARD_FAB2(SCH_1):PAGE41
  CK27    GND @BASEBOARD_FAB2_LIB.BASEBOARD_FAB2(SCH_1):GND   I284 @BASEBOARD_FAB2_LIB.BASEBOARD_FAB2(SCH_1):PAGE41
  CK63    GND @BASEBOARD_FAB2_LIB.BASEBOARD_FAB2(SCH_1):GND   I284 @BASEBOARD_FAB2_LIB.BASEBOARD_FAB2(SCH_1):PAGE41
  CK65    GND @BASEBOARD_FAB2_LIB.BASEBOARD_FAB2(SCH_1):GND   I284 @BASEBOARD_FAB2_LIB.BASEBOARD_FAB2(SCH_1):PAGE41
  CK67    GND @BASEBOARD_FAB2_LIB.BASEBOARD_FAB2(SCH_1):GND   I284 @BASEBOARD_FAB2_LIB.BASEBOARD_FAB2(SCH_1):PAGE41
  CK69    GND @BASEBOARD_FAB2_LIB.BASEBOARD_FAB2(SCH_1):GND   I284 @BASEBOARD_FAB2_LIB.BASEBOARD_FAB2(SCH_1):PAGE41
  CK71    GND @BASEBOARD_FAB2_LIB.BASEBOARD_FAB2(SCH_1):GND   I284 @BASEBOARD_FAB2_LIB.BASEBOARD_FAB2(SCH_1):PAGE41
  CK73    GND @BASEBOARD_FAB2_LIB.BASEBOARD_FAB2(SCH_1):GND   I284 @BASEBOARD_FAB2_LIB.BASEBOARD_FAB2(SCH_1):PAGE41
  CK75    GND @BASEBOARD_FAB2_LIB.BASEBOARD_FAB2(SCH_1):GND   I284 @BASEBOARD_FAB2_LIB.BASEBOARD_FAB2(SCH_1):PAGE41
  CK83    GND @BASEBOARD_FAB2_LIB.BASEBOARD_FAB2(SCH_1):GND   I284 @BASEBOARD_FAB2_LIB.BASEBOARD_FAB2(SCH_1):PAGE41
  CK85    GND @BASEBOARD_FAB2_LIB.BASEBOARD_FAB2(SCH_1):GND   I284 @BASEBOARD_FAB2_LIB.BASEBOARD_FAB2(SCH_1):PAGE41
   CL8    GND @BASEBOARD_FAB2_LIB.BASEBOARD_FAB2(SCH_1):GND   I284 @BASEBOARD_FAB2_LIB.BASEBOARD_FAB2(SCH_1):PAGE41
  CL14    GND @BASEBOARD_FAB2_LIB.BASEBOARD_FAB2(SCH_1):GND   I284 @BASEBOARD_FAB2_LIB.BASEBOARD_FAB2(SCH_1):PAGE41
  CL18    GND @BASEBOARD_FAB2_LIB.BASEBOARD_FAB2(SCH_1):GND   I284 @BASEBOARD_FAB2_LIB.BASEBOARD_FAB2(SCH_1):PAGE41
   P45    GND @BASEBOARD_FAB2_LIB.BASEBOARD_FAB2(SCH_1):GND   I284 @BASEBOARD_FAB2_LIB.BASEBOARD_FAB2(SCH_1):PAGE41
   H63    GND @BASEBOARD_FAB2_LIB.BASEBOARD_FAB2(SCH_1):GND   I284 @BASEBOARD_FAB2_LIB.BASEBOARD_FAB2(SCH_1):PAGE41
  CL62    GND @BASEBOARD_FAB2_LIB.BASEBOARD_FAB2(SCH_1):GND   I284 @BASEBOARD_FAB2_LIB.BASEBOARD_FAB2(SCH_1):PAGE41
  CL64    GND @BASEBOARD_FAB2_LIB.BASEBOARD_FAB2(SCH_1):GND   I284 @BASEBOARD_FAB2_LIB.BASEBOARD_FAB2(SCH_1):PAGE41
  CL66    GND @BASEBOARD_FAB2_LIB.BASEBOARD_FAB2(SCH_1):GND   I284 @BASEBOARD_FAB2_LIB.BASEBOARD_FAB2(SCH_1):PAGE41
  CL74    GND @BASEBOARD_FAB2_LIB.BASEBOARD_FAB2(SCH_1):GND   I284 @BASEBOARD_FAB2_LIB.BASEBOARD_FAB2(SCH_1):PAGE41
  CL76    GND @BASEBOARD_FAB2_LIB.BASEBOARD_FAB2(SCH_1):GND   I284 @BASEBOARD_FAB2_LIB.BASEBOARD_FAB2(SCH_1):PAGE41
  CL78    GND @BASEBOARD_FAB2_LIB.BASEBOARD_FAB2(SCH_1):GND   I284 @BASEBOARD_FAB2_LIB.BASEBOARD_FAB2(SCH_1):PAGE41
  CL80    GND @BASEBOARD_FAB2_LIB.BASEBOARD_FAB2(SCH_1):GND   I284 @BASEBOARD_FAB2_LIB.BASEBOARD_FAB2(SCH_1):PAGE41
  CM19    GND @BASEBOARD_FAB2_LIB.BASEBOARD_FAB2(SCH_1):GND   I284 @BASEBOARD_FAB2_LIB.BASEBOARD_FAB2(SCH_1):PAGE41
  CM29    GND @BASEBOARD_FAB2_LIB.BASEBOARD_FAB2(SCH_1):GND   I284 @BASEBOARD_FAB2_LIB.BASEBOARD_FAB2(SCH_1):PAGE41
   CM5    GND @BASEBOARD_FAB2_LIB.BASEBOARD_FAB2(SCH_1):GND   I284 @BASEBOARD_FAB2_LIB.BASEBOARD_FAB2(SCH_1):PAGE41
  CM31    GND @BASEBOARD_FAB2_LIB.BASEBOARD_FAB2(SCH_1):GND   I284 @BASEBOARD_FAB2_LIB.BASEBOARD_FAB2(SCH_1):PAGE41
  CM61    GND @BASEBOARD_FAB2_LIB.BASEBOARD_FAB2(SCH_1):GND   I284 @BASEBOARD_FAB2_LIB.BASEBOARD_FAB2(SCH_1):PAGE41
  CM63    GND @BASEBOARD_FAB2_LIB.BASEBOARD_FAB2(SCH_1):GND   I284 @BASEBOARD_FAB2_LIB.BASEBOARD_FAB2(SCH_1):PAGE41
  CM67    GND @BASEBOARD_FAB2_LIB.BASEBOARD_FAB2(SCH_1):GND   I284 @BASEBOARD_FAB2_LIB.BASEBOARD_FAB2(SCH_1):PAGE41
  CM73    GND @BASEBOARD_FAB2_LIB.BASEBOARD_FAB2(SCH_1):GND   I284 @BASEBOARD_FAB2_LIB.BASEBOARD_FAB2(SCH_1):PAGE41
  CM77    GND @BASEBOARD_FAB2_LIB.BASEBOARD_FAB2(SCH_1):GND   I284 @BASEBOARD_FAB2_LIB.BASEBOARD_FAB2(SCH_1):PAGE41
  CM83    GND @BASEBOARD_FAB2_LIB.BASEBOARD_FAB2(SCH_1):GND   I284 @BASEBOARD_FAB2_LIB.BASEBOARD_FAB2(SCH_1):PAGE41
  CM85    GND @BASEBOARD_FAB2_LIB.BASEBOARD_FAB2(SCH_1):GND   I284 @BASEBOARD_FAB2_LIB.BASEBOARD_FAB2(SCH_1):PAGE41
   CN2    GND @BASEBOARD_FAB2_LIB.BASEBOARD_FAB2(SCH_1):GND   I284 @BASEBOARD_FAB2_LIB.BASEBOARD_FAB2(SCH_1):PAGE41
  CN12    GND @BASEBOARD_FAB2_LIB.BASEBOARD_FAB2(SCH_1):GND   I284 @BASEBOARD_FAB2_LIB.BASEBOARD_FAB2(SCH_1):PAGE41
   H61    GND @BASEBOARD_FAB2_LIB.BASEBOARD_FAB2(SCH_1):GND   I284 @BASEBOARD_FAB2_LIB.BASEBOARD_FAB2(SCH_1):PAGE41
  CN26    GND @BASEBOARD_FAB2_LIB.BASEBOARD_FAB2(SCH_1):GND   I284 @BASEBOARD_FAB2_LIB.BASEBOARD_FAB2(SCH_1):PAGE41
  CN32    GND @BASEBOARD_FAB2_LIB.BASEBOARD_FAB2(SCH_1):GND   I284 @BASEBOARD_FAB2_LIB.BASEBOARD_FAB2(SCH_1):PAGE41
  CN60    GND @BASEBOARD_FAB2_LIB.BASEBOARD_FAB2(SCH_1):GND   I284 @BASEBOARD_FAB2_LIB.BASEBOARD_FAB2(SCH_1):PAGE41
  CN62    GND @BASEBOARD_FAB2_LIB.BASEBOARD_FAB2(SCH_1):GND   I284 @BASEBOARD_FAB2_LIB.BASEBOARD_FAB2(SCH_1):PAGE41
  CN68    GND @BASEBOARD_FAB2_LIB.BASEBOARD_FAB2(SCH_1):GND   I284 @BASEBOARD_FAB2_LIB.BASEBOARD_FAB2(SCH_1):PAGE41
  CN78    GND @BASEBOARD_FAB2_LIB.BASEBOARD_FAB2(SCH_1):GND   I284 @BASEBOARD_FAB2_LIB.BASEBOARD_FAB2(SCH_1):PAGE41
   CP1    GND @BASEBOARD_FAB2_LIB.BASEBOARD_FAB2(SCH_1):GND   I284 @BASEBOARD_FAB2_LIB.BASEBOARD_FAB2(SCH_1):PAGE41
   H59    GND @BASEBOARD_FAB2_LIB.BASEBOARD_FAB2(SCH_1):GND   I284 @BASEBOARD_FAB2_LIB.BASEBOARD_FAB2(SCH_1):PAGE41
  CP25    GND @BASEBOARD_FAB2_LIB.BASEBOARD_FAB2(SCH_1):GND   I284 @BASEBOARD_FAB2_LIB.BASEBOARD_FAB2(SCH_1):PAGE41
  CP59    GND @BASEBOARD_FAB2_LIB.BASEBOARD_FAB2(SCH_1):GND   I284 @BASEBOARD_FAB2_LIB.BASEBOARD_FAB2(SCH_1):PAGE41
  CP69    GND @BASEBOARD_FAB2_LIB.BASEBOARD_FAB2(SCH_1):GND   I284 @BASEBOARD_FAB2_LIB.BASEBOARD_FAB2(SCH_1):PAGE41
  CP73    GND @BASEBOARD_FAB2_LIB.BASEBOARD_FAB2(SCH_1):GND   I284 @BASEBOARD_FAB2_LIB.BASEBOARD_FAB2(SCH_1):PAGE41
  CP75    GND @BASEBOARD_FAB2_LIB.BASEBOARD_FAB2(SCH_1):GND   I284 @BASEBOARD_FAB2_LIB.BASEBOARD_FAB2(SCH_1):PAGE41
  CP81    GND @BASEBOARD_FAB2_LIB.BASEBOARD_FAB2(SCH_1):GND   I284 @BASEBOARD_FAB2_LIB.BASEBOARD_FAB2(SCH_1):PAGE41
  CP83    GND @BASEBOARD_FAB2_LIB.BASEBOARD_FAB2(SCH_1):GND   I284 @BASEBOARD_FAB2_LIB.BASEBOARD_FAB2(SCH_1):PAGE41
   CR6    GND @BASEBOARD_FAB2_LIB.BASEBOARD_FAB2(SCH_1):GND   I284 @BASEBOARD_FAB2_LIB.BASEBOARD_FAB2(SCH_1):PAGE41
  CR10    GND @BASEBOARD_FAB2_LIB.BASEBOARD_FAB2(SCH_1):GND   I284 @BASEBOARD_FAB2_LIB.BASEBOARD_FAB2(SCH_1):PAGE41
  CR22    GND @BASEBOARD_FAB2_LIB.BASEBOARD_FAB2(SCH_1):GND   I284 @BASEBOARD_FAB2_LIB.BASEBOARD_FAB2(SCH_1):PAGE41
  CR24    GND @BASEBOARD_FAB2_LIB.BASEBOARD_FAB2(SCH_1):GND   I284 @BASEBOARD_FAB2_LIB.BASEBOARD_FAB2(SCH_1):PAGE41
  CR32    GND @BASEBOARD_FAB2_LIB.BASEBOARD_FAB2(SCH_1):GND   I284 @BASEBOARD_FAB2_LIB.BASEBOARD_FAB2(SCH_1):PAGE41
  CR58    GND @BASEBOARD_FAB2_LIB.BASEBOARD_FAB2(SCH_1):GND   I284 @BASEBOARD_FAB2_LIB.BASEBOARD_FAB2(SCH_1):PAGE41
  CR62    GND @BASEBOARD_FAB2_LIB.BASEBOARD_FAB2(SCH_1):GND   I284 @BASEBOARD_FAB2_LIB.BASEBOARD_FAB2(SCH_1):PAGE41
  CR64    GND @BASEBOARD_FAB2_LIB.BASEBOARD_FAB2(SCH_1):GND   I284 @BASEBOARD_FAB2_LIB.BASEBOARD_FAB2(SCH_1):PAGE41
  CR66    GND @BASEBOARD_FAB2_LIB.BASEBOARD_FAB2(SCH_1):GND   I284 @BASEBOARD_FAB2_LIB.BASEBOARD_FAB2(SCH_1):PAGE41
  CR68    GND @BASEBOARD_FAB2_LIB.BASEBOARD_FAB2(SCH_1):GND   I284 @BASEBOARD_FAB2_LIB.BASEBOARD_FAB2(SCH_1):PAGE41
  CR78    GND @BASEBOARD_FAB2_LIB.BASEBOARD_FAB2(SCH_1):GND   I284 @BASEBOARD_FAB2_LIB.BASEBOARD_FAB2(SCH_1):PAGE41
  CR86    GND @BASEBOARD_FAB2_LIB.BASEBOARD_FAB2(SCH_1):GND   I284 @BASEBOARD_FAB2_LIB.BASEBOARD_FAB2(SCH_1):PAGE41
   H57    GND @BASEBOARD_FAB2_LIB.BASEBOARD_FAB2(SCH_1):GND   I284 @BASEBOARD_FAB2_LIB.BASEBOARD_FAB2(SCH_1):PAGE41
  CT13    GND @BASEBOARD_FAB2_LIB.BASEBOARD_FAB2(SCH_1):GND   I284 @BASEBOARD_FAB2_LIB.BASEBOARD_FAB2(SCH_1):PAGE41
  CT19    GND @BASEBOARD_FAB2_LIB.BASEBOARD_FAB2(SCH_1):GND   I284 @BASEBOARD_FAB2_LIB.BASEBOARD_FAB2(SCH_1):PAGE41
  CT27    GND @BASEBOARD_FAB2_LIB.BASEBOARD_FAB2(SCH_1):GND   I284 @BASEBOARD_FAB2_LIB.BASEBOARD_FAB2(SCH_1):PAGE41
  CT29    GND @BASEBOARD_FAB2_LIB.BASEBOARD_FAB2(SCH_1):GND   I284 @BASEBOARD_FAB2_LIB.BASEBOARD_FAB2(SCH_1):PAGE41
  CT33    GND @BASEBOARD_FAB2_LIB.BASEBOARD_FAB2(SCH_1):GND   I284 @BASEBOARD_FAB2_LIB.BASEBOARD_FAB2(SCH_1):PAGE41
  CT35    GND @BASEBOARD_FAB2_LIB.BASEBOARD_FAB2(SCH_1):GND   I284 @BASEBOARD_FAB2_LIB.BASEBOARD_FAB2(SCH_1):PAGE41
  CT57    GND @BASEBOARD_FAB2_LIB.BASEBOARD_FAB2(SCH_1):GND   I284 @BASEBOARD_FAB2_LIB.BASEBOARD_FAB2(SCH_1):PAGE41
  CT73    GND @BASEBOARD_FAB2_LIB.BASEBOARD_FAB2(SCH_1):GND   I284 @BASEBOARD_FAB2_LIB.BASEBOARD_FAB2(SCH_1):PAGE41
  CT79    GND @BASEBOARD_FAB2_LIB.BASEBOARD_FAB2(SCH_1):GND   I284 @BASEBOARD_FAB2_LIB.BASEBOARD_FAB2(SCH_1):PAGE41
  CT83    GND @BASEBOARD_FAB2_LIB.BASEBOARD_FAB2(SCH_1):GND   I284 @BASEBOARD_FAB2_LIB.BASEBOARD_FAB2(SCH_1):PAGE41
  CT85    GND @BASEBOARD_FAB2_LIB.BASEBOARD_FAB2(SCH_1):GND   I284 @BASEBOARD_FAB2_LIB.BASEBOARD_FAB2(SCH_1):PAGE41
   CU4    GND @BASEBOARD_FAB2_LIB.BASEBOARD_FAB2(SCH_1):GND   I284 @BASEBOARD_FAB2_LIB.BASEBOARD_FAB2(SCH_1):PAGE41
  CU22    GND @BASEBOARD_FAB2_LIB.BASEBOARD_FAB2(SCH_1):GND   I284 @BASEBOARD_FAB2_LIB.BASEBOARD_FAB2(SCH_1):PAGE41
  CU28    GND @BASEBOARD_FAB2_LIB.BASEBOARD_FAB2(SCH_1):GND   I284 @BASEBOARD_FAB2_LIB.BASEBOARD_FAB2(SCH_1):PAGE41
  CU30    GND @BASEBOARD_FAB2_LIB.BASEBOARD_FAB2(SCH_1):GND   I284 @BASEBOARD_FAB2_LIB.BASEBOARD_FAB2(SCH_1):PAGE41
  CU34    GND @BASEBOARD_FAB2_LIB.BASEBOARD_FAB2(SCH_1):GND   I284 @BASEBOARD_FAB2_LIB.BASEBOARD_FAB2(SCH_1):PAGE41
  CU36    GND @BASEBOARD_FAB2_LIB.BASEBOARD_FAB2(SCH_1):GND   I284 @BASEBOARD_FAB2_LIB.BASEBOARD_FAB2(SCH_1):PAGE41
  CU56    GND @BASEBOARD_FAB2_LIB.BASEBOARD_FAB2(SCH_1):GND   I284 @BASEBOARD_FAB2_LIB.BASEBOARD_FAB2(SCH_1):PAGE41
  CU62    GND @BASEBOARD_FAB2_LIB.BASEBOARD_FAB2(SCH_1):GND   I284 @BASEBOARD_FAB2_LIB.BASEBOARD_FAB2(SCH_1):PAGE41
  CU68    GND @BASEBOARD_FAB2_LIB.BASEBOARD_FAB2(SCH_1):GND   I284 @BASEBOARD_FAB2_LIB.BASEBOARD_FAB2(SCH_1):PAGE41
  CU76    GND @BASEBOARD_FAB2_LIB.BASEBOARD_FAB2(SCH_1):GND   I284 @BASEBOARD_FAB2_LIB.BASEBOARD_FAB2(SCH_1):PAGE41
  CU78    GND @BASEBOARD_FAB2_LIB.BASEBOARD_FAB2(SCH_1):GND   I284 @BASEBOARD_FAB2_LIB.BASEBOARD_FAB2(SCH_1):PAGE41
  CU80    GND @BASEBOARD_FAB2_LIB.BASEBOARD_FAB2(SCH_1):GND   I284 @BASEBOARD_FAB2_LIB.BASEBOARD_FAB2(SCH_1):PAGE41
  CU82    GND @BASEBOARD_FAB2_LIB.BASEBOARD_FAB2(SCH_1):GND   I284 @BASEBOARD_FAB2_LIB.BASEBOARD_FAB2(SCH_1):PAGE41
  CU86    GND @BASEBOARD_FAB2_LIB.BASEBOARD_FAB2(SCH_1):GND   I284 @BASEBOARD_FAB2_LIB.BASEBOARD_FAB2(SCH_1):PAGE41
   CV1    GND @BASEBOARD_FAB2_LIB.BASEBOARD_FAB2(SCH_1):GND   I284 @BASEBOARD_FAB2_LIB.BASEBOARD_FAB2(SCH_1):PAGE41
   H55    GND @BASEBOARD_FAB2_LIB.BASEBOARD_FAB2(SCH_1):GND   I284 @BASEBOARD_FAB2_LIB.BASEBOARD_FAB2(SCH_1):PAGE41
  CV17    GND @BASEBOARD_FAB2_LIB.BASEBOARD_FAB2(SCH_1):GND   I284 @BASEBOARD_FAB2_LIB.BASEBOARD_FAB2(SCH_1):PAGE41
  CV25    GND @BASEBOARD_FAB2_LIB.BASEBOARD_FAB2(SCH_1):GND   I284 @BASEBOARD_FAB2_LIB.BASEBOARD_FAB2(SCH_1):PAGE41
  CV27    GND @BASEBOARD_FAB2_LIB.BASEBOARD_FAB2(SCH_1):GND   I284 @BASEBOARD_FAB2_LIB.BASEBOARD_FAB2(SCH_1):PAGE41
  CV31    GND @BASEBOARD_FAB2_LIB.BASEBOARD_FAB2(SCH_1):GND   I284 @BASEBOARD_FAB2_LIB.BASEBOARD_FAB2(SCH_1):PAGE41
  CV33    GND @BASEBOARD_FAB2_LIB.BASEBOARD_FAB2(SCH_1):GND   I284 @BASEBOARD_FAB2_LIB.BASEBOARD_FAB2(SCH_1):PAGE41
  CV37    GND @BASEBOARD_FAB2_LIB.BASEBOARD_FAB2(SCH_1):GND   I284 @BASEBOARD_FAB2_LIB.BASEBOARD_FAB2(SCH_1):PAGE41
  CV39    GND @BASEBOARD_FAB2_LIB.BASEBOARD_FAB2(SCH_1):GND   I284 @BASEBOARD_FAB2_LIB.BASEBOARD_FAB2(SCH_1):PAGE41
  CV41    GND @BASEBOARD_FAB2_LIB.BASEBOARD_FAB2(SCH_1):GND   I284 @BASEBOARD_FAB2_LIB.BASEBOARD_FAB2(SCH_1):PAGE41
  CV53    GND @BASEBOARD_FAB2_LIB.BASEBOARD_FAB2(SCH_1):GND   I284 @BASEBOARD_FAB2_LIB.BASEBOARD_FAB2(SCH_1):PAGE41
  CV55    GND @BASEBOARD_FAB2_LIB.BASEBOARD_FAB2(SCH_1):GND   I284 @BASEBOARD_FAB2_LIB.BASEBOARD_FAB2(SCH_1):PAGE41
  CV63    GND @BASEBOARD_FAB2_LIB.BASEBOARD_FAB2(SCH_1):GND   I284 @BASEBOARD_FAB2_LIB.BASEBOARD_FAB2(SCH_1):PAGE41
  CV67    GND @BASEBOARD_FAB2_LIB.BASEBOARD_FAB2(SCH_1):GND   I284 @BASEBOARD_FAB2_LIB.BASEBOARD_FAB2(SCH_1):PAGE41
  CV73    GND @BASEBOARD_FAB2_LIB.BASEBOARD_FAB2(SCH_1):GND   I284 @BASEBOARD_FAB2_LIB.BASEBOARD_FAB2(SCH_1):PAGE41
  CV79    GND @BASEBOARD_FAB2_LIB.BASEBOARD_FAB2(SCH_1):GND   I284 @BASEBOARD_FAB2_LIB.BASEBOARD_FAB2(SCH_1):PAGE41
  CV81    GND @BASEBOARD_FAB2_LIB.BASEBOARD_FAB2(SCH_1):GND   I284 @BASEBOARD_FAB2_LIB.BASEBOARD_FAB2(SCH_1):PAGE41
  CV83    GND @BASEBOARD_FAB2_LIB.BASEBOARD_FAB2(SCH_1):GND   I284 @BASEBOARD_FAB2_LIB.BASEBOARD_FAB2(SCH_1):PAGE41
  CW12    GND @BASEBOARD_FAB2_LIB.BASEBOARD_FAB2(SCH_1):GND   I284 @BASEBOARD_FAB2_LIB.BASEBOARD_FAB2(SCH_1):PAGE41
  CW26    GND @BASEBOARD_FAB2_LIB.BASEBOARD_FAB2(SCH_1):GND   I284 @BASEBOARD_FAB2_LIB.BASEBOARD_FAB2(SCH_1):PAGE41
  CW32    GND @BASEBOARD_FAB2_LIB.BASEBOARD_FAB2(SCH_1):GND   I284 @BASEBOARD_FAB2_LIB.BASEBOARD_FAB2(SCH_1):PAGE41
  CW38    GND @BASEBOARD_FAB2_LIB.BASEBOARD_FAB2(SCH_1):GND   I284 @BASEBOARD_FAB2_LIB.BASEBOARD_FAB2(SCH_1):PAGE41
  CW40    GND @BASEBOARD_FAB2_LIB.BASEBOARD_FAB2(SCH_1):GND   I284 @BASEBOARD_FAB2_LIB.BASEBOARD_FAB2(SCH_1):PAGE41
  CW42    GND @BASEBOARD_FAB2_LIB.BASEBOARD_FAB2(SCH_1):GND   I284 @BASEBOARD_FAB2_LIB.BASEBOARD_FAB2(SCH_1):PAGE41
  CW52    GND @BASEBOARD_FAB2_LIB.BASEBOARD_FAB2(SCH_1):GND   I284 @BASEBOARD_FAB2_LIB.BASEBOARD_FAB2(SCH_1):PAGE41
  CW54    GND @BASEBOARD_FAB2_LIB.BASEBOARD_FAB2(SCH_1):GND   I284 @BASEBOARD_FAB2_LIB.BASEBOARD_FAB2(SCH_1):PAGE41
  CW64    GND @BASEBOARD_FAB2_LIB.BASEBOARD_FAB2(SCH_1):GND   I284 @BASEBOARD_FAB2_LIB.BASEBOARD_FAB2(SCH_1):PAGE41
  CW66    GND @BASEBOARD_FAB2_LIB.BASEBOARD_FAB2(SCH_1):GND   I284 @BASEBOARD_FAB2_LIB.BASEBOARD_FAB2(SCH_1):PAGE41
  CW68    GND @BASEBOARD_FAB2_LIB.BASEBOARD_FAB2(SCH_1):GND   I284 @BASEBOARD_FAB2_LIB.BASEBOARD_FAB2(SCH_1):PAGE41
  CW74    GND @BASEBOARD_FAB2_LIB.BASEBOARD_FAB2(SCH_1):GND   I284 @BASEBOARD_FAB2_LIB.BASEBOARD_FAB2(SCH_1):PAGE41
  CW78    GND @BASEBOARD_FAB2_LIB.BASEBOARD_FAB2(SCH_1):GND   I284 @BASEBOARD_FAB2_LIB.BASEBOARD_FAB2(SCH_1):PAGE41
  CW82    GND @BASEBOARD_FAB2_LIB.BASEBOARD_FAB2(SCH_1):GND   I284 @BASEBOARD_FAB2_LIB.BASEBOARD_FAB2(SCH_1):PAGE41
   CY1    GND @BASEBOARD_FAB2_LIB.BASEBOARD_FAB2(SCH_1):GND   I284 @BASEBOARD_FAB2_LIB.BASEBOARD_FAB2(SCH_1):PAGE41
   CY9    GND @BASEBOARD_FAB2_LIB.BASEBOARD_FAB2(SCH_1):GND   I284 @BASEBOARD_FAB2_LIB.BASEBOARD_FAB2(SCH_1):PAGE41
  CY13    GND @BASEBOARD_FAB2_LIB.BASEBOARD_FAB2(SCH_1):GND   I284 @BASEBOARD_FAB2_LIB.BASEBOARD_FAB2(SCH_1):PAGE41
  CY15    GND @BASEBOARD_FAB2_LIB.BASEBOARD_FAB2(SCH_1):GND   I284 @BASEBOARD_FAB2_LIB.BASEBOARD_FAB2(SCH_1):PAGE41
  CY21    GND @BASEBOARD_FAB2_LIB.BASEBOARD_FAB2(SCH_1):GND   I284 @BASEBOARD_FAB2_LIB.BASEBOARD_FAB2(SCH_1):PAGE41
  CY41    GND @BASEBOARD_FAB2_LIB.BASEBOARD_FAB2(SCH_1):GND   I284 @BASEBOARD_FAB2_LIB.BASEBOARD_FAB2(SCH_1):PAGE41
  CY45    GND @BASEBOARD_FAB2_LIB.BASEBOARD_FAB2(SCH_1):GND   I284 @BASEBOARD_FAB2_LIB.BASEBOARD_FAB2(SCH_1):PAGE41
  CY51    GND @BASEBOARD_FAB2_LIB.BASEBOARD_FAB2(SCH_1):GND   I284 @BASEBOARD_FAB2_LIB.BASEBOARD_FAB2(SCH_1):PAGE41
  CY59    GND @BASEBOARD_FAB2_LIB.BASEBOARD_FAB2(SCH_1):GND   I284 @BASEBOARD_FAB2_LIB.BASEBOARD_FAB2(SCH_1):PAGE41
  CY61    GND @BASEBOARD_FAB2_LIB.BASEBOARD_FAB2(SCH_1):GND   I284 @BASEBOARD_FAB2_LIB.BASEBOARD_FAB2(SCH_1):PAGE41
  CY65    GND @BASEBOARD_FAB2_LIB.BASEBOARD_FAB2(SCH_1):GND   I284 @BASEBOARD_FAB2_LIB.BASEBOARD_FAB2(SCH_1):PAGE41
  CY69    GND @BASEBOARD_FAB2_LIB.BASEBOARD_FAB2(SCH_1):GND   I284 @BASEBOARD_FAB2_LIB.BASEBOARD_FAB2(SCH_1):PAGE41
  CY75    GND @BASEBOARD_FAB2_LIB.BASEBOARD_FAB2(SCH_1):GND   I284 @BASEBOARD_FAB2_LIB.BASEBOARD_FAB2(SCH_1):PAGE41
  CY77    GND @BASEBOARD_FAB2_LIB.BASEBOARD_FAB2(SCH_1):GND   I284 @BASEBOARD_FAB2_LIB.BASEBOARD_FAB2(SCH_1):PAGE41
  CY83    GND @BASEBOARD_FAB2_LIB.BASEBOARD_FAB2(SCH_1):GND   I284 @BASEBOARD_FAB2_LIB.BASEBOARD_FAB2(SCH_1):PAGE41
  CY85    GND @BASEBOARD_FAB2_LIB.BASEBOARD_FAB2(SCH_1):GND   I284 @BASEBOARD_FAB2_LIB.BASEBOARD_FAB2(SCH_1):PAGE41
   DA6    GND @BASEBOARD_FAB2_LIB.BASEBOARD_FAB2(SCH_1):GND   I284 @BASEBOARD_FAB2_LIB.BASEBOARD_FAB2(SCH_1):PAGE41
   H53    GND @BASEBOARD_FAB2_LIB.BASEBOARD_FAB2(SCH_1):GND   I284 @BASEBOARD_FAB2_LIB.BASEBOARD_FAB2(SCH_1):PAGE41
  DA18    GND @BASEBOARD_FAB2_LIB.BASEBOARD_FAB2(SCH_1):GND   I284 @BASEBOARD_FAB2_LIB.BASEBOARD_FAB2(SCH_1):PAGE41
  DA26    GND @BASEBOARD_FAB2_LIB.BASEBOARD_FAB2(SCH_1):GND   I284 @BASEBOARD_FAB2_LIB.BASEBOARD_FAB2(SCH_1):PAGE41
  DA28    GND @BASEBOARD_FAB2_LIB.BASEBOARD_FAB2(SCH_1):GND   I284 @BASEBOARD_FAB2_LIB.BASEBOARD_FAB2(SCH_1):PAGE41
  DA30    GND @BASEBOARD_FAB2_LIB.BASEBOARD_FAB2(SCH_1):GND   I284 @BASEBOARD_FAB2_LIB.BASEBOARD_FAB2(SCH_1):PAGE41
  DA32    GND @BASEBOARD_FAB2_LIB.BASEBOARD_FAB2(SCH_1):GND   I284 @BASEBOARD_FAB2_LIB.BASEBOARD_FAB2(SCH_1):PAGE41
  DA34    GND @BASEBOARD_FAB2_LIB.BASEBOARD_FAB2(SCH_1):GND   I284 @BASEBOARD_FAB2_LIB.BASEBOARD_FAB2(SCH_1):PAGE41
  DA36    GND @BASEBOARD_FAB2_LIB.BASEBOARD_FAB2(SCH_1):GND   I284 @BASEBOARD_FAB2_LIB.BASEBOARD_FAB2(SCH_1):PAGE41
  DA38    GND @BASEBOARD_FAB2_LIB.BASEBOARD_FAB2(SCH_1):GND   I284 @BASEBOARD_FAB2_LIB.BASEBOARD_FAB2(SCH_1):PAGE41
  DA44    GND @BASEBOARD_FAB2_LIB.BASEBOARD_FAB2(SCH_1):GND   I284 @BASEBOARD_FAB2_LIB.BASEBOARD_FAB2(SCH_1):PAGE41
  DA46    GND @BASEBOARD_FAB2_LIB.BASEBOARD_FAB2(SCH_1):GND   I284 @BASEBOARD_FAB2_LIB.BASEBOARD_FAB2(SCH_1):PAGE41
  DA48    GND @BASEBOARD_FAB2_LIB.BASEBOARD_FAB2(SCH_1):GND   I285 @BASEBOARD_FAB2_LIB.BASEBOARD_FAB2(SCH_1):PAGE41
  DA50    GND @BASEBOARD_FAB2_LIB.BASEBOARD_FAB2(SCH_1):GND   I285 @BASEBOARD_FAB2_LIB.BASEBOARD_FAB2(SCH_1):PAGE41
  DA64    GND @BASEBOARD_FAB2_LIB.BASEBOARD_FAB2(SCH_1):GND   I285 @BASEBOARD_FAB2_LIB.BASEBOARD_FAB2(SCH_1):PAGE41
  DA70    GND @BASEBOARD_FAB2_LIB.BASEBOARD_FAB2(SCH_1):GND   I285 @BASEBOARD_FAB2_LIB.BASEBOARD_FAB2(SCH_1):PAGE41
  DA74    GND @BASEBOARD_FAB2_LIB.BASEBOARD_FAB2(SCH_1):GND   I285 @BASEBOARD_FAB2_LIB.BASEBOARD_FAB2(SCH_1):PAGE41
  DA76    GND @BASEBOARD_FAB2_LIB.BASEBOARD_FAB2(SCH_1):GND   I285 @BASEBOARD_FAB2_LIB.BASEBOARD_FAB2(SCH_1):PAGE41
  DA78    GND @BASEBOARD_FAB2_LIB.BASEBOARD_FAB2(SCH_1):GND   I285 @BASEBOARD_FAB2_LIB.BASEBOARD_FAB2(SCH_1):PAGE41
  DA80    GND @BASEBOARD_FAB2_LIB.BASEBOARD_FAB2(SCH_1):GND   I285 @BASEBOARD_FAB2_LIB.BASEBOARD_FAB2(SCH_1):PAGE41
   DB3    GND @BASEBOARD_FAB2_LIB.BASEBOARD_FAB2(SCH_1):GND   I285 @BASEBOARD_FAB2_LIB.BASEBOARD_FAB2(SCH_1):PAGE41
  DB13    GND @BASEBOARD_FAB2_LIB.BASEBOARD_FAB2(SCH_1):GND   I285 @BASEBOARD_FAB2_LIB.BASEBOARD_FAB2(SCH_1):PAGE41
  DB17    GND @BASEBOARD_FAB2_LIB.BASEBOARD_FAB2(SCH_1):GND   I285 @BASEBOARD_FAB2_LIB.BASEBOARD_FAB2(SCH_1):PAGE41
  DB23    GND @BASEBOARD_FAB2_LIB.BASEBOARD_FAB2(SCH_1):GND   I285 @BASEBOARD_FAB2_LIB.BASEBOARD_FAB2(SCH_1):PAGE41
  DB25    GND @BASEBOARD_FAB2_LIB.BASEBOARD_FAB2(SCH_1):GND   I285 @BASEBOARD_FAB2_LIB.BASEBOARD_FAB2(SCH_1):PAGE41
  DB39    GND @BASEBOARD_FAB2_LIB.BASEBOARD_FAB2(SCH_1):GND   I285 @BASEBOARD_FAB2_LIB.BASEBOARD_FAB2(SCH_1):PAGE41
  DB41    GND @BASEBOARD_FAB2_LIB.BASEBOARD_FAB2(SCH_1):GND   I285 @BASEBOARD_FAB2_LIB.BASEBOARD_FAB2(SCH_1):PAGE41
  DB47    GND @BASEBOARD_FAB2_LIB.BASEBOARD_FAB2(SCH_1):GND   I285 @BASEBOARD_FAB2_LIB.BASEBOARD_FAB2(SCH_1):PAGE41
  DB49    GND @BASEBOARD_FAB2_LIB.BASEBOARD_FAB2(SCH_1):GND   I285 @BASEBOARD_FAB2_LIB.BASEBOARD_FAB2(SCH_1):PAGE41
  DB73    GND @BASEBOARD_FAB2_LIB.BASEBOARD_FAB2(SCH_1):GND   I285 @BASEBOARD_FAB2_LIB.BASEBOARD_FAB2(SCH_1):PAGE41
  DB77    GND @BASEBOARD_FAB2_LIB.BASEBOARD_FAB2(SCH_1):GND   I285 @BASEBOARD_FAB2_LIB.BASEBOARD_FAB2(SCH_1):PAGE41
  DB83    GND @BASEBOARD_FAB2_LIB.BASEBOARD_FAB2(SCH_1):GND   I285 @BASEBOARD_FAB2_LIB.BASEBOARD_FAB2(SCH_1):PAGE41
  DB85    GND @BASEBOARD_FAB2_LIB.BASEBOARD_FAB2(SCH_1):GND   I285 @BASEBOARD_FAB2_LIB.BASEBOARD_FAB2(SCH_1):PAGE41
  DC14    GND @BASEBOARD_FAB2_LIB.BASEBOARD_FAB2(SCH_1):GND   I285 @BASEBOARD_FAB2_LIB.BASEBOARD_FAB2(SCH_1):PAGE41
  DC24    GND @BASEBOARD_FAB2_LIB.BASEBOARD_FAB2(SCH_1):GND   I285 @BASEBOARD_FAB2_LIB.BASEBOARD_FAB2(SCH_1):PAGE41
  DC26    GND @BASEBOARD_FAB2_LIB.BASEBOARD_FAB2(SCH_1):GND   I285 @BASEBOARD_FAB2_LIB.BASEBOARD_FAB2(SCH_1):PAGE41
  DC32    GND @BASEBOARD_FAB2_LIB.BASEBOARD_FAB2(SCH_1):GND   I285 @BASEBOARD_FAB2_LIB.BASEBOARD_FAB2(SCH_1):PAGE41
  DC38    GND @BASEBOARD_FAB2_LIB.BASEBOARD_FAB2(SCH_1):GND   I285 @BASEBOARD_FAB2_LIB.BASEBOARD_FAB2(SCH_1):PAGE41
  DC42    GND @BASEBOARD_FAB2_LIB.BASEBOARD_FAB2(SCH_1):GND   I285 @BASEBOARD_FAB2_LIB.BASEBOARD_FAB2(SCH_1):PAGE41
  DC64    GND @BASEBOARD_FAB2_LIB.BASEBOARD_FAB2(SCH_1):GND   I285 @BASEBOARD_FAB2_LIB.BASEBOARD_FAB2(SCH_1):PAGE41
  DC66    GND @BASEBOARD_FAB2_LIB.BASEBOARD_FAB2(SCH_1):GND   I285 @BASEBOARD_FAB2_LIB.BASEBOARD_FAB2(SCH_1):PAGE41
  DC68    GND @BASEBOARD_FAB2_LIB.BASEBOARD_FAB2(SCH_1):GND   I285 @BASEBOARD_FAB2_LIB.BASEBOARD_FAB2(SCH_1):PAGE41
  DC70    GND @BASEBOARD_FAB2_LIB.BASEBOARD_FAB2(SCH_1):GND   I285 @BASEBOARD_FAB2_LIB.BASEBOARD_FAB2(SCH_1):PAGE41
  DC78    GND @BASEBOARD_FAB2_LIB.BASEBOARD_FAB2(SCH_1):GND   I285 @BASEBOARD_FAB2_LIB.BASEBOARD_FAB2(SCH_1):PAGE41
  DC84    GND @BASEBOARD_FAB2_LIB.BASEBOARD_FAB2(SCH_1):GND   I285 @BASEBOARD_FAB2_LIB.BASEBOARD_FAB2(SCH_1):PAGE41
  DC86    GND @BASEBOARD_FAB2_LIB.BASEBOARD_FAB2(SCH_1):GND   I285 @BASEBOARD_FAB2_LIB.BASEBOARD_FAB2(SCH_1):PAGE41
  DD11    GND @BASEBOARD_FAB2_LIB.BASEBOARD_FAB2(SCH_1):GND   I285 @BASEBOARD_FAB2_LIB.BASEBOARD_FAB2(SCH_1):PAGE41
  DD23    GND @BASEBOARD_FAB2_LIB.BASEBOARD_FAB2(SCH_1):GND   I285 @BASEBOARD_FAB2_LIB.BASEBOARD_FAB2(SCH_1):PAGE41
  DD27    GND @BASEBOARD_FAB2_LIB.BASEBOARD_FAB2(SCH_1):GND   I285 @BASEBOARD_FAB2_LIB.BASEBOARD_FAB2(SCH_1):PAGE41
  DD31    GND @BASEBOARD_FAB2_LIB.BASEBOARD_FAB2(SCH_1):GND   I285 @BASEBOARD_FAB2_LIB.BASEBOARD_FAB2(SCH_1):PAGE41
  DD33    GND @BASEBOARD_FAB2_LIB.BASEBOARD_FAB2(SCH_1):GND   I285 @BASEBOARD_FAB2_LIB.BASEBOARD_FAB2(SCH_1):PAGE41
  DD37    GND @BASEBOARD_FAB2_LIB.BASEBOARD_FAB2(SCH_1):GND   I285 @BASEBOARD_FAB2_LIB.BASEBOARD_FAB2(SCH_1):PAGE41
  DD71    GND @BASEBOARD_FAB2_LIB.BASEBOARD_FAB2(SCH_1):GND   I285 @BASEBOARD_FAB2_LIB.BASEBOARD_FAB2(SCH_1):PAGE41
  DD73    GND @BASEBOARD_FAB2_LIB.BASEBOARD_FAB2(SCH_1):GND   I285 @BASEBOARD_FAB2_LIB.BASEBOARD_FAB2(SCH_1):PAGE41
  DD75    GND @BASEBOARD_FAB2_LIB.BASEBOARD_FAB2(SCH_1):GND   I285 @BASEBOARD_FAB2_LIB.BASEBOARD_FAB2(SCH_1):PAGE41
  DD81    GND @BASEBOARD_FAB2_LIB.BASEBOARD_FAB2(SCH_1):GND   I285 @BASEBOARD_FAB2_LIB.BASEBOARD_FAB2(SCH_1):PAGE41
  DD83    GND @BASEBOARD_FAB2_LIB.BASEBOARD_FAB2(SCH_1):GND   I285 @BASEBOARD_FAB2_LIB.BASEBOARD_FAB2(SCH_1):PAGE41
   DE6    GND @BASEBOARD_FAB2_LIB.BASEBOARD_FAB2(SCH_1):GND   I285 @BASEBOARD_FAB2_LIB.BASEBOARD_FAB2(SCH_1):PAGE41
   DE8    GND @BASEBOARD_FAB2_LIB.BASEBOARD_FAB2(SCH_1):GND   I285 @BASEBOARD_FAB2_LIB.BASEBOARD_FAB2(SCH_1):PAGE41
  DE18    GND @BASEBOARD_FAB2_LIB.BASEBOARD_FAB2(SCH_1):GND   I285 @BASEBOARD_FAB2_LIB.BASEBOARD_FAB2(SCH_1):PAGE41
  DE20    GND @BASEBOARD_FAB2_LIB.BASEBOARD_FAB2(SCH_1):GND   I285 @BASEBOARD_FAB2_LIB.BASEBOARD_FAB2(SCH_1):PAGE41
  DE24    GND @BASEBOARD_FAB2_LIB.BASEBOARD_FAB2(SCH_1):GND   I285 @BASEBOARD_FAB2_LIB.BASEBOARD_FAB2(SCH_1):PAGE41
  DE28    GND @BASEBOARD_FAB2_LIB.BASEBOARD_FAB2(SCH_1):GND   I285 @BASEBOARD_FAB2_LIB.BASEBOARD_FAB2(SCH_1):PAGE41
  DE30    GND @BASEBOARD_FAB2_LIB.BASEBOARD_FAB2(SCH_1):GND   I285 @BASEBOARD_FAB2_LIB.BASEBOARD_FAB2(SCH_1):PAGE41
  DE34    GND @BASEBOARD_FAB2_LIB.BASEBOARD_FAB2(SCH_1):GND   I285 @BASEBOARD_FAB2_LIB.BASEBOARD_FAB2(SCH_1):PAGE41
  DE36    GND @BASEBOARD_FAB2_LIB.BASEBOARD_FAB2(SCH_1):GND   I285 @BASEBOARD_FAB2_LIB.BASEBOARD_FAB2(SCH_1):PAGE41
  DE64    GND @BASEBOARD_FAB2_LIB.BASEBOARD_FAB2(SCH_1):GND   I285 @BASEBOARD_FAB2_LIB.BASEBOARD_FAB2(SCH_1):PAGE41
  DE70    GND @BASEBOARD_FAB2_LIB.BASEBOARD_FAB2(SCH_1):GND   I285 @BASEBOARD_FAB2_LIB.BASEBOARD_FAB2(SCH_1):PAGE41
  DE72    GND @BASEBOARD_FAB2_LIB.BASEBOARD_FAB2(SCH_1):GND   I285 @BASEBOARD_FAB2_LIB.BASEBOARD_FAB2(SCH_1):PAGE41
  DE78    GND @BASEBOARD_FAB2_LIB.BASEBOARD_FAB2(SCH_1):GND   I285 @BASEBOARD_FAB2_LIB.BASEBOARD_FAB2(SCH_1):PAGE41
   DF5    GND @BASEBOARD_FAB2_LIB.BASEBOARD_FAB2(SCH_1):GND   I285 @BASEBOARD_FAB2_LIB.BASEBOARD_FAB2(SCH_1):PAGE41
   DF7    GND @BASEBOARD_FAB2_LIB.BASEBOARD_FAB2(SCH_1):GND   I285 @BASEBOARD_FAB2_LIB.BASEBOARD_FAB2(SCH_1):PAGE41
   H51    GND @BASEBOARD_FAB2_LIB.BASEBOARD_FAB2(SCH_1):GND   I285 @BASEBOARD_FAB2_LIB.BASEBOARD_FAB2(SCH_1):PAGE41
  DF19    GND @BASEBOARD_FAB2_LIB.BASEBOARD_FAB2(SCH_1):GND   I285 @BASEBOARD_FAB2_LIB.BASEBOARD_FAB2(SCH_1):PAGE41
  DF29    GND @BASEBOARD_FAB2_LIB.BASEBOARD_FAB2(SCH_1):GND   I285 @BASEBOARD_FAB2_LIB.BASEBOARD_FAB2(SCH_1):PAGE41
  DF35    GND @BASEBOARD_FAB2_LIB.BASEBOARD_FAB2(SCH_1):GND   I285 @BASEBOARD_FAB2_LIB.BASEBOARD_FAB2(SCH_1):PAGE41
  DF37    GND @BASEBOARD_FAB2_LIB.BASEBOARD_FAB2(SCH_1):GND   I285 @BASEBOARD_FAB2_LIB.BASEBOARD_FAB2(SCH_1):PAGE41
  DF39    GND @BASEBOARD_FAB2_LIB.BASEBOARD_FAB2(SCH_1):GND   I285 @BASEBOARD_FAB2_LIB.BASEBOARD_FAB2(SCH_1):PAGE41
  DF41    GND @BASEBOARD_FAB2_LIB.BASEBOARD_FAB2(SCH_1):GND   I285 @BASEBOARD_FAB2_LIB.BASEBOARD_FAB2(SCH_1):PAGE41
  DF65    GND @BASEBOARD_FAB2_LIB.BASEBOARD_FAB2(SCH_1):GND   I285 @BASEBOARD_FAB2_LIB.BASEBOARD_FAB2(SCH_1):PAGE41
  DF69    GND @BASEBOARD_FAB2_LIB.BASEBOARD_FAB2(SCH_1):GND   I285 @BASEBOARD_FAB2_LIB.BASEBOARD_FAB2(SCH_1):PAGE41
  DF73    GND @BASEBOARD_FAB2_LIB.BASEBOARD_FAB2(SCH_1):GND   I285 @BASEBOARD_FAB2_LIB.BASEBOARD_FAB2(SCH_1):PAGE41
  DF79    GND @BASEBOARD_FAB2_LIB.BASEBOARD_FAB2(SCH_1):GND   I285 @BASEBOARD_FAB2_LIB.BASEBOARD_FAB2(SCH_1):PAGE41
  DF83    GND @BASEBOARD_FAB2_LIB.BASEBOARD_FAB2(SCH_1):GND   I285 @BASEBOARD_FAB2_LIB.BASEBOARD_FAB2(SCH_1):PAGE41
  DF85    GND @BASEBOARD_FAB2_LIB.BASEBOARD_FAB2(SCH_1):GND   I285 @BASEBOARD_FAB2_LIB.BASEBOARD_FAB2(SCH_1):PAGE41
   DG2    GND @BASEBOARD_FAB2_LIB.BASEBOARD_FAB2(SCH_1):GND   I285 @BASEBOARD_FAB2_LIB.BASEBOARD_FAB2(SCH_1):PAGE41
   H49    GND @BASEBOARD_FAB2_LIB.BASEBOARD_FAB2(SCH_1):GND   I285 @BASEBOARD_FAB2_LIB.BASEBOARD_FAB2(SCH_1):PAGE41
  DG14    GND @BASEBOARD_FAB2_LIB.BASEBOARD_FAB2(SCH_1):GND   I285 @BASEBOARD_FAB2_LIB.BASEBOARD_FAB2(SCH_1):PAGE41
  DG16    GND @BASEBOARD_FAB2_LIB.BASEBOARD_FAB2(SCH_1):GND   I285 @BASEBOARD_FAB2_LIB.BASEBOARD_FAB2(SCH_1):PAGE41
  DG24    GND @BASEBOARD_FAB2_LIB.BASEBOARD_FAB2(SCH_1):GND   I285 @BASEBOARD_FAB2_LIB.BASEBOARD_FAB2(SCH_1):PAGE41
  DG66    GND @BASEBOARD_FAB2_LIB.BASEBOARD_FAB2(SCH_1):GND   I285 @BASEBOARD_FAB2_LIB.BASEBOARD_FAB2(SCH_1):PAGE41
  DG68    GND @BASEBOARD_FAB2_LIB.BASEBOARD_FAB2(SCH_1):GND   I285 @BASEBOARD_FAB2_LIB.BASEBOARD_FAB2(SCH_1):PAGE41
  DG76    GND @BASEBOARD_FAB2_LIB.BASEBOARD_FAB2(SCH_1):GND   I285 @BASEBOARD_FAB2_LIB.BASEBOARD_FAB2(SCH_1):PAGE41
  DG78    GND @BASEBOARD_FAB2_LIB.BASEBOARD_FAB2(SCH_1):GND   I285 @BASEBOARD_FAB2_LIB.BASEBOARD_FAB2(SCH_1):PAGE41
  DG80    GND @BASEBOARD_FAB2_LIB.BASEBOARD_FAB2(SCH_1):GND   I285 @BASEBOARD_FAB2_LIB.BASEBOARD_FAB2(SCH_1):PAGE41
  DG82    GND @BASEBOARD_FAB2_LIB.BASEBOARD_FAB2(SCH_1):GND   I285 @BASEBOARD_FAB2_LIB.BASEBOARD_FAB2(SCH_1):PAGE41
  DH13    GND @BASEBOARD_FAB2_LIB.BASEBOARD_FAB2(SCH_1):GND   I285 @BASEBOARD_FAB2_LIB.BASEBOARD_FAB2(SCH_1):PAGE41
  DH15    GND @BASEBOARD_FAB2_LIB.BASEBOARD_FAB2(SCH_1):GND   I285 @BASEBOARD_FAB2_LIB.BASEBOARD_FAB2(SCH_1):PAGE41
  DH23    GND @BASEBOARD_FAB2_LIB.BASEBOARD_FAB2(SCH_1):GND   I285 @BASEBOARD_FAB2_LIB.BASEBOARD_FAB2(SCH_1):PAGE41
  DH25    GND @BASEBOARD_FAB2_LIB.BASEBOARD_FAB2(SCH_1):GND   I285 @BASEBOARD_FAB2_LIB.BASEBOARD_FAB2(SCH_1):PAGE41
  DH27    GND @BASEBOARD_FAB2_LIB.BASEBOARD_FAB2(SCH_1):GND   I285 @BASEBOARD_FAB2_LIB.BASEBOARD_FAB2(SCH_1):PAGE41
  DH29    GND @BASEBOARD_FAB2_LIB.BASEBOARD_FAB2(SCH_1):GND   I285 @BASEBOARD_FAB2_LIB.BASEBOARD_FAB2(SCH_1):PAGE41
  DH31    GND @BASEBOARD_FAB2_LIB.BASEBOARD_FAB2(SCH_1):GND   I285 @BASEBOARD_FAB2_LIB.BASEBOARD_FAB2(SCH_1):PAGE41
  DH33    GND @BASEBOARD_FAB2_LIB.BASEBOARD_FAB2(SCH_1):GND   I285 @BASEBOARD_FAB2_LIB.BASEBOARD_FAB2(SCH_1):PAGE41
  DH35    GND @BASEBOARD_FAB2_LIB.BASEBOARD_FAB2(SCH_1):GND   I285 @BASEBOARD_FAB2_LIB.BASEBOARD_FAB2(SCH_1):PAGE41
  DH37    GND @BASEBOARD_FAB2_LIB.BASEBOARD_FAB2(SCH_1):GND   I285 @BASEBOARD_FAB2_LIB.BASEBOARD_FAB2(SCH_1):PAGE41
  DH41    GND @BASEBOARD_FAB2_LIB.BASEBOARD_FAB2(SCH_1):GND   I285 @BASEBOARD_FAB2_LIB.BASEBOARD_FAB2(SCH_1):PAGE41
  DH67    GND @BASEBOARD_FAB2_LIB.BASEBOARD_FAB2(SCH_1):GND   I285 @BASEBOARD_FAB2_LIB.BASEBOARD_FAB2(SCH_1):PAGE41
  DH71    GND @BASEBOARD_FAB2_LIB.BASEBOARD_FAB2(SCH_1):GND   I285 @BASEBOARD_FAB2_LIB.BASEBOARD_FAB2(SCH_1):PAGE41
  DH73    GND @BASEBOARD_FAB2_LIB.BASEBOARD_FAB2(SCH_1):GND   I285 @BASEBOARD_FAB2_LIB.BASEBOARD_FAB2(SCH_1):PAGE41
  DH79    GND @BASEBOARD_FAB2_LIB.BASEBOARD_FAB2(SCH_1):GND   I285 @BASEBOARD_FAB2_LIB.BASEBOARD_FAB2(SCH_1):PAGE41
  DH81    GND @BASEBOARD_FAB2_LIB.BASEBOARD_FAB2(SCH_1):GND   I285 @BASEBOARD_FAB2_LIB.BASEBOARD_FAB2(SCH_1):PAGE41
  DH83    GND @BASEBOARD_FAB2_LIB.BASEBOARD_FAB2(SCH_1):GND   I285 @BASEBOARD_FAB2_LIB.BASEBOARD_FAB2(SCH_1):PAGE41
   DJ2    GND @BASEBOARD_FAB2_LIB.BASEBOARD_FAB2(SCH_1):GND   I285 @BASEBOARD_FAB2_LIB.BASEBOARD_FAB2(SCH_1):PAGE41
  DJ10    GND @BASEBOARD_FAB2_LIB.BASEBOARD_FAB2(SCH_1):GND   I285 @BASEBOARD_FAB2_LIB.BASEBOARD_FAB2(SCH_1):PAGE41
   H47    GND @BASEBOARD_FAB2_LIB.BASEBOARD_FAB2(SCH_1):GND   I285 @BASEBOARD_FAB2_LIB.BASEBOARD_FAB2(SCH_1):PAGE41
  DJ22    GND @BASEBOARD_FAB2_LIB.BASEBOARD_FAB2(SCH_1):GND   I285 @BASEBOARD_FAB2_LIB.BASEBOARD_FAB2(SCH_1):PAGE41
  DJ38    GND @BASEBOARD_FAB2_LIB.BASEBOARD_FAB2(SCH_1):GND   I285 @BASEBOARD_FAB2_LIB.BASEBOARD_FAB2(SCH_1):PAGE41
  DJ42    GND @BASEBOARD_FAB2_LIB.BASEBOARD_FAB2(SCH_1):GND   I285 @BASEBOARD_FAB2_LIB.BASEBOARD_FAB2(SCH_1):PAGE41
  DJ68    GND @BASEBOARD_FAB2_LIB.BASEBOARD_FAB2(SCH_1):GND   I285 @BASEBOARD_FAB2_LIB.BASEBOARD_FAB2(SCH_1):PAGE41
  DJ74    GND @BASEBOARD_FAB2_LIB.BASEBOARD_FAB2(SCH_1):GND   I285 @BASEBOARD_FAB2_LIB.BASEBOARD_FAB2(SCH_1):PAGE41
  DJ78    GND @BASEBOARD_FAB2_LIB.BASEBOARD_FAB2(SCH_1):GND   I285 @BASEBOARD_FAB2_LIB.BASEBOARD_FAB2(SCH_1):PAGE41
  DJ82    GND @BASEBOARD_FAB2_LIB.BASEBOARD_FAB2(SCH_1):GND   I285 @BASEBOARD_FAB2_LIB.BASEBOARD_FAB2(SCH_1):PAGE41
  DJ84    GND @BASEBOARD_FAB2_LIB.BASEBOARD_FAB2(SCH_1):GND   I285 @BASEBOARD_FAB2_LIB.BASEBOARD_FAB2(SCH_1):PAGE41
   DK7    GND @BASEBOARD_FAB2_LIB.BASEBOARD_FAB2(SCH_1):GND   I285 @BASEBOARD_FAB2_LIB.BASEBOARD_FAB2(SCH_1):PAGE41
  DK23    GND @BASEBOARD_FAB2_LIB.BASEBOARD_FAB2(SCH_1):GND   I285 @BASEBOARD_FAB2_LIB.BASEBOARD_FAB2(SCH_1):PAGE41
  DK29    GND @BASEBOARD_FAB2_LIB.BASEBOARD_FAB2(SCH_1):GND   I285 @BASEBOARD_FAB2_LIB.BASEBOARD_FAB2(SCH_1):PAGE41
  DK35    GND @BASEBOARD_FAB2_LIB.BASEBOARD_FAB2(SCH_1):GND   I285 @BASEBOARD_FAB2_LIB.BASEBOARD_FAB2(SCH_1):PAGE41
  DK39    GND @BASEBOARD_FAB2_LIB.BASEBOARD_FAB2(SCH_1):GND   I285 @BASEBOARD_FAB2_LIB.BASEBOARD_FAB2(SCH_1):PAGE41
  DK41    GND @BASEBOARD_FAB2_LIB.BASEBOARD_FAB2(SCH_1):GND   I285 @BASEBOARD_FAB2_LIB.BASEBOARD_FAB2(SCH_1):PAGE41
  DK73    GND @BASEBOARD_FAB2_LIB.BASEBOARD_FAB2(SCH_1):GND   I285 @BASEBOARD_FAB2_LIB.BASEBOARD_FAB2(SCH_1):PAGE41
  DK75    GND @BASEBOARD_FAB2_LIB.BASEBOARD_FAB2(SCH_1):GND   I285 @BASEBOARD_FAB2_LIB.BASEBOARD_FAB2(SCH_1):PAGE41
  DK77    GND @BASEBOARD_FAB2_LIB.BASEBOARD_FAB2(SCH_1):GND   I285 @BASEBOARD_FAB2_LIB.BASEBOARD_FAB2(SCH_1):PAGE41
  DK83    GND @BASEBOARD_FAB2_LIB.BASEBOARD_FAB2(SCH_1):GND   I285 @BASEBOARD_FAB2_LIB.BASEBOARD_FAB2(SCH_1):PAGE41
  DK85    GND @BASEBOARD_FAB2_LIB.BASEBOARD_FAB2(SCH_1):GND   I285 @BASEBOARD_FAB2_LIB.BASEBOARD_FAB2(SCH_1):PAGE41
  DL16    GND @BASEBOARD_FAB2_LIB.BASEBOARD_FAB2(SCH_1):GND   I285 @BASEBOARD_FAB2_LIB.BASEBOARD_FAB2(SCH_1):PAGE41
  DL18    GND @BASEBOARD_FAB2_LIB.BASEBOARD_FAB2(SCH_1):GND   I285 @BASEBOARD_FAB2_LIB.BASEBOARD_FAB2(SCH_1):PAGE41
   DL4    GND @BASEBOARD_FAB2_LIB.BASEBOARD_FAB2(SCH_1):GND   I285 @BASEBOARD_FAB2_LIB.BASEBOARD_FAB2(SCH_1):PAGE41
  DL22    GND @BASEBOARD_FAB2_LIB.BASEBOARD_FAB2(SCH_1):GND   I285 @BASEBOARD_FAB2_LIB.BASEBOARD_FAB2(SCH_1):PAGE41
  DL24    GND @BASEBOARD_FAB2_LIB.BASEBOARD_FAB2(SCH_1):GND   I285 @BASEBOARD_FAB2_LIB.BASEBOARD_FAB2(SCH_1):PAGE41
  DL28    GND @BASEBOARD_FAB2_LIB.BASEBOARD_FAB2(SCH_1):GND   I285 @BASEBOARD_FAB2_LIB.BASEBOARD_FAB2(SCH_1):PAGE41
  DL30    GND @BASEBOARD_FAB2_LIB.BASEBOARD_FAB2(SCH_1):GND   I285 @BASEBOARD_FAB2_LIB.BASEBOARD_FAB2(SCH_1):PAGE41
  DL34    GND @BASEBOARD_FAB2_LIB.BASEBOARD_FAB2(SCH_1):GND   I285 @BASEBOARD_FAB2_LIB.BASEBOARD_FAB2(SCH_1):PAGE41
  DL36    GND @BASEBOARD_FAB2_LIB.BASEBOARD_FAB2(SCH_1):GND   I285 @BASEBOARD_FAB2_LIB.BASEBOARD_FAB2(SCH_1):PAGE41
  DL40    GND @BASEBOARD_FAB2_LIB.BASEBOARD_FAB2(SCH_1):GND   I285 @BASEBOARD_FAB2_LIB.BASEBOARD_FAB2(SCH_1):PAGE41
  DL68    GND @BASEBOARD_FAB2_LIB.BASEBOARD_FAB2(SCH_1):GND   I285 @BASEBOARD_FAB2_LIB.BASEBOARD_FAB2(SCH_1):PAGE41
  DL70    GND @BASEBOARD_FAB2_LIB.BASEBOARD_FAB2(SCH_1):GND   I285 @BASEBOARD_FAB2_LIB.BASEBOARD_FAB2(SCH_1):PAGE41
  DL74    GND @BASEBOARD_FAB2_LIB.BASEBOARD_FAB2(SCH_1):GND   I285 @BASEBOARD_FAB2_LIB.BASEBOARD_FAB2(SCH_1):PAGE41
  DL76    GND @BASEBOARD_FAB2_LIB.BASEBOARD_FAB2(SCH_1):GND   I285 @BASEBOARD_FAB2_LIB.BASEBOARD_FAB2(SCH_1):PAGE41
  DL78    GND @BASEBOARD_FAB2_LIB.BASEBOARD_FAB2(SCH_1):GND   I285 @BASEBOARD_FAB2_LIB.BASEBOARD_FAB2(SCH_1):PAGE41
  DL80    GND @BASEBOARD_FAB2_LIB.BASEBOARD_FAB2(SCH_1):GND   I285 @BASEBOARD_FAB2_LIB.BASEBOARD_FAB2(SCH_1):PAGE41
  DM15    GND @BASEBOARD_FAB2_LIB.BASEBOARD_FAB2(SCH_1):GND   I285 @BASEBOARD_FAB2_LIB.BASEBOARD_FAB2(SCH_1):PAGE41
   H45    GND @BASEBOARD_FAB2_LIB.BASEBOARD_FAB2(SCH_1):GND   I285 @BASEBOARD_FAB2_LIB.BASEBOARD_FAB2(SCH_1):PAGE41
  DM25    GND @BASEBOARD_FAB2_LIB.BASEBOARD_FAB2(SCH_1):GND   I285 @BASEBOARD_FAB2_LIB.BASEBOARD_FAB2(SCH_1):PAGE41
  DM27    GND @BASEBOARD_FAB2_LIB.BASEBOARD_FAB2(SCH_1):GND   I285 @BASEBOARD_FAB2_LIB.BASEBOARD_FAB2(SCH_1):PAGE41
  DM31    GND @BASEBOARD_FAB2_LIB.BASEBOARD_FAB2(SCH_1):GND   I285 @BASEBOARD_FAB2_LIB.BASEBOARD_FAB2(SCH_1):PAGE41
  DM33    GND @BASEBOARD_FAB2_LIB.BASEBOARD_FAB2(SCH_1):GND   I285 @BASEBOARD_FAB2_LIB.BASEBOARD_FAB2(SCH_1):PAGE41
  DM37    GND @BASEBOARD_FAB2_LIB.BASEBOARD_FAB2(SCH_1):GND   I285 @BASEBOARD_FAB2_LIB.BASEBOARD_FAB2(SCH_1):PAGE41
  DM39    GND @BASEBOARD_FAB2_LIB.BASEBOARD_FAB2(SCH_1):GND   I285 @BASEBOARD_FAB2_LIB.BASEBOARD_FAB2(SCH_1):PAGE41
  DM65    GND @BASEBOARD_FAB2_LIB.BASEBOARD_FAB2(SCH_1):GND   I285 @BASEBOARD_FAB2_LIB.BASEBOARD_FAB2(SCH_1):PAGE41
  DM73    GND @BASEBOARD_FAB2_LIB.BASEBOARD_FAB2(SCH_1):GND   I285 @BASEBOARD_FAB2_LIB.BASEBOARD_FAB2(SCH_1):PAGE41
  DM77    GND @BASEBOARD_FAB2_LIB.BASEBOARD_FAB2(SCH_1):GND   I285 @BASEBOARD_FAB2_LIB.BASEBOARD_FAB2(SCH_1):PAGE41
  DM83    GND @BASEBOARD_FAB2_LIB.BASEBOARD_FAB2(SCH_1):GND   I285 @BASEBOARD_FAB2_LIB.BASEBOARD_FAB2(SCH_1):PAGE41
   DN2    GND @BASEBOARD_FAB2_LIB.BASEBOARD_FAB2(SCH_1):GND   I285 @BASEBOARD_FAB2_LIB.BASEBOARD_FAB2(SCH_1):PAGE41
  BH17    GND @BASEBOARD_FAB2_LIB.BASEBOARD_FAB2(SCH_1):GND   I285 @BASEBOARD_FAB2_LIB.BASEBOARD_FAB2(SCH_1):PAGE41
  DN12    GND @BASEBOARD_FAB2_LIB.BASEBOARD_FAB2(SCH_1):GND   I285 @BASEBOARD_FAB2_LIB.BASEBOARD_FAB2(SCH_1):PAGE41
  DN22    GND @BASEBOARD_FAB2_LIB.BASEBOARD_FAB2(SCH_1):GND   I285 @BASEBOARD_FAB2_LIB.BASEBOARD_FAB2(SCH_1):PAGE41
  DN26    GND @BASEBOARD_FAB2_LIB.BASEBOARD_FAB2(SCH_1):GND   I285 @BASEBOARD_FAB2_LIB.BASEBOARD_FAB2(SCH_1):PAGE41
  DN32    GND @BASEBOARD_FAB2_LIB.BASEBOARD_FAB2(SCH_1):GND   I285 @BASEBOARD_FAB2_LIB.BASEBOARD_FAB2(SCH_1):PAGE41
  DN38    GND @BASEBOARD_FAB2_LIB.BASEBOARD_FAB2(SCH_1):GND   I285 @BASEBOARD_FAB2_LIB.BASEBOARD_FAB2(SCH_1):PAGE41
  DN68    GND @BASEBOARD_FAB2_LIB.BASEBOARD_FAB2(SCH_1):GND   I285 @BASEBOARD_FAB2_LIB.BASEBOARD_FAB2(SCH_1):PAGE41
  DN72    GND @BASEBOARD_FAB2_LIB.BASEBOARD_FAB2(SCH_1):GND   I285 @BASEBOARD_FAB2_LIB.BASEBOARD_FAB2(SCH_1):PAGE41
  DN78    GND @BASEBOARD_FAB2_LIB.BASEBOARD_FAB2(SCH_1):GND   I286 @BASEBOARD_FAB2_LIB.BASEBOARD_FAB2(SCH_1):PAGE41
  DP67    GND @BASEBOARD_FAB2_LIB.BASEBOARD_FAB2(SCH_1):GND   I286 @BASEBOARD_FAB2_LIB.BASEBOARD_FAB2(SCH_1):PAGE41
  DP69    GND @BASEBOARD_FAB2_LIB.BASEBOARD_FAB2(SCH_1):GND   I286 @BASEBOARD_FAB2_LIB.BASEBOARD_FAB2(SCH_1):PAGE41
  DP71    GND @BASEBOARD_FAB2_LIB.BASEBOARD_FAB2(SCH_1):GND   I286 @BASEBOARD_FAB2_LIB.BASEBOARD_FAB2(SCH_1):PAGE41
  DP81    GND @BASEBOARD_FAB2_LIB.BASEBOARD_FAB2(SCH_1):GND   I286 @BASEBOARD_FAB2_LIB.BASEBOARD_FAB2(SCH_1):PAGE41
  DP83    GND @BASEBOARD_FAB2_LIB.BASEBOARD_FAB2(SCH_1):GND   I286 @BASEBOARD_FAB2_LIB.BASEBOARD_FAB2(SCH_1):PAGE41
  BR26    GND @BASEBOARD_FAB2_LIB.BASEBOARD_FAB2(SCH_1):GND   I286 @BASEBOARD_FAB2_LIB.BASEBOARD_FAB2(SCH_1):PAGE41
   DR6    GND @BASEBOARD_FAB2_LIB.BASEBOARD_FAB2(SCH_1):GND   I286 @BASEBOARD_FAB2_LIB.BASEBOARD_FAB2(SCH_1):PAGE41
  CA20    GND @BASEBOARD_FAB2_LIB.BASEBOARD_FAB2(SCH_1):GND   I286 @BASEBOARD_FAB2_LIB.BASEBOARD_FAB2(SCH_1):PAGE41
  CL22    GND @BASEBOARD_FAB2_LIB.BASEBOARD_FAB2(SCH_1):GND   I286 @BASEBOARD_FAB2_LIB.BASEBOARD_FAB2(SCH_1):PAGE41
  DR20    GND @BASEBOARD_FAB2_LIB.BASEBOARD_FAB2(SCH_1):GND   I286 @BASEBOARD_FAB2_LIB.BASEBOARD_FAB2(SCH_1):PAGE41
  DR22    GND @BASEBOARD_FAB2_LIB.BASEBOARD_FAB2(SCH_1):GND   I286 @BASEBOARD_FAB2_LIB.BASEBOARD_FAB2(SCH_1):PAGE41
  DR24    GND @BASEBOARD_FAB2_LIB.BASEBOARD_FAB2(SCH_1):GND   I286 @BASEBOARD_FAB2_LIB.BASEBOARD_FAB2(SCH_1):PAGE41
  DR26    GND @BASEBOARD_FAB2_LIB.BASEBOARD_FAB2(SCH_1):GND   I286 @BASEBOARD_FAB2_LIB.BASEBOARD_FAB2(SCH_1):PAGE41
  DR28    GND @BASEBOARD_FAB2_LIB.BASEBOARD_FAB2(SCH_1):GND   I286 @BASEBOARD_FAB2_LIB.BASEBOARD_FAB2(SCH_1):PAGE41
  DR30    GND @BASEBOARD_FAB2_LIB.BASEBOARD_FAB2(SCH_1):GND   I286 @BASEBOARD_FAB2_LIB.BASEBOARD_FAB2(SCH_1):PAGE41
  DR32    GND @BASEBOARD_FAB2_LIB.BASEBOARD_FAB2(SCH_1):GND   I286 @BASEBOARD_FAB2_LIB.BASEBOARD_FAB2(SCH_1):PAGE41
  DR34    GND @BASEBOARD_FAB2_LIB.BASEBOARD_FAB2(SCH_1):GND   I286 @BASEBOARD_FAB2_LIB.BASEBOARD_FAB2(SCH_1):PAGE41
  DR36    GND @BASEBOARD_FAB2_LIB.BASEBOARD_FAB2(SCH_1):GND   I286 @BASEBOARD_FAB2_LIB.BASEBOARD_FAB2(SCH_1):PAGE41
  DR38    GND @BASEBOARD_FAB2_LIB.BASEBOARD_FAB2(SCH_1):GND   I286 @BASEBOARD_FAB2_LIB.BASEBOARD_FAB2(SCH_1):PAGE41
  DR40    GND @BASEBOARD_FAB2_LIB.BASEBOARD_FAB2(SCH_1):GND   I286 @BASEBOARD_FAB2_LIB.BASEBOARD_FAB2(SCH_1):PAGE41
  DR42    GND @BASEBOARD_FAB2_LIB.BASEBOARD_FAB2(SCH_1):GND   I286 @BASEBOARD_FAB2_LIB.BASEBOARD_FAB2(SCH_1):PAGE41
  DR66    GND @BASEBOARD_FAB2_LIB.BASEBOARD_FAB2(SCH_1):GND   I286 @BASEBOARD_FAB2_LIB.BASEBOARD_FAB2(SCH_1):PAGE41
  DR68    GND @BASEBOARD_FAB2_LIB.BASEBOARD_FAB2(SCH_1):GND   I286 @BASEBOARD_FAB2_LIB.BASEBOARD_FAB2(SCH_1):PAGE41
  DR70    GND @BASEBOARD_FAB2_LIB.BASEBOARD_FAB2(SCH_1):GND   I286 @BASEBOARD_FAB2_LIB.BASEBOARD_FAB2(SCH_1):PAGE41
  DR72    GND @BASEBOARD_FAB2_LIB.BASEBOARD_FAB2(SCH_1):GND   I286 @BASEBOARD_FAB2_LIB.BASEBOARD_FAB2(SCH_1):PAGE41
  DR74    GND @BASEBOARD_FAB2_LIB.BASEBOARD_FAB2(SCH_1):GND   I286 @BASEBOARD_FAB2_LIB.BASEBOARD_FAB2(SCH_1):PAGE41
  DR76    GND @BASEBOARD_FAB2_LIB.BASEBOARD_FAB2(SCH_1):GND   I286 @BASEBOARD_FAB2_LIB.BASEBOARD_FAB2(SCH_1):PAGE41
  DR78    GND @BASEBOARD_FAB2_LIB.BASEBOARD_FAB2(SCH_1):GND   I286 @BASEBOARD_FAB2_LIB.BASEBOARD_FAB2(SCH_1):PAGE41
   DT3    GND @BASEBOARD_FAB2_LIB.BASEBOARD_FAB2(SCH_1):GND   I286 @BASEBOARD_FAB2_LIB.BASEBOARD_FAB2(SCH_1):PAGE41
  DT17    GND @BASEBOARD_FAB2_LIB.BASEBOARD_FAB2(SCH_1):GND   I286 @BASEBOARD_FAB2_LIB.BASEBOARD_FAB2(SCH_1):PAGE41
  DH21    GND @BASEBOARD_FAB2_LIB.BASEBOARD_FAB2(SCH_1):GND   I286 @BASEBOARD_FAB2_LIB.BASEBOARD_FAB2(SCH_1):PAGE41
  DT65    GND @BASEBOARD_FAB2_LIB.BASEBOARD_FAB2(SCH_1):GND   I286 @BASEBOARD_FAB2_LIB.BASEBOARD_FAB2(SCH_1):PAGE41
  DT69    GND @BASEBOARD_FAB2_LIB.BASEBOARD_FAB2(SCH_1):GND   I286 @BASEBOARD_FAB2_LIB.BASEBOARD_FAB2(SCH_1):PAGE41
  DT79    GND @BASEBOARD_FAB2_LIB.BASEBOARD_FAB2(SCH_1):GND   I286 @BASEBOARD_FAB2_LIB.BASEBOARD_FAB2(SCH_1):PAGE41
  DT83    GND @BASEBOARD_FAB2_LIB.BASEBOARD_FAB2(SCH_1):GND   I286 @BASEBOARD_FAB2_LIB.BASEBOARD_FAB2(SCH_1):PAGE41
  DT85    GND @BASEBOARD_FAB2_LIB.BASEBOARD_FAB2(SCH_1):GND   I286 @BASEBOARD_FAB2_LIB.BASEBOARD_FAB2(SCH_1):PAGE41
  DU10    GND @BASEBOARD_FAB2_LIB.BASEBOARD_FAB2(SCH_1):GND   I286 @BASEBOARD_FAB2_LIB.BASEBOARD_FAB2(SCH_1):PAGE41
  DU14    GND @BASEBOARD_FAB2_LIB.BASEBOARD_FAB2(SCH_1):GND   I286 @BASEBOARD_FAB2_LIB.BASEBOARD_FAB2(SCH_1):PAGE41
  CN14    GND @BASEBOARD_FAB2_LIB.BASEBOARD_FAB2(SCH_1):GND   I286 @BASEBOARD_FAB2_LIB.BASEBOARD_FAB2(SCH_1):PAGE41
  DU22    GND @BASEBOARD_FAB2_LIB.BASEBOARD_FAB2(SCH_1):GND   I286 @BASEBOARD_FAB2_LIB.BASEBOARD_FAB2(SCH_1):PAGE41
  DU26    GND @BASEBOARD_FAB2_LIB.BASEBOARD_FAB2(SCH_1):GND   I286 @BASEBOARD_FAB2_LIB.BASEBOARD_FAB2(SCH_1):PAGE41
  DU32    GND @BASEBOARD_FAB2_LIB.BASEBOARD_FAB2(SCH_1):GND   I286 @BASEBOARD_FAB2_LIB.BASEBOARD_FAB2(SCH_1):PAGE41
  DU38    GND @BASEBOARD_FAB2_LIB.BASEBOARD_FAB2(SCH_1):GND   I286 @BASEBOARD_FAB2_LIB.BASEBOARD_FAB2(SCH_1):PAGE41
  DU70    GND @BASEBOARD_FAB2_LIB.BASEBOARD_FAB2(SCH_1):GND   I286 @BASEBOARD_FAB2_LIB.BASEBOARD_FAB2(SCH_1):PAGE41
  DU72    GND @BASEBOARD_FAB2_LIB.BASEBOARD_FAB2(SCH_1):GND   I286 @BASEBOARD_FAB2_LIB.BASEBOARD_FAB2(SCH_1):PAGE41
  DU78    GND @BASEBOARD_FAB2_LIB.BASEBOARD_FAB2(SCH_1):GND   I286 @BASEBOARD_FAB2_LIB.BASEBOARD_FAB2(SCH_1):PAGE41
  DU80    GND @BASEBOARD_FAB2_LIB.BASEBOARD_FAB2(SCH_1):GND   I286 @BASEBOARD_FAB2_LIB.BASEBOARD_FAB2(SCH_1):PAGE41
  DU82    GND @BASEBOARD_FAB2_LIB.BASEBOARD_FAB2(SCH_1):GND   I286 @BASEBOARD_FAB2_LIB.BASEBOARD_FAB2(SCH_1):PAGE41
  DU84    GND @BASEBOARD_FAB2_LIB.BASEBOARD_FAB2(SCH_1):GND   I286 @BASEBOARD_FAB2_LIB.BASEBOARD_FAB2(SCH_1):PAGE41
  DV21    GND @BASEBOARD_FAB2_LIB.BASEBOARD_FAB2(SCH_1):GND   I286 @BASEBOARD_FAB2_LIB.BASEBOARD_FAB2(SCH_1):PAGE41
  DV25    GND @BASEBOARD_FAB2_LIB.BASEBOARD_FAB2(SCH_1):GND   I286 @BASEBOARD_FAB2_LIB.BASEBOARD_FAB2(SCH_1):PAGE41
  DV27    GND @BASEBOARD_FAB2_LIB.BASEBOARD_FAB2(SCH_1):GND   I286 @BASEBOARD_FAB2_LIB.BASEBOARD_FAB2(SCH_1):PAGE41
  DV31    GND @BASEBOARD_FAB2_LIB.BASEBOARD_FAB2(SCH_1):GND   I286 @BASEBOARD_FAB2_LIB.BASEBOARD_FAB2(SCH_1):PAGE41
  DV33    GND @BASEBOARD_FAB2_LIB.BASEBOARD_FAB2(SCH_1):GND   I286 @BASEBOARD_FAB2_LIB.BASEBOARD_FAB2(SCH_1):PAGE41
  DV37    GND @BASEBOARD_FAB2_LIB.BASEBOARD_FAB2(SCH_1):GND   I286 @BASEBOARD_FAB2_LIB.BASEBOARD_FAB2(SCH_1):PAGE41
  DV39    GND @BASEBOARD_FAB2_LIB.BASEBOARD_FAB2(SCH_1):GND   I286 @BASEBOARD_FAB2_LIB.BASEBOARD_FAB2(SCH_1):PAGE41
  DV73    GND @BASEBOARD_FAB2_LIB.BASEBOARD_FAB2(SCH_1):GND   I286 @BASEBOARD_FAB2_LIB.BASEBOARD_FAB2(SCH_1):PAGE41
  DV77    GND @BASEBOARD_FAB2_LIB.BASEBOARD_FAB2(SCH_1):GND   I286 @BASEBOARD_FAB2_LIB.BASEBOARD_FAB2(SCH_1):PAGE41
  DV81    GND @BASEBOARD_FAB2_LIB.BASEBOARD_FAB2(SCH_1):GND   I286 @BASEBOARD_FAB2_LIB.BASEBOARD_FAB2(SCH_1):PAGE41
  DW12    GND @BASEBOARD_FAB2_LIB.BASEBOARD_FAB2(SCH_1):GND   I286 @BASEBOARD_FAB2_LIB.BASEBOARD_FAB2(SCH_1):PAGE41
  DW20    GND @BASEBOARD_FAB2_LIB.BASEBOARD_FAB2(SCH_1):GND   I286 @BASEBOARD_FAB2_LIB.BASEBOARD_FAB2(SCH_1):PAGE41
  DW24    GND @BASEBOARD_FAB2_LIB.BASEBOARD_FAB2(SCH_1):GND   I286 @BASEBOARD_FAB2_LIB.BASEBOARD_FAB2(SCH_1):PAGE41
  DW28    GND @BASEBOARD_FAB2_LIB.BASEBOARD_FAB2(SCH_1):GND   I286 @BASEBOARD_FAB2_LIB.BASEBOARD_FAB2(SCH_1):PAGE41
  DW30    GND @BASEBOARD_FAB2_LIB.BASEBOARD_FAB2(SCH_1):GND   I286 @BASEBOARD_FAB2_LIB.BASEBOARD_FAB2(SCH_1):PAGE41
  DW34    GND @BASEBOARD_FAB2_LIB.BASEBOARD_FAB2(SCH_1):GND   I286 @BASEBOARD_FAB2_LIB.BASEBOARD_FAB2(SCH_1):PAGE41
  DW36    GND @BASEBOARD_FAB2_LIB.BASEBOARD_FAB2(SCH_1):GND   I286 @BASEBOARD_FAB2_LIB.BASEBOARD_FAB2(SCH_1):PAGE41
  DW40    GND @BASEBOARD_FAB2_LIB.BASEBOARD_FAB2(SCH_1):GND   I286 @BASEBOARD_FAB2_LIB.BASEBOARD_FAB2(SCH_1):PAGE41
  DW64    GND @BASEBOARD_FAB2_LIB.BASEBOARD_FAB2(SCH_1):GND   I286 @BASEBOARD_FAB2_LIB.BASEBOARD_FAB2(SCH_1):PAGE41
  DW66    GND @BASEBOARD_FAB2_LIB.BASEBOARD_FAB2(SCH_1):GND   I286 @BASEBOARD_FAB2_LIB.BASEBOARD_FAB2(SCH_1):PAGE41
  DW68    GND @BASEBOARD_FAB2_LIB.BASEBOARD_FAB2(SCH_1):GND   I286 @BASEBOARD_FAB2_LIB.BASEBOARD_FAB2(SCH_1):PAGE41
  DW70    GND @BASEBOARD_FAB2_LIB.BASEBOARD_FAB2(SCH_1):GND   I286 @BASEBOARD_FAB2_LIB.BASEBOARD_FAB2(SCH_1):PAGE41
  DW72    GND @BASEBOARD_FAB2_LIB.BASEBOARD_FAB2(SCH_1):GND   I286 @BASEBOARD_FAB2_LIB.BASEBOARD_FAB2(SCH_1):PAGE41
  DW74    GND @BASEBOARD_FAB2_LIB.BASEBOARD_FAB2(SCH_1):GND   I286 @BASEBOARD_FAB2_LIB.BASEBOARD_FAB2(SCH_1):PAGE41
  DW76    GND @BASEBOARD_FAB2_LIB.BASEBOARD_FAB2(SCH_1):GND   I286 @BASEBOARD_FAB2_LIB.BASEBOARD_FAB2(SCH_1):PAGE41
   DW8    GND @BASEBOARD_FAB2_LIB.BASEBOARD_FAB2(SCH_1):GND   I286 @BASEBOARD_FAB2_LIB.BASEBOARD_FAB2(SCH_1):PAGE41
  DW82    GND @BASEBOARD_FAB2_LIB.BASEBOARD_FAB2(SCH_1):GND   I286 @BASEBOARD_FAB2_LIB.BASEBOARD_FAB2(SCH_1):PAGE41
  DW84    GND @BASEBOARD_FAB2_LIB.BASEBOARD_FAB2(SCH_1):GND   I286 @BASEBOARD_FAB2_LIB.BASEBOARD_FAB2(SCH_1):PAGE41
   DY5    GND @BASEBOARD_FAB2_LIB.BASEBOARD_FAB2(SCH_1):GND   I286 @BASEBOARD_FAB2_LIB.BASEBOARD_FAB2(SCH_1):PAGE41
  DY19    GND @BASEBOARD_FAB2_LIB.BASEBOARD_FAB2(SCH_1):GND   I286 @BASEBOARD_FAB2_LIB.BASEBOARD_FAB2(SCH_1):PAGE41
  DY23    GND @BASEBOARD_FAB2_LIB.BASEBOARD_FAB2(SCH_1):GND   I286 @BASEBOARD_FAB2_LIB.BASEBOARD_FAB2(SCH_1):PAGE41
  DY29    GND @BASEBOARD_FAB2_LIB.BASEBOARD_FAB2(SCH_1):GND   I286 @BASEBOARD_FAB2_LIB.BASEBOARD_FAB2(SCH_1):PAGE41
  DY35    GND @BASEBOARD_FAB2_LIB.BASEBOARD_FAB2(SCH_1):GND   I286 @BASEBOARD_FAB2_LIB.BASEBOARD_FAB2(SCH_1):PAGE41
  DY41    GND @BASEBOARD_FAB2_LIB.BASEBOARD_FAB2(SCH_1):GND   I286 @BASEBOARD_FAB2_LIB.BASEBOARD_FAB2(SCH_1):PAGE41
  DY71    GND @BASEBOARD_FAB2_LIB.BASEBOARD_FAB2(SCH_1):GND   I286 @BASEBOARD_FAB2_LIB.BASEBOARD_FAB2(SCH_1):PAGE41
  DY75    GND @BASEBOARD_FAB2_LIB.BASEBOARD_FAB2(SCH_1):GND   I286 @BASEBOARD_FAB2_LIB.BASEBOARD_FAB2(SCH_1):PAGE41
   EA6    GND @BASEBOARD_FAB2_LIB.BASEBOARD_FAB2(SCH_1):GND   I286 @BASEBOARD_FAB2_LIB.BASEBOARD_FAB2(SCH_1):PAGE41
   J16    GND @BASEBOARD_FAB2_LIB.BASEBOARD_FAB2(SCH_1):GND   I286 @BASEBOARD_FAB2_LIB.BASEBOARD_FAB2(SCH_1):PAGE41
  EA16    GND @BASEBOARD_FAB2_LIB.BASEBOARD_FAB2(SCH_1):GND   I286 @BASEBOARD_FAB2_LIB.BASEBOARD_FAB2(SCH_1):PAGE41
  EA20    GND @BASEBOARD_FAB2_LIB.BASEBOARD_FAB2(SCH_1):GND   I286 @BASEBOARD_FAB2_LIB.BASEBOARD_FAB2(SCH_1):PAGE41
  EA22    GND @BASEBOARD_FAB2_LIB.BASEBOARD_FAB2(SCH_1):GND   I286 @BASEBOARD_FAB2_LIB.BASEBOARD_FAB2(SCH_1):PAGE41
  EA42    GND @BASEBOARD_FAB2_LIB.BASEBOARD_FAB2(SCH_1):GND   I286 @BASEBOARD_FAB2_LIB.BASEBOARD_FAB2(SCH_1):PAGE41
  EA64    GND @BASEBOARD_FAB2_LIB.BASEBOARD_FAB2(SCH_1):GND   I286 @BASEBOARD_FAB2_LIB.BASEBOARD_FAB2(SCH_1):PAGE41
  EA70    GND @BASEBOARD_FAB2_LIB.BASEBOARD_FAB2(SCH_1):GND   I286 @BASEBOARD_FAB2_LIB.BASEBOARD_FAB2(SCH_1):PAGE41
  EA76    GND @BASEBOARD_FAB2_LIB.BASEBOARD_FAB2(SCH_1):GND   I286 @BASEBOARD_FAB2_LIB.BASEBOARD_FAB2(SCH_1):PAGE41
  EA78    GND @BASEBOARD_FAB2_LIB.BASEBOARD_FAB2(SCH_1):GND   I286 @BASEBOARD_FAB2_LIB.BASEBOARD_FAB2(SCH_1):PAGE41
  EA80    GND @BASEBOARD_FAB2_LIB.BASEBOARD_FAB2(SCH_1):GND   I286 @BASEBOARD_FAB2_LIB.BASEBOARD_FAB2(SCH_1):PAGE41
  EA82    GND @BASEBOARD_FAB2_LIB.BASEBOARD_FAB2(SCH_1):GND   I286 @BASEBOARD_FAB2_LIB.BASEBOARD_FAB2(SCH_1):PAGE41
  EB13    GND @BASEBOARD_FAB2_LIB.BASEBOARD_FAB2(SCH_1):GND   I286 @BASEBOARD_FAB2_LIB.BASEBOARD_FAB2(SCH_1):PAGE41
  BR18    GND @BASEBOARD_FAB2_LIB.BASEBOARD_FAB2(SCH_1):GND   I286 @BASEBOARD_FAB2_LIB.BASEBOARD_FAB2(SCH_1):PAGE41
  EB23    GND @BASEBOARD_FAB2_LIB.BASEBOARD_FAB2(SCH_1):GND   I286 @BASEBOARD_FAB2_LIB.BASEBOARD_FAB2(SCH_1):PAGE41
  EB25    GND @BASEBOARD_FAB2_LIB.BASEBOARD_FAB2(SCH_1):GND   I286 @BASEBOARD_FAB2_LIB.BASEBOARD_FAB2(SCH_1):PAGE41
  EB27    GND @BASEBOARD_FAB2_LIB.BASEBOARD_FAB2(SCH_1):GND   I286 @BASEBOARD_FAB2_LIB.BASEBOARD_FAB2(SCH_1):PAGE41
  EB29    GND @BASEBOARD_FAB2_LIB.BASEBOARD_FAB2(SCH_1):GND   I286 @BASEBOARD_FAB2_LIB.BASEBOARD_FAB2(SCH_1):PAGE41
  EB31    GND @BASEBOARD_FAB2_LIB.BASEBOARD_FAB2(SCH_1):GND   I286 @BASEBOARD_FAB2_LIB.BASEBOARD_FAB2(SCH_1):PAGE41
  EB33    GND @BASEBOARD_FAB2_LIB.BASEBOARD_FAB2(SCH_1):GND   I286 @BASEBOARD_FAB2_LIB.BASEBOARD_FAB2(SCH_1):PAGE41
  EB35    GND @BASEBOARD_FAB2_LIB.BASEBOARD_FAB2(SCH_1):GND   I286 @BASEBOARD_FAB2_LIB.BASEBOARD_FAB2(SCH_1):PAGE41
  EB37    GND @BASEBOARD_FAB2_LIB.BASEBOARD_FAB2(SCH_1):GND   I286 @BASEBOARD_FAB2_LIB.BASEBOARD_FAB2(SCH_1):PAGE41
  EB39    GND @BASEBOARD_FAB2_LIB.BASEBOARD_FAB2(SCH_1):GND   I286 @BASEBOARD_FAB2_LIB.BASEBOARD_FAB2(SCH_1):PAGE41
  EB41    GND @BASEBOARD_FAB2_LIB.BASEBOARD_FAB2(SCH_1):GND   I286 @BASEBOARD_FAB2_LIB.BASEBOARD_FAB2(SCH_1):PAGE41
  EB65    GND @BASEBOARD_FAB2_LIB.BASEBOARD_FAB2(SCH_1):GND   I286 @BASEBOARD_FAB2_LIB.BASEBOARD_FAB2(SCH_1):PAGE41
  EB69    GND @BASEBOARD_FAB2_LIB.BASEBOARD_FAB2(SCH_1):GND   I286 @BASEBOARD_FAB2_LIB.BASEBOARD_FAB2(SCH_1):PAGE41
  EC10    GND @BASEBOARD_FAB2_LIB.BASEBOARD_FAB2(SCH_1):GND   I286 @BASEBOARD_FAB2_LIB.BASEBOARD_FAB2(SCH_1):PAGE41
  EC70    GND @BASEBOARD_FAB2_LIB.BASEBOARD_FAB2(SCH_1):GND   I286 @BASEBOARD_FAB2_LIB.BASEBOARD_FAB2(SCH_1):PAGE41
  EC72    GND @BASEBOARD_FAB2_LIB.BASEBOARD_FAB2(SCH_1):GND   I286 @BASEBOARD_FAB2_LIB.BASEBOARD_FAB2(SCH_1):PAGE41
  EC74    GND @BASEBOARD_FAB2_LIB.BASEBOARD_FAB2(SCH_1):GND   I286 @BASEBOARD_FAB2_LIB.BASEBOARD_FAB2(SCH_1):PAGE41
  EC76    GND @BASEBOARD_FAB2_LIB.BASEBOARD_FAB2(SCH_1):GND   I286 @BASEBOARD_FAB2_LIB.BASEBOARD_FAB2(SCH_1):PAGE41
  ED11    GND @BASEBOARD_FAB2_LIB.BASEBOARD_FAB2(SCH_1):GND   I286 @BASEBOARD_FAB2_LIB.BASEBOARD_FAB2(SCH_1):PAGE41
  ED15    GND @BASEBOARD_FAB2_LIB.BASEBOARD_FAB2(SCH_1):GND   I286 @BASEBOARD_FAB2_LIB.BASEBOARD_FAB2(SCH_1):PAGE41
  ED23    GND @BASEBOARD_FAB2_LIB.BASEBOARD_FAB2(SCH_1):GND   I286 @BASEBOARD_FAB2_LIB.BASEBOARD_FAB2(SCH_1):PAGE41
  ED29    GND @BASEBOARD_FAB2_LIB.BASEBOARD_FAB2(SCH_1):GND   I286 @BASEBOARD_FAB2_LIB.BASEBOARD_FAB2(SCH_1):PAGE41
  ED35    GND @BASEBOARD_FAB2_LIB.BASEBOARD_FAB2(SCH_1):GND   I286 @BASEBOARD_FAB2_LIB.BASEBOARD_FAB2(SCH_1):PAGE41
  ED77    GND @BASEBOARD_FAB2_LIB.BASEBOARD_FAB2(SCH_1):GND   I286 @BASEBOARD_FAB2_LIB.BASEBOARD_FAB2(SCH_1):PAGE41
  EE24    GND @BASEBOARD_FAB2_LIB.BASEBOARD_FAB2(SCH_1):GND   I286 @BASEBOARD_FAB2_LIB.BASEBOARD_FAB2(SCH_1):PAGE41
  EE28    GND @BASEBOARD_FAB2_LIB.BASEBOARD_FAB2(SCH_1):GND   I286 @BASEBOARD_FAB2_LIB.BASEBOARD_FAB2(SCH_1):PAGE41
  EE30    GND @BASEBOARD_FAB2_LIB.BASEBOARD_FAB2(SCH_1):GND   I286 @BASEBOARD_FAB2_LIB.BASEBOARD_FAB2(SCH_1):PAGE41
  EE34    GND @BASEBOARD_FAB2_LIB.BASEBOARD_FAB2(SCH_1):GND   I286 @BASEBOARD_FAB2_LIB.BASEBOARD_FAB2(SCH_1):PAGE41
  EE36    GND @BASEBOARD_FAB2_LIB.BASEBOARD_FAB2(SCH_1):GND   I286 @BASEBOARD_FAB2_LIB.BASEBOARD_FAB2(SCH_1):PAGE41
  EE70    GND @BASEBOARD_FAB2_LIB.BASEBOARD_FAB2(SCH_1):GND   I286 @BASEBOARD_FAB2_LIB.BASEBOARD_FAB2(SCH_1):PAGE41
  EE76    GND @BASEBOARD_FAB2_LIB.BASEBOARD_FAB2(SCH_1):GND   I286 @BASEBOARD_FAB2_LIB.BASEBOARD_FAB2(SCH_1):PAGE41
  EE78    GND @BASEBOARD_FAB2_LIB.BASEBOARD_FAB2(SCH_1):GND   I286 @BASEBOARD_FAB2_LIB.BASEBOARD_FAB2(SCH_1):PAGE41
  EF71    GND @BASEBOARD_FAB2_LIB.BASEBOARD_FAB2(SCH_1):GND   I286 @BASEBOARD_FAB2_LIB.BASEBOARD_FAB2(SCH_1):PAGE41
  EF75    GND @BASEBOARD_FAB2_LIB.BASEBOARD_FAB2(SCH_1):GND   I286 @BASEBOARD_FAB2_LIB.BASEBOARD_FAB2(SCH_1):PAGE41
  EF79    GND @BASEBOARD_FAB2_LIB.BASEBOARD_FAB2(SCH_1):GND   I286 @BASEBOARD_FAB2_LIB.BASEBOARD_FAB2(SCH_1):PAGE41

U6F1 PCA9617_SSOP-IC,G81764-001-GNDA
     5 TP_SMB_DDR_ABC_EN @BASEBOARD_FAB2_LIB.BASEBOARD_FAB2(SCH_1):TP_SMB_DDR_ABC_EN    I15 @BASEBOARD_FAB2_LIB.BASEBOARD_FAB2(SCH_1):PAGE99
     2 SMB_DDR_ABC_SCL_G @BASEBOARD_FAB2_LIB.BASEBOARD_FAB2(SCH_1):SMB_DDR_ABC_SCL_G    I15 @BASEBOARD_FAB2_LIB.BASEBOARD_FAB2(SCH_1):PAGE99
     7 SMB_DDR_ABC_VPP_SCL_R @BASEBOARD_FAB2_LIB.BASEBOARD_FAB2(SCH_1):SMB_DDR_ABC_VPP_SCL_R    I15 @BASEBOARD_FAB2_LIB.BASEBOARD_FAB2(SCH_1):PAGE99
     3 SMB_DDR_ABC_SDA_G @BASEBOARD_FAB2_LIB.BASEBOARD_FAB2(SCH_1):SMB_DDR_ABC_SDA_G    I15 @BASEBOARD_FAB2_LIB.BASEBOARD_FAB2(SCH_1):PAGE99
     6 SMB_DDR_ABC_VPP_SDA_R @BASEBOARD_FAB2_LIB.BASEBOARD_FAB2(SCH_1):SMB_DDR_ABC_VPP_SDA_R    I15 @BASEBOARD_FAB2_LIB.BASEBOARD_FAB2(SCH_1):PAGE99
     1 PVCCIO_CPU0 @BASEBOARD_FAB2_LIB.BASEBOARD_FAB2(SCH_1):PVCCIO_CPU0    I15 @BASEBOARD_FAB2_LIB.BASEBOARD_FAB2(SCH_1):PAGE99
     8 PVPP_ABC @BASEBOARD_FAB2_LIB.BASEBOARD_FAB2(SCH_1):PVPP_ABC    I15 @BASEBOARD_FAB2_LIB.BASEBOARD_FAB2(SCH_1):PAGE99

U6M1 74CBTLV1G125_SMLF-IC,C88177-00A
     4 JTAG_MCP_CPU1_TDI_R @BASEBOARD_FAB2_LIB.BASEBOARD_FAB2(SCH_1):JTAG_MCP_CPU1_TDI_R   I190 @BASEBOARD_FAB2_LIB.BASEBOARD_FAB2(SCH_1):PAGE113
     1 FM_CPU1_PKGID1 @BASEBOARD_FAB2_LIB.BASEBOARD_FAB2(SCH_1):FM_CPU1_PKGID1   I190 @BASEBOARD_FAB2_LIB.BASEBOARD_FAB2(SCH_1):PAGE113
     2 P1V8_MCP_CPU1 @BASEBOARD_FAB2_LIB.BASEBOARD_FAB2(SCH_1):P1V8_MCP_CPU1   I190 @BASEBOARD_FAB2_LIB.BASEBOARD_FAB2(SCH_1):PAGE113

U6W1 PCA9555PWRG4-GP_DISCRET-G5-PCAA
     1 PCA9555_INT_N @BASEBOARD_FAB2_LIB.BASEBOARD_FAB2(SCH_1):PCA9555_INT_N    I97 @BASEBOARD_FAB2_LIB.BASEBOARD_FAB2(SCH_1):PAGE247
     2 PCA9555_A1 @BASEBOARD_FAB2_LIB.BASEBOARD_FAB2(SCH_1):PCA9555_A1    I97 @BASEBOARD_FAB2_LIB.BASEBOARD_FAB2(SCH_1):PAGE247
     3 PCA9555_A2 @BASEBOARD_FAB2_LIB.BASEBOARD_FAB2(SCH_1):PCA9555_A2    I97 @BASEBOARD_FAB2_LIB.BASEBOARD_FAB2(SCH_1):PAGE247
     4 LED_POSTCODE_0_R @BASEBOARD_FAB2_LIB.BASEBOARD_FAB2(SCH_1):LED_POSTCODE_0_R    I97 @BASEBOARD_FAB2_LIB.BASEBOARD_FAB2(SCH_1):PAGE247
     5 LED_POSTCODE_1_R @BASEBOARD_FAB2_LIB.BASEBOARD_FAB2(SCH_1):LED_POSTCODE_1_R    I97 @BASEBOARD_FAB2_LIB.BASEBOARD_FAB2(SCH_1):PAGE247
     6 LED_POSTCODE_2_R @BASEBOARD_FAB2_LIB.BASEBOARD_FAB2(SCH_1):LED_POSTCODE_2_R    I97 @BASEBOARD_FAB2_LIB.BASEBOARD_FAB2(SCH_1):PAGE247
     7 LED_POSTCODE_3_R @BASEBOARD_FAB2_LIB.BASEBOARD_FAB2(SCH_1):LED_POSTCODE_3_R    I97 @BASEBOARD_FAB2_LIB.BASEBOARD_FAB2(SCH_1):PAGE247
     8 LED_POSTCODE_4_R @BASEBOARD_FAB2_LIB.BASEBOARD_FAB2(SCH_1):LED_POSTCODE_4_R    I97 @BASEBOARD_FAB2_LIB.BASEBOARD_FAB2(SCH_1):PAGE247
     9 LED_POSTCODE_5_R @BASEBOARD_FAB2_LIB.BASEBOARD_FAB2(SCH_1):LED_POSTCODE_5_R    I97 @BASEBOARD_FAB2_LIB.BASEBOARD_FAB2(SCH_1):PAGE247
    10 LED_POSTCODE_6_R @BASEBOARD_FAB2_LIB.BASEBOARD_FAB2(SCH_1):LED_POSTCODE_6_R    I97 @BASEBOARD_FAB2_LIB.BASEBOARD_FAB2(SCH_1):PAGE247
    11 LED_POSTCODE_7_R @BASEBOARD_FAB2_LIB.BASEBOARD_FAB2(SCH_1):LED_POSTCODE_7_R    I97 @BASEBOARD_FAB2_LIB.BASEBOARD_FAB2(SCH_1):PAGE247
    12    GND @BASEBOARD_FAB2_LIB.BASEBOARD_FAB2(SCH_1):GND    I97 @BASEBOARD_FAB2_LIB.BASEBOARD_FAB2(SCH_1):PAGE247
    13 FM_DEBUG_RST_BTN_N @BASEBOARD_FAB2_LIB.BASEBOARD_FAB2(SCH_1):FM_DEBUG_RST_BTN_N    I97 @BASEBOARD_FAB2_LIB.BASEBOARD_FAB2(SCH_1):PAGE247
    14 FP_PWR_BTN_R_N @BASEBOARD_FAB2_LIB.BASEBOARD_FAB2(SCH_1):FP_PWR_BTN_R_N    I97 @BASEBOARD_FAB2_LIB.BASEBOARD_FAB2(SCH_1):PAGE247
    15     NC     NC    I97 @BASEBOARD_FAB2_LIB.BASEBOARD_FAB2(SCH_1):PAGE247
    16     NC     NC    I97 @BASEBOARD_FAB2_LIB.BASEBOARD_FAB2(SCH_1):PAGE247
    17     NC     NC    I97 @BASEBOARD_FAB2_LIB.BASEBOARD_FAB2(SCH_1):PAGE247
    18     NC     NC    I97 @BASEBOARD_FAB2_LIB.BASEBOARD_FAB2(SCH_1):PAGE247
    19     NC     NC    I97 @BASEBOARD_FAB2_LIB.BASEBOARD_FAB2(SCH_1):PAGE247
    20     NC     NC    I97 @BASEBOARD_FAB2_LIB.BASEBOARD_FAB2(SCH_1):PAGE247
    21 PCA9555_A0 @BASEBOARD_FAB2_LIB.BASEBOARD_FAB2(SCH_1):PCA9555_A0    I97 @BASEBOARD_FAB2_LIB.BASEBOARD_FAB2(SCH_1):PAGE247
    22 SMB_IPMB_3V3AUX_SCL @BASEBOARD_FAB2_LIB.BASEBOARD_FAB2(SCH_1):SMB_IPMB_3V3AUX_SCL    I97 @BASEBOARD_FAB2_LIB.BASEBOARD_FAB2(SCH_1):PAGE247
    23 SMB_IPMB_3V3AUX_SDA @BASEBOARD_FAB2_LIB.BASEBOARD_FAB2(SCH_1):SMB_IPMB_3V3AUX_SDA    I97 @BASEBOARD_FAB2_LIB.BASEBOARD_FAB2(SCH_1):PAGE247
    24 P3V3_STBY @BASEBOARD_FAB2_LIB.BASEBOARD_FAB2(SCH_1):P3V3_STBY    I97 @BASEBOARD_FAB2_LIB.BASEBOARD_FAB2(SCH_1):PAGE247

U6W2 PCA9515ADGKR-1-GP_DISCRET-G5-PA
     1     NC     NC    I77 @BASEBOARD_FAB2_LIB.BASEBOARD_FAB2(SCH_1):PAGE247
     2 SMB_PMBUS_BMC_STBY_LVC3_SCL_R1 @BASEBOARD_FAB2_LIB.BASEBOARD_FAB2(SCH_1):SMB_PMBUS_BMC_STBY_LVC3_SCL_R1    I77 @BASEBOARD_FAB2_LIB.BASEBOARD_FAB2(SCH_1):PAGE247
     3 SMB_PMBUS_BMC_STBY_LVC3_SDA_R1 @BASEBOARD_FAB2_LIB.BASEBOARD_FAB2(SCH_1):SMB_PMBUS_BMC_STBY_LVC3_SDA_R1    I77 @BASEBOARD_FAB2_LIB.BASEBOARD_FAB2(SCH_1):PAGE247
     4    GND @BASEBOARD_FAB2_LIB.BASEBOARD_FAB2(SCH_1):GND    I77 @BASEBOARD_FAB2_LIB.BASEBOARD_FAB2(SCH_1):PAGE247
     5 HSC_SMBUS_SWITCH_EN @BASEBOARD_FAB2_LIB.BASEBOARD_FAB2(SCH_1):HSC_SMBUS_SWITCH_EN    I77 @BASEBOARD_FAB2_LIB.BASEBOARD_FAB2(SCH_1):PAGE247
     6 SMB_BMC_PMBUS_STBY_LVC3_SDA @BASEBOARD_FAB2_LIB.BASEBOARD_FAB2(SCH_1):SMB_BMC_PMBUS_STBY_LVC3_SDA    I77 @BASEBOARD_FAB2_LIB.BASEBOARD_FAB2(SCH_1):PAGE247
     7 SMB_BMC_PMBUS_STBY_LVC3_SCL @BASEBOARD_FAB2_LIB.BASEBOARD_FAB2(SCH_1):SMB_BMC_PMBUS_STBY_LVC3_SCL    I77 @BASEBOARD_FAB2_LIB.BASEBOARD_FAB2(SCH_1):PAGE247
     8 P3V3_STBY @BASEBOARD_FAB2_LIB.BASEBOARD_FAB2(SCH_1):P3V3_STBY    I77 @BASEBOARD_FAB2_LIB.BASEBOARD_FAB2(SCH_1):PAGE247

U6W3 AT24C64_SOICLF-IC,C47049-001-GA
     1    GND @BASEBOARD_FAB2_LIB.BASEBOARD_FAB2(SCH_1):GND    I89 @BASEBOARD_FAB2_LIB.BASEBOARD_FAB2(SCH_1):PAGE247
     2    GND @BASEBOARD_FAB2_LIB.BASEBOARD_FAB2(SCH_1):GND    I89 @BASEBOARD_FAB2_LIB.BASEBOARD_FAB2(SCH_1):PAGE247
     3 PU_ID_EEPROM_A2 @BASEBOARD_FAB2_LIB.BASEBOARD_FAB2(SCH_1):PU_ID_EEPROM_A2    I89 @BASEBOARD_FAB2_LIB.BASEBOARD_FAB2(SCH_1):PAGE247
     6 SMB_HOST_STBY_LVC3_SCL_R3 @BASEBOARD_FAB2_LIB.BASEBOARD_FAB2(SCH_1):SMB_HOST_STBY_LVC3_SCL_R3    I89 @BASEBOARD_FAB2_LIB.BASEBOARD_FAB2(SCH_1):PAGE247
     7 PD_ID_EEPROM_WP @BASEBOARD_FAB2_LIB.BASEBOARD_FAB2(SCH_1):PD_ID_EEPROM_WP    I89 @BASEBOARD_FAB2_LIB.BASEBOARD_FAB2(SCH_1):PAGE247
     5 SMB_HOST_STBY_LVC3_SDA_R3 @BASEBOARD_FAB2_LIB.BASEBOARD_FAB2(SCH_1):SMB_HOST_STBY_LVC3_SDA_R3    I89 @BASEBOARD_FAB2_LIB.BASEBOARD_FAB2(SCH_1):PAGE247

U6W10 TTL1G08_SOTLF-NC7SZ08,IC,D1032B
     4 SPA_MID_DBG_RX @BASEBOARD_FAB2_LIB.BASEBOARD_FAB2(SCH_1):SPA_MID_DBG_RX   I122 @BASEBOARD_FAB2_LIB.BASEBOARD_FAB2(SCH_1):PAGE176
     1 SPA_MID_DBG1__RX @BASEBOARD_FAB2_LIB.BASEBOARD_FAB2(SCH_1):SPA_MID_DBG1__RX   I122 @BASEBOARD_FAB2_LIB.BASEBOARD_FAB2(SCH_1):PAGE176
     2 SPA_MID_DBG2_RX @BASEBOARD_FAB2_LIB.BASEBOARD_FAB2(SCH_1):SPA_MID_DBG2_RX   I122 @BASEBOARD_FAB2_LIB.BASEBOARD_FAB2(SCH_1):PAGE176

U7C1 LBG_CORE_QAT_EXT_D_BGA1-IC,H91A
   A39 CLK_100M_PCH_XDP_DN @BASEBOARD_FAB2_LIB.BASEBOARD_FAB2(SCH_1):CLK_100M_PCH_XDP_DN    I40 @BASEBOARD_FAB2_LIB.BASEBOARD_FAB2(SCH_1):PAGE114
   C39 CLK_100M_PCH_XDP_DP @BASEBOARD_FAB2_LIB.BASEBOARD_FAB2(SCH_1):CLK_100M_PCH_XDP_DP    I40 @BASEBOARD_FAB2_LIB.BASEBOARD_FAB2(SCH_1):PAGE114
   A32 TP_CLK_100M_NSSCC0_DN @BASEBOARD_FAB2_LIB.BASEBOARD_FAB2(SCH_1):TP_CLK_100M_NSSCC0_DN    I40 @BASEBOARD_FAB2_LIB.BASEBOARD_FAB2(SCH_1):PAGE114
   C32 TP_CLK_100M_NSSCC0_DP @BASEBOARD_FAB2_LIB.BASEBOARD_FAB2(SCH_1):TP_CLK_100M_NSSCC0_DP    I40 @BASEBOARD_FAB2_LIB.BASEBOARD_FAB2(SCH_1):PAGE114
   B38 TP_CLK_100M_NSSCC1_DN @BASEBOARD_FAB2_LIB.BASEBOARD_FAB2(SCH_1):TP_CLK_100M_NSSCC1_DN    I40 @BASEBOARD_FAB2_LIB.BASEBOARD_FAB2(SCH_1):PAGE114
   D38 TP_CLK_100M_NSSCC1_DP @BASEBOARD_FAB2_LIB.BASEBOARD_FAB2(SCH_1):TP_CLK_100M_NSSCC1_DP    I40 @BASEBOARD_FAB2_LIB.BASEBOARD_FAB2(SCH_1):PAGE114
   B29 CLK_100M_BMC_PE_DN @BASEBOARD_FAB2_LIB.BASEBOARD_FAB2(SCH_1):CLK_100M_BMC_PE_DN    I40 @BASEBOARD_FAB2_LIB.BASEBOARD_FAB2(SCH_1):PAGE114
   D29 CLK_100M_BMC_PE_DP @BASEBOARD_FAB2_LIB.BASEBOARD_FAB2(SCH_1):CLK_100M_BMC_PE_DP    I40 @BASEBOARD_FAB2_LIB.BASEBOARD_FAB2(SCH_1):PAGE114
   B40 TP_CLK_100M_PLAT1_DN @BASEBOARD_FAB2_LIB.BASEBOARD_FAB2(SCH_1):TP_CLK_100M_PLAT1_DN    I40 @BASEBOARD_FAB2_LIB.BASEBOARD_FAB2(SCH_1):PAGE114
   D40 TP_CLK_100M_PLAT1_DP @BASEBOARD_FAB2_LIB.BASEBOARD_FAB2(SCH_1):TP_CLK_100M_PLAT1_DP    I40 @BASEBOARD_FAB2_LIB.BASEBOARD_FAB2(SCH_1):PAGE114
   K27 CLK_100M_M2_DN @BASEBOARD_FAB2_LIB.BASEBOARD_FAB2(SCH_1):CLK_100M_M2_DN    I40 @BASEBOARD_FAB2_LIB.BASEBOARD_FAB2(SCH_1):PAGE114
   C20 CLK_100M_SPRV_DN @BASEBOARD_FAB2_LIB.BASEBOARD_FAB2(SCH_1):CLK_100M_SPRV_DN    I40 @BASEBOARD_FAB2_LIB.BASEBOARD_FAB2(SCH_1):PAGE114
   C24 CLK_100M_SRC13_DN @BASEBOARD_FAB2_LIB.BASEBOARD_FAB2(SCH_1):CLK_100M_SRC13_DN    I40 @BASEBOARD_FAB2_LIB.BASEBOARD_FAB2(SCH_1):PAGE114
   K24 CLK_100M_SRC12_DN @BASEBOARD_FAB2_LIB.BASEBOARD_FAB2(SCH_1):CLK_100M_SRC12_DN    I40 @BASEBOARD_FAB2_LIB.BASEBOARD_FAB2(SCH_1):PAGE114
   B21 CLK_100M_MEZZ4_DN @BASEBOARD_FAB2_LIB.BASEBOARD_FAB2(SCH_1):CLK_100M_MEZZ4_DN    I40 @BASEBOARD_FAB2_LIB.BASEBOARD_FAB2(SCH_1):PAGE114
   B23 CLK_100M_MEZZ3_DN @BASEBOARD_FAB2_LIB.BASEBOARD_FAB2(SCH_1):CLK_100M_MEZZ3_DN    I40 @BASEBOARD_FAB2_LIB.BASEBOARD_FAB2(SCH_1):PAGE114
   J26 CLK_100M_MEZZ2_DN @BASEBOARD_FAB2_LIB.BASEBOARD_FAB2(SCH_1):CLK_100M_MEZZ2_DN    I40 @BASEBOARD_FAB2_LIB.BASEBOARD_FAB2(SCH_1):PAGE114
   D31 CLK_100M_MEZZ1_DN @BASEBOARD_FAB2_LIB.BASEBOARD_FAB2(SCH_1):CLK_100M_MEZZ1_DN    I40 @BASEBOARD_FAB2_LIB.BASEBOARD_FAB2(SCH_1):PAGE114
   H31 CLK_100M_PCH_SLOTX24_S5_DN @BASEBOARD_FAB2_LIB.BASEBOARD_FAB2(SCH_1):CLK_100M_PCH_SLOTX24_S5_DN    I40 @BASEBOARD_FAB2_LIB.BASEBOARD_FAB2(SCH_1):PAGE114
   D33 CLK_100M_PCH_SLOTX24_S4_DN @BASEBOARD_FAB2_LIB.BASEBOARD_FAB2(SCH_1):CLK_100M_PCH_SLOTX24_S4_DN    I40 @BASEBOARD_FAB2_LIB.BASEBOARD_FAB2(SCH_1):PAGE114
   J40 CLK_100M_PCH_SLOTX24_S3_DN @BASEBOARD_FAB2_LIB.BASEBOARD_FAB2(SCH_1):CLK_100M_PCH_SLOTX24_S3_DN    I40 @BASEBOARD_FAB2_LIB.BASEBOARD_FAB2(SCH_1):PAGE114
   A28 CLK_100M_PCH_SLOTX24_S2_DN @BASEBOARD_FAB2_LIB.BASEBOARD_FAB2(SCH_1):CLK_100M_PCH_SLOTX24_S2_DN    I40 @BASEBOARD_FAB2_LIB.BASEBOARD_FAB2(SCH_1):PAGE114
   K42 CLK_100M_PCH_SLOTX24_S1_DN @BASEBOARD_FAB2_LIB.BASEBOARD_FAB2(SCH_1):CLK_100M_PCH_SLOTX24_S1_DN    I40 @BASEBOARD_FAB2_LIB.BASEBOARD_FAB2(SCH_1):PAGE114
   J33 CLK_100M_PCH_SLOTX24_S0_DN @BASEBOARD_FAB2_LIB.BASEBOARD_FAB2(SCH_1):CLK_100M_PCH_SLOTX24_S0_DN    I40 @BASEBOARD_FAB2_LIB.BASEBOARD_FAB2(SCH_1):PAGE114
   K35 CLK_100M_DB1200_DN @BASEBOARD_FAB2_LIB.BASEBOARD_FAB2(SCH_1):CLK_100M_DB1200_DN    I40 @BASEBOARD_FAB2_LIB.BASEBOARD_FAB2(SCH_1):PAGE114
   K38 CLK_100M_AIRMAX8_PE1_DN @BASEBOARD_FAB2_LIB.BASEBOARD_FAB2(SCH_1):CLK_100M_AIRMAX8_PE1_DN    I40 @BASEBOARD_FAB2_LIB.BASEBOARD_FAB2(SCH_1):PAGE114
   H27 CLK_100M_M2_DP @BASEBOARD_FAB2_LIB.BASEBOARD_FAB2(SCH_1):CLK_100M_M2_DP    I40 @BASEBOARD_FAB2_LIB.BASEBOARD_FAB2(SCH_1):PAGE114
   A20 CLK_100M_SPRV_DP @BASEBOARD_FAB2_LIB.BASEBOARD_FAB2(SCH_1):CLK_100M_SPRV_DP    I40 @BASEBOARD_FAB2_LIB.BASEBOARD_FAB2(SCH_1):PAGE114
   A24 CLK_100M_SRC13_DP @BASEBOARD_FAB2_LIB.BASEBOARD_FAB2(SCH_1):CLK_100M_SRC13_DP    I40 @BASEBOARD_FAB2_LIB.BASEBOARD_FAB2(SCH_1):PAGE114
   H24 CLK_100M_SRC12_DP @BASEBOARD_FAB2_LIB.BASEBOARD_FAB2(SCH_1):CLK_100M_SRC12_DP    I40 @BASEBOARD_FAB2_LIB.BASEBOARD_FAB2(SCH_1):PAGE114
   D21 CLK_100M_MEZZ4_DP @BASEBOARD_FAB2_LIB.BASEBOARD_FAB2(SCH_1):CLK_100M_MEZZ4_DP    I40 @BASEBOARD_FAB2_LIB.BASEBOARD_FAB2(SCH_1):PAGE114
   D23 CLK_100M_MEZZ3_DP @BASEBOARD_FAB2_LIB.BASEBOARD_FAB2(SCH_1):CLK_100M_MEZZ3_DP    I40 @BASEBOARD_FAB2_LIB.BASEBOARD_FAB2(SCH_1):PAGE114
   G26 CLK_100M_MEZZ2_DP @BASEBOARD_FAB2_LIB.BASEBOARD_FAB2(SCH_1):CLK_100M_MEZZ2_DP    I40 @BASEBOARD_FAB2_LIB.BASEBOARD_FAB2(SCH_1):PAGE114
   B31 CLK_100M_MEZZ1_DP @BASEBOARD_FAB2_LIB.BASEBOARD_FAB2(SCH_1):CLK_100M_MEZZ1_DP    I40 @BASEBOARD_FAB2_LIB.BASEBOARD_FAB2(SCH_1):PAGE114
   K31 CLK_100M_PCH_SLOTX24_S5_DP @BASEBOARD_FAB2_LIB.BASEBOARD_FAB2(SCH_1):CLK_100M_PCH_SLOTX24_S5_DP    I40 @BASEBOARD_FAB2_LIB.BASEBOARD_FAB2(SCH_1):PAGE114
   B33 CLK_100M_PCH_SLOTX24_S4_DP @BASEBOARD_FAB2_LIB.BASEBOARD_FAB2(SCH_1):CLK_100M_PCH_SLOTX24_S4_DP    I40 @BASEBOARD_FAB2_LIB.BASEBOARD_FAB2(SCH_1):PAGE114
   G40 CLK_100M_PCH_SLOTX24_S3_DP @BASEBOARD_FAB2_LIB.BASEBOARD_FAB2(SCH_1):CLK_100M_PCH_SLOTX24_S3_DP    I40 @BASEBOARD_FAB2_LIB.BASEBOARD_FAB2(SCH_1):PAGE114
   C28 CLK_100M_PCH_SLOTX24_S2_DP @BASEBOARD_FAB2_LIB.BASEBOARD_FAB2(SCH_1):CLK_100M_PCH_SLOTX24_S2_DP    I40 @BASEBOARD_FAB2_LIB.BASEBOARD_FAB2(SCH_1):PAGE114
   H42 CLK_100M_PCH_SLOTX24_S1_DP @BASEBOARD_FAB2_LIB.BASEBOARD_FAB2(SCH_1):CLK_100M_PCH_SLOTX24_S1_DP    I40 @BASEBOARD_FAB2_LIB.BASEBOARD_FAB2(SCH_1):PAGE114
   G33 CLK_100M_PCH_SLOTX24_S0_DP @BASEBOARD_FAB2_LIB.BASEBOARD_FAB2(SCH_1):CLK_100M_PCH_SLOTX24_S0_DP    I40 @BASEBOARD_FAB2_LIB.BASEBOARD_FAB2(SCH_1):PAGE114
   H35 CLK_100M_DB1200_DP @BASEBOARD_FAB2_LIB.BASEBOARD_FAB2(SCH_1):CLK_100M_DB1200_DP    I40 @BASEBOARD_FAB2_LIB.BASEBOARD_FAB2(SCH_1):PAGE114
   H38 CLK_100M_AIRMAX8_PE1_DP @BASEBOARD_FAB2_LIB.BASEBOARD_FAB2(SCH_1):CLK_100M_AIRMAX8_PE1_DP    I40 @BASEBOARD_FAB2_LIB.BASEBOARD_FAB2(SCH_1):PAGE114
  BW50 CLK_48M_USB_BMC @BASEBOARD_FAB2_LIB.BASEBOARD_FAB2(SCH_1):CLK_48M_USB_BMC    I40 @BASEBOARD_FAB2_LIB.BASEBOARD_FAB2(SCH_1):PAGE114
  BY51 H_PMSYNC_CLK_24M_R @BASEBOARD_FAB2_LIB.BASEBOARD_FAB2(SCH_1):H_PMSYNC_CLK_24M_R    I40 @BASEBOARD_FAB2_LIB.BASEBOARD_FAB2(SCH_1):PAGE114
  BV51 TP_CLK_24M_PMSYNC2 @BASEBOARD_FAB2_LIB.BASEBOARD_FAB2(SCH_1):TP_CLK_24M_PMSYNC2    I40 @BASEBOARD_FAB2_LIB.BASEBOARD_FAB2(SCH_1):PAGE114
   A26 TP_PCH_RSVD65 @BASEBOARD_FAB2_LIB.BASEBOARD_FAB2(SCH_1):TP_PCH_RSVD65    I40 @BASEBOARD_FAB2_LIB.BASEBOARD_FAB2(SCH_1):PAGE114
   C26 TP_PCH_RSVD64 @BASEBOARD_FAB2_LIB.BASEBOARD_FAB2(SCH_1):TP_PCH_RSVD64    I40 @BASEBOARD_FAB2_LIB.BASEBOARD_FAB2(SCH_1):PAGE114
   K17 XTAL_33K_RTC1 @BASEBOARD_FAB2_LIB.BASEBOARD_FAB2(SCH_1):XTAL_33K_RTC1    I40 @BASEBOARD_FAB2_LIB.BASEBOARD_FAB2(SCH_1):PAGE114
   H17 XTAL_33K_RTC2 @BASEBOARD_FAB2_LIB.BASEBOARD_FAB2(SCH_1):XTAL_33K_RTC2    I40 @BASEBOARD_FAB2_LIB.BASEBOARD_FAB2(SCH_1):PAGE114
   G44 A_PCH_XCLK_BIASREF @BASEBOARD_FAB2_LIB.BASEBOARD_FAB2(SCH_1):A_PCH_XCLK_BIASREF    I40 @BASEBOARD_FAB2_LIB.BASEBOARD_FAB2(SCH_1):PAGE114
   B35 XTAL_PCH_48M_IN @BASEBOARD_FAB2_LIB.BASEBOARD_FAB2(SCH_1):XTAL_PCH_48M_IN    I40 @BASEBOARD_FAB2_LIB.BASEBOARD_FAB2(SCH_1):PAGE114
   D35 XTAL_PCH_48M_OUT @BASEBOARD_FAB2_LIB.BASEBOARD_FAB2(SCH_1):XTAL_PCH_48M_OUT    I40 @BASEBOARD_FAB2_LIB.BASEBOARD_FAB2(SCH_1):PAGE114
  BN68 TP_PCH_RSVD55 @BASEBOARD_FAB2_LIB.BASEBOARD_FAB2(SCH_1):TP_PCH_RSVD55    I74 @BASEBOARD_FAB2_LIB.BASEBOARD_FAB2(SCH_1):PAGE115
  BY60 USB2_P01_DN @BASEBOARD_FAB2_LIB.BASEBOARD_FAB2(SCH_1):USB2_P01_DN    I74 @BASEBOARD_FAB2_LIB.BASEBOARD_FAB2(SCH_1):PAGE115
  BW65 TP_USB2_P10_DN @BASEBOARD_FAB2_LIB.BASEBOARD_FAB2(SCH_1):TP_USB2_P10_DN    I74 @BASEBOARD_FAB2_LIB.BASEBOARD_FAB2(SCH_1):PAGE115
  CA54 TP_USB2_P11_DN @BASEBOARD_FAB2_LIB.BASEBOARD_FAB2(SCH_1):TP_USB2_P11_DN    I74 @BASEBOARD_FAB2_LIB.BASEBOARD_FAB2(SCH_1):PAGE115
  BW67 TP_USB2_P12_DN @BASEBOARD_FAB2_LIB.BASEBOARD_FAB2(SCH_1):TP_USB2_P12_DN    I74 @BASEBOARD_FAB2_LIB.BASEBOARD_FAB2(SCH_1):PAGE115
  BY53 TP_USB2_P13_DN @BASEBOARD_FAB2_LIB.BASEBOARD_FAB2(SCH_1):TP_USB2_P13_DN    I74 @BASEBOARD_FAB2_LIB.BASEBOARD_FAB2(SCH_1):PAGE115
  BW68 TP_USB2_P14_DN @BASEBOARD_FAB2_LIB.BASEBOARD_FAB2(SCH_1):TP_USB2_P14_DN    I74 @BASEBOARD_FAB2_LIB.BASEBOARD_FAB2(SCH_1):PAGE115
  CA61 USB2_P02_DN @BASEBOARD_FAB2_LIB.BASEBOARD_FAB2(SCH_1):USB2_P02_DN    I74 @BASEBOARD_FAB2_LIB.BASEBOARD_FAB2(SCH_1):PAGE115
  CA59 TP_USB2_P03_DN @BASEBOARD_FAB2_LIB.BASEBOARD_FAB2(SCH_1):TP_USB2_P03_DN    I74 @BASEBOARD_FAB2_LIB.BASEBOARD_FAB2(SCH_1):PAGE115
  BY62 USB_PCH_BMC_P4_DN @BASEBOARD_FAB2_LIB.BASEBOARD_FAB2(SCH_1):USB_PCH_BMC_P4_DN    I74 @BASEBOARD_FAB2_LIB.BASEBOARD_FAB2(SCH_1):PAGE115
  BY58 USB2_PCH_BMC_P5_DN @BASEBOARD_FAB2_LIB.BASEBOARD_FAB2(SCH_1):USB2_PCH_BMC_P5_DN    I74 @BASEBOARD_FAB2_LIB.BASEBOARD_FAB2(SCH_1):PAGE115
  CA63 TP_USB2_P06_DN @BASEBOARD_FAB2_LIB.BASEBOARD_FAB2(SCH_1):TP_USB2_P06_DN    I74 @BASEBOARD_FAB2_LIB.BASEBOARD_FAB2(SCH_1):PAGE115
  CA57 TP_USB2_P07_DN @BASEBOARD_FAB2_LIB.BASEBOARD_FAB2(SCH_1):TP_USB2_P07_DN    I74 @BASEBOARD_FAB2_LIB.BASEBOARD_FAB2(SCH_1):PAGE115
  BY64 TP_USB2_P8_DN @BASEBOARD_FAB2_LIB.BASEBOARD_FAB2(SCH_1):TP_USB2_P8_DN    I74 @BASEBOARD_FAB2_LIB.BASEBOARD_FAB2(SCH_1):PAGE115
  BY55 TP_USB2_P9_DN @BASEBOARD_FAB2_LIB.BASEBOARD_FAB2(SCH_1):TP_USB2_P9_DN    I74 @BASEBOARD_FAB2_LIB.BASEBOARD_FAB2(SCH_1):PAGE115
  BV60 USB2_P01_DP @BASEBOARD_FAB2_LIB.BASEBOARD_FAB2(SCH_1):USB2_P01_DP    I74 @BASEBOARD_FAB2_LIB.BASEBOARD_FAB2(SCH_1):PAGE115
  BU65 TP_USB2_P10_DP @BASEBOARD_FAB2_LIB.BASEBOARD_FAB2(SCH_1):TP_USB2_P10_DP    I74 @BASEBOARD_FAB2_LIB.BASEBOARD_FAB2(SCH_1):PAGE115
  BW54 TP_USB2_P11_DP @BASEBOARD_FAB2_LIB.BASEBOARD_FAB2(SCH_1):TP_USB2_P11_DP    I74 @BASEBOARD_FAB2_LIB.BASEBOARD_FAB2(SCH_1):PAGE115
  BV66 TP_USB2_P12_DP @BASEBOARD_FAB2_LIB.BASEBOARD_FAB2(SCH_1):TP_USB2_P12_DP    I74 @BASEBOARD_FAB2_LIB.BASEBOARD_FAB2(SCH_1):PAGE115
  BV53 TP_USB2_P13_DP @BASEBOARD_FAB2_LIB.BASEBOARD_FAB2(SCH_1):TP_USB2_P13_DP    I74 @BASEBOARD_FAB2_LIB.BASEBOARD_FAB2(SCH_1):PAGE115
  BU67 TP_USB2_P14_DP @BASEBOARD_FAB2_LIB.BASEBOARD_FAB2(SCH_1):TP_USB2_P14_DP    I74 @BASEBOARD_FAB2_LIB.BASEBOARD_FAB2(SCH_1):PAGE115
  BW61 USB2_P02_DP @BASEBOARD_FAB2_LIB.BASEBOARD_FAB2(SCH_1):USB2_P02_DP    I74 @BASEBOARD_FAB2_LIB.BASEBOARD_FAB2(SCH_1):PAGE115
  BW59 TP_USB2_P03_DP @BASEBOARD_FAB2_LIB.BASEBOARD_FAB2(SCH_1):TP_USB2_P03_DP    I74 @BASEBOARD_FAB2_LIB.BASEBOARD_FAB2(SCH_1):PAGE115
  BV62 USB_PCH_BMC_P4_DP @BASEBOARD_FAB2_LIB.BASEBOARD_FAB2(SCH_1):USB_PCH_BMC_P4_DP    I74 @BASEBOARD_FAB2_LIB.BASEBOARD_FAB2(SCH_1):PAGE115
  BV58 USB2_PCH_BMC_P5_DP @BASEBOARD_FAB2_LIB.BASEBOARD_FAB2(SCH_1):USB2_PCH_BMC_P5_DP    I74 @BASEBOARD_FAB2_LIB.BASEBOARD_FAB2(SCH_1):PAGE115
  BW63 TP_USB2_P06_DP @BASEBOARD_FAB2_LIB.BASEBOARD_FAB2(SCH_1):TP_USB2_P06_DP    I74 @BASEBOARD_FAB2_LIB.BASEBOARD_FAB2(SCH_1):PAGE115
  BW57 TP_USB2_P07_DP @BASEBOARD_FAB2_LIB.BASEBOARD_FAB2(SCH_1):TP_USB2_P07_DP    I74 @BASEBOARD_FAB2_LIB.BASEBOARD_FAB2(SCH_1):PAGE115
  BV64 TP_USB2_P8_DP @BASEBOARD_FAB2_LIB.BASEBOARD_FAB2(SCH_1):TP_USB2_P8_DP    I74 @BASEBOARD_FAB2_LIB.BASEBOARD_FAB2(SCH_1):PAGE115
  BV55 TP_USB2_P9_DP @BASEBOARD_FAB2_LIB.BASEBOARD_FAB2(SCH_1):TP_USB2_P9_DP    I74 @BASEBOARD_FAB2_LIB.BASEBOARD_FAB2(SCH_1):PAGE115
  BN70 A_USB2_COMP @BASEBOARD_FAB2_LIB.BASEBOARD_FAB2(SCH_1):A_USB2_COMP    I74 @BASEBOARD_FAB2_LIB.BASEBOARD_FAB2(SCH_1):PAGE115
  BR67 A_USB2_VBUS @BASEBOARD_FAB2_LIB.BASEBOARD_FAB2(SCH_1):A_USB2_VBUS    I74 @BASEBOARD_FAB2_LIB.BASEBOARD_FAB2(SCH_1):PAGE115
  BK71 USB3_P01_RXN @BASEBOARD_FAB2_LIB.BASEBOARD_FAB2(SCH_1):USB3_P01_RXN    I74 @BASEBOARD_FAB2_LIB.BASEBOARD_FAB2(SCH_1):PAGE115
  BK69 USB3_P01_RXP @BASEBOARD_FAB2_LIB.BASEBOARD_FAB2(SCH_1):USB3_P01_RXP    I74 @BASEBOARD_FAB2_LIB.BASEBOARD_FAB2(SCH_1):PAGE115
  BL52 USB3_P01_TXN @BASEBOARD_FAB2_LIB.BASEBOARD_FAB2(SCH_1):USB3_P01_TXN    I74 @BASEBOARD_FAB2_LIB.BASEBOARD_FAB2(SCH_1):PAGE115
  BK54 USB3_P01_TXP @BASEBOARD_FAB2_LIB.BASEBOARD_FAB2(SCH_1):USB3_P01_TXP    I74 @BASEBOARD_FAB2_LIB.BASEBOARD_FAB2(SCH_1):PAGE115
  BJ72 TP_USB3_P02_RXN @BASEBOARD_FAB2_LIB.BASEBOARD_FAB2(SCH_1):TP_USB3_P02_RXN    I74 @BASEBOARD_FAB2_LIB.BASEBOARD_FAB2(SCH_1):PAGE115
  BJ70 TP_USB3_P02_RXP @BASEBOARD_FAB2_LIB.BASEBOARD_FAB2(SCH_1):TP_USB3_P02_RXP    I74 @BASEBOARD_FAB2_LIB.BASEBOARD_FAB2(SCH_1):PAGE115
  BL56 TP_USB3_P02_TXN @BASEBOARD_FAB2_LIB.BASEBOARD_FAB2(SCH_1):TP_USB3_P02_TXN    I74 @BASEBOARD_FAB2_LIB.BASEBOARD_FAB2(SCH_1):PAGE115
  BJ56 TP_USB3_P02_TXP @BASEBOARD_FAB2_LIB.BASEBOARD_FAB2(SCH_1):TP_USB3_P02_TXP    I74 @BASEBOARD_FAB2_LIB.BASEBOARD_FAB2(SCH_1):PAGE115
  BH71 TP_USB3_P03_RXN @BASEBOARD_FAB2_LIB.BASEBOARD_FAB2(SCH_1):TP_USB3_P03_RXN    I74 @BASEBOARD_FAB2_LIB.BASEBOARD_FAB2(SCH_1):PAGE115
  BH69 TP_USB3_P03_RXP @BASEBOARD_FAB2_LIB.BASEBOARD_FAB2(SCH_1):TP_USB3_P03_RXP    I74 @BASEBOARD_FAB2_LIB.BASEBOARD_FAB2(SCH_1):PAGE115
  BM54 TP_USB3_P03_TXN @BASEBOARD_FAB2_LIB.BASEBOARD_FAB2(SCH_1):TP_USB3_P03_TXN    I74 @BASEBOARD_FAB2_LIB.BASEBOARD_FAB2(SCH_1):PAGE115
  BN56 TP_USB3_P03_TXP @BASEBOARD_FAB2_LIB.BASEBOARD_FAB2(SCH_1):TP_USB3_P03_TXP    I74 @BASEBOARD_FAB2_LIB.BASEBOARD_FAB2(SCH_1):PAGE115
  BF72 TP_USB3_P04_RXN @BASEBOARD_FAB2_LIB.BASEBOARD_FAB2(SCH_1):TP_USB3_P04_RXN    I74 @BASEBOARD_FAB2_LIB.BASEBOARD_FAB2(SCH_1):PAGE115
  BF70 TP_USB3_P04_RXP @BASEBOARD_FAB2_LIB.BASEBOARD_FAB2(SCH_1):TP_USB3_P04_RXP    I74 @BASEBOARD_FAB2_LIB.BASEBOARD_FAB2(SCH_1):PAGE115
  BH58 TP_USB3_P04_TXN @BASEBOARD_FAB2_LIB.BASEBOARD_FAB2(SCH_1):TP_USB3_P04_TXN    I74 @BASEBOARD_FAB2_LIB.BASEBOARD_FAB2(SCH_1):PAGE115
  BG56 TP_USB3_P04_TXP @BASEBOARD_FAB2_LIB.BASEBOARD_FAB2(SCH_1):TP_USB3_P04_TXP    I74 @BASEBOARD_FAB2_LIB.BASEBOARD_FAB2(SCH_1):PAGE115
  BE71 TP_USB3_P05_RXN @BASEBOARD_FAB2_LIB.BASEBOARD_FAB2(SCH_1):TP_USB3_P05_RXN    I74 @BASEBOARD_FAB2_LIB.BASEBOARD_FAB2(SCH_1):PAGE115
  BE69 TP_USB3_P05_RXP @BASEBOARD_FAB2_LIB.BASEBOARD_FAB2(SCH_1):TP_USB3_P05_RXP    I74 @BASEBOARD_FAB2_LIB.BASEBOARD_FAB2(SCH_1):PAGE115
  BK58 TP_USB3_P05_TXN @BASEBOARD_FAB2_LIB.BASEBOARD_FAB2(SCH_1):TP_USB3_P05_TXN    I74 @BASEBOARD_FAB2_LIB.BASEBOARD_FAB2(SCH_1):PAGE115
  BJ59 TP_USB3_P05_TXP @BASEBOARD_FAB2_LIB.BASEBOARD_FAB2(SCH_1):TP_USB3_P05_TXP    I74 @BASEBOARD_FAB2_LIB.BASEBOARD_FAB2(SCH_1):PAGE115
  BD72 TP_USB3_P06_RXN @BASEBOARD_FAB2_LIB.BASEBOARD_FAB2(SCH_1):TP_USB3_P06_RXN    I74 @BASEBOARD_FAB2_LIB.BASEBOARD_FAB2(SCH_1):PAGE115
  BD70 TP_USB3_P06_RXP @BASEBOARD_FAB2_LIB.BASEBOARD_FAB2(SCH_1):TP_USB3_P06_RXP    I74 @BASEBOARD_FAB2_LIB.BASEBOARD_FAB2(SCH_1):PAGE115
  BL59 TP_USB3_P06_TXN @BASEBOARD_FAB2_LIB.BASEBOARD_FAB2(SCH_1):TP_USB3_P06_TXN    I74 @BASEBOARD_FAB2_LIB.BASEBOARD_FAB2(SCH_1):PAGE115
  BM61 TP_USB3_P06_TXP @BASEBOARD_FAB2_LIB.BASEBOARD_FAB2(SCH_1):TP_USB3_P06_TXP    I74 @BASEBOARD_FAB2_LIB.BASEBOARD_FAB2(SCH_1):PAGE115
   D66 A_EXTCLKN @BASEBOARD_FAB2_LIB.BASEBOARD_FAB2(SCH_1):A_EXTCLKN   I220 @BASEBOARD_FAB2_LIB.BASEBOARD_FAB2(SCH_1):PAGE116
   E67 A_EXTCLKP @BASEBOARD_FAB2_LIB.BASEBOARD_FAB2(SCH_1):A_EXTCLKP   I220 @BASEBOARD_FAB2_LIB.BASEBOARD_FAB2(SCH_1):PAGE116
  AV63 SATA6G_RX_DN<2> @BASEBOARD_FAB2_LIB.BASEBOARD_FAB2(SCH_1):SATA6G_RX_DN(2)   I220 @BASEBOARD_FAB2_LIB.BASEBOARD_FAB2(SCH_1):PAGE116
  AU65 SATA6G_RX_DP<2> @BASEBOARD_FAB2_LIB.BASEBOARD_FAB2(SCH_1):SATA6G_RX_DP(2)   I220 @BASEBOARD_FAB2_LIB.BASEBOARD_FAB2(SCH_1):PAGE116
  AD70 SATA6G_TX_DN<2> @BASEBOARD_FAB2_LIB.BASEBOARD_FAB2(SCH_1):SATA6G_TX_DN(2)   I220 @BASEBOARD_FAB2_LIB.BASEBOARD_FAB2(SCH_1):PAGE116
  AD72 SATA6G_TX_DP<2> @BASEBOARD_FAB2_LIB.BASEBOARD_FAB2(SCH_1):SATA6G_TX_DP(2)   I220 @BASEBOARD_FAB2_LIB.BASEBOARD_FAB2(SCH_1):PAGE116
  AT66 SATA6G_RX_DN<3> @BASEBOARD_FAB2_LIB.BASEBOARD_FAB2(SCH_1):SATA6G_RX_DN(3)   I220 @BASEBOARD_FAB2_LIB.BASEBOARD_FAB2(SCH_1):PAGE116
  AV66 SATA6G_RX_DP<3> @BASEBOARD_FAB2_LIB.BASEBOARD_FAB2(SCH_1):SATA6G_RX_DP(3)   I220 @BASEBOARD_FAB2_LIB.BASEBOARD_FAB2(SCH_1):PAGE116
  AC69 SATA6G_TX_DN<3> @BASEBOARD_FAB2_LIB.BASEBOARD_FAB2(SCH_1):SATA6G_TX_DN(3)   I220 @BASEBOARD_FAB2_LIB.BASEBOARD_FAB2(SCH_1):PAGE116
  AC71 SATA6G_TX_DP<3> @BASEBOARD_FAB2_LIB.BASEBOARD_FAB2(SCH_1):SATA6G_TX_DP(3)   I220 @BASEBOARD_FAB2_LIB.BASEBOARD_FAB2(SCH_1):PAGE116
  AR61 SATA6G_PCH_PCIE_UP_SATA_RXN<0> @BASEBOARD_FAB2_LIB.BASEBOARD_FAB2(SCH_1):SATA6G_PCH_PCIE_UP_SATA_RXN(0)   I220 @BASEBOARD_FAB2_LIB.BASEBOARD_FAB2(SCH_1):PAGE116
  AT63 SATA6G_PCH_PCIE_UP_SATA_RXP<0> @BASEBOARD_FAB2_LIB.BASEBOARD_FAB2(SCH_1):SATA6G_PCH_PCIE_UP_SATA_RXP(0)   I220 @BASEBOARD_FAB2_LIB.BASEBOARD_FAB2(SCH_1):PAGE116
   W69 SATA6G_PCH_PCIE_UP_SATA_TXN<0> @BASEBOARD_FAB2_LIB.BASEBOARD_FAB2(SCH_1):SATA6G_PCH_PCIE_UP_SATA_TXN(0)   I220 @BASEBOARD_FAB2_LIB.BASEBOARD_FAB2(SCH_1):PAGE116
   W71 SATA6G_PCH_PCIE_UP_SATA_TXP<0> @BASEBOARD_FAB2_LIB.BASEBOARD_FAB2(SCH_1):SATA6G_PCH_PCIE_UP_SATA_TXP(0)   I220 @BASEBOARD_FAB2_LIB.BASEBOARD_FAB2(SCH_1):PAGE116
  AL66 SATA6G_PCH_PCIE_UP_SATA_RXN<1> @BASEBOARD_FAB2_LIB.BASEBOARD_FAB2(SCH_1):SATA6G_PCH_PCIE_UP_SATA_RXN(1)   I220 @BASEBOARD_FAB2_LIB.BASEBOARD_FAB2(SCH_1):PAGE116
  AN65 SATA6G_PCH_PCIE_UP_SATA_RXP<1> @BASEBOARD_FAB2_LIB.BASEBOARD_FAB2(SCH_1):SATA6G_PCH_PCIE_UP_SATA_RXP(1)   I220 @BASEBOARD_FAB2_LIB.BASEBOARD_FAB2(SCH_1):PAGE116
   V70 SATA6G_PCH_PCIE_UP_SATA_TXN<1> @BASEBOARD_FAB2_LIB.BASEBOARD_FAB2(SCH_1):SATA6G_PCH_PCIE_UP_SATA_TXN(1)   I220 @BASEBOARD_FAB2_LIB.BASEBOARD_FAB2(SCH_1):PAGE116
   V72 SATA6G_PCH_PCIE_UP_SATA_TXP<1> @BASEBOARD_FAB2_LIB.BASEBOARD_FAB2(SCH_1):SATA6G_PCH_PCIE_UP_SATA_TXP(1)   I220 @BASEBOARD_FAB2_LIB.BASEBOARD_FAB2(SCH_1):PAGE116
  AK65 SATA6G_PCH_PCIE_UP_SATA_RXN<2> @BASEBOARD_FAB2_LIB.BASEBOARD_FAB2(SCH_1):SATA6G_PCH_PCIE_UP_SATA_RXN(2)   I220 @BASEBOARD_FAB2_LIB.BASEBOARD_FAB2(SCH_1):PAGE116
  AJ63 SATA6G_PCH_PCIE_UP_SATA_RXP<2> @BASEBOARD_FAB2_LIB.BASEBOARD_FAB2(SCH_1):SATA6G_PCH_PCIE_UP_SATA_RXP(2)   I220 @BASEBOARD_FAB2_LIB.BASEBOARD_FAB2(SCH_1):PAGE116
   T69 SATA6G_PCH_PCIE_UP_SATA_TXN<2> @BASEBOARD_FAB2_LIB.BASEBOARD_FAB2(SCH_1):SATA6G_PCH_PCIE_UP_SATA_TXN(2)   I220 @BASEBOARD_FAB2_LIB.BASEBOARD_FAB2(SCH_1):PAGE116
   T71 SATA6G_PCH_PCIE_UP_SATA_TXP<2> @BASEBOARD_FAB2_LIB.BASEBOARD_FAB2(SCH_1):SATA6G_PCH_PCIE_UP_SATA_TXP(2)   I220 @BASEBOARD_FAB2_LIB.BASEBOARD_FAB2(SCH_1):PAGE116
  AP63 SATA6G_PCH_PCIE_UP_SATA_RXN<3> @BASEBOARD_FAB2_LIB.BASEBOARD_FAB2(SCH_1):SATA6G_PCH_PCIE_UP_SATA_RXN(3)   I220 @BASEBOARD_FAB2_LIB.BASEBOARD_FAB2(SCH_1):PAGE116
  AL63 SATA6G_PCH_PCIE_UP_SATA_RXP<3> @BASEBOARD_FAB2_LIB.BASEBOARD_FAB2(SCH_1):SATA6G_PCH_PCIE_UP_SATA_RXP(3)   I220 @BASEBOARD_FAB2_LIB.BASEBOARD_FAB2(SCH_1):PAGE116
   R70 SATA6G_PCH_PCIE_UP_SATA_TXN<3> @BASEBOARD_FAB2_LIB.BASEBOARD_FAB2(SCH_1):SATA6G_PCH_PCIE_UP_SATA_TXN(3)   I220 @BASEBOARD_FAB2_LIB.BASEBOARD_FAB2(SCH_1):PAGE116
   R72 SATA6G_PCH_PCIE_UP_SATA_TXP<3> @BASEBOARD_FAB2_LIB.BASEBOARD_FAB2(SCH_1):SATA6G_PCH_PCIE_UP_SATA_TXP(3)   I220 @BASEBOARD_FAB2_LIB.BASEBOARD_FAB2(SCH_1):PAGE116
  AF65 SATA6G_PCH_PCIE_UP_SATA_RXN<4> @BASEBOARD_FAB2_LIB.BASEBOARD_FAB2(SCH_1):SATA6G_PCH_PCIE_UP_SATA_RXN(4)   I220 @BASEBOARD_FAB2_LIB.BASEBOARD_FAB2(SCH_1):PAGE116
  AH65 SATA6G_PCH_PCIE_UP_SATA_RXP<4> @BASEBOARD_FAB2_LIB.BASEBOARD_FAB2(SCH_1):SATA6G_PCH_PCIE_UP_SATA_RXP(4)   I220 @BASEBOARD_FAB2_LIB.BASEBOARD_FAB2(SCH_1):PAGE116
   P69 SATA6G_PCH_PCIE_UP_SATA_TXN<4> @BASEBOARD_FAB2_LIB.BASEBOARD_FAB2(SCH_1):SATA6G_PCH_PCIE_UP_SATA_TXN(4)   I220 @BASEBOARD_FAB2_LIB.BASEBOARD_FAB2(SCH_1):PAGE116
   P71 SATA6G_PCH_PCIE_UP_SATA_TXP<4> @BASEBOARD_FAB2_LIB.BASEBOARD_FAB2(SCH_1):SATA6G_PCH_PCIE_UP_SATA_TXP(4)   I220 @BASEBOARD_FAB2_LIB.BASEBOARD_FAB2(SCH_1):PAGE116
  AH61 SATA6G_PCH_PCIE_UP_SATA_RXN<5> @BASEBOARD_FAB2_LIB.BASEBOARD_FAB2(SCH_1):SATA6G_PCH_PCIE_UP_SATA_RXN(5)   I220 @BASEBOARD_FAB2_LIB.BASEBOARD_FAB2(SCH_1):PAGE116
  AG63 SATA6G_PCH_PCIE_UP_SATA_RXP<5> @BASEBOARD_FAB2_LIB.BASEBOARD_FAB2(SCH_1):SATA6G_PCH_PCIE_UP_SATA_RXP(5)   I220 @BASEBOARD_FAB2_LIB.BASEBOARD_FAB2(SCH_1):PAGE116
   N70 SATA6G_PCH_PCIE_UP_SATA_TXN<5> @BASEBOARD_FAB2_LIB.BASEBOARD_FAB2(SCH_1):SATA6G_PCH_PCIE_UP_SATA_TXN(5)   I220 @BASEBOARD_FAB2_LIB.BASEBOARD_FAB2(SCH_1):PAGE116
   N72 SATA6G_PCH_PCIE_UP_SATA_TXP<5> @BASEBOARD_FAB2_LIB.BASEBOARD_FAB2(SCH_1):SATA6G_PCH_PCIE_UP_SATA_TXP(5)   I220 @BASEBOARD_FAB2_LIB.BASEBOARD_FAB2(SCH_1):PAGE116
  AP59 SATA6G_PCH_PCIE_UP_SATA_RXN<6> @BASEBOARD_FAB2_LIB.BASEBOARD_FAB2(SCH_1):SATA6G_PCH_PCIE_UP_SATA_RXN(6)   I220 @BASEBOARD_FAB2_LIB.BASEBOARD_FAB2(SCH_1):PAGE116
  AN61 SATA6G_PCH_PCIE_UP_SATA_RXP<6> @BASEBOARD_FAB2_LIB.BASEBOARD_FAB2(SCH_1):SATA6G_PCH_PCIE_UP_SATA_RXP(6)   I220 @BASEBOARD_FAB2_LIB.BASEBOARD_FAB2(SCH_1):PAGE116
   M69 SATA6G_PCH_PCIE_UP_SATA_TXN<6> @BASEBOARD_FAB2_LIB.BASEBOARD_FAB2(SCH_1):SATA6G_PCH_PCIE_UP_SATA_TXN(6)   I220 @BASEBOARD_FAB2_LIB.BASEBOARD_FAB2(SCH_1):PAGE116
   M71 SATA6G_PCH_PCIE_UP_SATA_TXP<6> @BASEBOARD_FAB2_LIB.BASEBOARD_FAB2(SCH_1):SATA6G_PCH_PCIE_UP_SATA_TXP(6)   I220 @BASEBOARD_FAB2_LIB.BASEBOARD_FAB2(SCH_1):PAGE116
  AA61 SATA6G_PCH_PCIE_UP_SATA_RXN<7> @BASEBOARD_FAB2_LIB.BASEBOARD_FAB2(SCH_1):SATA6G_PCH_PCIE_UP_SATA_RXN(7)   I220 @BASEBOARD_FAB2_LIB.BASEBOARD_FAB2(SCH_1):PAGE116
  AD61 SATA6G_PCH_PCIE_UP_SATA_RXP<7> @BASEBOARD_FAB2_LIB.BASEBOARD_FAB2(SCH_1):SATA6G_PCH_PCIE_UP_SATA_RXP(7)   I220 @BASEBOARD_FAB2_LIB.BASEBOARD_FAB2(SCH_1):PAGE116
   L70 SATA6G_PCH_PCIE_UP_SATA_TXN<7> @BASEBOARD_FAB2_LIB.BASEBOARD_FAB2(SCH_1):SATA6G_PCH_PCIE_UP_SATA_TXN(7)   I220 @BASEBOARD_FAB2_LIB.BASEBOARD_FAB2(SCH_1):PAGE116
   L72 SATA6G_PCH_PCIE_UP_SATA_TXP<7> @BASEBOARD_FAB2_LIB.BASEBOARD_FAB2(SCH_1):SATA6G_PCH_PCIE_UP_SATA_TXP(7)   I220 @BASEBOARD_FAB2_LIB.BASEBOARD_FAB2(SCH_1):PAGE116
  AN70 P2E_SSB_BMC_RX_C_DN @BASEBOARD_FAB2_LIB.BASEBOARD_FAB2(SCH_1):P2E_SSB_BMC_RX_C_DN   I220 @BASEBOARD_FAB2_LIB.BASEBOARD_FAB2(SCH_1):PAGE116
  AN72 P2E_SSB_BMC_RX_C_DP @BASEBOARD_FAB2_LIB.BASEBOARD_FAB2(SCH_1):P2E_SSB_BMC_RX_C_DP   I220 @BASEBOARD_FAB2_LIB.BASEBOARD_FAB2(SCH_1):PAGE116
  BG66 P2E_SSB_BMC_TX_DN @BASEBOARD_FAB2_LIB.BASEBOARD_FAB2(SCH_1):P2E_SSB_BMC_TX_DN   I220 @BASEBOARD_FAB2_LIB.BASEBOARD_FAB2(SCH_1):PAGE116
  BJ66 P2E_SSB_BMC_TX_DP @BASEBOARD_FAB2_LIB.BASEBOARD_FAB2(SCH_1):P2E_SSB_BMC_TX_DP   I220 @BASEBOARD_FAB2_LIB.BASEBOARD_FAB2(SCH_1):PAGE116
  AM69 PE_PCH_SPRV_RX_C_DN @BASEBOARD_FAB2_LIB.BASEBOARD_FAB2(SCH_1):PE_PCH_SPRV_RX_C_DN   I220 @BASEBOARD_FAB2_LIB.BASEBOARD_FAB2(SCH_1):PAGE116
  AM71 PE_PCH_SPRV_RX_C_DP @BASEBOARD_FAB2_LIB.BASEBOARD_FAB2(SCH_1):PE_PCH_SPRV_RX_C_DP   I220 @BASEBOARD_FAB2_LIB.BASEBOARD_FAB2(SCH_1):PAGE116
  BH65 PE_PCH_SPRV_TX_DN @BASEBOARD_FAB2_LIB.BASEBOARD_FAB2(SCH_1):PE_PCH_SPRV_TX_DN   I220 @BASEBOARD_FAB2_LIB.BASEBOARD_FAB2(SCH_1):PAGE116
  BJ63 PE_PCH_SPRV_TX_DP @BASEBOARD_FAB2_LIB.BASEBOARD_FAB2(SCH_1):PE_PCH_SPRV_TX_DP   I220 @BASEBOARD_FAB2_LIB.BASEBOARD_FAB2(SCH_1):PAGE116
  BB63 SATA6G_S0_RX_DN @BASEBOARD_FAB2_LIB.BASEBOARD_FAB2(SCH_1):SATA6G_S0_RX_DN   I220 @BASEBOARD_FAB2_LIB.BASEBOARD_FAB2(SCH_1):PAGE116
  BD61 SATA6G_S0_RX_DP @BASEBOARD_FAB2_LIB.BASEBOARD_FAB2(SCH_1):SATA6G_S0_RX_DP   I220 @BASEBOARD_FAB2_LIB.BASEBOARD_FAB2(SCH_1):PAGE116
  AJ70 SATA6G_S0_TX_DN @BASEBOARD_FAB2_LIB.BASEBOARD_FAB2(SCH_1):SATA6G_S0_TX_DN   I220 @BASEBOARD_FAB2_LIB.BASEBOARD_FAB2(SCH_1):PAGE116
  AJ72 SATA6G_S0_TX_DP @BASEBOARD_FAB2_LIB.BASEBOARD_FAB2(SCH_1):SATA6G_S0_TX_DP   I220 @BASEBOARD_FAB2_LIB.BASEBOARD_FAB2(SCH_1):PAGE116
  AY59 SATA6G_S1_RX_DN @BASEBOARD_FAB2_LIB.BASEBOARD_FAB2(SCH_1):SATA6G_S1_RX_DN   I220 @BASEBOARD_FAB2_LIB.BASEBOARD_FAB2(SCH_1):PAGE116
  BA61 SATA6G_S1_RX_DP @BASEBOARD_FAB2_LIB.BASEBOARD_FAB2(SCH_1):SATA6G_S1_RX_DP   I220 @BASEBOARD_FAB2_LIB.BASEBOARD_FAB2(SCH_1):PAGE116
  AH69 SATA6G_S1_TX_DN @BASEBOARD_FAB2_LIB.BASEBOARD_FAB2(SCH_1):SATA6G_S1_TX_DN   I220 @BASEBOARD_FAB2_LIB.BASEBOARD_FAB2(SCH_1):PAGE116
  AH71 SATA6G_S1_TX_DP @BASEBOARD_FAB2_LIB.BASEBOARD_FAB2(SCH_1):SATA6G_S1_TX_DP   I220 @BASEBOARD_FAB2_LIB.BASEBOARD_FAB2(SCH_1):PAGE116
  BA65 SATA6G_RX_DN<0> @BASEBOARD_FAB2_LIB.BASEBOARD_FAB2(SCH_1):SATA6G_RX_DN(0)   I220 @BASEBOARD_FAB2_LIB.BASEBOARD_FAB2(SCH_1):PAGE116
  BD65 SATA6G_RX_DP<0> @BASEBOARD_FAB2_LIB.BASEBOARD_FAB2(SCH_1):SATA6G_RX_DP(0)   I220 @BASEBOARD_FAB2_LIB.BASEBOARD_FAB2(SCH_1):PAGE116
  AF70 SATA6G_TX_DN<0> @BASEBOARD_FAB2_LIB.BASEBOARD_FAB2(SCH_1):SATA6G_TX_DN(0)   I220 @BASEBOARD_FAB2_LIB.BASEBOARD_FAB2(SCH_1):PAGE116
  AF72 SATA6G_TX_DP<0> @BASEBOARD_FAB2_LIB.BASEBOARD_FAB2(SCH_1):SATA6G_TX_DP(0)   I220 @BASEBOARD_FAB2_LIB.BASEBOARD_FAB2(SCH_1):PAGE116
  AW65 SATA6G_RX_DN<1> @BASEBOARD_FAB2_LIB.BASEBOARD_FAB2(SCH_1):SATA6G_RX_DN(1)   I220 @BASEBOARD_FAB2_LIB.BASEBOARD_FAB2(SCH_1):PAGE116
  AY66 SATA6G_RX_DP<1> @BASEBOARD_FAB2_LIB.BASEBOARD_FAB2(SCH_1):SATA6G_RX_DP(1)   I220 @BASEBOARD_FAB2_LIB.BASEBOARD_FAB2(SCH_1):PAGE116
  AE69 SATA6G_TX_DN<1> @BASEBOARD_FAB2_LIB.BASEBOARD_FAB2(SCH_1):SATA6G_TX_DN(1)   I220 @BASEBOARD_FAB2_LIB.BASEBOARD_FAB2(SCH_1):PAGE116
  AE71 SATA6G_TX_DP<1> @BASEBOARD_FAB2_LIB.BASEBOARD_FAB2(SCH_1):SATA6G_TX_DP(1)   I220 @BASEBOARD_FAB2_LIB.BASEBOARD_FAB2(SCH_1):PAGE116
  AF58 A_PCIEUP_RCOMP_N @BASEBOARD_FAB2_LIB.BASEBOARD_FAB2(SCH_1):A_PCIEUP_RCOMP_N   I220 @BASEBOARD_FAB2_LIB.BASEBOARD_FAB2(SCH_1):PAGE116
  AH58 A_PCIEUP_RCOMP_P @BASEBOARD_FAB2_LIB.BASEBOARD_FAB2(SCH_1):A_PCIEUP_RCOMP_P   I220 @BASEBOARD_FAB2_LIB.BASEBOARD_FAB2(SCH_1):PAGE116
  BD58 A_PCIE_RCOMP_N @BASEBOARD_FAB2_LIB.BASEBOARD_FAB2(SCH_1):A_PCIE_RCOMP_N   I220 @BASEBOARD_FAB2_LIB.BASEBOARD_FAB2(SCH_1):PAGE116
  BB56 A_PCIE_RCOMP_P @BASEBOARD_FAB2_LIB.BASEBOARD_FAB2(SCH_1):A_PCIE_RCOMP_P   I220 @BASEBOARD_FAB2_LIB.BASEBOARD_FAB2(SCH_1):PAGE116
  AA71 TP_PCH_RSVD52 @BASEBOARD_FAB2_LIB.BASEBOARD_FAB2(SCH_1):TP_PCH_RSVD52   I220 @BASEBOARD_FAB2_LIB.BASEBOARD_FAB2(SCH_1):PAGE116
  AA69 TP_PCH_RSVD51 @BASEBOARD_FAB2_LIB.BASEBOARD_FAB2(SCH_1):TP_PCH_RSVD51   I220 @BASEBOARD_FAB2_LIB.BASEBOARD_FAB2(SCH_1):PAGE116
   H69 TP_PCH_RSVD50 @BASEBOARD_FAB2_LIB.BASEBOARD_FAB2(SCH_1):TP_PCH_RSVD50   I220 @BASEBOARD_FAB2_LIB.BASEBOARD_FAB2(SCH_1):PAGE116
   G67 TP_PCH_RSVD49 @BASEBOARD_FAB2_LIB.BASEBOARD_FAB2(SCH_1):TP_PCH_RSVD49   I220 @BASEBOARD_FAB2_LIB.BASEBOARD_FAB2(SCH_1):PAGE116
  AP71 TP_PCH_RSVD48 @BASEBOARD_FAB2_LIB.BASEBOARD_FAB2(SCH_1):TP_PCH_RSVD48   I220 @BASEBOARD_FAB2_LIB.BASEBOARD_FAB2(SCH_1):PAGE116
  AP69 TP_PCH_RSVD47 @BASEBOARD_FAB2_LIB.BASEBOARD_FAB2(SCH_1):TP_PCH_RSVD47   I220 @BASEBOARD_FAB2_LIB.BASEBOARD_FAB2(SCH_1):PAGE116
  AV72 P3E_PCH_M2_RX_DN<3> @BASEBOARD_FAB2_LIB.BASEBOARD_FAB2(SCH_1):P3E_PCH_M2_RX_DN(3)   I220 @BASEBOARD_FAB2_LIB.BASEBOARD_FAB2(SCH_1):PAGE116
  AV70 P3E_PCH_M2_RX_DP<3> @BASEBOARD_FAB2_LIB.BASEBOARD_FAB2(SCH_1):P3E_PCH_M2_RX_DP(3)   I220 @BASEBOARD_FAB2_LIB.BASEBOARD_FAB2(SCH_1):PAGE116
  BH61 P3E_PCH_M2_TX_DN<3> @BASEBOARD_FAB2_LIB.BASEBOARD_FAB2(SCH_1):P3E_PCH_M2_TX_DN(3)   I220 @BASEBOARD_FAB2_LIB.BASEBOARD_FAB2(SCH_1):PAGE116
  BK61 P3E_PCH_M2_TX_DP<3> @BASEBOARD_FAB2_LIB.BASEBOARD_FAB2(SCH_1):P3E_PCH_M2_TX_DP(3)   I220 @BASEBOARD_FAB2_LIB.BASEBOARD_FAB2(SCH_1):PAGE116
  BA71 P3E_PCH_RX_0_DN @BASEBOARD_FAB2_LIB.BASEBOARD_FAB2(SCH_1):P3E_PCH_RX_0_DN   I220 @BASEBOARD_FAB2_LIB.BASEBOARD_FAB2(SCH_1):PAGE116
  BA69 P3E_PCH_RX_0_DP @BASEBOARD_FAB2_LIB.BASEBOARD_FAB2(SCH_1):P3E_PCH_RX_0_DP   I220 @BASEBOARD_FAB2_LIB.BASEBOARD_FAB2(SCH_1):PAGE116
  BR61 P3E_PCH_TX_0_DN @BASEBOARD_FAB2_LIB.BASEBOARD_FAB2(SCH_1):P3E_PCH_TX_0_DN   I220 @BASEBOARD_FAB2_LIB.BASEBOARD_FAB2(SCH_1):PAGE116
  BN63 P3E_PCH_TX_0_DP @BASEBOARD_FAB2_LIB.BASEBOARD_FAB2(SCH_1):P3E_PCH_TX_0_DP   I220 @BASEBOARD_FAB2_LIB.BASEBOARD_FAB2(SCH_1):PAGE116
  AY72 P3E_PCH_M2_RX_DN<1> @BASEBOARD_FAB2_LIB.BASEBOARD_FAB2(SCH_1):P3E_PCH_M2_RX_DN(1)   I220 @BASEBOARD_FAB2_LIB.BASEBOARD_FAB2(SCH_1):PAGE116
  AY70 P3E_PCH_M2_RX_DP<1> @BASEBOARD_FAB2_LIB.BASEBOARD_FAB2(SCH_1):P3E_PCH_M2_RX_DP(1)   I220 @BASEBOARD_FAB2_LIB.BASEBOARD_FAB2(SCH_1):PAGE116
  BM65 P3E_PCH_M2_TX_DN<1> @BASEBOARD_FAB2_LIB.BASEBOARD_FAB2(SCH_1):P3E_PCH_M2_TX_DN(1)   I220 @BASEBOARD_FAB2_LIB.BASEBOARD_FAB2(SCH_1):PAGE116
  BR65 P3E_PCH_M2_TX_DP<1> @BASEBOARD_FAB2_LIB.BASEBOARD_FAB2(SCH_1):P3E_PCH_M2_TX_DP(1)   I220 @BASEBOARD_FAB2_LIB.BASEBOARD_FAB2(SCH_1):PAGE116
  AW71 P3E_PCH_M2_RX_DN<2> @BASEBOARD_FAB2_LIB.BASEBOARD_FAB2(SCH_1):P3E_PCH_M2_RX_DN(2)   I220 @BASEBOARD_FAB2_LIB.BASEBOARD_FAB2(SCH_1):PAGE116
  AW69 P3E_PCH_M2_RX_DP<2> @BASEBOARD_FAB2_LIB.BASEBOARD_FAB2(SCH_1):P3E_PCH_M2_RX_DP(2)   I220 @BASEBOARD_FAB2_LIB.BASEBOARD_FAB2(SCH_1):PAGE116
  BK65 P3E_PCH_M2_TX_DN<2> @BASEBOARD_FAB2_LIB.BASEBOARD_FAB2(SCH_1):P3E_PCH_M2_TX_DN(2)   I220 @BASEBOARD_FAB2_LIB.BASEBOARD_FAB2(SCH_1):PAGE116
  BL66 P3E_PCH_M2_TX_DP<2> @BASEBOARD_FAB2_LIB.BASEBOARD_FAB2(SCH_1):P3E_PCH_M2_TX_DP(2)   I220 @BASEBOARD_FAB2_LIB.BASEBOARD_FAB2(SCH_1):PAGE116
   C45 DMI_CPU0_PCH_TX_C_DN<3> @BASEBOARD_FAB2_LIB.BASEBOARD_FAB2(SCH_1):DMI_CPU0_PCH_TX_C_DN(3)     I9 @BASEBOARD_FAB2_LIB.BASEBOARD_FAB2(SCH_1):PAGE117
   D44 DMI_CPU0_PCH_TX_C_DN<2> @BASEBOARD_FAB2_LIB.BASEBOARD_FAB2(SCH_1):DMI_CPU0_PCH_TX_C_DN(2)     I9 @BASEBOARD_FAB2_LIB.BASEBOARD_FAB2(SCH_1):PAGE117
   C43 DMI_CPU0_PCH_TX_C_DN<1> @BASEBOARD_FAB2_LIB.BASEBOARD_FAB2(SCH_1):DMI_CPU0_PCH_TX_C_DN(1)     I9 @BASEBOARD_FAB2_LIB.BASEBOARD_FAB2(SCH_1):PAGE117
   D42 DMI_CPU0_PCH_TX_C_DN<0> @BASEBOARD_FAB2_LIB.BASEBOARD_FAB2(SCH_1):DMI_CPU0_PCH_TX_C_DN(0)     I9 @BASEBOARD_FAB2_LIB.BASEBOARD_FAB2(SCH_1):PAGE117
   A45 DMI_CPU0_PCH_TX_C_DP<3> @BASEBOARD_FAB2_LIB.BASEBOARD_FAB2(SCH_1):DMI_CPU0_PCH_TX_C_DP(3)     I9 @BASEBOARD_FAB2_LIB.BASEBOARD_FAB2(SCH_1):PAGE117
   B44 DMI_CPU0_PCH_TX_C_DP<2> @BASEBOARD_FAB2_LIB.BASEBOARD_FAB2(SCH_1):DMI_CPU0_PCH_TX_C_DP(2)     I9 @BASEBOARD_FAB2_LIB.BASEBOARD_FAB2(SCH_1):PAGE117
   A43 DMI_CPU0_PCH_TX_C_DP<1> @BASEBOARD_FAB2_LIB.BASEBOARD_FAB2(SCH_1):DMI_CPU0_PCH_TX_C_DP(1)     I9 @BASEBOARD_FAB2_LIB.BASEBOARD_FAB2(SCH_1):PAGE117
   B42 DMI_CPU0_PCH_TX_C_DP<0> @BASEBOARD_FAB2_LIB.BASEBOARD_FAB2(SCH_1):DMI_CPU0_PCH_TX_C_DP(0)     I9 @BASEBOARD_FAB2_LIB.BASEBOARD_FAB2(SCH_1):PAGE117
   P52 DMI_CPU0_PCH_RX_DN<3> @BASEBOARD_FAB2_LIB.BASEBOARD_FAB2(SCH_1):DMI_CPU0_PCH_RX_DN(3)     I9 @BASEBOARD_FAB2_LIB.BASEBOARD_FAB2(SCH_1):PAGE117
   K50 DMI_CPU0_PCH_RX_DN<2> @BASEBOARD_FAB2_LIB.BASEBOARD_FAB2(SCH_1):DMI_CPU0_PCH_RX_DN(2)     I9 @BASEBOARD_FAB2_LIB.BASEBOARD_FAB2(SCH_1):PAGE117
   J48 DMI_CPU0_PCH_RX_DN<1> @BASEBOARD_FAB2_LIB.BASEBOARD_FAB2(SCH_1):DMI_CPU0_PCH_RX_DN(1)     I9 @BASEBOARD_FAB2_LIB.BASEBOARD_FAB2(SCH_1):PAGE117
   H46 DMI_CPU0_PCH_RX_DN<0> @BASEBOARD_FAB2_LIB.BASEBOARD_FAB2(SCH_1):DMI_CPU0_PCH_RX_DN(0)     I9 @BASEBOARD_FAB2_LIB.BASEBOARD_FAB2(SCH_1):PAGE117
   N54 DMI_CPU0_PCH_RX_DP<3> @BASEBOARD_FAB2_LIB.BASEBOARD_FAB2(SCH_1):DMI_CPU0_PCH_RX_DP(3)     I9 @BASEBOARD_FAB2_LIB.BASEBOARD_FAB2(SCH_1):PAGE117
   M52 DMI_CPU0_PCH_RX_DP<2> @BASEBOARD_FAB2_LIB.BASEBOARD_FAB2(SCH_1):DMI_CPU0_PCH_RX_DP(2)     I9 @BASEBOARD_FAB2_LIB.BASEBOARD_FAB2(SCH_1):PAGE117
   H50 DMI_CPU0_PCH_RX_DP<1> @BASEBOARD_FAB2_LIB.BASEBOARD_FAB2(SCH_1):DMI_CPU0_PCH_RX_DP(1)     I9 @BASEBOARD_FAB2_LIB.BASEBOARD_FAB2(SCH_1):PAGE117
   K46 DMI_CPU0_PCH_RX_DP<0> @BASEBOARD_FAB2_LIB.BASEBOARD_FAB2(SCH_1):DMI_CPU0_PCH_RX_DP(0)     I9 @BASEBOARD_FAB2_LIB.BASEBOARD_FAB2(SCH_1):PAGE117
   C48 P3E_CPU0_PE1_PCH_TXN<0> @BASEBOARD_FAB2_LIB.BASEBOARD_FAB2(SCH_1):P3E_CPU0_PE1_PCH_TXN(0)     I9 @BASEBOARD_FAB2_LIB.BASEBOARD_FAB2(SCH_1):PAGE117
   A48 P3E_CPU0_PE1_PCH_TXP<0> @BASEBOARD_FAB2_LIB.BASEBOARD_FAB2(SCH_1):P3E_CPU0_PE1_PCH_TXP(0)     I9 @BASEBOARD_FAB2_LIB.BASEBOARD_FAB2(SCH_1):PAGE117
   J52 P3E_CPU0_PE1_PCH_RXN<0> @BASEBOARD_FAB2_LIB.BASEBOARD_FAB2(SCH_1):P3E_CPU0_PE1_PCH_RXN(0)     I9 @BASEBOARD_FAB2_LIB.BASEBOARD_FAB2(SCH_1):PAGE117
   G52 P3E_CPU0_PE1_PCH_RXP<0> @BASEBOARD_FAB2_LIB.BASEBOARD_FAB2(SCH_1):P3E_CPU0_PE1_PCH_RXP(0)     I9 @BASEBOARD_FAB2_LIB.BASEBOARD_FAB2(SCH_1):PAGE117
   C59 P3E_CPU0_PE1_PCH_C_TXP<10> @BASEBOARD_FAB2_LIB.BASEBOARD_FAB2(SCH_1):P3E_CPU0_PE1_PCH_C_TXP(10)     I9 @BASEBOARD_FAB2_LIB.BASEBOARD_FAB2(SCH_1):PAGE117
   A59 P3E_CPU0_PE1_PCH_C_TXN<10> @BASEBOARD_FAB2_LIB.BASEBOARD_FAB2(SCH_1):P3E_CPU0_PE1_PCH_C_TXN(10)     I9 @BASEBOARD_FAB2_LIB.BASEBOARD_FAB2(SCH_1):PAGE117
   N65 P3E_CPU0_PE1_PCH_R_RXN<10> @BASEBOARD_FAB2_LIB.BASEBOARD_FAB2(SCH_1):P3E_CPU0_PE1_PCH_R_RXN(10)     I9 @BASEBOARD_FAB2_LIB.BASEBOARD_FAB2(SCH_1):PAGE117
   P66 P3E_CPU0_PE1_PCH_R_RXP<10> @BASEBOARD_FAB2_LIB.BASEBOARD_FAB2(SCH_1):P3E_CPU0_PE1_PCH_R_RXP(10)     I9 @BASEBOARD_FAB2_LIB.BASEBOARD_FAB2(SCH_1):PAGE117
   D60 P3E_CPU0_PE1_PCH_C_TXN<11> @BASEBOARD_FAB2_LIB.BASEBOARD_FAB2(SCH_1):P3E_CPU0_PE1_PCH_C_TXN(11)     I9 @BASEBOARD_FAB2_LIB.BASEBOARD_FAB2(SCH_1):PAGE117
   B60 P3E_CPU0_PE1_PCH_C_TXP<11> @BASEBOARD_FAB2_LIB.BASEBOARD_FAB2(SCH_1):P3E_CPU0_PE1_PCH_C_TXP(11)     I9 @BASEBOARD_FAB2_LIB.BASEBOARD_FAB2(SCH_1):PAGE117
   T59 P3E_CPU0_PE1_PCH_R_RXN<11> @BASEBOARD_FAB2_LIB.BASEBOARD_FAB2(SCH_1):P3E_CPU0_PE1_PCH_R_RXN(11)     I9 @BASEBOARD_FAB2_LIB.BASEBOARD_FAB2(SCH_1):PAGE117
   V59 P3E_CPU0_PE1_PCH_R_RXP<11> @BASEBOARD_FAB2_LIB.BASEBOARD_FAB2(SCH_1):P3E_CPU0_PE1_PCH_R_RXP(11)     I9 @BASEBOARD_FAB2_LIB.BASEBOARD_FAB2(SCH_1):PAGE117
   C61 P3E_CPU0_PE1_PCH_C_TXP<12> @BASEBOARD_FAB2_LIB.BASEBOARD_FAB2(SCH_1):P3E_CPU0_PE1_PCH_C_TXP(12)     I9 @BASEBOARD_FAB2_LIB.BASEBOARD_FAB2(SCH_1):PAGE117
   A61 P3E_CPU0_PE1_PCH_C_TXN<12> @BASEBOARD_FAB2_LIB.BASEBOARD_FAB2(SCH_1):P3E_CPU0_PE1_PCH_C_TXN(12)     I9 @BASEBOARD_FAB2_LIB.BASEBOARD_FAB2(SCH_1):PAGE117
   R65 P3E_CPU0_PE1_PCH_R_RXN<12> @BASEBOARD_FAB2_LIB.BASEBOARD_FAB2(SCH_1):P3E_CPU0_PE1_PCH_R_RXN(12)     I9 @BASEBOARD_FAB2_LIB.BASEBOARD_FAB2(SCH_1):PAGE117
   U65 P3E_CPU0_PE1_PCH_R_RXP<12> @BASEBOARD_FAB2_LIB.BASEBOARD_FAB2(SCH_1):P3E_CPU0_PE1_PCH_R_RXP(12)     I9 @BASEBOARD_FAB2_LIB.BASEBOARD_FAB2(SCH_1):PAGE117
   D62 P3E_CPU0_PE1_PCH_C_TXP<13> @BASEBOARD_FAB2_LIB.BASEBOARD_FAB2(SCH_1):P3E_CPU0_PE1_PCH_C_TXP(13)     I9 @BASEBOARD_FAB2_LIB.BASEBOARD_FAB2(SCH_1):PAGE117
   B62 P3E_CPU0_PE1_PCH_C_TXN<13> @BASEBOARD_FAB2_LIB.BASEBOARD_FAB2(SCH_1):P3E_CPU0_PE1_PCH_C_TXN(13)     I9 @BASEBOARD_FAB2_LIB.BASEBOARD_FAB2(SCH_1):PAGE117
   T63 P3E_CPU0_PE1_PCH_R_RXN<13> @BASEBOARD_FAB2_LIB.BASEBOARD_FAB2(SCH_1):P3E_CPU0_PE1_PCH_R_RXN(13)     I9 @BASEBOARD_FAB2_LIB.BASEBOARD_FAB2(SCH_1):PAGE117
   U61 P3E_CPU0_PE1_PCH_R_RXP<13> @BASEBOARD_FAB2_LIB.BASEBOARD_FAB2(SCH_1):P3E_CPU0_PE1_PCH_R_RXP(13)     I9 @BASEBOARD_FAB2_LIB.BASEBOARD_FAB2(SCH_1):PAGE117
   C63 P3E_CPU0_PE1_PCH_C_TXP<14> @BASEBOARD_FAB2_LIB.BASEBOARD_FAB2(SCH_1):P3E_CPU0_PE1_PCH_C_TXP(14)     I9 @BASEBOARD_FAB2_LIB.BASEBOARD_FAB2(SCH_1):PAGE117
   A63 P3E_CPU0_PE1_PCH_C_TXN<14> @BASEBOARD_FAB2_LIB.BASEBOARD_FAB2(SCH_1):P3E_CPU0_PE1_PCH_C_TXN(14)     I9 @BASEBOARD_FAB2_LIB.BASEBOARD_FAB2(SCH_1):PAGE117
   W65 P3E_CPU0_PE1_PCH_R_RXN<14> @BASEBOARD_FAB2_LIB.BASEBOARD_FAB2(SCH_1):P3E_CPU0_PE1_PCH_R_RXN(14)     I9 @BASEBOARD_FAB2_LIB.BASEBOARD_FAB2(SCH_1):PAGE117
   V63 P3E_CPU0_PE1_PCH_R_RXP<14> @BASEBOARD_FAB2_LIB.BASEBOARD_FAB2(SCH_1):P3E_CPU0_PE1_PCH_R_RXP(14)     I9 @BASEBOARD_FAB2_LIB.BASEBOARD_FAB2(SCH_1):PAGE117
   D64 P3E_CPU0_PE1_PCH_C_TXP<15> @BASEBOARD_FAB2_LIB.BASEBOARD_FAB2(SCH_1):P3E_CPU0_PE1_PCH_C_TXP(15)     I9 @BASEBOARD_FAB2_LIB.BASEBOARD_FAB2(SCH_1):PAGE117
   B64 P3E_CPU0_PE1_PCH_C_TXN<15> @BASEBOARD_FAB2_LIB.BASEBOARD_FAB2(SCH_1):P3E_CPU0_PE1_PCH_C_TXN(15)     I9 @BASEBOARD_FAB2_LIB.BASEBOARD_FAB2(SCH_1):PAGE117
   Y66 P3E_CPU0_PE1_PCH_R_RXN<15> @BASEBOARD_FAB2_LIB.BASEBOARD_FAB2(SCH_1):P3E_CPU0_PE1_PCH_R_RXN(15)     I9 @BASEBOARD_FAB2_LIB.BASEBOARD_FAB2(SCH_1):PAGE117
  AA65 P3E_CPU0_PE1_PCH_R_RXP<15> @BASEBOARD_FAB2_LIB.BASEBOARD_FAB2(SCH_1):P3E_CPU0_PE1_PCH_R_RXP(15)     I9 @BASEBOARD_FAB2_LIB.BASEBOARD_FAB2(SCH_1):PAGE117
   D49 P3E_CPU0_PE1_PCH_TXN<1> @BASEBOARD_FAB2_LIB.BASEBOARD_FAB2(SCH_1):P3E_CPU0_PE1_PCH_TXN(1)     I9 @BASEBOARD_FAB2_LIB.BASEBOARD_FAB2(SCH_1):PAGE117
   B49 P3E_CPU0_PE1_PCH_TXP<1> @BASEBOARD_FAB2_LIB.BASEBOARD_FAB2(SCH_1):P3E_CPU0_PE1_PCH_TXP(1)     I9 @BASEBOARD_FAB2_LIB.BASEBOARD_FAB2(SCH_1):PAGE117
   P56 P3E_CPU0_PE1_PCH_RXN<1> @BASEBOARD_FAB2_LIB.BASEBOARD_FAB2(SCH_1):P3E_CPU0_PE1_PCH_RXN(1)     I9 @BASEBOARD_FAB2_LIB.BASEBOARD_FAB2(SCH_1):PAGE117
   M56 P3E_CPU0_PE1_PCH_RXP<1> @BASEBOARD_FAB2_LIB.BASEBOARD_FAB2(SCH_1):P3E_CPU0_PE1_PCH_RXP(1)     I9 @BASEBOARD_FAB2_LIB.BASEBOARD_FAB2(SCH_1):PAGE117
   C50 P3E_CPU0_PE1_PCH_TXN<2> @BASEBOARD_FAB2_LIB.BASEBOARD_FAB2(SCH_1):P3E_CPU0_PE1_PCH_TXN(2)     I9 @BASEBOARD_FAB2_LIB.BASEBOARD_FAB2(SCH_1):PAGE117
   A50 P3E_CPU0_PE1_PCH_TXP<2> @BASEBOARD_FAB2_LIB.BASEBOARD_FAB2(SCH_1):P3E_CPU0_PE1_PCH_TXP(2)     I9 @BASEBOARD_FAB2_LIB.BASEBOARD_FAB2(SCH_1):PAGE117
   H54 P3E_CPU0_PE1_PCH_RXN<2> @BASEBOARD_FAB2_LIB.BASEBOARD_FAB2(SCH_1):P3E_CPU0_PE1_PCH_RXN(2)     I9 @BASEBOARD_FAB2_LIB.BASEBOARD_FAB2(SCH_1):PAGE117
   G56 P3E_CPU0_PE1_PCH_RXP<2> @BASEBOARD_FAB2_LIB.BASEBOARD_FAB2(SCH_1):P3E_CPU0_PE1_PCH_RXP(2)     I9 @BASEBOARD_FAB2_LIB.BASEBOARD_FAB2(SCH_1):PAGE117
   D51 P3E_CPU0_PE1_PCH_TXN<3> @BASEBOARD_FAB2_LIB.BASEBOARD_FAB2(SCH_1):P3E_CPU0_PE1_PCH_TXN(3)     I9 @BASEBOARD_FAB2_LIB.BASEBOARD_FAB2(SCH_1):PAGE117
   B51 P3E_CPU0_PE1_PCH_TXP<3> @BASEBOARD_FAB2_LIB.BASEBOARD_FAB2(SCH_1):P3E_CPU0_PE1_PCH_TXP(3)     I9 @BASEBOARD_FAB2_LIB.BASEBOARD_FAB2(SCH_1):PAGE117
   J56 P3E_CPU0_PE1_PCH_RXN<3> @BASEBOARD_FAB2_LIB.BASEBOARD_FAB2(SCH_1):P3E_CPU0_PE1_PCH_RXN(3)     I9 @BASEBOARD_FAB2_LIB.BASEBOARD_FAB2(SCH_1):PAGE117
   K58 P3E_CPU0_PE1_PCH_RXP<3> @BASEBOARD_FAB2_LIB.BASEBOARD_FAB2(SCH_1):P3E_CPU0_PE1_PCH_RXP(3)     I9 @BASEBOARD_FAB2_LIB.BASEBOARD_FAB2(SCH_1):PAGE117
   C52 P3E_CPU0_PE1_PCH_TXN<4> @BASEBOARD_FAB2_LIB.BASEBOARD_FAB2(SCH_1):P3E_CPU0_PE1_PCH_TXN(4)     I9 @BASEBOARD_FAB2_LIB.BASEBOARD_FAB2(SCH_1):PAGE117
   A52 P3E_CPU0_PE1_PCH_TXP<4> @BASEBOARD_FAB2_LIB.BASEBOARD_FAB2(SCH_1):P3E_CPU0_PE1_PCH_TXP(4)     I9 @BASEBOARD_FAB2_LIB.BASEBOARD_FAB2(SCH_1):PAGE117
   N58 P3E_CPU0_PE1_PCH_RXN<4> @BASEBOARD_FAB2_LIB.BASEBOARD_FAB2(SCH_1):P3E_CPU0_PE1_PCH_RXN(4)     I9 @BASEBOARD_FAB2_LIB.BASEBOARD_FAB2(SCH_1):PAGE117
   M59 P3E_CPU0_PE1_PCH_RXP<4> @BASEBOARD_FAB2_LIB.BASEBOARD_FAB2(SCH_1):P3E_CPU0_PE1_PCH_RXP(4)     I9 @BASEBOARD_FAB2_LIB.BASEBOARD_FAB2(SCH_1):PAGE117
   D53 P3E_CPU0_PE1_PCH_TXN<5> @BASEBOARD_FAB2_LIB.BASEBOARD_FAB2(SCH_1):P3E_CPU0_PE1_PCH_TXN(5)     I9 @BASEBOARD_FAB2_LIB.BASEBOARD_FAB2(SCH_1):PAGE117
   B53 P3E_CPU0_PE1_PCH_TXP<5> @BASEBOARD_FAB2_LIB.BASEBOARD_FAB2(SCH_1):P3E_CPU0_PE1_PCH_TXP(5)     I9 @BASEBOARD_FAB2_LIB.BASEBOARD_FAB2(SCH_1):PAGE117
   N61 P3E_CPU0_PE1_PCH_RXN<5> @BASEBOARD_FAB2_LIB.BASEBOARD_FAB2(SCH_1):P3E_CPU0_PE1_PCH_RXN(5)     I9 @BASEBOARD_FAB2_LIB.BASEBOARD_FAB2(SCH_1):PAGE117
   K61 P3E_CPU0_PE1_PCH_RXP<5> @BASEBOARD_FAB2_LIB.BASEBOARD_FAB2(SCH_1):P3E_CPU0_PE1_PCH_RXP(5)     I9 @BASEBOARD_FAB2_LIB.BASEBOARD_FAB2(SCH_1):PAGE117
   C54 P3E_CPU0_PE1_PCH_TXN<6> @BASEBOARD_FAB2_LIB.BASEBOARD_FAB2(SCH_1):P3E_CPU0_PE1_PCH_TXN(6)     I9 @BASEBOARD_FAB2_LIB.BASEBOARD_FAB2(SCH_1):PAGE117
   A54 P3E_CPU0_PE1_PCH_TXP<6> @BASEBOARD_FAB2_LIB.BASEBOARD_FAB2(SCH_1):P3E_CPU0_PE1_PCH_TXP(6)     I9 @BASEBOARD_FAB2_LIB.BASEBOARD_FAB2(SCH_1):PAGE117
   H61 P3E_CPU0_PE1_PCH_RXN<6> @BASEBOARD_FAB2_LIB.BASEBOARD_FAB2(SCH_1):P3E_CPU0_PE1_PCH_RXN(6)     I9 @BASEBOARD_FAB2_LIB.BASEBOARD_FAB2(SCH_1):PAGE117
   J63 P3E_CPU0_PE1_PCH_RXP<6> @BASEBOARD_FAB2_LIB.BASEBOARD_FAB2(SCH_1):P3E_CPU0_PE1_PCH_RXP(6)     I9 @BASEBOARD_FAB2_LIB.BASEBOARD_FAB2(SCH_1):PAGE117
   D55 P3E_CPU0_PE1_PCH_TXN<7> @BASEBOARD_FAB2_LIB.BASEBOARD_FAB2(SCH_1):P3E_CPU0_PE1_PCH_TXN(7)     I9 @BASEBOARD_FAB2_LIB.BASEBOARD_FAB2(SCH_1):PAGE117
   B55 P3E_CPU0_PE1_PCH_TXP<7> @BASEBOARD_FAB2_LIB.BASEBOARD_FAB2(SCH_1):P3E_CPU0_PE1_PCH_TXP(7)     I9 @BASEBOARD_FAB2_LIB.BASEBOARD_FAB2(SCH_1):PAGE117
   P59 P3E_CPU0_PE1_PCH_RXN<7> @BASEBOARD_FAB2_LIB.BASEBOARD_FAB2(SCH_1):P3E_CPU0_PE1_PCH_RXN(7)     I9 @BASEBOARD_FAB2_LIB.BASEBOARD_FAB2(SCH_1):PAGE117
   R61 P3E_CPU0_PE1_PCH_RXP<7> @BASEBOARD_FAB2_LIB.BASEBOARD_FAB2(SCH_1):P3E_CPU0_PE1_PCH_RXP(7)     I9 @BASEBOARD_FAB2_LIB.BASEBOARD_FAB2(SCH_1):PAGE117
   C57 P3E_CPU0_PE1_PCH_C_TXP<8> @BASEBOARD_FAB2_LIB.BASEBOARD_FAB2(SCH_1):P3E_CPU0_PE1_PCH_C_TXP(8)     I9 @BASEBOARD_FAB2_LIB.BASEBOARD_FAB2(SCH_1):PAGE117
   A57 P3E_CPU0_PE1_PCH_C_TXN<8> @BASEBOARD_FAB2_LIB.BASEBOARD_FAB2(SCH_1):P3E_CPU0_PE1_PCH_C_TXN(8)     I9 @BASEBOARD_FAB2_LIB.BASEBOARD_FAB2(SCH_1):PAGE117
   K65 P3E_CPU0_PE1_PCH_R_RXN<8> @BASEBOARD_FAB2_LIB.BASEBOARD_FAB2(SCH_1):P3E_CPU0_PE1_PCH_R_RXN(8)     I9 @BASEBOARD_FAB2_LIB.BASEBOARD_FAB2(SCH_1):PAGE117
   M63 P3E_CPU0_PE1_PCH_R_RXP<8> @BASEBOARD_FAB2_LIB.BASEBOARD_FAB2(SCH_1):P3E_CPU0_PE1_PCH_R_RXP(8)     I9 @BASEBOARD_FAB2_LIB.BASEBOARD_FAB2(SCH_1):PAGE117
   D58 P3E_CPU0_PE1_PCH_C_TXP<9> @BASEBOARD_FAB2_LIB.BASEBOARD_FAB2(SCH_1):P3E_CPU0_PE1_PCH_C_TXP(9)     I9 @BASEBOARD_FAB2_LIB.BASEBOARD_FAB2(SCH_1):PAGE117
   B58 P3E_CPU0_PE1_PCH_C_TXN<9> @BASEBOARD_FAB2_LIB.BASEBOARD_FAB2(SCH_1):P3E_CPU0_PE1_PCH_C_TXN(9)     I9 @BASEBOARD_FAB2_LIB.BASEBOARD_FAB2(SCH_1):PAGE117
   J66 P3E_CPU0_PE1_PCH_R_RXN<9> @BASEBOARD_FAB2_LIB.BASEBOARD_FAB2(SCH_1):P3E_CPU0_PE1_PCH_R_RXN(9)     I9 @BASEBOARD_FAB2_LIB.BASEBOARD_FAB2(SCH_1):PAGE117
   M66 P3E_CPU0_PE1_PCH_R_RXP<9> @BASEBOARD_FAB2_LIB.BASEBOARD_FAB2(SCH_1):P3E_CPU0_PE1_PCH_R_RXP(9)     I9 @BASEBOARD_FAB2_LIB.BASEBOARD_FAB2(SCH_1):PAGE117
  AT56 XDP_TRST_N @BASEBOARD_FAB2_LIB.BASEBOARD_FAB2(SCH_1):XDP_TRST_N    I73 @BASEBOARD_FAB2_LIB.BASEBOARD_FAB2(SCH_1):PAGE118
   K13 PWRGD_DSW_PWROK @BASEBOARD_FAB2_LIB.BASEBOARD_FAB2(SCH_1):PWRGD_DSW_PWROK    I73 @BASEBOARD_FAB2_LIB.BASEBOARD_FAB2(SCH_1):PAGE118
   G15 XDP_PCH_PWR_DEBUG_N @BASEBOARD_FAB2_LIB.BASEBOARD_FAB2(SCH_1):XDP_PCH_PWR_DEBUG_N    I73 @BASEBOARD_FAB2_LIB.BASEBOARD_FAB2(SCH_1):PAGE118
   B14 FM_CPU0_RC_ERROR_N @BASEBOARD_FAB2_LIB.BASEBOARD_FAB2(SCH_1):FM_CPU0_RC_ERROR_N    I73 @BASEBOARD_FAB2_LIB.BASEBOARD_FAB2(SCH_1):PAGE118
   A13 FM_GBE_LOM_DISABLE_N @BASEBOARD_FAB2_LIB.BASEBOARD_FAB2(SCH_1):FM_GBE_LOM_DISABLE_N    I73 @BASEBOARD_FAB2_LIB.BASEBOARD_FAB2(SCH_1):PAGE118
   H13 FM_CPU1_SKTOCC_LVT3_N @BASEBOARD_FAB2_LIB.BASEBOARD_FAB2(SCH_1):FM_CPU1_SKTOCC_LVT3_N    I73 @BASEBOARD_FAB2_LIB.BASEBOARD_FAB2(SCH_1):PAGE118
   M11 RST_BMC_SRST_R_N @BASEBOARD_FAB2_LIB.BASEBOARD_FAB2(SCH_1):RST_BMC_SRST_R_N    I73 @BASEBOARD_FAB2_LIB.BASEBOARD_FAB2(SCH_1):PAGE118
   C15 FM_PCH_PWRBTN_N @BASEBOARD_FAB2_LIB.BASEBOARD_FAB2(SCH_1):FM_PCH_PWRBTN_N    I73 @BASEBOARD_FAB2_LIB.BASEBOARD_FAB2(SCH_1):PAGE118
   D14 FM_SLPS3_N @BASEBOARD_FAB2_LIB.BASEBOARD_FAB2(SCH_1):FM_SLPS3_N    I73 @BASEBOARD_FAB2_LIB.BASEBOARD_FAB2(SCH_1):PAGE118
   B16 FM_SLPS4_N @BASEBOARD_FAB2_LIB.BASEBOARD_FAB2(SCH_1):FM_SLPS4_N    I73 @BASEBOARD_FAB2_LIB.BASEBOARD_FAB2(SCH_1):PAGE118
   G11 FM_CPU0_SKTOCC_LVT3_N @BASEBOARD_FAB2_LIB.BASEBOARD_FAB2(SCH_1):FM_CPU0_SKTOCC_LVT3_N    I73 @BASEBOARD_FAB2_LIB.BASEBOARD_FAB2(SCH_1):PAGE118
    H9 FM_BATTERY_SENSE_EN_N @BASEBOARD_FAB2_LIB.BASEBOARD_FAB2(SCH_1):FM_BATTERY_SENSE_EN_N    I73 @BASEBOARD_FAB2_LIB.BASEBOARD_FAB2(SCH_1):PAGE118
   C13 IRQ_SML1_PMBUS_ALERT_N @BASEBOARD_FAB2_LIB.BASEBOARD_FAB2(SCH_1):IRQ_SML1_PMBUS_ALERT_N    I73 @BASEBOARD_FAB2_LIB.BASEBOARD_FAB2(SCH_1):PAGE118
   A15 FM_BMC_CPLD_MP_RST_N @BASEBOARD_FAB2_LIB.BASEBOARD_FAB2(SCH_1):FM_BMC_CPLD_MP_RST_N    I73 @BASEBOARD_FAB2_LIB.BASEBOARD_FAB2(SCH_1):PAGE118
  AR54 XDP_ITP_PMODE @BASEBOARD_FAB2_LIB.BASEBOARD_FAB2(SCH_1):XDP_ITP_PMODE    I73 @BASEBOARD_FAB2_LIB.BASEBOARD_FAB2(SCH_1):PAGE118
  AF54 XDP_PCH_CPU_TCK0 @BASEBOARD_FAB2_LIB.BASEBOARD_FAB2(SCH_1):XDP_PCH_CPU_TCK0    I73 @BASEBOARD_FAB2_LIB.BASEBOARD_FAB2(SCH_1):PAGE118
  AL56 XDP_PCH_TCK1 @BASEBOARD_FAB2_LIB.BASEBOARD_FAB2(SCH_1):XDP_PCH_TCK1    I73 @BASEBOARD_FAB2_LIB.BASEBOARD_FAB2(SCH_1):PAGE118
  AN54 XDP_TDI @BASEBOARD_FAB2_LIB.BASEBOARD_FAB2(SCH_1):XDP_TDI    I73 @BASEBOARD_FAB2_LIB.BASEBOARD_FAB2(SCH_1):PAGE118
  AP56 XDP_TDO @BASEBOARD_FAB2_LIB.BASEBOARD_FAB2(SCH_1):XDP_TDO    I73 @BASEBOARD_FAB2_LIB.BASEBOARD_FAB2(SCH_1):PAGE118
  AH54 XDP_TMS @BASEBOARD_FAB2_LIB.BASEBOARD_FAB2(SCH_1):XDP_TMS    I73 @BASEBOARD_FAB2_LIB.BASEBOARD_FAB2(SCH_1):PAGE118
  BB29 A_KR0_RBIAS @BASEBOARD_FAB2_LIB.BASEBOARD_FAB2(SCH_1):A_KR0_RBIAS    I73 @BASEBOARD_FAB2_LIB.BASEBOARD_FAB2(SCH_1):PAGE118
  BD42 A_KR1_RBIAS @BASEBOARD_FAB2_LIB.BASEBOARD_FAB2(SCH_1):A_KR1_RBIAS    I73 @BASEBOARD_FAB2_LIB.BASEBOARD_FAB2(SCH_1):PAGE118
  BH31 KR_P0_OCP_RX_C_DN @BASEBOARD_FAB2_LIB.BASEBOARD_FAB2(SCH_1):KR_P0_OCP_RX_C_DN    I73 @BASEBOARD_FAB2_LIB.BASEBOARD_FAB2(SCH_1):PAGE118
  BF31 KR_P0_OCP_RX_C_DP @BASEBOARD_FAB2_LIB.BASEBOARD_FAB2(SCH_1):KR_P0_OCP_RX_C_DP    I73 @BASEBOARD_FAB2_LIB.BASEBOARD_FAB2(SCH_1):PAGE118
  BG29 KR_P1_OCP_RX_C_DN @BASEBOARD_FAB2_LIB.BASEBOARD_FAB2(SCH_1):KR_P1_OCP_RX_C_DN    I73 @BASEBOARD_FAB2_LIB.BASEBOARD_FAB2(SCH_1):PAGE118
  BJ29 KR_P1_OCP_RX_C_DP @BASEBOARD_FAB2_LIB.BASEBOARD_FAB2(SCH_1):KR_P1_OCP_RX_C_DP    I73 @BASEBOARD_FAB2_LIB.BASEBOARD_FAB2(SCH_1):PAGE118
  BJ37 KR_P2_OCP_RX_C_DN @BASEBOARD_FAB2_LIB.BASEBOARD_FAB2(SCH_1):KR_P2_OCP_RX_C_DN    I73 @BASEBOARD_FAB2_LIB.BASEBOARD_FAB2(SCH_1):PAGE118
  BG37 KR_P2_OCP_RX_C_DP @BASEBOARD_FAB2_LIB.BASEBOARD_FAB2(SCH_1):KR_P2_OCP_RX_C_DP    I73 @BASEBOARD_FAB2_LIB.BASEBOARD_FAB2(SCH_1):PAGE118
  BF35 KR_P3_OCP_RX_C_DN @BASEBOARD_FAB2_LIB.BASEBOARD_FAB2(SCH_1):KR_P3_OCP_RX_C_DN    I73 @BASEBOARD_FAB2_LIB.BASEBOARD_FAB2(SCH_1):PAGE118
  BH35 KR_P3_OCP_RX_C_DP @BASEBOARD_FAB2_LIB.BASEBOARD_FAB2(SCH_1):KR_P3_OCP_RX_C_DP    I73 @BASEBOARD_FAB2_LIB.BASEBOARD_FAB2(SCH_1):PAGE118
  BM27 KR_P0_OCP_TX_DN @BASEBOARD_FAB2_LIB.BASEBOARD_FAB2(SCH_1):KR_P0_OCP_TX_DN    I73 @BASEBOARD_FAB2_LIB.BASEBOARD_FAB2(SCH_1):PAGE118
  BR27 KR_P0_OCP_TX_DP @BASEBOARD_FAB2_LIB.BASEBOARD_FAB2(SCH_1):KR_P0_OCP_TX_DP    I73 @BASEBOARD_FAB2_LIB.BASEBOARD_FAB2(SCH_1):PAGE118
  BM24 KR_P1_OCP_TX_DN @BASEBOARD_FAB2_LIB.BASEBOARD_FAB2(SCH_1):KR_P1_OCP_TX_DN    I73 @BASEBOARD_FAB2_LIB.BASEBOARD_FAB2(SCH_1):PAGE118
  BR24 KR_P1_OCP_TX_DP @BASEBOARD_FAB2_LIB.BASEBOARD_FAB2(SCH_1):KR_P1_OCP_TX_DP    I73 @BASEBOARD_FAB2_LIB.BASEBOARD_FAB2(SCH_1):PAGE118
  BM35 KR_P2_OCP_TX_DN @BASEBOARD_FAB2_LIB.BASEBOARD_FAB2(SCH_1):KR_P2_OCP_TX_DN    I73 @BASEBOARD_FAB2_LIB.BASEBOARD_FAB2(SCH_1):PAGE118
  BR35 KR_P2_OCP_TX_DP @BASEBOARD_FAB2_LIB.BASEBOARD_FAB2(SCH_1):KR_P2_OCP_TX_DP    I73 @BASEBOARD_FAB2_LIB.BASEBOARD_FAB2(SCH_1):PAGE118
  BR31 KR_P3_OCP_TX_DN @BASEBOARD_FAB2_LIB.BASEBOARD_FAB2(SCH_1):KR_P3_OCP_TX_DN    I73 @BASEBOARD_FAB2_LIB.BASEBOARD_FAB2(SCH_1):PAGE118
  BM31 KR_P3_OCP_TX_DP @BASEBOARD_FAB2_LIB.BASEBOARD_FAB2(SCH_1):KR_P3_OCP_TX_DP    I73 @BASEBOARD_FAB2_LIB.BASEBOARD_FAB2(SCH_1):PAGE118
  BV16 XTAL_KR_25M_IN @BASEBOARD_FAB2_LIB.BASEBOARD_FAB2(SCH_1):XTAL_KR_25M_IN    I73 @BASEBOARD_FAB2_LIB.BASEBOARD_FAB2(SCH_1):PAGE118
  BY16 XTAL_KR_25M_OUT @BASEBOARD_FAB2_LIB.BASEBOARD_FAB2(SCH_1):XTAL_KR_25M_OUT    I73 @BASEBOARD_FAB2_LIB.BASEBOARD_FAB2(SCH_1):PAGE118
   R17 PWRGD_PCH_PWROK @BASEBOARD_FAB2_LIB.BASEBOARD_FAB2(SCH_1):PWRGD_PCH_PWROK    I73 @BASEBOARD_FAB2_LIB.BASEBOARD_FAB2(SCH_1):PAGE118
    U9 PECI_PCH @BASEBOARD_FAB2_LIB.BASEBOARD_FAB2(SCH_1):PECI_PCH    I73 @BASEBOARD_FAB2_LIB.BASEBOARD_FAB2(SCH_1):PAGE118
   U17 TP_PLTRST_CPU_N @BASEBOARD_FAB2_LIB.BASEBOARD_FAB2(SCH_1):TP_PLTRST_CPU_N    I73 @BASEBOARD_FAB2_LIB.BASEBOARD_FAB2(SCH_1):PAGE118
   U13 H_PM_SYNC1_GTL_R @BASEBOARD_FAB2_LIB.BASEBOARD_FAB2(SCH_1):H_PM_SYNC1_GTL_R    I73 @BASEBOARD_FAB2_LIB.BASEBOARD_FAB2(SCH_1):PAGE118
    V7 TP_PM_SYNC_GTL @BASEBOARD_FAB2_LIB.BASEBOARD_FAB2(SCH_1):TP_PM_SYNC_GTL    I73 @BASEBOARD_FAB2_LIB.BASEBOARD_FAB2(SCH_1):PAGE118
  AD54 XDP_PRDY_N @BASEBOARD_FAB2_LIB.BASEBOARD_FAB2(SCH_1):XDP_PRDY_N    I73 @BASEBOARD_FAB2_LIB.BASEBOARD_FAB2(SCH_1):PAGE118
   U54 XDP_PREQ_N @BASEBOARD_FAB2_LIB.BASEBOARD_FAB2(SCH_1):XDP_PREQ_N    I73 @BASEBOARD_FAB2_LIB.BASEBOARD_FAB2(SCH_1):PAGE118
    R9 PWRGD_CPUPWRGD_GTL @BASEBOARD_FAB2_LIB.BASEBOARD_FAB2(SCH_1):PWRGD_CPUPWRGD_GTL    I73 @BASEBOARD_FAB2_LIB.BASEBOARD_FAB2(SCH_1):PAGE118
   P15 RST_RSMRST_N @BASEBOARD_FAB2_LIB.BASEBOARD_FAB2(SCH_1):RST_RSMRST_N    I73 @BASEBOARD_FAB2_LIB.BASEBOARD_FAB2(SCH_1):PAGE118
   R24 TP_PCH_RSVD54 @BASEBOARD_FAB2_LIB.BASEBOARD_FAB2(SCH_1):TP_PCH_RSVD54    I73 @BASEBOARD_FAB2_LIB.BASEBOARD_FAB2(SCH_1):PAGE118
   P26 TP_PCH_RSVD53 @BASEBOARD_FAB2_LIB.BASEBOARD_FAB2(SCH_1):TP_PCH_RSVD53    I73 @BASEBOARD_FAB2_LIB.BASEBOARD_FAB2(SCH_1):PAGE118
   P22 TP_PCH_RSVD45 @BASEBOARD_FAB2_LIB.BASEBOARD_FAB2(SCH_1):TP_PCH_RSVD45    I73 @BASEBOARD_FAB2_LIB.BASEBOARD_FAB2(SCH_1):PAGE118
  BN33 TP_10GBE_KR1_MON_DP @BASEBOARD_FAB2_LIB.BASEBOARD_FAB2(SCH_1):TP_10GBE_KR1_MON_DP    I73 @BASEBOARD_FAB2_LIB.BASEBOARD_FAB2(SCH_1):PAGE118
  BL33 TP_10GBE_KR1_MON_DN @BASEBOARD_FAB2_LIB.BASEBOARD_FAB2(SCH_1):TP_10GBE_KR1_MON_DN    I73 @BASEBOARD_FAB2_LIB.BASEBOARD_FAB2(SCH_1):PAGE118
  BG40 TP_PCH_RSVD42 @BASEBOARD_FAB2_LIB.BASEBOARD_FAB2(SCH_1):TP_PCH_RSVD42    I73 @BASEBOARD_FAB2_LIB.BASEBOARD_FAB2(SCH_1):PAGE118
  BJ40 TP_PCH_RSVD41 @BASEBOARD_FAB2_LIB.BASEBOARD_FAB2(SCH_1):TP_PCH_RSVD41    I73 @BASEBOARD_FAB2_LIB.BASEBOARD_FAB2(SCH_1):PAGE118
  BN26 TP_10GBE_KR0_MON_DP @BASEBOARD_FAB2_LIB.BASEBOARD_FAB2(SCH_1):TP_10GBE_KR0_MON_DP    I73 @BASEBOARD_FAB2_LIB.BASEBOARD_FAB2(SCH_1):PAGE118
  BL26 TP_10GBE_KR0_MON_DN @BASEBOARD_FAB2_LIB.BASEBOARD_FAB2(SCH_1):TP_10GBE_KR0_MON_DN    I73 @BASEBOARD_FAB2_LIB.BASEBOARD_FAB2(SCH_1):PAGE118
  BL29 TP_PCH_RSVD38 @BASEBOARD_FAB2_LIB.BASEBOARD_FAB2(SCH_1):TP_PCH_RSVD38    I73 @BASEBOARD_FAB2_LIB.BASEBOARD_FAB2(SCH_1):PAGE118
  BN29 TP_PCH_RSVD37 @BASEBOARD_FAB2_LIB.BASEBOARD_FAB2(SCH_1):TP_PCH_RSVD37    I73 @BASEBOARD_FAB2_LIB.BASEBOARD_FAB2(SCH_1):PAGE118
  AK54 TP_PCH_RSVD36 @BASEBOARD_FAB2_LIB.BASEBOARD_FAB2(SCH_1):TP_PCH_RSVD36    I73 @BASEBOARD_FAB2_LIB.BASEBOARD_FAB2(SCH_1):PAGE118
   W54 TP_PCH_RSVD35 @BASEBOARD_FAB2_LIB.BASEBOARD_FAB2(SCH_1):TP_PCH_RSVD35    I73 @BASEBOARD_FAB2_LIB.BASEBOARD_FAB2(SCH_1):PAGE118
   Y56 TP_PCH_RSVD34 @BASEBOARD_FAB2_LIB.BASEBOARD_FAB2(SCH_1):TP_PCH_RSVD34    I73 @BASEBOARD_FAB2_LIB.BASEBOARD_FAB2(SCH_1):PAGE118
   V56 TP_PCH_RSVD33 @BASEBOARD_FAB2_LIB.BASEBOARD_FAB2(SCH_1):TP_PCH_RSVD33    I73 @BASEBOARD_FAB2_LIB.BASEBOARD_FAB2(SCH_1):PAGE118
  AA54 TP_PCH_RSVD32 @BASEBOARD_FAB2_LIB.BASEBOARD_FAB2(SCH_1):TP_PCH_RSVD32    I73 @BASEBOARD_FAB2_LIB.BASEBOARD_FAB2(SCH_1):PAGE118
   M15 TP_SLP_LAN_N @BASEBOARD_FAB2_LIB.BASEBOARD_FAB2(SCH_1):TP_SLP_LAN_N    I73 @BASEBOARD_FAB2_LIB.BASEBOARD_FAB2(SCH_1):PAGE118
    P7 FM_SLP_SUS_N @BASEBOARD_FAB2_LIB.BASEBOARD_FAB2(SCH_1):FM_SLP_SUS_N    I73 @BASEBOARD_FAB2_LIB.BASEBOARD_FAB2(SCH_1):PAGE118
  BY19 PWRGD_SYS_PWROK @BASEBOARD_FAB2_LIB.BASEBOARD_FAB2(SCH_1):PWRGD_SYS_PWROK    I73 @BASEBOARD_FAB2_LIB.BASEBOARD_FAB2(SCH_1):PAGE118
  BV19 RST_BMC_SYSRST_BTN_OUT_B_N @BASEBOARD_FAB2_LIB.BASEBOARD_FAB2(SCH_1):RST_BMC_SYSRST_BTN_OUT_B_N    I73 @BASEBOARD_FAB2_LIB.BASEBOARD_FAB2(SCH_1):PAGE118
   V15 FM_PCH_LVC1_THERMTRIP_N @BASEBOARD_FAB2_LIB.BASEBOARD_FAB2(SCH_1):FM_PCH_LVC1_THERMTRIP_N    I73 @BASEBOARD_FAB2_LIB.BASEBOARD_FAB2(SCH_1):PAGE118
    M7 TP_CPU_PCH_TRIGGER_IN @BASEBOARD_FAB2_LIB.BASEBOARD_FAB2(SCH_1):TP_CPU_PCH_TRIGGER_IN    I73 @BASEBOARD_FAB2_LIB.BASEBOARD_FAB2(SCH_1):PAGE118
   R13 TP_CPU_PCH_TRIGGER_OUT @BASEBOARD_FAB2_LIB.BASEBOARD_FAB2(SCH_1):TP_CPU_PCH_TRIGGER_OUT    I73 @BASEBOARD_FAB2_LIB.BASEBOARD_FAB2(SCH_1):PAGE118
    K9 IRQ_LVC3_WAKE_N @BASEBOARD_FAB2_LIB.BASEBOARD_FAB2(SCH_1):IRQ_LVC3_WAKE_N    I73 @BASEBOARD_FAB2_LIB.BASEBOARD_FAB2(SCH_1):PAGE118
    N3 PU_FM_RCIN_N @BASEBOARD_FAB2_LIB.BASEBOARD_FAB2(SCH_1):PU_FM_RCIN_N   I115 @BASEBOARD_FAB2_LIB.BASEBOARD_FAB2(SCH_1):PAGE119
   AA4 IRQ_VM_INT_N @BASEBOARD_FAB2_LIB.BASEBOARD_FAB2(SCH_1):IRQ_VM_INT_N   I115 @BASEBOARD_FAB2_LIB.BASEBOARD_FAB2(SCH_1):PAGE119
   AC2 PU_LPC_PME_N @BASEBOARD_FAB2_LIB.BASEBOARD_FAB2(SCH_1):PU_LPC_PME_N   I115 @BASEBOARD_FAB2_LIB.BASEBOARD_FAB2(SCH_1):PAGE119
    R1 PU_IRQ_PCH_SCI_WHEA_N @BASEBOARD_FAB2_LIB.BASEBOARD_FAB2(SCH_1):PU_IRQ_PCH_SCI_WHEA_N   I115 @BASEBOARD_FAB2_LIB.BASEBOARD_FAB2(SCH_1):PAGE119
    T4 FM_MB_SLOT_ID0 @BASEBOARD_FAB2_LIB.BASEBOARD_FAB2(SCH_1):FM_MB_SLOT_ID0   I115 @BASEBOARD_FAB2_LIB.BASEBOARD_FAB2(SCH_1):PAGE119
   AB3 FM_MB_SLOT_ID1 @BASEBOARD_FAB2_LIB.BASEBOARD_FAB2(SCH_1):FM_MB_SLOT_ID1   I115 @BASEBOARD_FAB2_LIB.BASEBOARD_FAB2(SCH_1):PAGE119
   AC4 FM_MB_SLOT_ID2 @BASEBOARD_FAB2_LIB.BASEBOARD_FAB2(SCH_1):FM_MB_SLOT_ID2   I115 @BASEBOARD_FAB2_LIB.BASEBOARD_FAB2(SCH_1):PAGE119
    T2 FM_UART_PRES_N @BASEBOARD_FAB2_LIB.BASEBOARD_FAB2(SCH_1):FM_UART_PRES_N   I115 @BASEBOARD_FAB2_LIB.BASEBOARD_FAB2(SCH_1):PAGE119
   AD1 FM_CPU_BMC_INIT @BASEBOARD_FAB2_LIB.BASEBOARD_FAB2(SCH_1):FM_CPU_BMC_INIT   I115 @BASEBOARD_FAB2_LIB.BASEBOARD_FAB2(SCH_1):PAGE119
   AD3 RST_PCH_SYSRST_BTN_OUT_N @BASEBOARD_FAB2_LIB.BASEBOARD_FAB2(SCH_1):RST_PCH_SYSRST_BTN_OUT_N   I115 @BASEBOARD_FAB2_LIB.BASEBOARD_FAB2(SCH_1):PAGE119
    V3 FM_ME_RECOVER_N @BASEBOARD_FAB2_LIB.BASEBOARD_FAB2(SCH_1):FM_ME_RECOVER_N   I115 @BASEBOARD_FAB2_LIB.BASEBOARD_FAB2(SCH_1):PAGE119
    Y3 LPC_LAD0_IO0 @BASEBOARD_FAB2_LIB.BASEBOARD_FAB2(SCH_1):LPC_LAD0_IO0   I115 @BASEBOARD_FAB2_LIB.BASEBOARD_FAB2(SCH_1):PAGE119
    W4 FM_POST_CARD_PRES_BMC_N @BASEBOARD_FAB2_LIB.BASEBOARD_FAB2(SCH_1):FM_POST_CARD_PRES_BMC_N   I115 @BASEBOARD_FAB2_LIB.BASEBOARD_FAB2(SCH_1):PAGE119
   AE2 FM_OCP_MEZZA_PRES_N @BASEBOARD_FAB2_LIB.BASEBOARD_FAB2(SCH_1):FM_OCP_MEZZA_PRES_N   I115 @BASEBOARD_FAB2_LIB.BASEBOARD_FAB2(SCH_1):PAGE119
   AE4 FM_TPM_PRES_N @BASEBOARD_FAB2_LIB.BASEBOARD_FAB2(SCH_1):FM_TPM_PRES_N   I115 @BASEBOARD_FAB2_LIB.BASEBOARD_FAB2(SCH_1):PAGE119
    V1 FM_BMC_READY_N @BASEBOARD_FAB2_LIB.BASEBOARD_FAB2(SCH_1):FM_BMC_READY_N   I115 @BASEBOARD_FAB2_LIB.BASEBOARD_FAB2(SCH_1):PAGE119
    N1 LPC_LAD1_IO1 @BASEBOARD_FAB2_LIB.BASEBOARD_FAB2(SCH_1):LPC_LAD1_IO1   I115 @BASEBOARD_FAB2_LIB.BASEBOARD_FAB2(SCH_1):PAGE119
    W2 LPC_LAD2_IO2 @BASEBOARD_FAB2_LIB.BASEBOARD_FAB2(SCH_1):LPC_LAD2_IO2   I115 @BASEBOARD_FAB2_LIB.BASEBOARD_FAB2(SCH_1):PAGE119
    Y1 LPC_LAD3_IO3 @BASEBOARD_FAB2_LIB.BASEBOARD_FAB2(SCH_1):LPC_LAD3_IO3   I115 @BASEBOARD_FAB2_LIB.BASEBOARD_FAB2(SCH_1):PAGE119
    P4 LPC_LFRAME_N_CS0_N @BASEBOARD_FAB2_LIB.BASEBOARD_FAB2(SCH_1):LPC_LFRAME_N_CS0_N   I115 @BASEBOARD_FAB2_LIB.BASEBOARD_FAB2(SCH_1):PAGE119
    P2 IRQ_LPC_SERIRQ_N @BASEBOARD_FAB2_LIB.BASEBOARD_FAB2(SCH_1):IRQ_LPC_SERIRQ_N   I115 @BASEBOARD_FAB2_LIB.BASEBOARD_FAB2(SCH_1):PAGE119
   AA2 IRQ_PIRQA_SPI_TPM_N @BASEBOARD_FAB2_LIB.BASEBOARD_FAB2(SCH_1):IRQ_PIRQA_SPI_TPM_N   I115 @BASEBOARD_FAB2_LIB.BASEBOARD_FAB2(SCH_1):PAGE119
   AB1 PU_LPC_CLKRUN_N @BASEBOARD_FAB2_LIB.BASEBOARD_FAB2(SCH_1):PU_LPC_CLKRUN_N   I115 @BASEBOARD_FAB2_LIB.BASEBOARD_FAB2(SCH_1):PAGE119
    R3 CLK_24M_BMC_LPC_R @BASEBOARD_FAB2_LIB.BASEBOARD_FAB2(SCH_1):CLK_24M_BMC_LPC_R   I115 @BASEBOARD_FAB2_LIB.BASEBOARD_FAB2(SCH_1):PAGE119
   BL7 VID_PCH_CORE_PVNN_AUX_VID_0 @BASEBOARD_FAB2_LIB.BASEBOARD_FAB2(SCH_1):VID_PCH_CORE_PVNN_AUX_VID_0   I115 @BASEBOARD_FAB2_LIB.BASEBOARD_FAB2(SCH_1):PAGE119
  BL11 RST_SYSTEM_BTN_N @BASEBOARD_FAB2_LIB.BASEBOARD_FAB2(SCH_1):RST_SYSTEM_BTN_N   I115 @BASEBOARD_FAB2_LIB.BASEBOARD_FAB2(SCH_1):PAGE119
   BK9 FM_PMBUS_ALERT_BUF_EN_N @BASEBOARD_FAB2_LIB.BASEBOARD_FAB2(SCH_1):FM_PMBUS_ALERT_BUF_EN_N   I115 @BASEBOARD_FAB2_LIB.BASEBOARD_FAB2(SCH_1):PAGE119
  BL18 FM_GLOBAL_RST_WARN_N @BASEBOARD_FAB2_LIB.BASEBOARD_FAB2(SCH_1):FM_GLOBAL_RST_WARN_N   I115 @BASEBOARD_FAB2_LIB.BASEBOARD_FAB2(SCH_1):PAGE119
  BN18 RST_PLTRST_N @BASEBOARD_FAB2_LIB.BASEBOARD_FAB2(SCH_1):RST_PLTRST_N   I115 @BASEBOARD_FAB2_LIB.BASEBOARD_FAB2(SCH_1):PAGE119
  BH13 FM_BIOS_TOP_SWAP_SPKR @BASEBOARD_FAB2_LIB.BASEBOARD_FAB2(SCH_1):FM_BIOS_TOP_SWAP_SPKR   I115 @BASEBOARD_FAB2_LIB.BASEBOARD_FAB2(SCH_1):PAGE119
  BK13 FM_UART_ALERT_N @BASEBOARD_FAB2_LIB.BASEBOARD_FAB2(SCH_1):FM_UART_ALERT_N   I115 @BASEBOARD_FAB2_LIB.BASEBOARD_FAB2(SCH_1):PAGE119
  BG22 IRQ_PCH_NIC_ALERT_N @BASEBOARD_FAB2_LIB.BASEBOARD_FAB2(SCH_1):IRQ_PCH_NIC_ALERT_N   I115 @BASEBOARD_FAB2_LIB.BASEBOARD_FAB2(SCH_1):PAGE119
  BG15 FM_PCH_PWRBTN_OUT_N @BASEBOARD_FAB2_LIB.BASEBOARD_FAB2(SCH_1):FM_PCH_PWRBTN_OUT_N   I115 @BASEBOARD_FAB2_LIB.BASEBOARD_FAB2(SCH_1):PAGE119
  BL15 FM_UV_ADR_TRIGGER_EN @BASEBOARD_FAB2_LIB.BASEBOARD_FAB2(SCH_1):FM_UV_ADR_TRIGGER_EN   I115 @BASEBOARD_FAB2_LIB.BASEBOARD_FAB2(SCH_1):PAGE119
  BK20 FM_BIOS_PREFRB2_GOOD @BASEBOARD_FAB2_LIB.BASEBOARD_FAB2(SCH_1):FM_BIOS_PREFRB2_GOOD   I115 @BASEBOARD_FAB2_LIB.BASEBOARD_FAB2(SCH_1):PAGE119
   BH9 VID_PCH_CORE_PVNN_AUX_VID_1 @BASEBOARD_FAB2_LIB.BASEBOARD_FAB2(SCH_1):VID_PCH_CORE_PVNN_AUX_VID_1   I115 @BASEBOARD_FAB2_LIB.BASEBOARD_FAB2(SCH_1):PAGE119
  BN15 PU_IRQ_VRALERT_N @BASEBOARD_FAB2_LIB.BASEBOARD_FAB2(SCH_1):PU_IRQ_VRALERT_N   I115 @BASEBOARD_FAB2_LIB.BASEBOARD_FAB2(SCH_1):PAGE119
  BJ22 FM_BIOS_POST_CMPLT_N @BASEBOARD_FAB2_LIB.BASEBOARD_FAB2(SCH_1):FM_BIOS_POST_CMPLT_N   I115 @BASEBOARD_FAB2_LIB.BASEBOARD_FAB2(SCH_1):PAGE119
  BH17 FM_FAST_PROCHOT_EN_N @BASEBOARD_FAB2_LIB.BASEBOARD_FAB2(SCH_1):FM_FAST_PROCHOT_EN_N   I115 @BASEBOARD_FAB2_LIB.BASEBOARD_FAB2(SCH_1):PAGE119
  BR17 FM_USB_P0_EN_BOOT_BIOS_STRAP_N @BASEBOARD_FAB2_LIB.BASEBOARD_FAB2(SCH_1):FM_USB_P0_EN_BOOT_BIOS_STRAP_N   I115 @BASEBOARD_FAB2_LIB.BASEBOARD_FAB2(SCH_1):PAGE119
  BM20 FM_PCH_BMC_THERMTRIP_EXI_STRAP_ @BASEBOARD_FAB2_LIB.BASEBOARD_FAB2(SCH_1):FM_PCH_BMC_THERMTRIP_EXI_STRAP_N   I115 @BASEBOARD_FAB2_LIB.BASEBOARD_FAB2(SCH_1):PAGE119
   BR9 FM_QAT_EN_N @BASEBOARD_FAB2_LIB.BASEBOARD_FAB2(SCH_1):FM_QAT_EN_N   I115 @BASEBOARD_FAB2_LIB.BASEBOARD_FAB2(SCH_1):PAGE119
   BN7 IRQ_PVDDQ_ABC_VRHOT_LVT3_N @BASEBOARD_FAB2_LIB.BASEBOARD_FAB2(SCH_1):IRQ_PVDDQ_ABC_VRHOT_LVT3_N   I115 @BASEBOARD_FAB2_LIB.BASEBOARD_FAB2(SCH_1):PAGE119
  BK17 IRQ_PVDDQ_DEF_VRHOT_LVT3_N @BASEBOARD_FAB2_LIB.BASEBOARD_FAB2(SCH_1):IRQ_PVDDQ_DEF_VRHOT_LVT3_N   I115 @BASEBOARD_FAB2_LIB.BASEBOARD_FAB2(SCH_1):PAGE119
  BG18 IRQ_PVDDQ_GHJ_VRHOT_LVT3_N @BASEBOARD_FAB2_LIB.BASEBOARD_FAB2(SCH_1):IRQ_PVDDQ_GHJ_VRHOT_LVT3_N   I115 @BASEBOARD_FAB2_LIB.BASEBOARD_FAB2(SCH_1):PAGE119
  BR13 IRQ_PVDDQ_KLM_VRHOT_LVT3_N @BASEBOARD_FAB2_LIB.BASEBOARD_FAB2(SCH_1):IRQ_PVDDQ_KLM_VRHOT_LVT3_N   I115 @BASEBOARD_FAB2_LIB.BASEBOARD_FAB2(SCH_1):PAGE119
  BN11 FP_NMI_BTN_N @BASEBOARD_FAB2_LIB.BASEBOARD_FAB2(SCH_1):FP_NMI_BTN_N   I115 @BASEBOARD_FAB2_LIB.BASEBOARD_FAB2(SCH_1):PAGE119
  BH20 FM_PWR_BTN_N @BASEBOARD_FAB2_LIB.BASEBOARD_FAB2(SCH_1):FM_PWR_BTN_N   I115 @BASEBOARD_FAB2_LIB.BASEBOARD_FAB2(SCH_1):PAGE119
  BW28 SMB_HOST_STBY_LVC3_SCL_R1 @BASEBOARD_FAB2_LIB.BASEBOARD_FAB2(SCH_1):SMB_HOST_STBY_LVC3_SCL_R1   I115 @BASEBOARD_FAB2_LIB.BASEBOARD_FAB2(SCH_1):PAGE119
  BV31 FM_PCH_SATA_RAID_KEY @BASEBOARD_FAB2_LIB.BASEBOARD_FAB2(SCH_1):FM_PCH_SATA_RAID_KEY   I115 @BASEBOARD_FAB2_LIB.BASEBOARD_FAB2(SCH_1):PAGE119
  BV33 FM_BOARD_REV_ID2 @BASEBOARD_FAB2_LIB.BASEBOARD_FAB2(SCH_1):FM_BOARD_REV_ID2   I115 @BASEBOARD_FAB2_LIB.BASEBOARD_FAB2(SCH_1):PAGE119
  CA30 FM_BOARD_REV_ID0 @BASEBOARD_FAB2_LIB.BASEBOARD_FAB2(SCH_1):FM_BOARD_REV_ID0   I115 @BASEBOARD_FAB2_LIB.BASEBOARD_FAB2(SCH_1):PAGE119
  BV38 FM_BOARD_REV_ID1 @BASEBOARD_FAB2_LIB.BASEBOARD_FAB2(SCH_1):FM_BOARD_REV_ID1   I115 @BASEBOARD_FAB2_LIB.BASEBOARD_FAB2(SCH_1):PAGE119
  BY38 IRQ_BMC_PCH_SCI_LPC_N @BASEBOARD_FAB2_LIB.BASEBOARD_FAB2(SCH_1):IRQ_BMC_PCH_SCI_LPC_N   I115 @BASEBOARD_FAB2_LIB.BASEBOARD_FAB2(SCH_1):PAGE119
  CA32 FM_SLT_CFG0 @BASEBOARD_FAB2_LIB.BASEBOARD_FAB2(SCH_1):FM_SLT_CFG0   I115 @BASEBOARD_FAB2_LIB.BASEBOARD_FAB2(SCH_1):PAGE119
  BW37 FM_SLT_CFG1 @BASEBOARD_FAB2_LIB.BASEBOARD_FAB2(SCH_1):FM_SLT_CFG1   I115 @BASEBOARD_FAB2_LIB.BASEBOARD_FAB2(SCH_1):PAGE119
  BY31 FM_SLT_CFG2_R @BASEBOARD_FAB2_LIB.BASEBOARD_FAB2(SCH_1):FM_SLT_CFG2_R   I115 @BASEBOARD_FAB2_LIB.BASEBOARD_FAB2(SCH_1):PAGE119
  BY35 FM_PMBUS_ALERT_BUF_EN_N @BASEBOARD_FAB2_LIB.BASEBOARD_FAB2(SCH_1):FM_PMBUS_ALERT_BUF_EN_N   I115 @BASEBOARD_FAB2_LIB.BASEBOARD_FAB2(SCH_1):PAGE119
  BW39 FM_BB_BMC_MP_GPIO @BASEBOARD_FAB2_LIB.BASEBOARD_FAB2(SCH_1):FM_BB_BMC_MP_GPIO   I115 @BASEBOARD_FAB2_LIB.BASEBOARD_FAB2(SCH_1):PAGE119
  BV27 SMB_HOST_STBY_LVC3_SDA_R1 @BASEBOARD_FAB2_LIB.BASEBOARD_FAB2(SCH_1):SMB_HOST_STBY_LVC3_SDA_R1   I115 @BASEBOARD_FAB2_LIB.BASEBOARD_FAB2(SCH_1):PAGE119
  CA39 FM_THROTTLE_N @BASEBOARD_FAB2_LIB.BASEBOARD_FAB2(SCH_1):FM_THROTTLE_N   I115 @BASEBOARD_FAB2_LIB.BASEBOARD_FAB2(SCH_1):PAGE119
  BY33 FM_BIOS_POST_CMPLT_N @BASEBOARD_FAB2_LIB.BASEBOARD_FAB2(SCH_1):FM_BIOS_POST_CMPLT_N   I115 @BASEBOARD_FAB2_LIB.BASEBOARD_FAB2(SCH_1):PAGE119
  CA34 IRQ_BMC_PCH_SMI_LPC_N @BASEBOARD_FAB2_LIB.BASEBOARD_FAB2(SCH_1):IRQ_BMC_PCH_SMI_LPC_N   I115 @BASEBOARD_FAB2_LIB.BASEBOARD_FAB2(SCH_1):PAGE119
  CA37 FM_CPU_CATERR_DLY_LVT3_R_N @BASEBOARD_FAB2_LIB.BASEBOARD_FAB2(SCH_1):FM_CPU_CATERR_DLY_LVT3_R_N   I115 @BASEBOARD_FAB2_LIB.BASEBOARD_FAB2(SCH_1):PAGE119
  BY27 PU_PCH_TLS_ENABLE_STRAP @BASEBOARD_FAB2_LIB.BASEBOARD_FAB2(SCH_1):PU_PCH_TLS_ENABLE_STRAP   I115 @BASEBOARD_FAB2_LIB.BASEBOARD_FAB2(SCH_1):PAGE119
  BV29 SMB_SMLINK0_STBY_LVC3_SCL_R1 @BASEBOARD_FAB2_LIB.BASEBOARD_FAB2(SCH_1):SMB_SMLINK0_STBY_LVC3_SCL_R1   I115 @BASEBOARD_FAB2_LIB.BASEBOARD_FAB2(SCH_1):PAGE119
  BW30 SMB_SMLINK0_STBY_LVC3_SDA_R1 @BASEBOARD_FAB2_LIB.BASEBOARD_FAB2(SCH_1):SMB_SMLINK0_STBY_LVC3_SDA_R1   I115 @BASEBOARD_FAB2_LIB.BASEBOARD_FAB2(SCH_1):PAGE119
  BW34 IRQ_SML0_ALERT_N @BASEBOARD_FAB2_LIB.BASEBOARD_FAB2(SCH_1):IRQ_SML0_ALERT_N   I115 @BASEBOARD_FAB2_LIB.BASEBOARD_FAB2(SCH_1):PAGE119
  CA28 SMB_PMBUS_BMC_STBY_LVC3_SCL_R1 @BASEBOARD_FAB2_LIB.BASEBOARD_FAB2(SCH_1):SMB_PMBUS_BMC_STBY_LVC3_SCL_R1   I115 @BASEBOARD_FAB2_LIB.BASEBOARD_FAB2(SCH_1):PAGE119
  BV35 SMB_PMBUS_BMC_STBY_LVC3_SDA_R1 @BASEBOARD_FAB2_LIB.BASEBOARD_FAB2(SCH_1):SMB_PMBUS_BMC_STBY_LVC3_SDA_R1   I115 @BASEBOARD_FAB2_LIB.BASEBOARD_FAB2(SCH_1):PAGE119
  BW32 FM_PASSWORD_CLEAR_N @BASEBOARD_FAB2_LIB.BASEBOARD_FAB2(SCH_1):FM_PASSWORD_CLEAR_N   I115 @BASEBOARD_FAB2_LIB.BASEBOARD_FAB2(SCH_1):PAGE119
  BY29 FM_CPU1_RC_EN @BASEBOARD_FAB2_LIB.BASEBOARD_FAB2(SCH_1):FM_CPU1_RC_EN   I115 @BASEBOARD_FAB2_LIB.BASEBOARD_FAB2(SCH_1):PAGE119
  BR42 IRQ_BMC_PCH_NMI_STBY_R_N @BASEBOARD_FAB2_LIB.BASEBOARD_FAB2(SCH_1):IRQ_BMC_PCH_NMI_STBY_R_N   I115 @BASEBOARD_FAB2_LIB.BASEBOARD_FAB2(SCH_1):PAGE119
  BK46 FM_PWR_LED_N @BASEBOARD_FAB2_LIB.BASEBOARD_FAB2(SCH_1):FM_PWR_LED_N   I115 @BASEBOARD_FAB2_LIB.BASEBOARD_FAB2(SCH_1):PAGE119
  BV47 H_CPU0_FAST_WAKE_LVT3_N @BASEBOARD_FAB2_LIB.BASEBOARD_FAB2(SCH_1):H_CPU0_FAST_WAKE_LVT3_N   I115 @BASEBOARD_FAB2_LIB.BASEBOARD_FAB2(SCH_1):PAGE119
  BY47 IRQ_LOM_ALERT_N @BASEBOARD_FAB2_LIB.BASEBOARD_FAB2(SCH_1):IRQ_LOM_ALERT_N   I115 @BASEBOARD_FAB2_LIB.BASEBOARD_FAB2(SCH_1):PAGE119
  BN40 TP_PCH_GPP_D12 @BASEBOARD_FAB2_LIB.BASEBOARD_FAB2(SCH_1):TP_PCH_GPP_D12   I115 @BASEBOARD_FAB2_LIB.BASEBOARD_FAB2(SCH_1):PAGE119
  BY44 SMB_SLOTX24_STBY_LVC3_SCL_R1 @BASEBOARD_FAB2_LIB.BASEBOARD_FAB2(SCH_1):SMB_SLOTX24_STBY_LVC3_SCL_R1   I115 @BASEBOARD_FAB2_LIB.BASEBOARD_FAB2(SCH_1):PAGE119
  BL44 SMB_SLOTX24_STBY_LVC3_SDA_R1 @BASEBOARD_FAB2_LIB.BASEBOARD_FAB2(SCH_1):SMB_SLOTX24_STBY_LVC3_SDA_R1   I115 @BASEBOARD_FAB2_LIB.BASEBOARD_FAB2(SCH_1):PAGE119
  BW43 SGPIO_PCH_SSATA_DOUT0 @BASEBOARD_FAB2_LIB.BASEBOARD_FAB2(SCH_1):SGPIO_PCH_SSATA_DOUT0   I115 @BASEBOARD_FAB2_LIB.BASEBOARD_FAB2(SCH_1):PAGE119
  BV42 IRQ_OOB_MGMT_RISER_ALERT_N @BASEBOARD_FAB2_LIB.BASEBOARD_FAB2(SCH_1):IRQ_OOB_MGMT_RISER_ALERT_N   I115 @BASEBOARD_FAB2_LIB.BASEBOARD_FAB2(SCH_1):PAGE119
  BW48 FM_XRC_PRESENT_N @BASEBOARD_FAB2_LIB.BASEBOARD_FAB2(SCH_1):FM_XRC_PRESENT_N   I115 @BASEBOARD_FAB2_LIB.BASEBOARD_FAB2(SCH_1):PAGE119
  CA41 FM_XRC_READY_N @BASEBOARD_FAB2_LIB.BASEBOARD_FAB2(SCH_1):FM_XRC_READY_N   I115 @BASEBOARD_FAB2_LIB.BASEBOARD_FAB2(SCH_1):PAGE119
  CA43 FM_ADR_MODE_SEL_R @BASEBOARD_FAB2_LIB.BASEBOARD_FAB2(SCH_1):FM_ADR_MODE_SEL_R   I115 @BASEBOARD_FAB2_LIB.BASEBOARD_FAB2(SCH_1):PAGE119
  BJ44 IRQ_HSC_FAULT_N @BASEBOARD_FAB2_LIB.BASEBOARD_FAB2(SCH_1):IRQ_HSC_FAULT_N   I115 @BASEBOARD_FAB2_LIB.BASEBOARD_FAB2(SCH_1):PAGE119
  CA48 FM_BMC_HEARTBEAT_N @BASEBOARD_FAB2_LIB.BASEBOARD_FAB2(SCH_1):FM_BMC_HEARTBEAT_N   I115 @BASEBOARD_FAB2_LIB.BASEBOARD_FAB2(SCH_1):PAGE119
  BV44 SP2_BMC_CM_UART_RX @BASEBOARD_FAB2_LIB.BASEBOARD_FAB2(SCH_1):SP2_BMC_CM_UART_RX   I115 @BASEBOARD_FAB2_LIB.BASEBOARD_FAB2(SCH_1):PAGE119
  BR46 SP2_BMC_CM_UART_TX @BASEBOARD_FAB2_LIB.BASEBOARD_FAB2(SCH_1):SP2_BMC_CM_UART_TX   I115 @BASEBOARD_FAB2_LIB.BASEBOARD_FAB2(SCH_1):PAGE119
  BN44 FM_CPU0_THERMTRIP_LATCH_LVT3_N @BASEBOARD_FAB2_LIB.BASEBOARD_FAB2(SCH_1):FM_CPU0_THERMTRIP_LATCH_LVT3_N   I115 @BASEBOARD_FAB2_LIB.BASEBOARD_FAB2(SCH_1):PAGE119
  BW45 IRQ_MEZZ_LAN_ALERT_N @BASEBOARD_FAB2_LIB.BASEBOARD_FAB2(SCH_1):IRQ_MEZZ_LAN_ALERT_N   I115 @BASEBOARD_FAB2_LIB.BASEBOARD_FAB2(SCH_1):PAGE119
  BM42 FM_PCH_PLD_DATA_R @BASEBOARD_FAB2_LIB.BASEBOARD_FAB2(SCH_1):FM_PCH_PLD_DATA_R   I115 @BASEBOARD_FAB2_LIB.BASEBOARD_FAB2(SCH_1):PAGE119
  BM38 FM_BMC_ENABLE_N @BASEBOARD_FAB2_LIB.BASEBOARD_FAB2(SCH_1):FM_BMC_ENABLE_N   I115 @BASEBOARD_FAB2_LIB.BASEBOARD_FAB2(SCH_1):PAGE119
  BW41 FM_CPLD_BMC_PWRDN_N @BASEBOARD_FAB2_LIB.BASEBOARD_FAB2(SCH_1):FM_CPLD_BMC_PWRDN_N   I115 @BASEBOARD_FAB2_LIB.BASEBOARD_FAB2(SCH_1):PAGE119
  CA45 FM_BMC_CPLD_GPO @BASEBOARD_FAB2_LIB.BASEBOARD_FAB2(SCH_1):FM_BMC_CPLD_GPO   I115 @BASEBOARD_FAB2_LIB.BASEBOARD_FAB2(SCH_1):PAGE119
  BR38 FM_BMC_FAULT_LED_N @BASEBOARD_FAB2_LIB.BASEBOARD_FAB2(SCH_1):FM_BMC_FAULT_LED_N   I115 @BASEBOARD_FAB2_LIB.BASEBOARD_FAB2(SCH_1):PAGE119
  BY42 IRQ_FORCE_NM_THROTTLE_N @BASEBOARD_FAB2_LIB.BASEBOARD_FAB2(SCH_1):IRQ_FORCE_NM_THROTTLE_N   I115 @BASEBOARD_FAB2_LIB.BASEBOARD_FAB2(SCH_1):PAGE119
  BY25 A_RCOMP_3P3 @BASEBOARD_FAB2_LIB.BASEBOARD_FAB2(SCH_1):A_RCOMP_3P3   I147 @BASEBOARD_FAB2_LIB.BASEBOARD_FAB2(SCH_1):PAGE120
  BH50 FM_CPU0_RC_ERROR_N @BASEBOARD_FAB2_LIB.BASEBOARD_FAB2(SCH_1):FM_CPU0_RC_ERROR_N   I147 @BASEBOARD_FAB2_LIB.BASEBOARD_FAB2(SCH_1):PAGE120
  BN48 IRQ_BMC_PCH_SCI_LPC_N @BASEBOARD_FAB2_LIB.BASEBOARD_FAB2(SCH_1):IRQ_BMC_PCH_SCI_LPC_N   I147 @BASEBOARD_FAB2_LIB.BASEBOARD_FAB2(SCH_1):PAGE120
  AW54 IRQ_BMC_PCH_SMI_LPC_N @BASEBOARD_FAB2_LIB.BASEBOARD_FAB2(SCH_1):IRQ_BMC_PCH_SMI_LPC_N   I147 @BASEBOARD_FAB2_LIB.BASEBOARD_FAB2(SCH_1):PAGE120
  AU58 IRQ_UV_DETECT_N @BASEBOARD_FAB2_LIB.BASEBOARD_FAB2(SCH_1):IRQ_UV_DETECT_N   I147 @BASEBOARD_FAB2_LIB.BASEBOARD_FAB2(SCH_1):PAGE120
  AY52 FM_CPU1_RC_ERROR_N @BASEBOARD_FAB2_LIB.BASEBOARD_FAB2(SCH_1):FM_CPU1_RC_ERROR_N   I147 @BASEBOARD_FAB2_LIB.BASEBOARD_FAB2(SCH_1):PAGE120
  BG52 FM_POST_CARD_PRES_BMC_N @BASEBOARD_FAB2_LIB.BASEBOARD_FAB2(SCH_1):FM_POST_CARD_PRES_BMC_N   I147 @BASEBOARD_FAB2_LIB.BASEBOARD_FAB2(SCH_1):PAGE120
  BE52 FM_CPLD_ADR_TRIGGER_R_N @BASEBOARD_FAB2_LIB.BASEBOARD_FAB2(SCH_1):FM_CPLD_ADR_TRIGGER_R_N   I147 @BASEBOARD_FAB2_LIB.BASEBOARD_FAB2(SCH_1):PAGE120
  AV52 FM_CPU_ERR2_LVT3_N @BASEBOARD_FAB2_LIB.BASEBOARD_FAB2(SCH_1):FM_CPU_ERR2_LVT3_N   I147 @BASEBOARD_FAB2_LIB.BASEBOARD_FAB2(SCH_1):PAGE120
  AT52 FM_CPU_MSMI_LVT3_N @BASEBOARD_FAB2_LIB.BASEBOARD_FAB2(SCH_1):FM_CPU_MSMI_LVT3_N   I147 @BASEBOARD_FAB2_LIB.BASEBOARD_FAB2(SCH_1):PAGE120
  BB52 IRQ_BMC_PCH_NMI_STBY_N @BASEBOARD_FAB2_LIB.BASEBOARD_FAB2(SCH_1):IRQ_BMC_PCH_NMI_STBY_N   I147 @BASEBOARD_FAB2_LIB.BASEBOARD_FAB2(SCH_1):PAGE120
  BJ48 FM_ADR_SMI_GPIO_N @BASEBOARD_FAB2_LIB.BASEBOARD_FAB2(SCH_1):FM_ADR_SMI_GPIO_N   I147 @BASEBOARD_FAB2_LIB.BASEBOARD_FAB2(SCH_1):PAGE120
  AV56 LED_PCH_SATA_HDD_N @BASEBOARD_FAB2_LIB.BASEBOARD_FAB2(SCH_1):LED_PCH_SATA_HDD_N   I147 @BASEBOARD_FAB2_LIB.BASEBOARD_FAB2(SCH_1):PAGE120
  BL48 FM_OC0_USB_N @BASEBOARD_FAB2_LIB.BASEBOARD_FAB2(SCH_1):FM_OC0_USB_N   I147 @BASEBOARD_FAB2_LIB.BASEBOARD_FAB2(SCH_1):PAGE120
   AG7 IRQ_OC_DETECT_N @BASEBOARD_FAB2_LIB.BASEBOARD_FAB2(SCH_1):IRQ_OC_DETECT_N   I147 @BASEBOARD_FAB2_LIB.BASEBOARD_FAB2(SCH_1):PAGE120
   AL7 SGPIO_PCH_SATA_CLOCK @BASEBOARD_FAB2_LIB.BASEBOARD_FAB2(SCH_1):SGPIO_PCH_SATA_CLOCK   I147 @BASEBOARD_FAB2_LIB.BASEBOARD_FAB2(SCH_1):PAGE120
   AR9 SGPIO_PCH_SATA_LOAD @BASEBOARD_FAB2_LIB.BASEBOARD_FAB2(SCH_1):SGPIO_PCH_SATA_LOAD   I147 @BASEBOARD_FAB2_LIB.BASEBOARD_FAB2(SCH_1):PAGE120
   AP7 TP_PCH_GPP_F12 @BASEBOARD_FAB2_LIB.BASEBOARD_FAB2(SCH_1):TP_PCH_GPP_F12   I147 @BASEBOARD_FAB2_LIB.BASEBOARD_FAB2(SCH_1):PAGE120
  AP11 SGPIO_PCH_SATA_DOUT0 @BASEBOARD_FAB2_LIB.BASEBOARD_FAB2(SCH_1):SGPIO_PCH_SATA_DOUT0   I147 @BASEBOARD_FAB2_LIB.BASEBOARD_FAB2(SCH_1):PAGE120
  AL11 LED_PCH_SSATA_HDD_N @BASEBOARD_FAB2_LIB.BASEBOARD_FAB2(SCH_1):LED_PCH_SSATA_HDD_N   I147 @BASEBOARD_FAB2_LIB.BASEBOARD_FAB2(SCH_1):PAGE120
  AR13 FM_FORCE_ADR_N @BASEBOARD_FAB2_LIB.BASEBOARD_FAB2(SCH_1):FM_FORCE_ADR_N   I147 @BASEBOARD_FAB2_LIB.BASEBOARD_FAB2(SCH_1):PAGE120
  AU13 FM_IE_DISABLE_N @BASEBOARD_FAB2_LIB.BASEBOARD_FAB2(SCH_1):FM_IE_DISABLE_N   I147 @BASEBOARD_FAB2_LIB.BASEBOARD_FAB2(SCH_1):PAGE120
  AP15 FM_BIOS_TOP_SWAP @BASEBOARD_FAB2_LIB.BASEBOARD_FAB2(SCH_1):FM_BIOS_TOP_SWAP   I147 @BASEBOARD_FAB2_LIB.BASEBOARD_FAB2(SCH_1):PAGE120
  AL15 FM_MEM_THERM_EVENT_PCH_N @BASEBOARD_FAB2_LIB.BASEBOARD_FAB2(SCH_1):FM_MEM_THERM_EVENT_PCH_N   I147 @BASEBOARD_FAB2_LIB.BASEBOARD_FAB2(SCH_1):PAGE120
   AU9 SMB_LAN_STBY_LVC3_SCL_R2 @BASEBOARD_FAB2_LIB.BASEBOARD_FAB2(SCH_1):SMB_LAN_STBY_LVC3_SCL_R2   I147 @BASEBOARD_FAB2_LIB.BASEBOARD_FAB2(SCH_1):PAGE120
   AK9 FM_HSC_TIMER_EXP_N @BASEBOARD_FAB2_LIB.BASEBOARD_FAB2(SCH_1):FM_HSC_TIMER_EXP_N   I147 @BASEBOARD_FAB2_LIB.BASEBOARD_FAB2(SCH_1):PAGE120
  AU20 SMB_LAN_STBY_LVC3_SDA_R2 @BASEBOARD_FAB2_LIB.BASEBOARD_FAB2(SCH_1):SMB_LAN_STBY_LVC3_SDA_R2   I147 @BASEBOARD_FAB2_LIB.BASEBOARD_FAB2(SCH_1):PAGE120
  AR17 IRQ_PCH_NIC_ALERT_N @BASEBOARD_FAB2_LIB.BASEBOARD_FAB2(SCH_1):IRQ_PCH_NIC_ALERT_N   I147 @BASEBOARD_FAB2_LIB.BASEBOARD_FAB2(SCH_1):PAGE120
  AP18 SGPIO_PCH_SSATA_CLOCK @BASEBOARD_FAB2_LIB.BASEBOARD_FAB2(SCH_1):SGPIO_PCH_SSATA_CLOCK   I147 @BASEBOARD_FAB2_LIB.BASEBOARD_FAB2(SCH_1):PAGE120
  AU17 SGPIO_PCH_SSATA_LOAD @BASEBOARD_FAB2_LIB.BASEBOARD_FAB2(SCH_1):SGPIO_PCH_SSATA_LOAD   I147 @BASEBOARD_FAB2_LIB.BASEBOARD_FAB2(SCH_1):PAGE120
  AK20 FM_MP_PS_FAIL_N @BASEBOARD_FAB2_LIB.BASEBOARD_FAB2(SCH_1):FM_MP_PS_FAIL_N   I147 @BASEBOARD_FAB2_LIB.BASEBOARD_FAB2(SCH_1):PAGE120
  AK13 FM_MP_PS_REDUNDANT_LOST_N @BASEBOARD_FAB2_LIB.BASEBOARD_FAB2(SCH_1):FM_MP_PS_REDUNDANT_LOST_N   I147 @BASEBOARD_FAB2_LIB.BASEBOARD_FAB2(SCH_1):PAGE120
  AH13 FM_BMC_READY_N @BASEBOARD_FAB2_LIB.BASEBOARD_FAB2(SCH_1):FM_BMC_READY_N   I147 @BASEBOARD_FAB2_LIB.BASEBOARD_FAB2(SCH_1):PAGE120
  AH17 FM_BIOS_USB_RECOVERY @BASEBOARD_FAB2_LIB.BASEBOARD_FAB2(SCH_1):FM_BIOS_USB_RECOVERY   I147 @BASEBOARD_FAB2_LIB.BASEBOARD_FAB2(SCH_1):PAGE120
  AL18 JTAG_PCH_PLD_TCK @BASEBOARD_FAB2_LIB.BASEBOARD_FAB2(SCH_1):JTAG_PCH_PLD_TCK   I147 @BASEBOARD_FAB2_LIB.BASEBOARD_FAB2(SCH_1):PAGE120
  AK17 JTAG_PCH_PLD_TDI @BASEBOARD_FAB2_LIB.BASEBOARD_FAB2(SCH_1):JTAG_PCH_PLD_TDI   I147 @BASEBOARD_FAB2_LIB.BASEBOARD_FAB2(SCH_1):PAGE120
   AH9 JTAG_PCH_PLD_TMS @BASEBOARD_FAB2_LIB.BASEBOARD_FAB2(SCH_1):JTAG_PCH_PLD_TMS   I147 @BASEBOARD_FAB2_LIB.BASEBOARD_FAB2(SCH_1):PAGE120
  AR20 JTAG_PCH_PLD_TDO @BASEBOARD_FAB2_LIB.BASEBOARD_FAB2(SCH_1):JTAG_PCH_PLD_TDO   I147 @BASEBOARD_FAB2_LIB.BASEBOARD_FAB2(SCH_1):PAGE120
  AY11 FAN_TACH0 @BASEBOARD_FAB2_LIB.BASEBOARD_FAB2(SCH_1):FAN_TACH0   I147 @BASEBOARD_FAB2_LIB.BASEBOARD_FAB2(SCH_1):PAGE120
  BE11 FM_CPU0_FIVR_FAULT_LVT3_N @BASEBOARD_FAB2_LIB.BASEBOARD_FAB2(SCH_1):FM_CPU0_FIVR_FAULT_LVT3_N   I147 @BASEBOARD_FAB2_LIB.BASEBOARD_FAB2(SCH_1):PAGE120
  BA20 FM_CPU1_FIVR_FAULT_LVT3_N @BASEBOARD_FAB2_LIB.BASEBOARD_FAB2(SCH_1):FM_CPU1_FIVR_FAULT_LVT3_N   I147 @BASEBOARD_FAB2_LIB.BASEBOARD_FAB2(SCH_1):PAGE120
  BD13 FM_BOARD_SKU_ID0 @BASEBOARD_FAB2_LIB.BASEBOARD_FAB2(SCH_1):FM_BOARD_SKU_ID0   I147 @BASEBOARD_FAB2_LIB.BASEBOARD_FAB2(SCH_1):PAGE120
  AY18 FM_BOARD_SKU_ID1 @BASEBOARD_FAB2_LIB.BASEBOARD_FAB2(SCH_1):FM_BOARD_SKU_ID1   I147 @BASEBOARD_FAB2_LIB.BASEBOARD_FAB2(SCH_1):PAGE120
   AV7 FM_BOARD_SKU_ID2 @BASEBOARD_FAB2_LIB.BASEBOARD_FAB2(SCH_1):FM_BOARD_SKU_ID2   I147 @BASEBOARD_FAB2_LIB.BASEBOARD_FAB2(SCH_1):PAGE120
  BE18 FM_BOARD_SKU_ID3 @BASEBOARD_FAB2_LIB.BASEBOARD_FAB2(SCH_1):FM_BOARD_SKU_ID3   I147 @BASEBOARD_FAB2_LIB.BASEBOARD_FAB2(SCH_1):PAGE120
  BD17 FM_BOARD_SKU_ID4 @BASEBOARD_FAB2_LIB.BASEBOARD_FAB2(SCH_1):FM_BOARD_SKU_ID4   I147 @BASEBOARD_FAB2_LIB.BASEBOARD_FAB2(SCH_1):PAGE120
   BD9 FM_ADR_COMPLETE_R1 @BASEBOARD_FAB2_LIB.BASEBOARD_FAB2(SCH_1):FM_ADR_COMPLETE_R1   I147 @BASEBOARD_FAB2_LIB.BASEBOARD_FAB2(SCH_1):PAGE120
   BE7 FM_NMI_EVENT_N @BASEBOARD_FAB2_LIB.BASEBOARD_FAB2(SCH_1):FM_NMI_EVENT_N   I147 @BASEBOARD_FAB2_LIB.BASEBOARD_FAB2(SCH_1):PAGE120
  BE15 FM_BIOS_SMI_ACTIVE_N @BASEBOARD_FAB2_LIB.BASEBOARD_FAB2(SCH_1):FM_BIOS_SMI_ACTIVE_N   I147 @BASEBOARD_FAB2_LIB.BASEBOARD_FAB2(SCH_1):PAGE120
  AV15 FAN_TACH1 @BASEBOARD_FAB2_LIB.BASEBOARD_FAB2(SCH_1):FAN_TACH1   I147 @BASEBOARD_FAB2_LIB.BASEBOARD_FAB2(SCH_1):PAGE120
  BA17 IRQ_FORCE_NM_THROTTLE_N @BASEBOARD_FAB2_LIB.BASEBOARD_FAB2(SCH_1):IRQ_FORCE_NM_THROTTLE_N   I147 @BASEBOARD_FAB2_LIB.BASEBOARD_FAB2(SCH_1):PAGE120
   BG7 FM_SOL_UART_CH_SEL @BASEBOARD_FAB2_LIB.BASEBOARD_FAB2(SCH_1):FM_SOL_UART_CH_SEL   I147 @BASEBOARD_FAB2_LIB.BASEBOARD_FAB2(SCH_1):PAGE120
  BD20 FM_CPU0_RC_EN @BASEBOARD_FAB2_LIB.BASEBOARD_FAB2(SCH_1):FM_CPU0_RC_EN   I147 @BASEBOARD_FAB2_LIB.BASEBOARD_FAB2(SCH_1):PAGE120
  BA13 FM_UARTSW_MSB_N @BASEBOARD_FAB2_LIB.BASEBOARD_FAB2(SCH_1):FM_UARTSW_MSB_N   I147 @BASEBOARD_FAB2_LIB.BASEBOARD_FAB2(SCH_1):PAGE120
  BE22 FAN_TACH2 @BASEBOARD_FAB2_LIB.BASEBOARD_FAB2(SCH_1):FAN_TACH2   I147 @BASEBOARD_FAB2_LIB.BASEBOARD_FAB2(SCH_1):PAGE120
   AY7 FAN_TACH3 @BASEBOARD_FAB2_LIB.BASEBOARD_FAB2(SCH_1):FAN_TACH3   I147 @BASEBOARD_FAB2_LIB.BASEBOARD_FAB2(SCH_1):PAGE120
   BA9 IRQ_PVCCIN_CPU0_VRHOT_LVC3_N @BASEBOARD_FAB2_LIB.BASEBOARD_FAB2(SCH_1):IRQ_PVCCIN_CPU0_VRHOT_LVC3_N   I147 @BASEBOARD_FAB2_LIB.BASEBOARD_FAB2(SCH_1):PAGE120
  AW20 IRQ_PVCCIN_CPU1_VRHOT_LVC3_N @BASEBOARD_FAB2_LIB.BASEBOARD_FAB2(SCH_1):IRQ_PVCCIN_CPU1_VRHOT_LVC3_N   I147 @BASEBOARD_FAB2_LIB.BASEBOARD_FAB2(SCH_1):PAGE120
  AV18 FM_CPU1_THERMTRIP_LATCH_LVT3_N @BASEBOARD_FAB2_LIB.BASEBOARD_FAB2(SCH_1):FM_CPU1_THERMTRIP_LATCH_LVT3_N   I147 @BASEBOARD_FAB2_LIB.BASEBOARD_FAB2(SCH_1):PAGE120
  AY15 FM_THROTTLE_N @BASEBOARD_FAB2_LIB.BASEBOARD_FAB2(SCH_1):FM_THROTTLE_N   I147 @BASEBOARD_FAB2_LIB.BASEBOARD_FAB2(SCH_1):PAGE120
  BG11 FAN_PWM_OUT_SYS0 @BASEBOARD_FAB2_LIB.BASEBOARD_FAB2(SCH_1):FAN_PWM_OUT_SYS0   I147 @BASEBOARD_FAB2_LIB.BASEBOARD_FAB2(SCH_1):PAGE120
  AV11 FAN_PWM_OUT_SYS1 @BASEBOARD_FAB2_LIB.BASEBOARD_FAB2(SCH_1):FAN_PWM_OUT_SYS1   I147 @BASEBOARD_FAB2_LIB.BASEBOARD_FAB2(SCH_1):PAGE120
   AT4 FM_UARTSW_LSB_N @BASEBOARD_FAB2_LIB.BASEBOARD_FAB2(SCH_1):FM_UARTSW_LSB_N   I147 @BASEBOARD_FAB2_LIB.BASEBOARD_FAB2(SCH_1):PAGE120
   BA4 SMB_VR_STBY_LVC3_SCL_R1 @BASEBOARD_FAB2_LIB.BASEBOARD_FAB2(SCH_1):SMB_VR_STBY_LVC3_SCL_R1   I147 @BASEBOARD_FAB2_LIB.BASEBOARD_FAB2(SCH_1):PAGE120
   BD1 SMB_VR_STBY_LVC3_SDA_R1 @BASEBOARD_FAB2_LIB.BASEBOARD_FAB2(SCH_1):SMB_VR_STBY_LVC3_SDA_R1   I147 @BASEBOARD_FAB2_LIB.BASEBOARD_FAB2(SCH_1):PAGE120
   BB1 FM_FLASH_ATTACH_CFG_STRAP @BASEBOARD_FAB2_LIB.BASEBOARD_FAB2(SCH_1):FM_FLASH_ATTACH_CFG_STRAP   I147 @BASEBOARD_FAB2_LIB.BASEBOARD_FAB2(SCH_1):PAGE120
   AY1 SMB_SENSOR_STBY_LVC3_SCL_R1 @BASEBOARD_FAB2_LIB.BASEBOARD_FAB2(SCH_1):SMB_SENSOR_STBY_LVC3_SCL_R1   I147 @BASEBOARD_FAB2_LIB.BASEBOARD_FAB2(SCH_1):PAGE120
   BC2 SMB_SENSOR_STBY_LVC3_SDA_R1 @BASEBOARD_FAB2_LIB.BASEBOARD_FAB2(SCH_1):SMB_SENSOR_STBY_LVC3_SDA_R1   I147 @BASEBOARD_FAB2_LIB.BASEBOARD_FAB2(SCH_1):PAGE120
   BB3 PU_ADR_TIMER_HOLD_OFF_N @BASEBOARD_FAB2_LIB.BASEBOARD_FAB2(SCH_1):PU_ADR_TIMER_HOLD_OFF_N   I147 @BASEBOARD_FAB2_LIB.BASEBOARD_FAB2(SCH_1):PAGE120
   BF1 SMB_LAN_STBY_LVC3_SCL_R1 @BASEBOARD_FAB2_LIB.BASEBOARD_FAB2(SCH_1):SMB_LAN_STBY_LVC3_SCL_R1   I147 @BASEBOARD_FAB2_LIB.BASEBOARD_FAB2(SCH_1):PAGE120
   BE4 SMB_LAN_STBY_LVC3_SDA_R1 @BASEBOARD_FAB2_LIB.BASEBOARD_FAB2(SCH_1):SMB_LAN_STBY_LVC3_SDA_R1   I147 @BASEBOARD_FAB2_LIB.BASEBOARD_FAB2(SCH_1):PAGE120
   BC4 FM_OC_DETECT_EN_N @BASEBOARD_FAB2_LIB.BASEBOARD_FAB2(SCH_1):FM_OC_DETECT_EN_N   I147 @BASEBOARD_FAB2_LIB.BASEBOARD_FAB2(SCH_1):PAGE120
   BD3 FP_PWR_ID_LED_N @BASEBOARD_FAB2_LIB.BASEBOARD_FAB2(SCH_1):FP_PWR_ID_LED_N   I147 @BASEBOARD_FAB2_LIB.BASEBOARD_FAB2(SCH_1):PAGE120
   AW4 FM_BACKUP_BIOS_SEL_N @BASEBOARD_FAB2_LIB.BASEBOARD_FAB2(SCH_1):FM_BACKUP_BIOS_SEL_N   I147 @BASEBOARD_FAB2_LIB.BASEBOARD_FAB2(SCH_1):PAGE120
   BF3 FM_BMC_NMI_N @BASEBOARD_FAB2_LIB.BASEBOARD_FAB2(SCH_1):FM_BMC_NMI_N   I147 @BASEBOARD_FAB2_LIB.BASEBOARD_FAB2(SCH_1):PAGE120
   BA2 FM_BIOS_SMI_ACTIVE_N @BASEBOARD_FAB2_LIB.BASEBOARD_FAB2(SCH_1):FM_BIOS_SMI_ACTIVE_N   I147 @BASEBOARD_FAB2_LIB.BASEBOARD_FAB2(SCH_1):PAGE120
   BH2 FM_PCH_BMC_THERMTRIP_N @BASEBOARD_FAB2_LIB.BASEBOARD_FAB2(SCH_1):FM_PCH_BMC_THERMTRIP_N   I147 @BASEBOARD_FAB2_LIB.BASEBOARD_FAB2(SCH_1):PAGE120
   BH4 FM_SSATA_PCIE_M2_SEL @BASEBOARD_FAB2_LIB.BASEBOARD_FAB2(SCH_1):FM_SSATA_PCIE_M2_SEL   I147 @BASEBOARD_FAB2_LIB.BASEBOARD_FAB2(SCH_1):PAGE120
   AV3 LED_POSTCODE_0 @BASEBOARD_FAB2_LIB.BASEBOARD_FAB2(SCH_1):LED_POSTCODE_0   I147 @BASEBOARD_FAB2_LIB.BASEBOARD_FAB2(SCH_1):PAGE120
   AR1 LED_POSTCODE_1 @BASEBOARD_FAB2_LIB.BASEBOARD_FAB2(SCH_1):LED_POSTCODE_1   I147 @BASEBOARD_FAB2_LIB.BASEBOARD_FAB2(SCH_1):PAGE120
   AT2 LED_POSTCODE_2 @BASEBOARD_FAB2_LIB.BASEBOARD_FAB2(SCH_1):LED_POSTCODE_2   I147 @BASEBOARD_FAB2_LIB.BASEBOARD_FAB2(SCH_1):PAGE120
   AY3 LED_POSTCODE_3 @BASEBOARD_FAB2_LIB.BASEBOARD_FAB2(SCH_1):LED_POSTCODE_3   I147 @BASEBOARD_FAB2_LIB.BASEBOARD_FAB2(SCH_1):PAGE120
   AW2 LED_POSTCODE_4 @BASEBOARD_FAB2_LIB.BASEBOARD_FAB2(SCH_1):LED_POSTCODE_4   I147 @BASEBOARD_FAB2_LIB.BASEBOARD_FAB2(SCH_1):PAGE120
   AV1 LED_POSTCODE_5 @BASEBOARD_FAB2_LIB.BASEBOARD_FAB2(SCH_1):LED_POSTCODE_5   I147 @BASEBOARD_FAB2_LIB.BASEBOARD_FAB2(SCH_1):PAGE120
   AR3 LED_POSTCODE_6 @BASEBOARD_FAB2_LIB.BASEBOARD_FAB2(SCH_1):LED_POSTCODE_6   I147 @BASEBOARD_FAB2_LIB.BASEBOARD_FAB2(SCH_1):PAGE120
   BE2 LED_POSTCODE_7 @BASEBOARD_FAB2_LIB.BASEBOARD_FAB2(SCH_1):LED_POSTCODE_7   I147 @BASEBOARD_FAB2_LIB.BASEBOARD_FAB2(SCH_1):PAGE120
  CA20 JTAG_PCH_GBE_TDO @BASEBOARD_FAB2_LIB.BASEBOARD_FAB2(SCH_1):JTAG_PCH_GBE_TDO   I147 @BASEBOARD_FAB2_LIB.BASEBOARD_FAB2(SCH_1):PAGE120
  BV25 FM_BIOS_MRC_DEBUG_MSG_DIS_N @BASEBOARD_FAB2_LIB.BASEBOARD_FAB2(SCH_1):FM_BIOS_MRC_DEBUG_MSG_DIS_N   I147 @BASEBOARD_FAB2_LIB.BASEBOARD_FAB2(SCH_1):PAGE120
  BV21 JTAG_PCH_GBE_CLK @BASEBOARD_FAB2_LIB.BASEBOARD_FAB2(SCH_1):JTAG_PCH_GBE_CLK   I147 @BASEBOARD_FAB2_LIB.BASEBOARD_FAB2(SCH_1):PAGE120
  CA22 JTAG_PCH_GBE_TMS @BASEBOARD_FAB2_LIB.BASEBOARD_FAB2(SCH_1):JTAG_PCH_GBE_TMS   I147 @BASEBOARD_FAB2_LIB.BASEBOARD_FAB2(SCH_1):PAGE120
  BY23 JTAG_PCH_GBE_TDI @BASEBOARD_FAB2_LIB.BASEBOARD_FAB2(SCH_1):JTAG_PCH_GBE_TDI   I147 @BASEBOARD_FAB2_LIB.BASEBOARD_FAB2(SCH_1):PAGE120
  BW20 IRQ_DIMM_SAVE_LVT3_N @BASEBOARD_FAB2_LIB.BASEBOARD_FAB2(SCH_1):IRQ_DIMM_SAVE_LVT3_N   I147 @BASEBOARD_FAB2_LIB.BASEBOARD_FAB2(SCH_1):PAGE120
  BW24 IRQ_BOARD_BMC_ALERT_N @BASEBOARD_FAB2_LIB.BASEBOARD_FAB2(SCH_1):IRQ_BOARD_BMC_ALERT_N   I147 @BASEBOARD_FAB2_LIB.BASEBOARD_FAB2(SCH_1):PAGE120
  BV23 FM_CPU1_RC_ERROR_N @BASEBOARD_FAB2_LIB.BASEBOARD_FAB2(SCH_1):FM_CPU1_RC_ERROR_N   I147 @BASEBOARD_FAB2_LIB.BASEBOARD_FAB2(SCH_1):PAGE120
  CA24 JTAG_PCH_GBE_TRST_N @BASEBOARD_FAB2_LIB.BASEBOARD_FAB2(SCH_1):JTAG_PCH_GBE_TRST_N   I147 @BASEBOARD_FAB2_LIB.BASEBOARD_FAB2(SCH_1):PAGE120
  BW22 PU_10GBE_LOM_PCI_DISABLE_N @BASEBOARD_FAB2_LIB.BASEBOARD_FAB2(SCH_1):PU_10GBE_LOM_PCI_DISABLE_N   I147 @BASEBOARD_FAB2_LIB.BASEBOARD_FAB2(SCH_1):PAGE120
  BY21 FM_10GBE_LOM_DISABLE_N @BASEBOARD_FAB2_LIB.BASEBOARD_FAB2(SCH_1):FM_10GBE_LOM_DISABLE_N   I147 @BASEBOARD_FAB2_LIB.BASEBOARD_FAB2(SCH_1):PAGE120
   BL1 LED_GBE_P0_0 @BASEBOARD_FAB2_LIB.BASEBOARD_FAB2(SCH_1):LED_GBE_P0_0   I147 @BASEBOARD_FAB2_LIB.BASEBOARD_FAB2(SCH_1):PAGE120
   BW5 SMB_PCH_MEZZ_LOM1_SCL @BASEBOARD_FAB2_LIB.BASEBOARD_FAB2(SCH_1):SMB_PCH_MEZZ_LOM1_SCL   I147 @BASEBOARD_FAB2_LIB.BASEBOARD_FAB2(SCH_1):PAGE120
   BV8 SMB_PCH_MEZZ_LOM1_SDA @BASEBOARD_FAB2_LIB.BASEBOARD_FAB2(SCH_1):SMB_PCH_MEZZ_LOM1_SDA   I147 @BASEBOARD_FAB2_LIB.BASEBOARD_FAB2(SCH_1):PAGE120
   BT5 SMB_PCH_MEZZ_LOM2_SCL @BASEBOARD_FAB2_LIB.BASEBOARD_FAB2(SCH_1):SMB_PCH_MEZZ_LOM2_SCL   I147 @BASEBOARD_FAB2_LIB.BASEBOARD_FAB2(SCH_1):PAGE120
  BW11 SMB_PCH_MEZZ_LOM2_SDA @BASEBOARD_FAB2_LIB.BASEBOARD_FAB2(SCH_1):SMB_PCH_MEZZ_LOM2_SDA   I147 @BASEBOARD_FAB2_LIB.BASEBOARD_FAB2(SCH_1):PAGE120
   BW6 SMB_PCH_MEZZ_LOM3_SCL @BASEBOARD_FAB2_LIB.BASEBOARD_FAB2(SCH_1):SMB_PCH_MEZZ_LOM3_SCL   I147 @BASEBOARD_FAB2_LIB.BASEBOARD_FAB2(SCH_1):PAGE120
   BW9 SMB_PCH_MEZZ_LOM3_SDA @BASEBOARD_FAB2_LIB.BASEBOARD_FAB2(SCH_1):SMB_PCH_MEZZ_LOM3_SDA   I147 @BASEBOARD_FAB2_LIB.BASEBOARD_FAB2(SCH_1):PAGE120
  BV10 FM_GBE0_LVC3_MOD_ABS @BASEBOARD_FAB2_LIB.BASEBOARD_FAB2(SCH_1):FM_GBE0_LVC3_MOD_ABS   I147 @BASEBOARD_FAB2_LIB.BASEBOARD_FAB2(SCH_1):PAGE120
  CA11 TP_PCH_GPP_J17 @BASEBOARD_FAB2_LIB.BASEBOARD_FAB2(SCH_1):TP_PCH_GPP_J17   I147 @BASEBOARD_FAB2_LIB.BASEBOARD_FAB2(SCH_1):PAGE120
  BY10 FM_GBE1_LVC3_MOD_ABS @BASEBOARD_FAB2_LIB.BASEBOARD_FAB2(SCH_1):FM_GBE1_LVC3_MOD_ABS   I147 @BASEBOARD_FAB2_LIB.BASEBOARD_FAB2(SCH_1):PAGE120
  BY14 TP_PCH_GPP_J19 @BASEBOARD_FAB2_LIB.BASEBOARD_FAB2(SCH_1):TP_PCH_GPP_J19   I147 @BASEBOARD_FAB2_LIB.BASEBOARD_FAB2(SCH_1):PAGE120
   BK4 LED_GBE_P0_1 @BASEBOARD_FAB2_LIB.BASEBOARD_FAB2(SCH_1):LED_GBE_P0_1   I147 @BASEBOARD_FAB2_LIB.BASEBOARD_FAB2(SCH_1):PAGE120
  BW13 FM_GBE2_LVC3_MOD_ABS @BASEBOARD_FAB2_LIB.BASEBOARD_FAB2(SCH_1):FM_GBE2_LVC3_MOD_ABS   I147 @BASEBOARD_FAB2_LIB.BASEBOARD_FAB2(SCH_1):PAGE120
  BV12 TP_PCH_GPP_J21 @BASEBOARD_FAB2_LIB.BASEBOARD_FAB2(SCH_1):TP_PCH_GPP_J21   I147 @BASEBOARD_FAB2_LIB.BASEBOARD_FAB2(SCH_1):PAGE120
  BY12 FM_GBE3_LVC3_MOD_ABS @BASEBOARD_FAB2_LIB.BASEBOARD_FAB2(SCH_1):FM_GBE3_LVC3_MOD_ABS   I147 @BASEBOARD_FAB2_LIB.BASEBOARD_FAB2(SCH_1):PAGE120
  BV14 TP_PCH_GPP_J23 @BASEBOARD_FAB2_LIB.BASEBOARD_FAB2(SCH_1):TP_PCH_GPP_J23   I147 @BASEBOARD_FAB2_LIB.BASEBOARD_FAB2(SCH_1):PAGE120
   BP4 LED_GBE_P1_0 @BASEBOARD_FAB2_LIB.BASEBOARD_FAB2(SCH_1):LED_GBE_P1_0   I147 @BASEBOARD_FAB2_LIB.BASEBOARD_FAB2(SCH_1):PAGE120
   BK2 LED_GBE_P1_1 @BASEBOARD_FAB2_LIB.BASEBOARD_FAB2(SCH_1):LED_GBE_P1_1   I147 @BASEBOARD_FAB2_LIB.BASEBOARD_FAB2(SCH_1):PAGE120
   BL3 LED_GBE_P2_0 @BASEBOARD_FAB2_LIB.BASEBOARD_FAB2(SCH_1):LED_GBE_P2_0   I147 @BASEBOARD_FAB2_LIB.BASEBOARD_FAB2(SCH_1):PAGE120
   BU6 LED_GBE_P2_1 @BASEBOARD_FAB2_LIB.BASEBOARD_FAB2(SCH_1):LED_GBE_P2_1   I147 @BASEBOARD_FAB2_LIB.BASEBOARD_FAB2(SCH_1):PAGE120
  CA13 LED_GBE_P3_0 @BASEBOARD_FAB2_LIB.BASEBOARD_FAB2(SCH_1):LED_GBE_P3_0   I147 @BASEBOARD_FAB2_LIB.BASEBOARD_FAB2(SCH_1):PAGE120
   BM2 LED_GBE_P3_1 @BASEBOARD_FAB2_LIB.BASEBOARD_FAB2(SCH_1):LED_GBE_P3_1   I147 @BASEBOARD_FAB2_LIB.BASEBOARD_FAB2(SCH_1):PAGE120
   BM4 SMB_PCH_MEZZ_LOM0_SCL @BASEBOARD_FAB2_LIB.BASEBOARD_FAB2(SCH_1):SMB_PCH_MEZZ_LOM0_SCL   I147 @BASEBOARD_FAB2_LIB.BASEBOARD_FAB2(SCH_1):PAGE120
   BN3 SMB_PCH_MEZZ_LOM0_SDA @BASEBOARD_FAB2_LIB.BASEBOARD_FAB2(SCH_1):SMB_PCH_MEZZ_LOM0_SDA   I147 @BASEBOARD_FAB2_LIB.BASEBOARD_FAB2(SCH_1):PAGE120
   C70 FM_PCH_PRSNT_N @BASEBOARD_FAB2_LIB.BASEBOARD_FAB2(SCH_1):FM_PCH_PRSNT_N    I34 @BASEBOARD_FAB2_LIB.BASEBOARD_FAB2(SCH_1):PAGE121
   AM4 A_1P8_3P3_RCOMP @BASEBOARD_FAB2_LIB.BASEBOARD_FAB2(SCH_1):A_1P8_3P3_RCOMP    I34 @BASEBOARD_FAB2_LIB.BASEBOARD_FAB2(SCH_1):PAGE121
   AJ1 CLK_50M_CKMNG_PCH_10GBE @BASEBOARD_FAB2_LIB.BASEBOARD_FAB2(SCH_1):CLK_50M_CKMNG_PCH_10GBE    I34 @BASEBOARD_FAB2_LIB.BASEBOARD_FAB2(SCH_1):PAGE121
   AH4 RST_PCIE_PCH_PERST_N @BASEBOARD_FAB2_LIB.BASEBOARD_FAB2(SCH_1):RST_PCIE_PCH_PERST_N    I34 @BASEBOARD_FAB2_LIB.BASEBOARD_FAB2(SCH_1):PAGE121
   AM2 RMII_BMC_PCH_SPRNGVLLE_TXD0 @BASEBOARD_FAB2_LIB.BASEBOARD_FAB2(SCH_1):RMII_BMC_PCH_SPRNGVLLE_TXD0    I34 @BASEBOARD_FAB2_LIB.BASEBOARD_FAB2(SCH_1):PAGE121
   AK2 RMII_BMC_PCH_SPRNGVLLE_TXD1 @BASEBOARD_FAB2_LIB.BASEBOARD_FAB2(SCH_1):RMII_BMC_PCH_SPRNGVLLE_TXD1    I34 @BASEBOARD_FAB2_LIB.BASEBOARD_FAB2(SCH_1):PAGE121
   AL3 RMII_BMC_PCH_SPRNGVLLE_TXEN @BASEBOARD_FAB2_LIB.BASEBOARD_FAB2(SCH_1):RMII_BMC_PCH_SPRNGVLLE_TXEN    I34 @BASEBOARD_FAB2_LIB.BASEBOARD_FAB2(SCH_1):PAGE121
   AN3 RMII_BMC_PCH_SPRNGVLLE_CRSDV_R1 @BASEBOARD_FAB2_LIB.BASEBOARD_FAB2(SCH_1):RMII_BMC_PCH_SPRNGVLLE_CRSDV_R1    I34 @BASEBOARD_FAB2_LIB.BASEBOARD_FAB2(SCH_1):PAGE121
   AL1 RMII_SPRNGVLLE_BMC_PCH_RXD0_R1 @BASEBOARD_FAB2_LIB.BASEBOARD_FAB2(SCH_1):RMII_SPRNGVLLE_BMC_PCH_RXD0_R1    I34 @BASEBOARD_FAB2_LIB.BASEBOARD_FAB2(SCH_1):PAGE121
   AN1 RMII_SPRNGVLLE_BMC_PCH_RXD1_R1 @BASEBOARD_FAB2_LIB.BASEBOARD_FAB2(SCH_1):RMII_SPRNGVLLE_BMC_PCH_RXD1_R1    I34 @BASEBOARD_FAB2_LIB.BASEBOARD_FAB2(SCH_1):PAGE121
   AH2 RMII_BMC_PCH_SPRNGVLLE_RXER_R @BASEBOARD_FAB2_LIB.BASEBOARD_FAB2(SCH_1):RMII_BMC_PCH_SPRNGVLLE_RXER_R    I34 @BASEBOARD_FAB2_LIB.BASEBOARD_FAB2(SCH_1):PAGE121
   AJ3 RMII_PCH_SPRNGVLLE_ARB_IN @BASEBOARD_FAB2_LIB.BASEBOARD_FAB2(SCH_1):RMII_PCH_SPRNGVLLE_ARB_IN    I34 @BASEBOARD_FAB2_LIB.BASEBOARD_FAB2(SCH_1):PAGE121
   AK4 RMII_PCH_SPRNGVLLE_ARB_OUT_R @BASEBOARD_FAB2_LIB.BASEBOARD_FAB2(SCH_1):RMII_PCH_SPRNGVLLE_ARB_OUT_R    I34 @BASEBOARD_FAB2_LIB.BASEBOARD_FAB2(SCH_1):PAGE121
  AF20 TP_PCH_GPP_L10 @BASEBOARD_FAB2_LIB.BASEBOARD_FAB2(SCH_1):TP_PCH_GPP_L10    I34 @BASEBOARD_FAB2_LIB.BASEBOARD_FAB2(SCH_1):PAGE121
  AD20 TP_PCH_GPP_L11 @BASEBOARD_FAB2_LIB.BASEBOARD_FAB2(SCH_1):TP_PCH_GPP_L11    I34 @BASEBOARD_FAB2_LIB.BASEBOARD_FAB2(SCH_1):PAGE121
   Y15 H_CPU0_MEMABC_MEMHOT_PCH_N @BASEBOARD_FAB2_LIB.BASEBOARD_FAB2(SCH_1):H_CPU0_MEMABC_MEMHOT_PCH_N    I34 @BASEBOARD_FAB2_LIB.BASEBOARD_FAB2(SCH_1):PAGE121
  AD13 H_CPU0_MEMDEF_MEMHOT_PCH_N @BASEBOARD_FAB2_LIB.BASEBOARD_FAB2(SCH_1):H_CPU0_MEMDEF_MEMHOT_PCH_N    I34 @BASEBOARD_FAB2_LIB.BASEBOARD_FAB2(SCH_1):PAGE121
  AA13 H_CPU1_MEMGHJ_MEMHOT_PCH_N @BASEBOARD_FAB2_LIB.BASEBOARD_FAB2(SCH_1):H_CPU1_MEMGHJ_MEMHOT_PCH_N    I34 @BASEBOARD_FAB2_LIB.BASEBOARD_FAB2(SCH_1):PAGE121
   Y11 H_CPU1_MEMKLM_MEMHOT_PCH_N @BASEBOARD_FAB2_LIB.BASEBOARD_FAB2(SCH_1):H_CPU1_MEMKLM_MEMHOT_PCH_N    I34 @BASEBOARD_FAB2_LIB.BASEBOARD_FAB2(SCH_1):PAGE121
    Y7 FM_CPU0_PROCHOT_PCH_N @BASEBOARD_FAB2_LIB.BASEBOARD_FAB2(SCH_1):FM_CPU0_PROCHOT_PCH_N    I34 @BASEBOARD_FAB2_LIB.BASEBOARD_FAB2(SCH_1):PAGE121
   AA9 FM_CPU1_PROCHOT_PCH_N @BASEBOARD_FAB2_LIB.BASEBOARD_FAB2(SCH_1):FM_CPU1_PROCHOT_PCH_N    I34 @BASEBOARD_FAB2_LIB.BASEBOARD_FAB2(SCH_1):PAGE121
   AE7 FM_CPU_ERR0_PCH_N @BASEBOARD_FAB2_LIB.BASEBOARD_FAB2(SCH_1):FM_CPU_ERR0_PCH_N    I34 @BASEBOARD_FAB2_LIB.BASEBOARD_FAB2(SCH_1):PAGE121
  AG11 FM_CPU_ERR1_PCH_N @BASEBOARD_FAB2_LIB.BASEBOARD_FAB2(SCH_1):FM_CPU_ERR1_PCH_N    I34 @BASEBOARD_FAB2_LIB.BASEBOARD_FAB2(SCH_1):PAGE121
  AE18 FM_PRSNT_2_1_N @BASEBOARD_FAB2_LIB.BASEBOARD_FAB2(SCH_1):FM_PRSNT_2_1_N    I34 @BASEBOARD_FAB2_LIB.BASEBOARD_FAB2(SCH_1):PAGE121
  AE15 FM_PRSNT_2_2_N @BASEBOARD_FAB2_LIB.BASEBOARD_FAB2(SCH_1):FM_PRSNT_2_2_N    I34 @BASEBOARD_FAB2_LIB.BASEBOARD_FAB2(SCH_1):PAGE121
  AE11 FM_PRSNT_2_3_N @BASEBOARD_FAB2_LIB.BASEBOARD_FAB2(SCH_1):FM_PRSNT_2_3_N    I34 @BASEBOARD_FAB2_LIB.BASEBOARD_FAB2(SCH_1):PAGE121
   Y18 FM_PRSNT_2_4_N @BASEBOARD_FAB2_LIB.BASEBOARD_FAB2(SCH_1):FM_PRSNT_2_4_N    I34 @BASEBOARD_FAB2_LIB.BASEBOARD_FAB2(SCH_1):PAGE121
  AA20 FM_PRSNT_2_5_N @BASEBOARD_FAB2_LIB.BASEBOARD_FAB2(SCH_1):FM_PRSNT_2_5_N    I34 @BASEBOARD_FAB2_LIB.BASEBOARD_FAB2(SCH_1):PAGE121
  AA17 FM_PRSNT_2_6_N @BASEBOARD_FAB2_LIB.BASEBOARD_FAB2(SCH_1):FM_PRSNT_2_6_N    I34 @BASEBOARD_FAB2_LIB.BASEBOARD_FAB2(SCH_1):PAGE121
   AD9 FM_OCP_MEZZB_PRES_N @BASEBOARD_FAB2_LIB.BASEBOARD_FAB2(SCH_1):FM_OCP_MEZZB_PRES_N    I34 @BASEBOARD_FAB2_LIB.BASEBOARD_FAB2(SCH_1):PAGE121
  AD17 FM_OCP_MEZZC_PRES_N @BASEBOARD_FAB2_LIB.BASEBOARD_FAB2(SCH_1):FM_OCP_MEZZC_PRES_N    I34 @BASEBOARD_FAB2_LIB.BASEBOARD_FAB2(SCH_1):PAGE121
   P18 TP_PCH_HDA_BCLK @BASEBOARD_FAB2_LIB.BASEBOARD_FAB2(SCH_1):TP_PCH_HDA_BCLK    I34 @BASEBOARD_FAB2_LIB.BASEBOARD_FAB2(SCH_1):PAGE121
   M18 TP_PCH_HSA_RST_N @BASEBOARD_FAB2_LIB.BASEBOARD_FAB2(SCH_1):TP_PCH_HSA_RST_N    I34 @BASEBOARD_FAB2_LIB.BASEBOARD_FAB2(SCH_1):PAGE121
   K20 TP_PCH_HDA_SDI_0 @BASEBOARD_FAB2_LIB.BASEBOARD_FAB2(SCH_1):TP_PCH_HDA_SDI_0    I34 @BASEBOARD_FAB2_LIB.BASEBOARD_FAB2(SCH_1):PAGE121
   V18 TP_PCH_HDA_SDI_1 @BASEBOARD_FAB2_LIB.BASEBOARD_FAB2(SCH_1):TP_PCH_HDA_SDI_1    I34 @BASEBOARD_FAB2_LIB.BASEBOARD_FAB2(SCH_1):PAGE121
   U24 FM_FLASH_DESC_OVERRIDE @BASEBOARD_FAB2_LIB.BASEBOARD_FAB2(SCH_1):FM_FLASH_DESC_OVERRIDE    I34 @BASEBOARD_FAB2_LIB.BASEBOARD_FAB2(SCH_1):PAGE121
   H20 TP_PCH_HDA_SYNC @BASEBOARD_FAB2_LIB.BASEBOARD_FAB2(SCH_1):TP_PCH_HDA_SYNC    I34 @BASEBOARD_FAB2_LIB.BASEBOARD_FAB2(SCH_1):PAGE121
  AG18 FM_INTRUDER_HDR_PCH_N @BASEBOARD_FAB2_LIB.BASEBOARD_FAB2(SCH_1):FM_INTRUDER_HDR_PCH_N    I34 @BASEBOARD_FAB2_LIB.BASEBOARD_FAB2(SCH_1):PAGE121
   V22 TP_PCH_DISPA_SDO @BASEBOARD_FAB2_LIB.BASEBOARD_FAB2(SCH_1):TP_PCH_DISPA_SDO    I34 @BASEBOARD_FAB2_LIB.BASEBOARD_FAB2(SCH_1):PAGE121
   R20 TP_PCH_DISPA_SDI @BASEBOARD_FAB2_LIB.BASEBOARD_FAB2(SCH_1):TP_PCH_DISPA_SDI    I34 @BASEBOARD_FAB2_LIB.BASEBOARD_FAB2(SCH_1):PAGE121
   U20 TP_PCH_DISPA_BCLK @BASEBOARD_FAB2_LIB.BASEBOARD_FAB2(SCH_1):TP_PCH_DISPA_BCLK    I34 @BASEBOARD_FAB2_LIB.BASEBOARD_FAB2(SCH_1):PAGE121
   BW3 TP_PCH_RSVD46 @BASEBOARD_FAB2_LIB.BASEBOARD_FAB2(SCH_1):TP_PCH_RSVD46    I34 @BASEBOARD_FAB2_LIB.BASEBOARD_FAB2(SCH_1):PAGE121
  BG26 TP_PCH_RSVD27 @BASEBOARD_FAB2_LIB.BASEBOARD_FAB2(SCH_1):TP_PCH_RSVD27    I34 @BASEBOARD_FAB2_LIB.BASEBOARD_FAB2(SCH_1):PAGE121
  BH24 TP_PCH_RSVD26 @BASEBOARD_FAB2_LIB.BASEBOARD_FAB2(SCH_1):TP_PCH_RSVD26    I34 @BASEBOARD_FAB2_LIB.BASEBOARD_FAB2(SCH_1):PAGE121
   P48 TP_PCH_RSVD25 @BASEBOARD_FAB2_LIB.BASEBOARD_FAB2(SCH_1):TP_PCH_RSVD25    I34 @BASEBOARD_FAB2_LIB.BASEBOARD_FAB2(SCH_1):PAGE121
   P44 TP_PCH_RSVD24 @BASEBOARD_FAB2_LIB.BASEBOARD_FAB2(SCH_1):TP_PCH_RSVD24    I34 @BASEBOARD_FAB2_LIB.BASEBOARD_FAB2(SCH_1):PAGE121
   P40 TP_PCH_RSVD23 @BASEBOARD_FAB2_LIB.BASEBOARD_FAB2(SCH_1):TP_PCH_RSVD23    I34 @BASEBOARD_FAB2_LIB.BASEBOARD_FAB2(SCH_1):PAGE121
  AT71 TP_PCH_RSVD22 @BASEBOARD_FAB2_LIB.BASEBOARD_FAB2(SCH_1):TP_PCH_RSVD22    I34 @BASEBOARD_FAB2_LIB.BASEBOARD_FAB2(SCH_1):PAGE121
   A11 TP_PCH_RSVD21 @BASEBOARD_FAB2_LIB.BASEBOARD_FAB2(SCH_1):TP_PCH_RSVD21    I34 @BASEBOARD_FAB2_LIB.BASEBOARD_FAB2(SCH_1):PAGE121
   D10 TP_PCH_RSVD20 @BASEBOARD_FAB2_LIB.BASEBOARD_FAB2(SCH_1):TP_PCH_RSVD20    I34 @BASEBOARD_FAB2_LIB.BASEBOARD_FAB2(SCH_1):PAGE121
    C9 TP_PCH_RSVD19 @BASEBOARD_FAB2_LIB.BASEBOARD_FAB2(SCH_1):TP_PCH_RSVD19    I34 @BASEBOARD_FAB2_LIB.BASEBOARD_FAB2(SCH_1):PAGE121
   C11 TP_PCH_RSVD18 @BASEBOARD_FAB2_LIB.BASEBOARD_FAB2(SCH_1):TP_PCH_RSVD18    I34 @BASEBOARD_FAB2_LIB.BASEBOARD_FAB2(SCH_1):PAGE121
   B10 TP_PCH_RSVD17 @BASEBOARD_FAB2_LIB.BASEBOARD_FAB2(SCH_1):TP_PCH_RSVD17    I34 @BASEBOARD_FAB2_LIB.BASEBOARD_FAB2(SCH_1):PAGE121
    C5 TP_PCH_RSVD16 @BASEBOARD_FAB2_LIB.BASEBOARD_FAB2(SCH_1):TP_PCH_RSVD16    I34 @BASEBOARD_FAB2_LIB.BASEBOARD_FAB2(SCH_1):PAGE121
    C6 TP_PCH_RSVD15 @BASEBOARD_FAB2_LIB.BASEBOARD_FAB2(SCH_1):TP_PCH_RSVD15    I34 @BASEBOARD_FAB2_LIB.BASEBOARD_FAB2(SCH_1):PAGE121
   E18 TP_PCH_RSVD14 @BASEBOARD_FAB2_LIB.BASEBOARD_FAB2(SCH_1):TP_PCH_RSVD14    I34 @BASEBOARD_FAB2_LIB.BASEBOARD_FAB2(SCH_1):PAGE121
   C67 TP_PCH_RSVD13 @BASEBOARD_FAB2_LIB.BASEBOARD_FAB2(SCH_1):TP_PCH_RSVD13    I34 @BASEBOARD_FAB2_LIB.BASEBOARD_FAB2(SCH_1):PAGE121
   C68 TP_PCH_RSVD12 @BASEBOARD_FAB2_LIB.BASEBOARD_FAB2(SCH_1):TP_PCH_RSVD12    I34 @BASEBOARD_FAB2_LIB.BASEBOARD_FAB2(SCH_1):PAGE121
   C18 FM_SINT_PRSNT_N @BASEBOARD_FAB2_LIB.BASEBOARD_FAB2(SCH_1):FM_SINT_PRSNT_N    I34 @BASEBOARD_FAB2_LIB.BASEBOARD_FAB2(SCH_1):PAGE121
    D8 FM_WBG_PRSNT_N @BASEBOARD_FAB2_LIB.BASEBOARD_FAB2(SCH_1):FM_WBG_PRSNT_N    I34 @BASEBOARD_FAB2_LIB.BASEBOARD_FAB2(SCH_1):PAGE121
   F66 TP_PCH_RSVD9 @BASEBOARD_FAB2_LIB.BASEBOARD_FAB2(SCH_1):TP_PCH_RSVD9    I34 @BASEBOARD_FAB2_LIB.BASEBOARD_FAB2(SCH_1):PAGE121
   F69 TP_PCH_RSVD8 @BASEBOARD_FAB2_LIB.BASEBOARD_FAB2(SCH_1):TP_PCH_RSVD8    I34 @BASEBOARD_FAB2_LIB.BASEBOARD_FAB2(SCH_1):PAGE121
    F8 TP_PCH_RSVD7 @BASEBOARD_FAB2_LIB.BASEBOARD_FAB2(SCH_1):TP_PCH_RSVD7    I34 @BASEBOARD_FAB2_LIB.BASEBOARD_FAB2(SCH_1):PAGE121
  AT69 TP_PCH_RSVD6 @BASEBOARD_FAB2_LIB.BASEBOARD_FAB2(SCH_1):TP_PCH_RSVD6    I34 @BASEBOARD_FAB2_LIB.BASEBOARD_FAB2(SCH_1):PAGE121
  AG15 TP_PCH_RSVD5 @BASEBOARD_FAB2_LIB.BASEBOARD_FAB2(SCH_1):TP_PCH_RSVD5    I34 @BASEBOARD_FAB2_LIB.BASEBOARD_FAB2(SCH_1):PAGE121
   P37 TP_PCH_RSVD4 @BASEBOARD_FAB2_LIB.BASEBOARD_FAB2(SCH_1):TP_PCH_RSVD4    I34 @BASEBOARD_FAB2_LIB.BASEBOARD_FAB2(SCH_1):PAGE121
   V11 TP_PCH_RSVD3 @BASEBOARD_FAB2_LIB.BASEBOARD_FAB2(SCH_1):TP_PCH_RSVD3    I34 @BASEBOARD_FAB2_LIB.BASEBOARD_FAB2(SCH_1):PAGE121
  AA58 TP_PCH_RSVD2 @BASEBOARD_FAB2_LIB.BASEBOARD_FAB2(SCH_1):TP_PCH_RSVD2    I34 @BASEBOARD_FAB2_LIB.BASEBOARD_FAB2(SCH_1):PAGE121
  AC56 TP_PCH_RSVD1 @BASEBOARD_FAB2_LIB.BASEBOARD_FAB2(SCH_1):TP_PCH_RSVD1    I34 @BASEBOARD_FAB2_LIB.BASEBOARD_FAB2(SCH_1):PAGE121
  AF61 TP_PCH_RSVD0 @BASEBOARD_FAB2_LIB.BASEBOARD_FAB2(SCH_1):TP_PCH_RSVD0    I34 @BASEBOARD_FAB2_LIB.BASEBOARD_FAB2(SCH_1):PAGE121
   P11 RST_RTCRST_N @BASEBOARD_FAB2_LIB.BASEBOARD_FAB2(SCH_1):RST_RTCRST_N    I34 @BASEBOARD_FAB2_LIB.BASEBOARD_FAB2(SCH_1):PAGE121
    K2 SPI_PCH_CLK @BASEBOARD_FAB2_LIB.BASEBOARD_FAB2(SCH_1):SPI_PCH_CLK    I34 @BASEBOARD_FAB2_LIB.BASEBOARD_FAB2(SCH_1):PAGE121
    J3 SPI_PCH_CS0_R_N @BASEBOARD_FAB2_LIB.BASEBOARD_FAB2(SCH_1):SPI_PCH_CS0_R_N    I34 @BASEBOARD_FAB2_LIB.BASEBOARD_FAB2(SCH_1):PAGE121
    G7 TP_SPI_PCH_CS1_R1_N @BASEBOARD_FAB2_LIB.BASEBOARD_FAB2(SCH_1):TP_SPI_PCH_CS1_R1_N    I34 @BASEBOARD_FAB2_LIB.BASEBOARD_FAB2(SCH_1):PAGE121
    F5 SPI_PCH_IO2 @BASEBOARD_FAB2_LIB.BASEBOARD_FAB2(SCH_1):SPI_PCH_IO2    I34 @BASEBOARD_FAB2_LIB.BASEBOARD_FAB2(SCH_1):PAGE121
    L1 SPI_PCH_IO3 @BASEBOARD_FAB2_LIB.BASEBOARD_FAB2(SCH_1):SPI_PCH_IO3    I34 @BASEBOARD_FAB2_LIB.BASEBOARD_FAB2(SCH_1):PAGE121
    L3 SPI_PCH_MISO @BASEBOARD_FAB2_LIB.BASEBOARD_FAB2(SCH_1):SPI_PCH_MISO    I34 @BASEBOARD_FAB2_LIB.BASEBOARD_FAB2(SCH_1):PAGE121
    H4 SPI_PCH_MOSI_R @BASEBOARD_FAB2_LIB.BASEBOARD_FAB2(SCH_1):SPI_PCH_MOSI_R    I34 @BASEBOARD_FAB2_LIB.BASEBOARD_FAB2(SCH_1):PAGE121
    K4 SPI_PCH_TPM_CS_N @BASEBOARD_FAB2_LIB.BASEBOARD_FAB2(SCH_1):SPI_PCH_TPM_CS_N    I34 @BASEBOARD_FAB2_LIB.BASEBOARD_FAB2(SCH_1):PAGE121
   G18 RST_SRTCRST_N @BASEBOARD_FAB2_LIB.BASEBOARD_FAB2(SCH_1):RST_SRTCRST_N    I34 @BASEBOARD_FAB2_LIB.BASEBOARD_FAB2(SCH_1):PAGE121
  AT27 TP_PCH_RSVD59 @BASEBOARD_FAB2_LIB.BASEBOARD_FAB2(SCH_1):TP_PCH_RSVD59    I63 @BASEBOARD_FAB2_LIB.BASEBOARD_FAB2(SCH_1):PAGE122
  AP27 TP_PCH_RSVD58 @BASEBOARD_FAB2_LIB.BASEBOARD_FAB2(SCH_1):TP_PCH_RSVD58    I63 @BASEBOARD_FAB2_LIB.BASEBOARD_FAB2(SCH_1):PAGE122
   P29 TP_PCH_RSVD31 @BASEBOARD_FAB2_LIB.BASEBOARD_FAB2(SCH_1):TP_PCH_RSVD31    I63 @BASEBOARD_FAB2_LIB.BASEBOARD_FAB2(SCH_1):PAGE122
   R31 TP_PCH_RSVD30 @BASEBOARD_FAB2_LIB.BASEBOARD_FAB2(SCH_1):TP_PCH_RSVD30    I63 @BASEBOARD_FAB2_LIB.BASEBOARD_FAB2(SCH_1):PAGE122
   P33 TP_PCH_RSVD29 @BASEBOARD_FAB2_LIB.BASEBOARD_FAB2(SCH_1):TP_PCH_RSVD29    I63 @BASEBOARD_FAB2_LIB.BASEBOARD_FAB2(SCH_1):PAGE122
   R35 TP_PCH_RSVD28 @BASEBOARD_FAB2_LIB.BASEBOARD_FAB2(SCH_1):TP_PCH_RSVD28    I63 @BASEBOARD_FAB2_LIB.BASEBOARD_FAB2(SCH_1):PAGE122
  AE46 P1V05_PCH_STBY_ISCLK_PLL @BASEBOARD_FAB2_LIB.BASEBOARD_FAB2(SCH_1):P1V05_PCH_STBY_ISCLK_PLL    I63 @BASEBOARD_FAB2_LIB.BASEBOARD_FAB2(SCH_1):PAGE122
  AJ48 P1V05_PCH_STBY_ISCLK_PLL @BASEBOARD_FAB2_LIB.BASEBOARD_FAB2(SCH_1):P1V05_PCH_STBY_ISCLK_PLL    I63 @BASEBOARD_FAB2_LIB.BASEBOARD_FAB2(SCH_1):PAGE122
  AJ46 P1V05_PCH_STBY_ISCLK_PLL @BASEBOARD_FAB2_LIB.BASEBOARD_FAB2(SCH_1):P1V05_PCH_STBY_ISCLK_PLL    I63 @BASEBOARD_FAB2_LIB.BASEBOARD_FAB2(SCH_1):PAGE122
  AG45 P1V05_PCH_STBY_ISCLK_PLL @BASEBOARD_FAB2_LIB.BASEBOARD_FAB2(SCH_1):P1V05_PCH_STBY_ISCLK_PLL    I63 @BASEBOARD_FAB2_LIB.BASEBOARD_FAB2(SCH_1):PAGE122
   W50 P1V05_PCH_STBY_ISCLK_PLL @BASEBOARD_FAB2_LIB.BASEBOARD_FAB2(SCH_1):P1V05_PCH_STBY_ISCLK_PLL    I63 @BASEBOARD_FAB2_LIB.BASEBOARD_FAB2(SCH_1):PAGE122
   U50 P1V05_PCH_STBY @BASEBOARD_FAB2_LIB.BASEBOARD_FAB2(SCH_1):P1V05_PCH_STBY    I63 @BASEBOARD_FAB2_LIB.BASEBOARD_FAB2(SCH_1):PAGE122
  AH50 P1V05_PCH_STBY @BASEBOARD_FAB2_LIB.BASEBOARD_FAB2(SCH_1):P1V05_PCH_STBY    I63 @BASEBOARD_FAB2_LIB.BASEBOARD_FAB2(SCH_1):PAGE122
  AD50 P1V05_PCH_STBY_VCCA_XTAL @BASEBOARD_FAB2_LIB.BASEBOARD_FAB2(SCH_1):P1V05_PCH_STBY_VCCA_XTAL    I63 @BASEBOARD_FAB2_LIB.BASEBOARD_FAB2(SCH_1):PAGE122
  AG48 P1V05_PCH_STBY_VCCA_PLL0 @BASEBOARD_FAB2_LIB.BASEBOARD_FAB2(SCH_1):P1V05_PCH_STBY_VCCA_PLL0    I63 @BASEBOARD_FAB2_LIB.BASEBOARD_FAB2(SCH_1):PAGE122
  AE45 P1V05_PCH_STBY_VCCA_PLL1 @BASEBOARD_FAB2_LIB.BASEBOARD_FAB2(SCH_1):P1V05_PCH_STBY_VCCA_PLL1    I63 @BASEBOARD_FAB2_LIB.BASEBOARD_FAB2(SCH_1):PAGE122
  AK43 P1V05_PCH_STBY @BASEBOARD_FAB2_LIB.BASEBOARD_FAB2(SCH_1):P1V05_PCH_STBY    I63 @BASEBOARD_FAB2_LIB.BASEBOARD_FAB2(SCH_1):PAGE122
  AK45 P1V05_PCH_STBY @BASEBOARD_FAB2_LIB.BASEBOARD_FAB2(SCH_1):P1V05_PCH_STBY    I63 @BASEBOARD_FAB2_LIB.BASEBOARD_FAB2(SCH_1):PAGE122
  AM43 P1V05_PCH_STBY @BASEBOARD_FAB2_LIB.BASEBOARD_FAB2(SCH_1):P1V05_PCH_STBY    I63 @BASEBOARD_FAB2_LIB.BASEBOARD_FAB2(SCH_1):PAGE122
  AM45 P1V05_PCH_STBY @BASEBOARD_FAB2_LIB.BASEBOARD_FAB2(SCH_1):P1V05_PCH_STBY    I63 @BASEBOARD_FAB2_LIB.BASEBOARD_FAB2(SCH_1):PAGE122
  AP43 P1V05_PCH_STBY @BASEBOARD_FAB2_LIB.BASEBOARD_FAB2(SCH_1):P1V05_PCH_STBY    I63 @BASEBOARD_FAB2_LIB.BASEBOARD_FAB2(SCH_1):PAGE122
  AP45 P1V05_PCH_STBY @BASEBOARD_FAB2_LIB.BASEBOARD_FAB2(SCH_1):P1V05_PCH_STBY    I63 @BASEBOARD_FAB2_LIB.BASEBOARD_FAB2(SCH_1):PAGE122
  AT43 P1V05_PCH_STBY @BASEBOARD_FAB2_LIB.BASEBOARD_FAB2(SCH_1):P1V05_PCH_STBY    I63 @BASEBOARD_FAB2_LIB.BASEBOARD_FAB2(SCH_1):PAGE122
  AT45 P1V05_PCH_STBY @BASEBOARD_FAB2_LIB.BASEBOARD_FAB2(SCH_1):P1V05_PCH_STBY    I63 @BASEBOARD_FAB2_LIB.BASEBOARD_FAB2(SCH_1):PAGE122
  AU43 P1V05_PCH_STBY @BASEBOARD_FAB2_LIB.BASEBOARD_FAB2(SCH_1):P1V05_PCH_STBY    I63 @BASEBOARD_FAB2_LIB.BASEBOARD_FAB2(SCH_1):PAGE122
  AU45 P1V05_PCH_STBY @BASEBOARD_FAB2_LIB.BASEBOARD_FAB2(SCH_1):P1V05_PCH_STBY    I63 @BASEBOARD_FAB2_LIB.BASEBOARD_FAB2(SCH_1):PAGE122
  AJ43 P1V05_PCH_STBY @BASEBOARD_FAB2_LIB.BASEBOARD_FAB2(SCH_1):P1V05_PCH_STBY    I63 @BASEBOARD_FAB2_LIB.BASEBOARD_FAB2(SCH_1):PAGE122
  AW43 P1V05_PCH_STBY @BASEBOARD_FAB2_LIB.BASEBOARD_FAB2(SCH_1):P1V05_PCH_STBY    I63 @BASEBOARD_FAB2_LIB.BASEBOARD_FAB2(SCH_1):PAGE122
  AW45 P1V05_PCH_STBY @BASEBOARD_FAB2_LIB.BASEBOARD_FAB2(SCH_1):P1V05_PCH_STBY    I63 @BASEBOARD_FAB2_LIB.BASEBOARD_FAB2(SCH_1):PAGE122
  BA39 P1V05_PCH_STBY_KR_PLL @BASEBOARD_FAB2_LIB.BASEBOARD_FAB2(SCH_1):P1V05_PCH_STBY_KR_PLL    I63 @BASEBOARD_FAB2_LIB.BASEBOARD_FAB2(SCH_1):PAGE122
  BA41 P1V05_PCH_STBY_KR_PLL @BASEBOARD_FAB2_LIB.BASEBOARD_FAB2(SCH_1):P1V05_PCH_STBY_KR_PLL    I63 @BASEBOARD_FAB2_LIB.BASEBOARD_FAB2(SCH_1):PAGE122
  BB40 P1V05_PCH_STBY_KR_PLL @BASEBOARD_FAB2_LIB.BASEBOARD_FAB2(SCH_1):P1V05_PCH_STBY_KR_PLL    I63 @BASEBOARD_FAB2_LIB.BASEBOARD_FAB2(SCH_1):PAGE122
  BD38 P1V05_PCH_STBY_KR_PLL @BASEBOARD_FAB2_LIB.BASEBOARD_FAB2(SCH_1):P1V05_PCH_STBY_KR_PLL    I63 @BASEBOARD_FAB2_LIB.BASEBOARD_FAB2(SCH_1):PAGE122
  BA27 P1V8_PCH_STBY @BASEBOARD_FAB2_LIB.BASEBOARD_FAB2(SCH_1):P1V8_PCH_STBY    I63 @BASEBOARD_FAB2_LIB.BASEBOARD_FAB2(SCH_1):PAGE122
  BA29 P1V8_PCH_STBY @BASEBOARD_FAB2_LIB.BASEBOARD_FAB2(SCH_1):P1V8_PCH_STBY    I63 @BASEBOARD_FAB2_LIB.BASEBOARD_FAB2(SCH_1):PAGE122
  BA30 P1V05_PCH_STBY @BASEBOARD_FAB2_LIB.BASEBOARD_FAB2(SCH_1):P1V05_PCH_STBY    I63 @BASEBOARD_FAB2_LIB.BASEBOARD_FAB2(SCH_1):PAGE122
  BA32 P1V05_PCH_STBY @BASEBOARD_FAB2_LIB.BASEBOARD_FAB2(SCH_1):P1V05_PCH_STBY    I63 @BASEBOARD_FAB2_LIB.BASEBOARD_FAB2(SCH_1):PAGE122
  BA34 P1V05_PCH_STBY @BASEBOARD_FAB2_LIB.BASEBOARD_FAB2(SCH_1):P1V05_PCH_STBY    I63 @BASEBOARD_FAB2_LIB.BASEBOARD_FAB2(SCH_1):PAGE122
  BA36 P1V05_PCH_STBY @BASEBOARD_FAB2_LIB.BASEBOARD_FAB2(SCH_1):P1V05_PCH_STBY    I63 @BASEBOARD_FAB2_LIB.BASEBOARD_FAB2(SCH_1):PAGE122
  BA37 P1V05_PCH_STBY @BASEBOARD_FAB2_LIB.BASEBOARD_FAB2(SCH_1):P1V05_PCH_STBY    I63 @BASEBOARD_FAB2_LIB.BASEBOARD_FAB2(SCH_1):PAGE122
  BB33 P1V05_PCH_STBY @BASEBOARD_FAB2_LIB.BASEBOARD_FAB2(SCH_1):P1V05_PCH_STBY    I63 @BASEBOARD_FAB2_LIB.BASEBOARD_FAB2(SCH_1):PAGE122
  BB37 P1V05_PCH_STBY @BASEBOARD_FAB2_LIB.BASEBOARD_FAB2(SCH_1):P1V05_PCH_STBY    I63 @BASEBOARD_FAB2_LIB.BASEBOARD_FAB2(SCH_1):PAGE122
  AH24 P3V3_STBY @BASEBOARD_FAB2_LIB.BASEBOARD_FAB2(SCH_1):P3V3_STBY    I63 @BASEBOARD_FAB2_LIB.BASEBOARD_FAB2(SCH_1):PAGE122
  AW24 P3V3_STBY @BASEBOARD_FAB2_LIB.BASEBOARD_FAB2(SCH_1):P3V3_STBY    I63 @BASEBOARD_FAB2_LIB.BASEBOARD_FAB2(SCH_1):PAGE122
  BE26 P3V3_STBY @BASEBOARD_FAB2_LIB.BASEBOARD_FAB2(SCH_1):P3V3_STBY    I63 @BASEBOARD_FAB2_LIB.BASEBOARD_FAB2(SCH_1):PAGE122
  BE40 P3V3_STBY @BASEBOARD_FAB2_LIB.BASEBOARD_FAB2(SCH_1):P3V3_STBY    I63 @BASEBOARD_FAB2_LIB.BASEBOARD_FAB2(SCH_1):PAGE122
  BA43 P3V3_STBY @BASEBOARD_FAB2_LIB.BASEBOARD_FAB2(SCH_1):P3V3_STBY    I63 @BASEBOARD_FAB2_LIB.BASEBOARD_FAB2(SCH_1):PAGE122
  BE44 P3V3_STBY @BASEBOARD_FAB2_LIB.BASEBOARD_FAB2(SCH_1):P3V3_STBY    I63 @BASEBOARD_FAB2_LIB.BASEBOARD_FAB2(SCH_1):PAGE122
  AU27 P3V3_STBY @BASEBOARD_FAB2_LIB.BASEBOARD_FAB2(SCH_1):P3V3_STBY    I63 @BASEBOARD_FAB2_LIB.BASEBOARD_FAB2(SCH_1):PAGE122
  BA26 P3V3_STBY @BASEBOARD_FAB2_LIB.BASEBOARD_FAB2(SCH_1):P3V3_STBY    I63 @BASEBOARD_FAB2_LIB.BASEBOARD_FAB2(SCH_1):PAGE122
  BA24 P3V3_STBY @BASEBOARD_FAB2_LIB.BASEBOARD_FAB2(SCH_1):P3V3_STBY    I63 @BASEBOARD_FAB2_LIB.BASEBOARD_FAB2(SCH_1):PAGE122
  BB26 P3V3_STBY @BASEBOARD_FAB2_LIB.BASEBOARD_FAB2(SCH_1):P3V3_STBY    I63 @BASEBOARD_FAB2_LIB.BASEBOARD_FAB2(SCH_1):PAGE122
  AU24 P3V3_STBY @BASEBOARD_FAB2_LIB.BASEBOARD_FAB2(SCH_1):P3V3_STBY    I63 @BASEBOARD_FAB2_LIB.BASEBOARD_FAB2(SCH_1):PAGE122
  AK24 P1V8_PCH_STBY @BASEBOARD_FAB2_LIB.BASEBOARD_FAB2(SCH_1):P1V8_PCH_STBY    I63 @BASEBOARD_FAB2_LIB.BASEBOARD_FAB2(SCH_1):PAGE122
  AW27 P1V8_PCH_STBY @BASEBOARD_FAB2_LIB.BASEBOARD_FAB2(SCH_1):P1V8_PCH_STBY    I63 @BASEBOARD_FAB2_LIB.BASEBOARD_FAB2(SCH_1):PAGE122
  AP29 P1V8_PCH_STBY @BASEBOARD_FAB2_LIB.BASEBOARD_FAB2(SCH_1):P1V8_PCH_STBY    I63 @BASEBOARD_FAB2_LIB.BASEBOARD_FAB2(SCH_1):PAGE122
  AM29 P1V8_PCH_STBY @BASEBOARD_FAB2_LIB.BASEBOARD_FAB2(SCH_1):P1V8_PCH_STBY    I63 @BASEBOARD_FAB2_LIB.BASEBOARD_FAB2(SCH_1):PAGE122
  AT29 P1V8_PCH_STBY @BASEBOARD_FAB2_LIB.BASEBOARD_FAB2(SCH_1):P1V8_PCH_STBY    I63 @BASEBOARD_FAB2_LIB.BASEBOARD_FAB2(SCH_1):PAGE122
  AW29 P1V8_PCH_STBY @BASEBOARD_FAB2_LIB.BASEBOARD_FAB2(SCH_1):P1V8_PCH_STBY    I63 @BASEBOARD_FAB2_LIB.BASEBOARD_FAB2(SCH_1):PAGE122
  AU29 P1V8_PCH_STBY @BASEBOARD_FAB2_LIB.BASEBOARD_FAB2(SCH_1):P1V8_PCH_STBY    I63 @BASEBOARD_FAB2_LIB.BASEBOARD_FAB2(SCH_1):PAGE122
  AG27 P1V8_PCH_STBY @BASEBOARD_FAB2_LIB.BASEBOARD_FAB2(SCH_1):P1V8_PCH_STBY    I63 @BASEBOARD_FAB2_LIB.BASEBOARD_FAB2(SCH_1):PAGE122
   Y26 P1V05_PCH_STBY @BASEBOARD_FAB2_LIB.BASEBOARD_FAB2(SCH_1):P1V05_PCH_STBY    I63 @BASEBOARD_FAB2_LIB.BASEBOARD_FAB2(SCH_1):PAGE122
  AA24 P1V05_PCH_STBY @BASEBOARD_FAB2_LIB.BASEBOARD_FAB2(SCH_1):P1V05_PCH_STBY    I63 @BASEBOARD_FAB2_LIB.BASEBOARD_FAB2(SCH_1):PAGE122
  AK27 P1V05_PCH_STBY @BASEBOARD_FAB2_LIB.BASEBOARD_FAB2(SCH_1):P1V05_PCH_STBY    I63 @BASEBOARD_FAB2_LIB.BASEBOARD_FAB2(SCH_1):PAGE122
   R42 P1V05_PCH_STBY @BASEBOARD_FAB2_LIB.BASEBOARD_FAB2(SCH_1):P1V05_PCH_STBY    I63 @BASEBOARD_FAB2_LIB.BASEBOARD_FAB2(SCH_1):PAGE122
   R46 P1V05_PCH_STBY @BASEBOARD_FAB2_LIB.BASEBOARD_FAB2(SCH_1):P1V05_PCH_STBY    I63 @BASEBOARD_FAB2_LIB.BASEBOARD_FAB2(SCH_1):PAGE122
   T44 P1V05_PCH_STBY @BASEBOARD_FAB2_LIB.BASEBOARD_FAB2(SCH_1):P1V05_PCH_STBY    I63 @BASEBOARD_FAB2_LIB.BASEBOARD_FAB2(SCH_1):PAGE122
   U46 P1V05_PCH_STBY @BASEBOARD_FAB2_LIB.BASEBOARD_FAB2(SCH_1):P1V05_PCH_STBY    I63 @BASEBOARD_FAB2_LIB.BASEBOARD_FAB2(SCH_1):PAGE122
   V44 P1V05_PCH_STBY @BASEBOARD_FAB2_LIB.BASEBOARD_FAB2(SCH_1):P1V05_PCH_STBY    I63 @BASEBOARD_FAB2_LIB.BASEBOARD_FAB2(SCH_1):PAGE122
   Y45 P1V05_PCH_STBY @BASEBOARD_FAB2_LIB.BASEBOARD_FAB2(SCH_1):P1V05_PCH_STBY    I63 @BASEBOARD_FAB2_LIB.BASEBOARD_FAB2(SCH_1):PAGE122
   Y46 P1V05_PCH_STBY @BASEBOARD_FAB2_LIB.BASEBOARD_FAB2(SCH_1):P1V05_PCH_STBY    I63 @BASEBOARD_FAB2_LIB.BASEBOARD_FAB2(SCH_1):PAGE122
  AA45 P1V05_PCH_STBY @BASEBOARD_FAB2_LIB.BASEBOARD_FAB2(SCH_1):P1V05_PCH_STBY    I63 @BASEBOARD_FAB2_LIB.BASEBOARD_FAB2(SCH_1):PAGE122
  AA46 P1V05_PCH_STBY @BASEBOARD_FAB2_LIB.BASEBOARD_FAB2(SCH_1):P1V05_PCH_STBY    I63 @BASEBOARD_FAB2_LIB.BASEBOARD_FAB2(SCH_1):PAGE122
  AC26 P1V05_PCH_STBY @BASEBOARD_FAB2_LIB.BASEBOARD_FAB2(SCH_1):P1V05_PCH_STBY    I63 @BASEBOARD_FAB2_LIB.BASEBOARD_FAB2(SCH_1):PAGE122
  AJ29 P1V05_PCH_STBY @BASEBOARD_FAB2_LIB.BASEBOARD_FAB2(SCH_1):P1V05_PCH_STBY    I63 @BASEBOARD_FAB2_LIB.BASEBOARD_FAB2(SCH_1):PAGE122
  AM27 P1V05_PCH_STBY @BASEBOARD_FAB2_LIB.BASEBOARD_FAB2(SCH_1):P1V05_PCH_STBY    I63 @BASEBOARD_FAB2_LIB.BASEBOARD_FAB2(SCH_1):PAGE122
  AT39 P1V05_PCH_STBY @BASEBOARD_FAB2_LIB.BASEBOARD_FAB2(SCH_1):P1V05_PCH_STBY    I63 @BASEBOARD_FAB2_LIB.BASEBOARD_FAB2(SCH_1):PAGE122
  AU37 P1V05_PCH_STBY @BASEBOARD_FAB2_LIB.BASEBOARD_FAB2(SCH_1):P1V05_PCH_STBY    I63 @BASEBOARD_FAB2_LIB.BASEBOARD_FAB2(SCH_1):PAGE122
  AU39 P1V05_PCH_STBY @BASEBOARD_FAB2_LIB.BASEBOARD_FAB2(SCH_1):P1V05_PCH_STBY    I63 @BASEBOARD_FAB2_LIB.BASEBOARD_FAB2(SCH_1):PAGE122
  BE48 P1V05_PCH_STBY @BASEBOARD_FAB2_LIB.BASEBOARD_FAB2(SCH_1):P1V05_PCH_STBY    I63 @BASEBOARD_FAB2_LIB.BASEBOARD_FAB2(SCH_1):PAGE122
  BF46 P1V05_PCH_STBY @BASEBOARD_FAB2_LIB.BASEBOARD_FAB2(SCH_1):P1V05_PCH_STBY    I63 @BASEBOARD_FAB2_LIB.BASEBOARD_FAB2(SCH_1):PAGE122
  AJ27 P3V3_RTC_STBY @BASEBOARD_FAB2_LIB.BASEBOARD_FAB2(SCH_1):P3V3_RTC_STBY    I63 @BASEBOARD_FAB2_LIB.BASEBOARD_FAB2(SCH_1):PAGE122
  AG29 P3V3_STBY @BASEBOARD_FAB2_LIB.BASEBOARD_FAB2(SCH_1):P3V3_STBY    I63 @BASEBOARD_FAB2_LIB.BASEBOARD_FAB2(SCH_1):PAGE122
  AR24 P3V3_STBY @BASEBOARD_FAB2_LIB.BASEBOARD_FAB2(SCH_1):P3V3_STBY    I63 @BASEBOARD_FAB2_LIB.BASEBOARD_FAB2(SCH_1):PAGE122
  AK29 P1V8_PCH_STBY @BASEBOARD_FAB2_LIB.BASEBOARD_FAB2(SCH_1):P1V8_PCH_STBY    I63 @BASEBOARD_FAB2_LIB.BASEBOARD_FAB2(SCH_1):PAGE122
  BA48 P3V3_STBY @BASEBOARD_FAB2_LIB.BASEBOARD_FAB2(SCH_1):P3V3_STBY    I63 @BASEBOARD_FAB2_LIB.BASEBOARD_FAB2(SCH_1):PAGE122
  AE26 P1V8_PCH_STBY @BASEBOARD_FAB2_LIB.BASEBOARD_FAB2(SCH_1):P1V8_PCH_STBY    I63 @BASEBOARD_FAB2_LIB.BASEBOARD_FAB2(SCH_1):PAGE122
  BD46 P1V8_PCH_STBY @BASEBOARD_FAB2_LIB.BASEBOARD_FAB2(SCH_1):P1V8_PCH_STBY    I63 @BASEBOARD_FAB2_LIB.BASEBOARD_FAB2(SCH_1):PAGE122
  AN24 P3V3_STBY @BASEBOARD_FAB2_LIB.BASEBOARD_FAB2(SCH_1):P3V3_STBY    I63 @BASEBOARD_FAB2_LIB.BASEBOARD_FAB2(SCH_1):PAGE122
  AD24 P3V3_STBY @BASEBOARD_FAB2_LIB.BASEBOARD_FAB2(SCH_1):P3V3_STBY    I63 @BASEBOARD_FAB2_LIB.BASEBOARD_FAB2(SCH_1):PAGE122
  BA45 P3V3_STBY @BASEBOARD_FAB2_LIB.BASEBOARD_FAB2(SCH_1):P3V3_STBY    I63 @BASEBOARD_FAB2_LIB.BASEBOARD_FAB2(SCH_1):PAGE122
  BA46 P3V3_STBY @BASEBOARD_FAB2_LIB.BASEBOARD_FAB2(SCH_1):P3V3_STBY    I63 @BASEBOARD_FAB2_LIB.BASEBOARD_FAB2(SCH_1):PAGE122
  AT48 P1V05_PCH_STBY @BASEBOARD_FAB2_LIB.BASEBOARD_FAB2(SCH_1):P1V05_PCH_STBY    I63 @BASEBOARD_FAB2_LIB.BASEBOARD_FAB2(SCH_1):PAGE122
  AP48 P1V05_PCH_STBY_WM26_PLL @BASEBOARD_FAB2_LIB.BASEBOARD_FAB2(SCH_1):P1V05_PCH_STBY_WM26_PLL    I63 @BASEBOARD_FAB2_LIB.BASEBOARD_FAB2(SCH_1):PAGE122
  AU48 P1V05_PCH_STBY_WM26_PLL @BASEBOARD_FAB2_LIB.BASEBOARD_FAB2(SCH_1):P1V05_PCH_STBY_WM26_PLL    I63 @BASEBOARD_FAB2_LIB.BASEBOARD_FAB2(SCH_1):PAGE122
  AW48 P1V05_PCH_STBY_WM26_PLL @BASEBOARD_FAB2_LIB.BASEBOARD_FAB2(SCH_1):P1V05_PCH_STBY_WM26_PLL    I63 @BASEBOARD_FAB2_LIB.BASEBOARD_FAB2(SCH_1):PAGE122
  AM48 P1V05_PCH_STBY @BASEBOARD_FAB2_LIB.BASEBOARD_FAB2(SCH_1):P1V05_PCH_STBY    I63 @BASEBOARD_FAB2_LIB.BASEBOARD_FAB2(SCH_1):PAGE122
  AK50 P1V05_PCH_STBY_WM20_PLL @BASEBOARD_FAB2_LIB.BASEBOARD_FAB2(SCH_1):P1V05_PCH_STBY_WM20_PLL    I63 @BASEBOARD_FAB2_LIB.BASEBOARD_FAB2(SCH_1):PAGE122
  AN50 P1V05_PCH_STBY_WM20_PLL @BASEBOARD_FAB2_LIB.BASEBOARD_FAB2(SCH_1):P1V05_PCH_STBY_WM20_PLL    I63 @BASEBOARD_FAB2_LIB.BASEBOARD_FAB2(SCH_1):PAGE122
  AG22 A_PVCCRTC_EXT_CAP @BASEBOARD_FAB2_LIB.BASEBOARD_FAB2(SCH_1):A_PVCCRTC_EXT_CAP    I63 @BASEBOARD_FAB2_LIB.BASEBOARD_FAB2(SCH_1):PAGE122
  AE27 P1V05_PCH_STBY @BASEBOARD_FAB2_LIB.BASEBOARD_FAB2(SCH_1):P1V05_PCH_STBY    I21 @BASEBOARD_FAB2_LIB.BASEBOARD_FAB2(SCH_1):PAGE123
  AK32 PVNN_PCH_STBY @BASEBOARD_FAB2_LIB.BASEBOARD_FAB2(SCH_1):PVNN_PCH_STBY    I21 @BASEBOARD_FAB2_LIB.BASEBOARD_FAB2(SCH_1):PAGE123
   U31 PVNN_PCH_STBY @BASEBOARD_FAB2_LIB.BASEBOARD_FAB2(SCH_1):PVNN_PCH_STBY    I21 @BASEBOARD_FAB2_LIB.BASEBOARD_FAB2(SCH_1):PAGE123
   U35 PVNN_PCH_STBY @BASEBOARD_FAB2_LIB.BASEBOARD_FAB2(SCH_1):PVNN_PCH_STBY    I21 @BASEBOARD_FAB2_LIB.BASEBOARD_FAB2(SCH_1):PAGE123
   U38 PVNN_PCH_STBY @BASEBOARD_FAB2_LIB.BASEBOARD_FAB2(SCH_1):PVNN_PCH_STBY    I21 @BASEBOARD_FAB2_LIB.BASEBOARD_FAB2(SCH_1):PAGE123
   V29 PVNN_PCH_STBY @BASEBOARD_FAB2_LIB.BASEBOARD_FAB2(SCH_1):PVNN_PCH_STBY    I21 @BASEBOARD_FAB2_LIB.BASEBOARD_FAB2(SCH_1):PAGE123
   V33 PVNN_PCH_STBY @BASEBOARD_FAB2_LIB.BASEBOARD_FAB2(SCH_1):PVNN_PCH_STBY    I21 @BASEBOARD_FAB2_LIB.BASEBOARD_FAB2(SCH_1):PAGE123
   V40 PVNN_PCH_STBY @BASEBOARD_FAB2_LIB.BASEBOARD_FAB2(SCH_1):PVNN_PCH_STBY    I21 @BASEBOARD_FAB2_LIB.BASEBOARD_FAB2(SCH_1):PAGE123
   Y29 PVNN_PCH_STBY @BASEBOARD_FAB2_LIB.BASEBOARD_FAB2(SCH_1):PVNN_PCH_STBY    I21 @BASEBOARD_FAB2_LIB.BASEBOARD_FAB2(SCH_1):PAGE123
   Y30 PVNN_PCH_STBY @BASEBOARD_FAB2_LIB.BASEBOARD_FAB2(SCH_1):PVNN_PCH_STBY    I21 @BASEBOARD_FAB2_LIB.BASEBOARD_FAB2(SCH_1):PAGE123
   Y32 PVNN_PCH_STBY @BASEBOARD_FAB2_LIB.BASEBOARD_FAB2(SCH_1):PVNN_PCH_STBY    I21 @BASEBOARD_FAB2_LIB.BASEBOARD_FAB2(SCH_1):PAGE123
   Y34 PVNN_PCH_STBY @BASEBOARD_FAB2_LIB.BASEBOARD_FAB2(SCH_1):PVNN_PCH_STBY    I21 @BASEBOARD_FAB2_LIB.BASEBOARD_FAB2(SCH_1):PAGE123
   Y36 PVNN_PCH_STBY @BASEBOARD_FAB2_LIB.BASEBOARD_FAB2(SCH_1):PVNN_PCH_STBY    I21 @BASEBOARD_FAB2_LIB.BASEBOARD_FAB2(SCH_1):PAGE123
   Y37 PVNN_PCH_STBY @BASEBOARD_FAB2_LIB.BASEBOARD_FAB2(SCH_1):PVNN_PCH_STBY    I21 @BASEBOARD_FAB2_LIB.BASEBOARD_FAB2(SCH_1):PAGE123
   Y39 PVNN_PCH_STBY @BASEBOARD_FAB2_LIB.BASEBOARD_FAB2(SCH_1):PVNN_PCH_STBY    I21 @BASEBOARD_FAB2_LIB.BASEBOARD_FAB2(SCH_1):PAGE123
   Y41 PVNN_PCH_STBY @BASEBOARD_FAB2_LIB.BASEBOARD_FAB2(SCH_1):PVNN_PCH_STBY    I21 @BASEBOARD_FAB2_LIB.BASEBOARD_FAB2(SCH_1):PAGE123
  AA29 PVNN_PCH_STBY @BASEBOARD_FAB2_LIB.BASEBOARD_FAB2(SCH_1):PVNN_PCH_STBY    I21 @BASEBOARD_FAB2_LIB.BASEBOARD_FAB2(SCH_1):PAGE123
  AA30 PVNN_PCH_STBY @BASEBOARD_FAB2_LIB.BASEBOARD_FAB2(SCH_1):PVNN_PCH_STBY    I21 @BASEBOARD_FAB2_LIB.BASEBOARD_FAB2(SCH_1):PAGE123
  AA32 PVNN_PCH_STBY @BASEBOARD_FAB2_LIB.BASEBOARD_FAB2(SCH_1):PVNN_PCH_STBY    I21 @BASEBOARD_FAB2_LIB.BASEBOARD_FAB2(SCH_1):PAGE123
  AA34 PVNN_PCH_STBY @BASEBOARD_FAB2_LIB.BASEBOARD_FAB2(SCH_1):PVNN_PCH_STBY    I21 @BASEBOARD_FAB2_LIB.BASEBOARD_FAB2(SCH_1):PAGE123
  AA36 PVNN_PCH_STBY @BASEBOARD_FAB2_LIB.BASEBOARD_FAB2(SCH_1):PVNN_PCH_STBY    I21 @BASEBOARD_FAB2_LIB.BASEBOARD_FAB2(SCH_1):PAGE123
  AA37 PVNN_PCH_STBY @BASEBOARD_FAB2_LIB.BASEBOARD_FAB2(SCH_1):PVNN_PCH_STBY    I21 @BASEBOARD_FAB2_LIB.BASEBOARD_FAB2(SCH_1):PAGE123
  AA39 PVNN_PCH_STBY @BASEBOARD_FAB2_LIB.BASEBOARD_FAB2(SCH_1):PVNN_PCH_STBY    I21 @BASEBOARD_FAB2_LIB.BASEBOARD_FAB2(SCH_1):PAGE123
  AA41 PVNN_PCH_STBY @BASEBOARD_FAB2_LIB.BASEBOARD_FAB2(SCH_1):PVNN_PCH_STBY    I21 @BASEBOARD_FAB2_LIB.BASEBOARD_FAB2(SCH_1):PAGE123
  AC29 PVNN_PCH_STBY @BASEBOARD_FAB2_LIB.BASEBOARD_FAB2(SCH_1):PVNN_PCH_STBY    I21 @BASEBOARD_FAB2_LIB.BASEBOARD_FAB2(SCH_1):PAGE123
  AC30 PVNN_PCH_STBY @BASEBOARD_FAB2_LIB.BASEBOARD_FAB2(SCH_1):PVNN_PCH_STBY    I21 @BASEBOARD_FAB2_LIB.BASEBOARD_FAB2(SCH_1):PAGE123
  AC32 PVNN_PCH_STBY @BASEBOARD_FAB2_LIB.BASEBOARD_FAB2(SCH_1):PVNN_PCH_STBY    I21 @BASEBOARD_FAB2_LIB.BASEBOARD_FAB2(SCH_1):PAGE123
  AC34 PVNN_PCH_STBY @BASEBOARD_FAB2_LIB.BASEBOARD_FAB2(SCH_1):PVNN_PCH_STBY    I21 @BASEBOARD_FAB2_LIB.BASEBOARD_FAB2(SCH_1):PAGE123
  AC36 PVNN_PCH_STBY @BASEBOARD_FAB2_LIB.BASEBOARD_FAB2(SCH_1):PVNN_PCH_STBY    I21 @BASEBOARD_FAB2_LIB.BASEBOARD_FAB2(SCH_1):PAGE123
  AC37 PVNN_PCH_STBY @BASEBOARD_FAB2_LIB.BASEBOARD_FAB2(SCH_1):PVNN_PCH_STBY    I21 @BASEBOARD_FAB2_LIB.BASEBOARD_FAB2(SCH_1):PAGE123
  AC39 PVNN_PCH_STBY @BASEBOARD_FAB2_LIB.BASEBOARD_FAB2(SCH_1):PVNN_PCH_STBY    I21 @BASEBOARD_FAB2_LIB.BASEBOARD_FAB2(SCH_1):PAGE123
  AC41 PVNN_PCH_STBY @BASEBOARD_FAB2_LIB.BASEBOARD_FAB2(SCH_1):PVNN_PCH_STBY    I21 @BASEBOARD_FAB2_LIB.BASEBOARD_FAB2(SCH_1):PAGE123
   U27 PVNN_PCH_STBY @BASEBOARD_FAB2_LIB.BASEBOARD_FAB2(SCH_1):PVNN_PCH_STBY    I21 @BASEBOARD_FAB2_LIB.BASEBOARD_FAB2(SCH_1):PAGE123
  AE30 PVNN_PCH_STBY @BASEBOARD_FAB2_LIB.BASEBOARD_FAB2(SCH_1):PVNN_PCH_STBY    I21 @BASEBOARD_FAB2_LIB.BASEBOARD_FAB2(SCH_1):PAGE123
  AE32 PVNN_PCH_STBY @BASEBOARD_FAB2_LIB.BASEBOARD_FAB2(SCH_1):PVNN_PCH_STBY    I21 @BASEBOARD_FAB2_LIB.BASEBOARD_FAB2(SCH_1):PAGE123
  AE34 PVNN_PCH_STBY @BASEBOARD_FAB2_LIB.BASEBOARD_FAB2(SCH_1):PVNN_PCH_STBY    I21 @BASEBOARD_FAB2_LIB.BASEBOARD_FAB2(SCH_1):PAGE123
  AE36 PVNN_PCH_STBY @BASEBOARD_FAB2_LIB.BASEBOARD_FAB2(SCH_1):PVNN_PCH_STBY    I21 @BASEBOARD_FAB2_LIB.BASEBOARD_FAB2(SCH_1):PAGE123
  AE37 PVNN_PCH_STBY @BASEBOARD_FAB2_LIB.BASEBOARD_FAB2(SCH_1):PVNN_PCH_STBY    I21 @BASEBOARD_FAB2_LIB.BASEBOARD_FAB2(SCH_1):PAGE123
  AE39 PVNN_PCH_STBY @BASEBOARD_FAB2_LIB.BASEBOARD_FAB2(SCH_1):PVNN_PCH_STBY    I21 @BASEBOARD_FAB2_LIB.BASEBOARD_FAB2(SCH_1):PAGE123
  AE41 PVNN_PCH_STBY @BASEBOARD_FAB2_LIB.BASEBOARD_FAB2(SCH_1):PVNN_PCH_STBY    I21 @BASEBOARD_FAB2_LIB.BASEBOARD_FAB2(SCH_1):PAGE123
  AG32 PVNN_PCH_STBY @BASEBOARD_FAB2_LIB.BASEBOARD_FAB2(SCH_1):PVNN_PCH_STBY    I21 @BASEBOARD_FAB2_LIB.BASEBOARD_FAB2(SCH_1):PAGE123
  AG34 PVNN_PCH_STBY @BASEBOARD_FAB2_LIB.BASEBOARD_FAB2(SCH_1):PVNN_PCH_STBY    I21 @BASEBOARD_FAB2_LIB.BASEBOARD_FAB2(SCH_1):PAGE123
  AG36 PVNN_PCH_STBY @BASEBOARD_FAB2_LIB.BASEBOARD_FAB2(SCH_1):PVNN_PCH_STBY    I21 @BASEBOARD_FAB2_LIB.BASEBOARD_FAB2(SCH_1):PAGE123
  AG37 PVNN_PCH_STBY @BASEBOARD_FAB2_LIB.BASEBOARD_FAB2(SCH_1):PVNN_PCH_STBY    I21 @BASEBOARD_FAB2_LIB.BASEBOARD_FAB2(SCH_1):PAGE123
  AG39 PVNN_PCH_STBY @BASEBOARD_FAB2_LIB.BASEBOARD_FAB2(SCH_1):PVNN_PCH_STBY    I21 @BASEBOARD_FAB2_LIB.BASEBOARD_FAB2(SCH_1):PAGE123
  AK34 PVNN_PCH_STBY @BASEBOARD_FAB2_LIB.BASEBOARD_FAB2(SCH_1):PVNN_PCH_STBY    I21 @BASEBOARD_FAB2_LIB.BASEBOARD_FAB2(SCH_1):PAGE123
  AK37 PVNN_PCH_STBY @BASEBOARD_FAB2_LIB.BASEBOARD_FAB2(SCH_1):PVNN_PCH_STBY    I21 @BASEBOARD_FAB2_LIB.BASEBOARD_FAB2(SCH_1):PAGE123
  AK39 PVNN_PCH_STBY @BASEBOARD_FAB2_LIB.BASEBOARD_FAB2(SCH_1):PVNN_PCH_STBY    I21 @BASEBOARD_FAB2_LIB.BASEBOARD_FAB2(SCH_1):PAGE123
  AM32 PVNN_PCH_STBY @BASEBOARD_FAB2_LIB.BASEBOARD_FAB2(SCH_1):PVNN_PCH_STBY    I21 @BASEBOARD_FAB2_LIB.BASEBOARD_FAB2(SCH_1):PAGE123
  AM34 PVNN_PCH_STBY @BASEBOARD_FAB2_LIB.BASEBOARD_FAB2(SCH_1):PVNN_PCH_STBY    I21 @BASEBOARD_FAB2_LIB.BASEBOARD_FAB2(SCH_1):PAGE123
  AM36 PVNN_PCH_STBY @BASEBOARD_FAB2_LIB.BASEBOARD_FAB2(SCH_1):PVNN_PCH_STBY    I21 @BASEBOARD_FAB2_LIB.BASEBOARD_FAB2(SCH_1):PAGE123
  AM37 PVNN_PCH_STBY @BASEBOARD_FAB2_LIB.BASEBOARD_FAB2(SCH_1):PVNN_PCH_STBY    I21 @BASEBOARD_FAB2_LIB.BASEBOARD_FAB2(SCH_1):PAGE123
  AM39 PVNN_PCH_STBY @BASEBOARD_FAB2_LIB.BASEBOARD_FAB2(SCH_1):PVNN_PCH_STBY    I21 @BASEBOARD_FAB2_LIB.BASEBOARD_FAB2(SCH_1):PAGE123
  AP32 PVNN_PCH_STBY @BASEBOARD_FAB2_LIB.BASEBOARD_FAB2(SCH_1):PVNN_PCH_STBY    I21 @BASEBOARD_FAB2_LIB.BASEBOARD_FAB2(SCH_1):PAGE123
  AP34 PVNN_PCH_STBY @BASEBOARD_FAB2_LIB.BASEBOARD_FAB2(SCH_1):PVNN_PCH_STBY    I21 @BASEBOARD_FAB2_LIB.BASEBOARD_FAB2(SCH_1):PAGE123
  AP36 PVNN_PCH_STBY @BASEBOARD_FAB2_LIB.BASEBOARD_FAB2(SCH_1):PVNN_PCH_STBY    I21 @BASEBOARD_FAB2_LIB.BASEBOARD_FAB2(SCH_1):PAGE123
  AP37 PVNN_PCH_STBY @BASEBOARD_FAB2_LIB.BASEBOARD_FAB2(SCH_1):PVNN_PCH_STBY    I21 @BASEBOARD_FAB2_LIB.BASEBOARD_FAB2(SCH_1):PAGE123
  AP39 PVNN_PCH_STBY @BASEBOARD_FAB2_LIB.BASEBOARD_FAB2(SCH_1):PVNN_PCH_STBY    I21 @BASEBOARD_FAB2_LIB.BASEBOARD_FAB2(SCH_1):PAGE123
  AT32 PVNN_PCH_STBY @BASEBOARD_FAB2_LIB.BASEBOARD_FAB2(SCH_1):PVNN_PCH_STBY    I21 @BASEBOARD_FAB2_LIB.BASEBOARD_FAB2(SCH_1):PAGE123
  AT34 PVNN_PCH_STBY @BASEBOARD_FAB2_LIB.BASEBOARD_FAB2(SCH_1):PVNN_PCH_STBY    I21 @BASEBOARD_FAB2_LIB.BASEBOARD_FAB2(SCH_1):PAGE123
  AT36 PVNN_PCH_STBY @BASEBOARD_FAB2_LIB.BASEBOARD_FAB2(SCH_1):PVNN_PCH_STBY    I21 @BASEBOARD_FAB2_LIB.BASEBOARD_FAB2(SCH_1):PAGE123
  AU32 PVNN_PCH_STBY @BASEBOARD_FAB2_LIB.BASEBOARD_FAB2(SCH_1):PVNN_PCH_STBY    I21 @BASEBOARD_FAB2_LIB.BASEBOARD_FAB2(SCH_1):PAGE123
  AU34 PVNN_PCH_STBY @BASEBOARD_FAB2_LIB.BASEBOARD_FAB2(SCH_1):PVNN_PCH_STBY    I21 @BASEBOARD_FAB2_LIB.BASEBOARD_FAB2(SCH_1):PAGE123
  AU36 PVNN_PCH_STBY @BASEBOARD_FAB2_LIB.BASEBOARD_FAB2(SCH_1):PVNN_PCH_STBY    I21 @BASEBOARD_FAB2_LIB.BASEBOARD_FAB2(SCH_1):PAGE123
   V37 VSENSE_PVNN_PCH_STBY_QAT @BASEBOARD_FAB2_LIB.BASEBOARD_FAB2(SCH_1):VSENSE_PVNN_PCH_STBY_QAT    I21 @BASEBOARD_FAB2_LIB.BASEBOARD_FAB2(SCH_1):PAGE123
  AK36 VSENSE_PVNN_PCH_STBY_FPK @BASEBOARD_FAB2_LIB.BASEBOARD_FAB2(SCH_1):VSENSE_PVNN_PCH_STBY_FPK    I21 @BASEBOARD_FAB2_LIB.BASEBOARD_FAB2(SCH_1):PAGE123
  BP69    GND @BASEBOARD_FAB2_LIB.BASEBOARD_FAB2(SCH_1):GND    I13 @BASEBOARD_FAB2_LIB.BASEBOARD_FAB2(SCH_1):PAGE123
  BT69    GND @BASEBOARD_FAB2_LIB.BASEBOARD_FAB2(SCH_1):GND    I13 @BASEBOARD_FAB2_LIB.BASEBOARD_FAB2(SCH_1):PAGE123
  BU70    GND @BASEBOARD_FAB2_LIB.BASEBOARD_FAB2(SCH_1):GND    I13 @BASEBOARD_FAB2_LIB.BASEBOARD_FAB2(SCH_1):PAGE123
  BR70    GND @BASEBOARD_FAB2_LIB.BASEBOARD_FAB2(SCH_1):GND    I13 @BASEBOARD_FAB2_LIB.BASEBOARD_FAB2(SCH_1):PAGE123
   F70    GND @BASEBOARD_FAB2_LIB.BASEBOARD_FAB2(SCH_1):GND    I13 @BASEBOARD_FAB2_LIB.BASEBOARD_FAB2(SCH_1):PAGE123
   E70    GND @BASEBOARD_FAB2_LIB.BASEBOARD_FAB2(SCH_1):GND    I13 @BASEBOARD_FAB2_LIB.BASEBOARD_FAB2(SCH_1):PAGE123
   BU3    GND @BASEBOARD_FAB2_LIB.BASEBOARD_FAB2(SCH_1):GND    I13 @BASEBOARD_FAB2_LIB.BASEBOARD_FAB2(SCH_1):PAGE123
   BR3    GND @BASEBOARD_FAB2_LIB.BASEBOARD_FAB2(SCH_1):GND    I13 @BASEBOARD_FAB2_LIB.BASEBOARD_FAB2(SCH_1):PAGE123
    F3    GND @BASEBOARD_FAB2_LIB.BASEBOARD_FAB2(SCH_1):GND    I13 @BASEBOARD_FAB2_LIB.BASEBOARD_FAB2(SCH_1):PAGE123
    E3    GND @BASEBOARD_FAB2_LIB.BASEBOARD_FAB2(SCH_1):GND    I13 @BASEBOARD_FAB2_LIB.BASEBOARD_FAB2(SCH_1):PAGE123
    A5    GND @BASEBOARD_FAB2_LIB.BASEBOARD_FAB2(SCH_1):GND    I13 @BASEBOARD_FAB2_LIB.BASEBOARD_FAB2(SCH_1):PAGE123
    A7    GND @BASEBOARD_FAB2_LIB.BASEBOARD_FAB2(SCH_1):GND    I13 @BASEBOARD_FAB2_LIB.BASEBOARD_FAB2(SCH_1):PAGE123
    A9    GND @BASEBOARD_FAB2_LIB.BASEBOARD_FAB2(SCH_1):GND    I13 @BASEBOARD_FAB2_LIB.BASEBOARD_FAB2(SCH_1):PAGE123
   A65    GND @BASEBOARD_FAB2_LIB.BASEBOARD_FAB2(SCH_1):GND    I13 @BASEBOARD_FAB2_LIB.BASEBOARD_FAB2(SCH_1):PAGE123
   A66    GND @BASEBOARD_FAB2_LIB.BASEBOARD_FAB2(SCH_1):GND    I13 @BASEBOARD_FAB2_LIB.BASEBOARD_FAB2(SCH_1):PAGE123
   A68    GND @BASEBOARD_FAB2_LIB.BASEBOARD_FAB2(SCH_1):GND    I13 @BASEBOARD_FAB2_LIB.BASEBOARD_FAB2(SCH_1):PAGE123
    J1    GND @BASEBOARD_FAB2_LIB.BASEBOARD_FAB2(SCH_1):GND    I13 @BASEBOARD_FAB2_LIB.BASEBOARD_FAB2(SCH_1):PAGE123
   J72    GND @BASEBOARD_FAB2_LIB.BASEBOARD_FAB2(SCH_1):GND    I13 @BASEBOARD_FAB2_LIB.BASEBOARD_FAB2(SCH_1):PAGE123
   BN1    GND @BASEBOARD_FAB2_LIB.BASEBOARD_FAB2(SCH_1):GND    I13 @BASEBOARD_FAB2_LIB.BASEBOARD_FAB2(SCH_1):PAGE123
  BN72    GND @BASEBOARD_FAB2_LIB.BASEBOARD_FAB2(SCH_1):GND    I13 @BASEBOARD_FAB2_LIB.BASEBOARD_FAB2(SCH_1):PAGE123
  CA68    GND @BASEBOARD_FAB2_LIB.BASEBOARD_FAB2(SCH_1):GND    I13 @BASEBOARD_FAB2_LIB.BASEBOARD_FAB2(SCH_1):PAGE123
  CA66    GND @BASEBOARD_FAB2_LIB.BASEBOARD_FAB2(SCH_1):GND    I13 @BASEBOARD_FAB2_LIB.BASEBOARD_FAB2(SCH_1):PAGE123
  CA65    GND @BASEBOARD_FAB2_LIB.BASEBOARD_FAB2(SCH_1):GND    I13 @BASEBOARD_FAB2_LIB.BASEBOARD_FAB2(SCH_1):PAGE123
   CA9    GND @BASEBOARD_FAB2_LIB.BASEBOARD_FAB2(SCH_1):GND    I13 @BASEBOARD_FAB2_LIB.BASEBOARD_FAB2(SCH_1):PAGE123
   CA7    GND @BASEBOARD_FAB2_LIB.BASEBOARD_FAB2(SCH_1):GND    I13 @BASEBOARD_FAB2_LIB.BASEBOARD_FAB2(SCH_1):PAGE123
   CA5    GND @BASEBOARD_FAB2_LIB.BASEBOARD_FAB2(SCH_1):GND    I13 @BASEBOARD_FAB2_LIB.BASEBOARD_FAB2(SCH_1):PAGE123
   A70    GND @BASEBOARD_FAB2_LIB.BASEBOARD_FAB2(SCH_1):GND    I13 @BASEBOARD_FAB2_LIB.BASEBOARD_FAB2(SCH_1):PAGE123
   CA3    GND @BASEBOARD_FAB2_LIB.BASEBOARD_FAB2(SCH_1):GND    I13 @BASEBOARD_FAB2_LIB.BASEBOARD_FAB2(SCH_1):PAGE123
   BW1    GND @BASEBOARD_FAB2_LIB.BASEBOARD_FAB2(SCH_1):GND    I13 @BASEBOARD_FAB2_LIB.BASEBOARD_FAB2(SCH_1):PAGE123
   BU1    GND @BASEBOARD_FAB2_LIB.BASEBOARD_FAB2(SCH_1):GND    I13 @BASEBOARD_FAB2_LIB.BASEBOARD_FAB2(SCH_1):PAGE123
   BR1    GND @BASEBOARD_FAB2_LIB.BASEBOARD_FAB2(SCH_1):GND    I13 @BASEBOARD_FAB2_LIB.BASEBOARD_FAB2(SCH_1):PAGE123
    C3    GND @BASEBOARD_FAB2_LIB.BASEBOARD_FAB2(SCH_1):GND    I13 @BASEBOARD_FAB2_LIB.BASEBOARD_FAB2(SCH_1):PAGE123
   C72    GND @BASEBOARD_FAB2_LIB.BASEBOARD_FAB2(SCH_1):GND    I13 @BASEBOARD_FAB2_LIB.BASEBOARD_FAB2(SCH_1):PAGE123
    E1    GND @BASEBOARD_FAB2_LIB.BASEBOARD_FAB2(SCH_1):GND    I13 @BASEBOARD_FAB2_LIB.BASEBOARD_FAB2(SCH_1):PAGE123
   E72    GND @BASEBOARD_FAB2_LIB.BASEBOARD_FAB2(SCH_1):GND    I13 @BASEBOARD_FAB2_LIB.BASEBOARD_FAB2(SCH_1):PAGE123
    G1    GND @BASEBOARD_FAB2_LIB.BASEBOARD_FAB2(SCH_1):GND    I13 @BASEBOARD_FAB2_LIB.BASEBOARD_FAB2(SCH_1):PAGE123
   G72    GND @BASEBOARD_FAB2_LIB.BASEBOARD_FAB2(SCH_1):GND    I13 @BASEBOARD_FAB2_LIB.BASEBOARD_FAB2(SCH_1):PAGE123
  BR72    GND @BASEBOARD_FAB2_LIB.BASEBOARD_FAB2(SCH_1):GND    I13 @BASEBOARD_FAB2_LIB.BASEBOARD_FAB2(SCH_1):PAGE123
  BU72    GND @BASEBOARD_FAB2_LIB.BASEBOARD_FAB2(SCH_1):GND    I13 @BASEBOARD_FAB2_LIB.BASEBOARD_FAB2(SCH_1):PAGE123
  BW70    GND @BASEBOARD_FAB2_LIB.BASEBOARD_FAB2(SCH_1):GND    I13 @BASEBOARD_FAB2_LIB.BASEBOARD_FAB2(SCH_1):PAGE123
  BW72    GND @BASEBOARD_FAB2_LIB.BASEBOARD_FAB2(SCH_1):GND    I13 @BASEBOARD_FAB2_LIB.BASEBOARD_FAB2(SCH_1):PAGE123
  CA70    GND @BASEBOARD_FAB2_LIB.BASEBOARD_FAB2(SCH_1):GND    I13 @BASEBOARD_FAB2_LIB.BASEBOARD_FAB2(SCH_1):PAGE123
  BB48    GND @BASEBOARD_FAB2_LIB.BASEBOARD_FAB2(SCH_1):GND    I13 @BASEBOARD_FAB2_LIB.BASEBOARD_FAB2(SCH_1):PAGE123
  AT37    GND @BASEBOARD_FAB2_LIB.BASEBOARD_FAB2(SCH_1):GND    I13 @BASEBOARD_FAB2_LIB.BASEBOARD_FAB2(SCH_1):PAGE123
   Y72    GND @BASEBOARD_FAB2_LIB.BASEBOARD_FAB2(SCH_1):GND    I13 @BASEBOARD_FAB2_LIB.BASEBOARD_FAB2(SCH_1):PAGE123
   Y70    GND @BASEBOARD_FAB2_LIB.BASEBOARD_FAB2(SCH_1):GND    I13 @BASEBOARD_FAB2_LIB.BASEBOARD_FAB2(SCH_1):PAGE123
   A18    GND @BASEBOARD_FAB2_LIB.BASEBOARD_FAB2(SCH_1):GND    I13 @BASEBOARD_FAB2_LIB.BASEBOARD_FAB2(SCH_1):PAGE123
   A22    GND @BASEBOARD_FAB2_LIB.BASEBOARD_FAB2(SCH_1):GND    I13 @BASEBOARD_FAB2_LIB.BASEBOARD_FAB2(SCH_1):PAGE123
   A30    GND @BASEBOARD_FAB2_LIB.BASEBOARD_FAB2(SCH_1):GND    I13 @BASEBOARD_FAB2_LIB.BASEBOARD_FAB2(SCH_1):PAGE123
   A34    GND @BASEBOARD_FAB2_LIB.BASEBOARD_FAB2(SCH_1):GND    I13 @BASEBOARD_FAB2_LIB.BASEBOARD_FAB2(SCH_1):PAGE123
   A37    GND @BASEBOARD_FAB2_LIB.BASEBOARD_FAB2(SCH_1):GND    I13 @BASEBOARD_FAB2_LIB.BASEBOARD_FAB2(SCH_1):PAGE123
   A41    GND @BASEBOARD_FAB2_LIB.BASEBOARD_FAB2(SCH_1):GND    I13 @BASEBOARD_FAB2_LIB.BASEBOARD_FAB2(SCH_1):PAGE123
   B12    GND @BASEBOARD_FAB2_LIB.BASEBOARD_FAB2(SCH_1):GND    I13 @BASEBOARD_FAB2_LIB.BASEBOARD_FAB2(SCH_1):PAGE123
   B19    GND @BASEBOARD_FAB2_LIB.BASEBOARD_FAB2(SCH_1):GND    I13 @BASEBOARD_FAB2_LIB.BASEBOARD_FAB2(SCH_1):PAGE123
   B25    GND @BASEBOARD_FAB2_LIB.BASEBOARD_FAB2(SCH_1):GND    I13 @BASEBOARD_FAB2_LIB.BASEBOARD_FAB2(SCH_1):PAGE123
   B27    GND @BASEBOARD_FAB2_LIB.BASEBOARD_FAB2(SCH_1):GND    I13 @BASEBOARD_FAB2_LIB.BASEBOARD_FAB2(SCH_1):PAGE123
   B47    GND @BASEBOARD_FAB2_LIB.BASEBOARD_FAB2(SCH_1):GND    I13 @BASEBOARD_FAB2_LIB.BASEBOARD_FAB2(SCH_1):PAGE123
   C22    GND @BASEBOARD_FAB2_LIB.BASEBOARD_FAB2(SCH_1):GND    I13 @BASEBOARD_FAB2_LIB.BASEBOARD_FAB2(SCH_1):PAGE123
   C30    GND @BASEBOARD_FAB2_LIB.BASEBOARD_FAB2(SCH_1):GND    I13 @BASEBOARD_FAB2_LIB.BASEBOARD_FAB2(SCH_1):PAGE123
   C34    GND @BASEBOARD_FAB2_LIB.BASEBOARD_FAB2(SCH_1):GND    I13 @BASEBOARD_FAB2_LIB.BASEBOARD_FAB2(SCH_1):PAGE123
   C37    GND @BASEBOARD_FAB2_LIB.BASEBOARD_FAB2(SCH_1):GND    I13 @BASEBOARD_FAB2_LIB.BASEBOARD_FAB2(SCH_1):PAGE123
   C41    GND @BASEBOARD_FAB2_LIB.BASEBOARD_FAB2(SCH_1):GND    I13 @BASEBOARD_FAB2_LIB.BASEBOARD_FAB2(SCH_1):PAGE123
   C65    GND @BASEBOARD_FAB2_LIB.BASEBOARD_FAB2(SCH_1):GND    I13 @BASEBOARD_FAB2_LIB.BASEBOARD_FAB2(SCH_1):PAGE123
   D12    GND @BASEBOARD_FAB2_LIB.BASEBOARD_FAB2(SCH_1):GND    I13 @BASEBOARD_FAB2_LIB.BASEBOARD_FAB2(SCH_1):PAGE123
   D16    GND @BASEBOARD_FAB2_LIB.BASEBOARD_FAB2(SCH_1):GND    I13 @BASEBOARD_FAB2_LIB.BASEBOARD_FAB2(SCH_1):PAGE123
   D19    GND @BASEBOARD_FAB2_LIB.BASEBOARD_FAB2(SCH_1):GND    I13 @BASEBOARD_FAB2_LIB.BASEBOARD_FAB2(SCH_1):PAGE123
   D25    GND @BASEBOARD_FAB2_LIB.BASEBOARD_FAB2(SCH_1):GND    I13 @BASEBOARD_FAB2_LIB.BASEBOARD_FAB2(SCH_1):PAGE123
   D27    GND @BASEBOARD_FAB2_LIB.BASEBOARD_FAB2(SCH_1):GND    I13 @BASEBOARD_FAB2_LIB.BASEBOARD_FAB2(SCH_1):PAGE123
   E59    GND @BASEBOARD_FAB2_LIB.BASEBOARD_FAB2(SCH_1):GND    I13 @BASEBOARD_FAB2_LIB.BASEBOARD_FAB2(SCH_1):PAGE123
   E65    GND @BASEBOARD_FAB2_LIB.BASEBOARD_FAB2(SCH_1):GND    I13 @BASEBOARD_FAB2_LIB.BASEBOARD_FAB2(SCH_1):PAGE123
   D47    GND @BASEBOARD_FAB2_LIB.BASEBOARD_FAB2(SCH_1):GND    I13 @BASEBOARD_FAB2_LIB.BASEBOARD_FAB2(SCH_1):PAGE123
   E11    GND @BASEBOARD_FAB2_LIB.BASEBOARD_FAB2(SCH_1):GND    I13 @BASEBOARD_FAB2_LIB.BASEBOARD_FAB2(SCH_1):PAGE123
   E13    GND @BASEBOARD_FAB2_LIB.BASEBOARD_FAB2(SCH_1):GND    I13 @BASEBOARD_FAB2_LIB.BASEBOARD_FAB2(SCH_1):PAGE123
   E15    GND @BASEBOARD_FAB2_LIB.BASEBOARD_FAB2(SCH_1):GND    I13 @BASEBOARD_FAB2_LIB.BASEBOARD_FAB2(SCH_1):PAGE123
   E20    GND @BASEBOARD_FAB2_LIB.BASEBOARD_FAB2(SCH_1):GND    I13 @BASEBOARD_FAB2_LIB.BASEBOARD_FAB2(SCH_1):PAGE123
   E22    GND @BASEBOARD_FAB2_LIB.BASEBOARD_FAB2(SCH_1):GND    I13 @BASEBOARD_FAB2_LIB.BASEBOARD_FAB2(SCH_1):PAGE123
   E24    GND @BASEBOARD_FAB2_LIB.BASEBOARD_FAB2(SCH_1):GND    I13 @BASEBOARD_FAB2_LIB.BASEBOARD_FAB2(SCH_1):PAGE123
   E26    GND @BASEBOARD_FAB2_LIB.BASEBOARD_FAB2(SCH_1):GND    I13 @BASEBOARD_FAB2_LIB.BASEBOARD_FAB2(SCH_1):PAGE123
   E28    GND @BASEBOARD_FAB2_LIB.BASEBOARD_FAB2(SCH_1):GND    I13 @BASEBOARD_FAB2_LIB.BASEBOARD_FAB2(SCH_1):PAGE123
   E30    GND @BASEBOARD_FAB2_LIB.BASEBOARD_FAB2(SCH_1):GND    I13 @BASEBOARD_FAB2_LIB.BASEBOARD_FAB2(SCH_1):PAGE123
   E32    GND @BASEBOARD_FAB2_LIB.BASEBOARD_FAB2(SCH_1):GND    I13 @BASEBOARD_FAB2_LIB.BASEBOARD_FAB2(SCH_1):PAGE123
   E34    GND @BASEBOARD_FAB2_LIB.BASEBOARD_FAB2(SCH_1):GND    I13 @BASEBOARD_FAB2_LIB.BASEBOARD_FAB2(SCH_1):PAGE123
   E37    GND @BASEBOARD_FAB2_LIB.BASEBOARD_FAB2(SCH_1):GND    I13 @BASEBOARD_FAB2_LIB.BASEBOARD_FAB2(SCH_1):PAGE123
   E39    GND @BASEBOARD_FAB2_LIB.BASEBOARD_FAB2(SCH_1):GND    I13 @BASEBOARD_FAB2_LIB.BASEBOARD_FAB2(SCH_1):PAGE123
   E41    GND @BASEBOARD_FAB2_LIB.BASEBOARD_FAB2(SCH_1):GND    I13 @BASEBOARD_FAB2_LIB.BASEBOARD_FAB2(SCH_1):PAGE123
   E43    GND @BASEBOARD_FAB2_LIB.BASEBOARD_FAB2(SCH_1):GND    I13 @BASEBOARD_FAB2_LIB.BASEBOARD_FAB2(SCH_1):PAGE123
   E45    GND @BASEBOARD_FAB2_LIB.BASEBOARD_FAB2(SCH_1):GND    I13 @BASEBOARD_FAB2_LIB.BASEBOARD_FAB2(SCH_1):PAGE123
   E48    GND @BASEBOARD_FAB2_LIB.BASEBOARD_FAB2(SCH_1):GND    I13 @BASEBOARD_FAB2_LIB.BASEBOARD_FAB2(SCH_1):PAGE123
   E50    GND @BASEBOARD_FAB2_LIB.BASEBOARD_FAB2(SCH_1):GND    I13 @BASEBOARD_FAB2_LIB.BASEBOARD_FAB2(SCH_1):PAGE123
   E52    GND @BASEBOARD_FAB2_LIB.BASEBOARD_FAB2(SCH_1):GND    I13 @BASEBOARD_FAB2_LIB.BASEBOARD_FAB2(SCH_1):PAGE123
   E54    GND @BASEBOARD_FAB2_LIB.BASEBOARD_FAB2(SCH_1):GND    I13 @BASEBOARD_FAB2_LIB.BASEBOARD_FAB2(SCH_1):PAGE123
   E57    GND @BASEBOARD_FAB2_LIB.BASEBOARD_FAB2(SCH_1):GND    I13 @BASEBOARD_FAB2_LIB.BASEBOARD_FAB2(SCH_1):PAGE123
    E6    GND @BASEBOARD_FAB2_LIB.BASEBOARD_FAB2(SCH_1):GND    I13 @BASEBOARD_FAB2_LIB.BASEBOARD_FAB2(SCH_1):PAGE123
   E61    GND @BASEBOARD_FAB2_LIB.BASEBOARD_FAB2(SCH_1):GND    I13 @BASEBOARD_FAB2_LIB.BASEBOARD_FAB2(SCH_1):PAGE123
   E63    GND @BASEBOARD_FAB2_LIB.BASEBOARD_FAB2(SCH_1):GND    I13 @BASEBOARD_FAB2_LIB.BASEBOARD_FAB2(SCH_1):PAGE123
   G59    GND @BASEBOARD_FAB2_LIB.BASEBOARD_FAB2(SCH_1):GND    I13 @BASEBOARD_FAB2_LIB.BASEBOARD_FAB2(SCH_1):PAGE123
    E9    GND @BASEBOARD_FAB2_LIB.BASEBOARD_FAB2(SCH_1):GND    I13 @BASEBOARD_FAB2_LIB.BASEBOARD_FAB2(SCH_1):PAGE123
   G22    GND @BASEBOARD_FAB2_LIB.BASEBOARD_FAB2(SCH_1):GND    I13 @BASEBOARD_FAB2_LIB.BASEBOARD_FAB2(SCH_1):PAGE123
   G29    GND @BASEBOARD_FAB2_LIB.BASEBOARD_FAB2(SCH_1):GND    I13 @BASEBOARD_FAB2_LIB.BASEBOARD_FAB2(SCH_1):PAGE123
   G37    GND @BASEBOARD_FAB2_LIB.BASEBOARD_FAB2(SCH_1):GND    I13 @BASEBOARD_FAB2_LIB.BASEBOARD_FAB2(SCH_1):PAGE123
   G48    GND @BASEBOARD_FAB2_LIB.BASEBOARD_FAB2(SCH_1):GND    I13 @BASEBOARD_FAB2_LIB.BASEBOARD_FAB2(SCH_1):PAGE123
    G6    GND @BASEBOARD_FAB2_LIB.BASEBOARD_FAB2(SCH_1):GND    I13 @BASEBOARD_FAB2_LIB.BASEBOARD_FAB2(SCH_1):PAGE123
   G63    GND @BASEBOARD_FAB2_LIB.BASEBOARD_FAB2(SCH_1):GND    I13 @BASEBOARD_FAB2_LIB.BASEBOARD_FAB2(SCH_1):PAGE123
   G66    GND @BASEBOARD_FAB2_LIB.BASEBOARD_FAB2(SCH_1):GND    I13 @BASEBOARD_FAB2_LIB.BASEBOARD_FAB2(SCH_1):PAGE123
   H58    GND @BASEBOARD_FAB2_LIB.BASEBOARD_FAB2(SCH_1):GND    I13 @BASEBOARD_FAB2_LIB.BASEBOARD_FAB2(SCH_1):PAGE123
   J29    GND @BASEBOARD_FAB2_LIB.BASEBOARD_FAB2(SCH_1):GND    I13 @BASEBOARD_FAB2_LIB.BASEBOARD_FAB2(SCH_1):PAGE123
    J5    GND @BASEBOARD_FAB2_LIB.BASEBOARD_FAB2(SCH_1):GND    I13 @BASEBOARD_FAB2_LIB.BASEBOARD_FAB2(SCH_1):PAGE123
    J7    GND @BASEBOARD_FAB2_LIB.BASEBOARD_FAB2(SCH_1):GND    I13 @BASEBOARD_FAB2_LIB.BASEBOARD_FAB2(SCH_1):PAGE123
   H65    GND @BASEBOARD_FAB2_LIB.BASEBOARD_FAB2(SCH_1):GND    I13 @BASEBOARD_FAB2_LIB.BASEBOARD_FAB2(SCH_1):PAGE123
   J11    GND @BASEBOARD_FAB2_LIB.BASEBOARD_FAB2(SCH_1):GND    I13 @BASEBOARD_FAB2_LIB.BASEBOARD_FAB2(SCH_1):PAGE123
   J15    GND @BASEBOARD_FAB2_LIB.BASEBOARD_FAB2(SCH_1):GND    I13 @BASEBOARD_FAB2_LIB.BASEBOARD_FAB2(SCH_1):PAGE123
   J22    GND @BASEBOARD_FAB2_LIB.BASEBOARD_FAB2(SCH_1):GND    I13 @BASEBOARD_FAB2_LIB.BASEBOARD_FAB2(SCH_1):PAGE123
   J37    GND @BASEBOARD_FAB2_LIB.BASEBOARD_FAB2(SCH_1):GND    I13 @BASEBOARD_FAB2_LIB.BASEBOARD_FAB2(SCH_1):PAGE123
   J44    GND @BASEBOARD_FAB2_LIB.BASEBOARD_FAB2(SCH_1):GND    I13 @BASEBOARD_FAB2_LIB.BASEBOARD_FAB2(SCH_1):PAGE123
   J59    GND @BASEBOARD_FAB2_LIB.BASEBOARD_FAB2(SCH_1):GND    I13 @BASEBOARD_FAB2_LIB.BASEBOARD_FAB2(SCH_1):PAGE123
   J68    GND @BASEBOARD_FAB2_LIB.BASEBOARD_FAB2(SCH_1):GND    I13 @BASEBOARD_FAB2_LIB.BASEBOARD_FAB2(SCH_1):PAGE123
   J70    GND @BASEBOARD_FAB2_LIB.BASEBOARD_FAB2(SCH_1):GND    I13 @BASEBOARD_FAB2_LIB.BASEBOARD_FAB2(SCH_1):PAGE123
   K54    GND @BASEBOARD_FAB2_LIB.BASEBOARD_FAB2(SCH_1):GND    I13 @BASEBOARD_FAB2_LIB.BASEBOARD_FAB2(SCH_1):PAGE123
   K69    GND @BASEBOARD_FAB2_LIB.BASEBOARD_FAB2(SCH_1):GND    I13 @BASEBOARD_FAB2_LIB.BASEBOARD_FAB2(SCH_1):PAGE123
   K71    GND @BASEBOARD_FAB2_LIB.BASEBOARD_FAB2(SCH_1):GND    I13 @BASEBOARD_FAB2_LIB.BASEBOARD_FAB2(SCH_1):PAGE123
    L5    GND @BASEBOARD_FAB2_LIB.BASEBOARD_FAB2(SCH_1):GND    I13 @BASEBOARD_FAB2_LIB.BASEBOARD_FAB2(SCH_1):PAGE123
   L68    GND @BASEBOARD_FAB2_LIB.BASEBOARD_FAB2(SCH_1):GND    I13 @BASEBOARD_FAB2_LIB.BASEBOARD_FAB2(SCH_1):PAGE123
    M2    GND @BASEBOARD_FAB2_LIB.BASEBOARD_FAB2(SCH_1):GND    I13 @BASEBOARD_FAB2_LIB.BASEBOARD_FAB2(SCH_1):PAGE123
   M22    GND @BASEBOARD_FAB2_LIB.BASEBOARD_FAB2(SCH_1):GND    I13 @BASEBOARD_FAB2_LIB.BASEBOARD_FAB2(SCH_1):PAGE123
   M26    GND @BASEBOARD_FAB2_LIB.BASEBOARD_FAB2(SCH_1):GND    I13 @BASEBOARD_FAB2_LIB.BASEBOARD_FAB2(SCH_1):PAGE123
   M29    GND @BASEBOARD_FAB2_LIB.BASEBOARD_FAB2(SCH_1):GND    I13 @BASEBOARD_FAB2_LIB.BASEBOARD_FAB2(SCH_1):PAGE123
   M33    GND @BASEBOARD_FAB2_LIB.BASEBOARD_FAB2(SCH_1):GND    I13 @BASEBOARD_FAB2_LIB.BASEBOARD_FAB2(SCH_1):PAGE123
   M37    GND @BASEBOARD_FAB2_LIB.BASEBOARD_FAB2(SCH_1):GND    I13 @BASEBOARD_FAB2_LIB.BASEBOARD_FAB2(SCH_1):PAGE123
    M4    GND @BASEBOARD_FAB2_LIB.BASEBOARD_FAB2(SCH_1):GND    I13 @BASEBOARD_FAB2_LIB.BASEBOARD_FAB2(SCH_1):PAGE123
   M40    GND @BASEBOARD_FAB2_LIB.BASEBOARD_FAB2(SCH_1):GND    I13 @BASEBOARD_FAB2_LIB.BASEBOARD_FAB2(SCH_1):PAGE123
   N42    GND @BASEBOARD_FAB2_LIB.BASEBOARD_FAB2(SCH_1):GND    I13 @BASEBOARD_FAB2_LIB.BASEBOARD_FAB2(SCH_1):PAGE123
   N50    GND @BASEBOARD_FAB2_LIB.BASEBOARD_FAB2(SCH_1):GND    I13 @BASEBOARD_FAB2_LIB.BASEBOARD_FAB2(SCH_1):PAGE123
   M44    GND @BASEBOARD_FAB2_LIB.BASEBOARD_FAB2(SCH_1):GND    I13 @BASEBOARD_FAB2_LIB.BASEBOARD_FAB2(SCH_1):PAGE123
   M48    GND @BASEBOARD_FAB2_LIB.BASEBOARD_FAB2(SCH_1):GND    I13 @BASEBOARD_FAB2_LIB.BASEBOARD_FAB2(SCH_1):PAGE123
   N13    GND @BASEBOARD_FAB2_LIB.BASEBOARD_FAB2(SCH_1):GND    I13 @BASEBOARD_FAB2_LIB.BASEBOARD_FAB2(SCH_1):PAGE123
   N17    GND @BASEBOARD_FAB2_LIB.BASEBOARD_FAB2(SCH_1):GND    I13 @BASEBOARD_FAB2_LIB.BASEBOARD_FAB2(SCH_1):PAGE123
   N20    GND @BASEBOARD_FAB2_LIB.BASEBOARD_FAB2(SCH_1):GND    I13 @BASEBOARD_FAB2_LIB.BASEBOARD_FAB2(SCH_1):PAGE123
   N24    GND @BASEBOARD_FAB2_LIB.BASEBOARD_FAB2(SCH_1):GND    I13 @BASEBOARD_FAB2_LIB.BASEBOARD_FAB2(SCH_1):PAGE123
   N27    GND @BASEBOARD_FAB2_LIB.BASEBOARD_FAB2(SCH_1):GND    I13 @BASEBOARD_FAB2_LIB.BASEBOARD_FAB2(SCH_1):PAGE123
   N31    GND @BASEBOARD_FAB2_LIB.BASEBOARD_FAB2(SCH_1):GND    I13 @BASEBOARD_FAB2_LIB.BASEBOARD_FAB2(SCH_1):PAGE123
   N35    GND @BASEBOARD_FAB2_LIB.BASEBOARD_FAB2(SCH_1):GND    I17 @BASEBOARD_FAB2_LIB.BASEBOARD_FAB2(SCH_1):PAGE124
   N38    GND @BASEBOARD_FAB2_LIB.BASEBOARD_FAB2(SCH_1):GND    I17 @BASEBOARD_FAB2_LIB.BASEBOARD_FAB2(SCH_1):PAGE124
   N46    GND @BASEBOARD_FAB2_LIB.BASEBOARD_FAB2(SCH_1):GND    I17 @BASEBOARD_FAB2_LIB.BASEBOARD_FAB2(SCH_1):PAGE124
    N5    GND @BASEBOARD_FAB2_LIB.BASEBOARD_FAB2(SCH_1):GND    I17 @BASEBOARD_FAB2_LIB.BASEBOARD_FAB2(SCH_1):PAGE124
   R38    GND @BASEBOARD_FAB2_LIB.BASEBOARD_FAB2(SCH_1):GND    I17 @BASEBOARD_FAB2_LIB.BASEBOARD_FAB2(SCH_1):PAGE124
   N68    GND @BASEBOARD_FAB2_LIB.BASEBOARD_FAB2(SCH_1):GND    I17 @BASEBOARD_FAB2_LIB.BASEBOARD_FAB2(SCH_1):PAGE124
    N9    GND @BASEBOARD_FAB2_LIB.BASEBOARD_FAB2(SCH_1):GND    I17 @BASEBOARD_FAB2_LIB.BASEBOARD_FAB2(SCH_1):PAGE124
  AE43    GND @BASEBOARD_FAB2_LIB.BASEBOARD_FAB2(SCH_1):GND    I17 @BASEBOARD_FAB2_LIB.BASEBOARD_FAB2(SCH_1):PAGE124
   P63    GND @BASEBOARD_FAB2_LIB.BASEBOARD_FAB2(SCH_1):GND    I17 @BASEBOARD_FAB2_LIB.BASEBOARD_FAB2(SCH_1):PAGE124
   R27    GND @BASEBOARD_FAB2_LIB.BASEBOARD_FAB2(SCH_1):GND    I17 @BASEBOARD_FAB2_LIB.BASEBOARD_FAB2(SCH_1):PAGE124
   U42    GND @BASEBOARD_FAB2_LIB.BASEBOARD_FAB2(SCH_1):GND    I17 @BASEBOARD_FAB2_LIB.BASEBOARD_FAB2(SCH_1):PAGE124
    R5    GND @BASEBOARD_FAB2_LIB.BASEBOARD_FAB2(SCH_1):GND    I17 @BASEBOARD_FAB2_LIB.BASEBOARD_FAB2(SCH_1):PAGE124
   R50    GND @BASEBOARD_FAB2_LIB.BASEBOARD_FAB2(SCH_1):GND    I17 @BASEBOARD_FAB2_LIB.BASEBOARD_FAB2(SCH_1):PAGE124
   R54    GND @BASEBOARD_FAB2_LIB.BASEBOARD_FAB2(SCH_1):GND    I17 @BASEBOARD_FAB2_LIB.BASEBOARD_FAB2(SCH_1):PAGE124
   T56    GND @BASEBOARD_FAB2_LIB.BASEBOARD_FAB2(SCH_1):GND    I17 @BASEBOARD_FAB2_LIB.BASEBOARD_FAB2(SCH_1):PAGE124
   R58    GND @BASEBOARD_FAB2_LIB.BASEBOARD_FAB2(SCH_1):GND    I17 @BASEBOARD_FAB2_LIB.BASEBOARD_FAB2(SCH_1):PAGE124
   R68    GND @BASEBOARD_FAB2_LIB.BASEBOARD_FAB2(SCH_1):GND    I17 @BASEBOARD_FAB2_LIB.BASEBOARD_FAB2(SCH_1):PAGE124
   T11    GND @BASEBOARD_FAB2_LIB.BASEBOARD_FAB2(SCH_1):GND    I17 @BASEBOARD_FAB2_LIB.BASEBOARD_FAB2(SCH_1):PAGE124
   T15    GND @BASEBOARD_FAB2_LIB.BASEBOARD_FAB2(SCH_1):GND    I17 @BASEBOARD_FAB2_LIB.BASEBOARD_FAB2(SCH_1):PAGE124
   T18    GND @BASEBOARD_FAB2_LIB.BASEBOARD_FAB2(SCH_1):GND    I17 @BASEBOARD_FAB2_LIB.BASEBOARD_FAB2(SCH_1):PAGE124
   T22    GND @BASEBOARD_FAB2_LIB.BASEBOARD_FAB2(SCH_1):GND    I17 @BASEBOARD_FAB2_LIB.BASEBOARD_FAB2(SCH_1):PAGE124
   T26    GND @BASEBOARD_FAB2_LIB.BASEBOARD_FAB2(SCH_1):GND    I17 @BASEBOARD_FAB2_LIB.BASEBOARD_FAB2(SCH_1):PAGE124
   T29    GND @BASEBOARD_FAB2_LIB.BASEBOARD_FAB2(SCH_1):GND    I17 @BASEBOARD_FAB2_LIB.BASEBOARD_FAB2(SCH_1):PAGE124
   T33    GND @BASEBOARD_FAB2_LIB.BASEBOARD_FAB2(SCH_1):GND    I17 @BASEBOARD_FAB2_LIB.BASEBOARD_FAB2(SCH_1):PAGE124
   T37    GND @BASEBOARD_FAB2_LIB.BASEBOARD_FAB2(SCH_1):GND    I17 @BASEBOARD_FAB2_LIB.BASEBOARD_FAB2(SCH_1):PAGE124
   T40    GND @BASEBOARD_FAB2_LIB.BASEBOARD_FAB2(SCH_1):GND    I17 @BASEBOARD_FAB2_LIB.BASEBOARD_FAB2(SCH_1):PAGE124
  AJ45    GND @BASEBOARD_FAB2_LIB.BASEBOARD_FAB2(SCH_1):GND    I17 @BASEBOARD_FAB2_LIB.BASEBOARD_FAB2(SCH_1):PAGE124
   T48    GND @BASEBOARD_FAB2_LIB.BASEBOARD_FAB2(SCH_1):GND    I17 @BASEBOARD_FAB2_LIB.BASEBOARD_FAB2(SCH_1):PAGE124
   T52    GND @BASEBOARD_FAB2_LIB.BASEBOARD_FAB2(SCH_1):GND    I17 @BASEBOARD_FAB2_LIB.BASEBOARD_FAB2(SCH_1):PAGE124
   T66    GND @BASEBOARD_FAB2_LIB.BASEBOARD_FAB2(SCH_1):GND    I17 @BASEBOARD_FAB2_LIB.BASEBOARD_FAB2(SCH_1):PAGE124
    T7    GND @BASEBOARD_FAB2_LIB.BASEBOARD_FAB2(SCH_1):GND    I17 @BASEBOARD_FAB2_LIB.BASEBOARD_FAB2(SCH_1):PAGE124
  AF50    GND @BASEBOARD_FAB2_LIB.BASEBOARD_FAB2(SCH_1):GND    I17 @BASEBOARD_FAB2_LIB.BASEBOARD_FAB2(SCH_1):PAGE124
  AG46    GND @BASEBOARD_FAB2_LIB.BASEBOARD_FAB2(SCH_1):GND    I17 @BASEBOARD_FAB2_LIB.BASEBOARD_FAB2(SCH_1):PAGE124
   U58    GND @BASEBOARD_FAB2_LIB.BASEBOARD_FAB2(SCH_1):GND    I17 @BASEBOARD_FAB2_LIB.BASEBOARD_FAB2(SCH_1):PAGE124
   V26    GND @BASEBOARD_FAB2_LIB.BASEBOARD_FAB2(SCH_1):GND    I17 @BASEBOARD_FAB2_LIB.BASEBOARD_FAB2(SCH_1):PAGE124
   V48    GND @BASEBOARD_FAB2_LIB.BASEBOARD_FAB2(SCH_1):GND    I17 @BASEBOARD_FAB2_LIB.BASEBOARD_FAB2(SCH_1):PAGE124
    V5    GND @BASEBOARD_FAB2_LIB.BASEBOARD_FAB2(SCH_1):GND    I17 @BASEBOARD_FAB2_LIB.BASEBOARD_FAB2(SCH_1):PAGE124
   V52    GND @BASEBOARD_FAB2_LIB.BASEBOARD_FAB2(SCH_1):GND    I17 @BASEBOARD_FAB2_LIB.BASEBOARD_FAB2(SCH_1):PAGE124
   W58    GND @BASEBOARD_FAB2_LIB.BASEBOARD_FAB2(SCH_1):GND    I17 @BASEBOARD_FAB2_LIB.BASEBOARD_FAB2(SCH_1):PAGE124
   V66    GND @BASEBOARD_FAB2_LIB.BASEBOARD_FAB2(SCH_1):GND    I17 @BASEBOARD_FAB2_LIB.BASEBOARD_FAB2(SCH_1):PAGE124
   V68    GND @BASEBOARD_FAB2_LIB.BASEBOARD_FAB2(SCH_1):GND    I17 @BASEBOARD_FAB2_LIB.BASEBOARD_FAB2(SCH_1):PAGE124
   W13    GND @BASEBOARD_FAB2_LIB.BASEBOARD_FAB2(SCH_1):GND    I17 @BASEBOARD_FAB2_LIB.BASEBOARD_FAB2(SCH_1):PAGE124
   W17    GND @BASEBOARD_FAB2_LIB.BASEBOARD_FAB2(SCH_1):GND    I17 @BASEBOARD_FAB2_LIB.BASEBOARD_FAB2(SCH_1):PAGE124
   W20    GND @BASEBOARD_FAB2_LIB.BASEBOARD_FAB2(SCH_1):GND    I17 @BASEBOARD_FAB2_LIB.BASEBOARD_FAB2(SCH_1):PAGE124
   W24    GND @BASEBOARD_FAB2_LIB.BASEBOARD_FAB2(SCH_1):GND    I17 @BASEBOARD_FAB2_LIB.BASEBOARD_FAB2(SCH_1):PAGE124
  AA50    GND @BASEBOARD_FAB2_LIB.BASEBOARD_FAB2(SCH_1):GND    I17 @BASEBOARD_FAB2_LIB.BASEBOARD_FAB2(SCH_1):PAGE124
   Y43    GND @BASEBOARD_FAB2_LIB.BASEBOARD_FAB2(SCH_1):GND    I17 @BASEBOARD_FAB2_LIB.BASEBOARD_FAB2(SCH_1):PAGE124
   W61    GND @BASEBOARD_FAB2_LIB.BASEBOARD_FAB2(SCH_1):GND    I17 @BASEBOARD_FAB2_LIB.BASEBOARD_FAB2(SCH_1):PAGE124
    W9    GND @BASEBOARD_FAB2_LIB.BASEBOARD_FAB2(SCH_1):GND    I17 @BASEBOARD_FAB2_LIB.BASEBOARD_FAB2(SCH_1):PAGE124
   Y22    GND @BASEBOARD_FAB2_LIB.BASEBOARD_FAB2(SCH_1):GND    I17 @BASEBOARD_FAB2_LIB.BASEBOARD_FAB2(SCH_1):PAGE124
   Y27    GND @BASEBOARD_FAB2_LIB.BASEBOARD_FAB2(SCH_1):GND    I17 @BASEBOARD_FAB2_LIB.BASEBOARD_FAB2(SCH_1):PAGE124
   Y48    GND @BASEBOARD_FAB2_LIB.BASEBOARD_FAB2(SCH_1):GND    I17 @BASEBOARD_FAB2_LIB.BASEBOARD_FAB2(SCH_1):PAGE124
    Y5    GND @BASEBOARD_FAB2_LIB.BASEBOARD_FAB2(SCH_1):GND    I17 @BASEBOARD_FAB2_LIB.BASEBOARD_FAB2(SCH_1):PAGE124
   Y52    GND @BASEBOARD_FAB2_LIB.BASEBOARD_FAB2(SCH_1):GND    I17 @BASEBOARD_FAB2_LIB.BASEBOARD_FAB2(SCH_1):PAGE124
   Y59    GND @BASEBOARD_FAB2_LIB.BASEBOARD_FAB2(SCH_1):GND    I17 @BASEBOARD_FAB2_LIB.BASEBOARD_FAB2(SCH_1):PAGE124
   Y63    GND @BASEBOARD_FAB2_LIB.BASEBOARD_FAB2(SCH_1):GND    I17 @BASEBOARD_FAB2_LIB.BASEBOARD_FAB2(SCH_1):PAGE124
   Y68    GND @BASEBOARD_FAB2_LIB.BASEBOARD_FAB2(SCH_1):GND    I17 @BASEBOARD_FAB2_LIB.BASEBOARD_FAB2(SCH_1):PAGE124
  AA26    GND @BASEBOARD_FAB2_LIB.BASEBOARD_FAB2(SCH_1):GND    I17 @BASEBOARD_FAB2_LIB.BASEBOARD_FAB2(SCH_1):PAGE124
  AA27    GND @BASEBOARD_FAB2_LIB.BASEBOARD_FAB2(SCH_1):GND    I17 @BASEBOARD_FAB2_LIB.BASEBOARD_FAB2(SCH_1):PAGE124
  AA43    GND @BASEBOARD_FAB2_LIB.BASEBOARD_FAB2(SCH_1):GND    I17 @BASEBOARD_FAB2_LIB.BASEBOARD_FAB2(SCH_1):PAGE124
  AA48    GND @BASEBOARD_FAB2_LIB.BASEBOARD_FAB2(SCH_1):GND    I17 @BASEBOARD_FAB2_LIB.BASEBOARD_FAB2(SCH_1):PAGE124
   AB5    GND @BASEBOARD_FAB2_LIB.BASEBOARD_FAB2(SCH_1):GND    I17 @BASEBOARD_FAB2_LIB.BASEBOARD_FAB2(SCH_1):PAGE124
  AB68    GND @BASEBOARD_FAB2_LIB.BASEBOARD_FAB2(SCH_1):GND    I17 @BASEBOARD_FAB2_LIB.BASEBOARD_FAB2(SCH_1):PAGE124
  AB70    GND @BASEBOARD_FAB2_LIB.BASEBOARD_FAB2(SCH_1):GND    I17 @BASEBOARD_FAB2_LIB.BASEBOARD_FAB2(SCH_1):PAGE124
  AB72    GND @BASEBOARD_FAB2_LIB.BASEBOARD_FAB2(SCH_1):GND    I17 @BASEBOARD_FAB2_LIB.BASEBOARD_FAB2(SCH_1):PAGE124
  AC11    GND @BASEBOARD_FAB2_LIB.BASEBOARD_FAB2(SCH_1):GND    I17 @BASEBOARD_FAB2_LIB.BASEBOARD_FAB2(SCH_1):PAGE124
  AC15    GND @BASEBOARD_FAB2_LIB.BASEBOARD_FAB2(SCH_1):GND    I17 @BASEBOARD_FAB2_LIB.BASEBOARD_FAB2(SCH_1):PAGE124
  AC18    GND @BASEBOARD_FAB2_LIB.BASEBOARD_FAB2(SCH_1):GND    I17 @BASEBOARD_FAB2_LIB.BASEBOARD_FAB2(SCH_1):PAGE124
  AC22    GND @BASEBOARD_FAB2_LIB.BASEBOARD_FAB2(SCH_1):GND    I17 @BASEBOARD_FAB2_LIB.BASEBOARD_FAB2(SCH_1):PAGE124
  AC45    GND @BASEBOARD_FAB2_LIB.BASEBOARD_FAB2(SCH_1):GND    I17 @BASEBOARD_FAB2_LIB.BASEBOARD_FAB2(SCH_1):PAGE124
  AD58    GND @BASEBOARD_FAB2_LIB.BASEBOARD_FAB2(SCH_1):GND    I17 @BASEBOARD_FAB2_LIB.BASEBOARD_FAB2(SCH_1):PAGE124
  AC27    GND @BASEBOARD_FAB2_LIB.BASEBOARD_FAB2(SCH_1):GND    I17 @BASEBOARD_FAB2_LIB.BASEBOARD_FAB2(SCH_1):PAGE124
  AC43    GND @BASEBOARD_FAB2_LIB.BASEBOARD_FAB2(SCH_1):GND    I17 @BASEBOARD_FAB2_LIB.BASEBOARD_FAB2(SCH_1):PAGE124
  AC46    GND @BASEBOARD_FAB2_LIB.BASEBOARD_FAB2(SCH_1):GND    I17 @BASEBOARD_FAB2_LIB.BASEBOARD_FAB2(SCH_1):PAGE124
  AC48    GND @BASEBOARD_FAB2_LIB.BASEBOARD_FAB2(SCH_1):GND    I17 @BASEBOARD_FAB2_LIB.BASEBOARD_FAB2(SCH_1):PAGE124
  AC52    GND @BASEBOARD_FAB2_LIB.BASEBOARD_FAB2(SCH_1):GND    I17 @BASEBOARD_FAB2_LIB.BASEBOARD_FAB2(SCH_1):PAGE124
  AC59    GND @BASEBOARD_FAB2_LIB.BASEBOARD_FAB2(SCH_1):GND    I17 @BASEBOARD_FAB2_LIB.BASEBOARD_FAB2(SCH_1):PAGE124
  AC63    GND @BASEBOARD_FAB2_LIB.BASEBOARD_FAB2(SCH_1):GND    I17 @BASEBOARD_FAB2_LIB.BASEBOARD_FAB2(SCH_1):PAGE124
  AC66    GND @BASEBOARD_FAB2_LIB.BASEBOARD_FAB2(SCH_1):GND    I17 @BASEBOARD_FAB2_LIB.BASEBOARD_FAB2(SCH_1):PAGE124
   AC7    GND @BASEBOARD_FAB2_LIB.BASEBOARD_FAB2(SCH_1):GND    I17 @BASEBOARD_FAB2_LIB.BASEBOARD_FAB2(SCH_1):PAGE124
   AD5    GND @BASEBOARD_FAB2_LIB.BASEBOARD_FAB2(SCH_1):GND    I17 @BASEBOARD_FAB2_LIB.BASEBOARD_FAB2(SCH_1):PAGE124
  AD65    GND @BASEBOARD_FAB2_LIB.BASEBOARD_FAB2(SCH_1):GND    I17 @BASEBOARD_FAB2_LIB.BASEBOARD_FAB2(SCH_1):PAGE124
  AD68    GND @BASEBOARD_FAB2_LIB.BASEBOARD_FAB2(SCH_1):GND    I17 @BASEBOARD_FAB2_LIB.BASEBOARD_FAB2(SCH_1):PAGE124
  AE29    GND @BASEBOARD_FAB2_LIB.BASEBOARD_FAB2(SCH_1):GND    I17 @BASEBOARD_FAB2_LIB.BASEBOARD_FAB2(SCH_1):PAGE124
   J18    GND @BASEBOARD_FAB2_LIB.BASEBOARD_FAB2(SCH_1):GND    I17 @BASEBOARD_FAB2_LIB.BASEBOARD_FAB2(SCH_1):PAGE124
  AE48    GND @BASEBOARD_FAB2_LIB.BASEBOARD_FAB2(SCH_1):GND    I17 @BASEBOARD_FAB2_LIB.BASEBOARD_FAB2(SCH_1):PAGE124
  AE52    GND @BASEBOARD_FAB2_LIB.BASEBOARD_FAB2(SCH_1):GND    I17 @BASEBOARD_FAB2_LIB.BASEBOARD_FAB2(SCH_1):PAGE124
  AE56    GND @BASEBOARD_FAB2_LIB.BASEBOARD_FAB2(SCH_1):GND    I17 @BASEBOARD_FAB2_LIB.BASEBOARD_FAB2(SCH_1):PAGE124
  AE59    GND @BASEBOARD_FAB2_LIB.BASEBOARD_FAB2(SCH_1):GND    I17 @BASEBOARD_FAB2_LIB.BASEBOARD_FAB2(SCH_1):PAGE124
  AE63    GND @BASEBOARD_FAB2_LIB.BASEBOARD_FAB2(SCH_1):GND    I17 @BASEBOARD_FAB2_LIB.BASEBOARD_FAB2(SCH_1):PAGE124
  AE66    GND @BASEBOARD_FAB2_LIB.BASEBOARD_FAB2(SCH_1):GND    I17 @BASEBOARD_FAB2_LIB.BASEBOARD_FAB2(SCH_1):PAGE124
   AF1    GND @BASEBOARD_FAB2_LIB.BASEBOARD_FAB2(SCH_1):GND    I17 @BASEBOARD_FAB2_LIB.BASEBOARD_FAB2(SCH_1):PAGE124
  AF13    GND @BASEBOARD_FAB2_LIB.BASEBOARD_FAB2(SCH_1):GND    I17 @BASEBOARD_FAB2_LIB.BASEBOARD_FAB2(SCH_1):PAGE124
   AF5    GND @BASEBOARD_FAB2_LIB.BASEBOARD_FAB2(SCH_1):GND    I17 @BASEBOARD_FAB2_LIB.BASEBOARD_FAB2(SCH_1):PAGE124
   AF9    GND @BASEBOARD_FAB2_LIB.BASEBOARD_FAB2(SCH_1):GND    I17 @BASEBOARD_FAB2_LIB.BASEBOARD_FAB2(SCH_1):PAGE124
  AF17    GND @BASEBOARD_FAB2_LIB.BASEBOARD_FAB2(SCH_1):GND    I17 @BASEBOARD_FAB2_LIB.BASEBOARD_FAB2(SCH_1):PAGE124
  AF24    GND @BASEBOARD_FAB2_LIB.BASEBOARD_FAB2(SCH_1):GND    I17 @BASEBOARD_FAB2_LIB.BASEBOARD_FAB2(SCH_1):PAGE124
   AF3    GND @BASEBOARD_FAB2_LIB.BASEBOARD_FAB2(SCH_1):GND    I17 @BASEBOARD_FAB2_LIB.BASEBOARD_FAB2(SCH_1):PAGE124
  AF68    GND @BASEBOARD_FAB2_LIB.BASEBOARD_FAB2(SCH_1):GND    I17 @BASEBOARD_FAB2_LIB.BASEBOARD_FAB2(SCH_1):PAGE124
  AG26    GND @BASEBOARD_FAB2_LIB.BASEBOARD_FAB2(SCH_1):GND    I17 @BASEBOARD_FAB2_LIB.BASEBOARD_FAB2(SCH_1):PAGE124
  AG30    GND @BASEBOARD_FAB2_LIB.BASEBOARD_FAB2(SCH_1):GND    I17 @BASEBOARD_FAB2_LIB.BASEBOARD_FAB2(SCH_1):PAGE124
  AG41    GND @BASEBOARD_FAB2_LIB.BASEBOARD_FAB2(SCH_1):GND    I17 @BASEBOARD_FAB2_LIB.BASEBOARD_FAB2(SCH_1):PAGE124
  AG43    GND @BASEBOARD_FAB2_LIB.BASEBOARD_FAB2(SCH_1):GND    I17 @BASEBOARD_FAB2_LIB.BASEBOARD_FAB2(SCH_1):PAGE124
  AG52    GND @BASEBOARD_FAB2_LIB.BASEBOARD_FAB2(SCH_1):GND    I17 @BASEBOARD_FAB2_LIB.BASEBOARD_FAB2(SCH_1):PAGE124
  AG56    GND @BASEBOARD_FAB2_LIB.BASEBOARD_FAB2(SCH_1):GND    I17 @BASEBOARD_FAB2_LIB.BASEBOARD_FAB2(SCH_1):PAGE124
  AG59    GND @BASEBOARD_FAB2_LIB.BASEBOARD_FAB2(SCH_1):GND    I17 @BASEBOARD_FAB2_LIB.BASEBOARD_FAB2(SCH_1):PAGE124
  AG66    GND @BASEBOARD_FAB2_LIB.BASEBOARD_FAB2(SCH_1):GND    I17 @BASEBOARD_FAB2_LIB.BASEBOARD_FAB2(SCH_1):PAGE124
  AH20    GND @BASEBOARD_FAB2_LIB.BASEBOARD_FAB2(SCH_1):GND    I17 @BASEBOARD_FAB2_LIB.BASEBOARD_FAB2(SCH_1):PAGE124
  AJ11    GND @BASEBOARD_FAB2_LIB.BASEBOARD_FAB2(SCH_1):GND    I17 @BASEBOARD_FAB2_LIB.BASEBOARD_FAB2(SCH_1):PAGE124
  AJ32    GND @BASEBOARD_FAB2_LIB.BASEBOARD_FAB2(SCH_1):GND    I17 @BASEBOARD_FAB2_LIB.BASEBOARD_FAB2(SCH_1):PAGE124
  AJ56    GND @BASEBOARD_FAB2_LIB.BASEBOARD_FAB2(SCH_1):GND    I17 @BASEBOARD_FAB2_LIB.BASEBOARD_FAB2(SCH_1):PAGE124
  AK30    GND @BASEBOARD_FAB2_LIB.BASEBOARD_FAB2(SCH_1):GND    I17 @BASEBOARD_FAB2_LIB.BASEBOARD_FAB2(SCH_1):PAGE124
  AJ15    GND @BASEBOARD_FAB2_LIB.BASEBOARD_FAB2(SCH_1):GND    I17 @BASEBOARD_FAB2_LIB.BASEBOARD_FAB2(SCH_1):PAGE124
  AJ18    GND @BASEBOARD_FAB2_LIB.BASEBOARD_FAB2(SCH_1):GND    I17 @BASEBOARD_FAB2_LIB.BASEBOARD_FAB2(SCH_1):PAGE124
  AJ22    GND @BASEBOARD_FAB2_LIB.BASEBOARD_FAB2(SCH_1):GND    I17 @BASEBOARD_FAB2_LIB.BASEBOARD_FAB2(SCH_1):PAGE124
  AJ26    GND @BASEBOARD_FAB2_LIB.BASEBOARD_FAB2(SCH_1):GND    I17 @BASEBOARD_FAB2_LIB.BASEBOARD_FAB2(SCH_1):PAGE124
  AJ30    GND @BASEBOARD_FAB2_LIB.BASEBOARD_FAB2(SCH_1):GND    I17 @BASEBOARD_FAB2_LIB.BASEBOARD_FAB2(SCH_1):PAGE124
  AJ34    GND @BASEBOARD_FAB2_LIB.BASEBOARD_FAB2(SCH_1):GND    I17 @BASEBOARD_FAB2_LIB.BASEBOARD_FAB2(SCH_1):PAGE124
  AJ36    GND @BASEBOARD_FAB2_LIB.BASEBOARD_FAB2(SCH_1):GND    I17 @BASEBOARD_FAB2_LIB.BASEBOARD_FAB2(SCH_1):PAGE124
  AJ37    GND @BASEBOARD_FAB2_LIB.BASEBOARD_FAB2(SCH_1):GND    I17 @BASEBOARD_FAB2_LIB.BASEBOARD_FAB2(SCH_1):PAGE124
  AJ39    GND @BASEBOARD_FAB2_LIB.BASEBOARD_FAB2(SCH_1):GND    I17 @BASEBOARD_FAB2_LIB.BASEBOARD_FAB2(SCH_1):PAGE124
  AJ41    GND @BASEBOARD_FAB2_LIB.BASEBOARD_FAB2(SCH_1):GND    I17 @BASEBOARD_FAB2_LIB.BASEBOARD_FAB2(SCH_1):PAGE124
   AJ5    GND @BASEBOARD_FAB2_LIB.BASEBOARD_FAB2(SCH_1):GND    I17 @BASEBOARD_FAB2_LIB.BASEBOARD_FAB2(SCH_1):PAGE124
  AJ52    GND @BASEBOARD_FAB2_LIB.BASEBOARD_FAB2(SCH_1):GND    I17 @BASEBOARD_FAB2_LIB.BASEBOARD_FAB2(SCH_1):PAGE124
  AJ59    GND @BASEBOARD_FAB2_LIB.BASEBOARD_FAB2(SCH_1):GND    I17 @BASEBOARD_FAB2_LIB.BASEBOARD_FAB2(SCH_1):PAGE124
  AJ66    GND @BASEBOARD_FAB2_LIB.BASEBOARD_FAB2(SCH_1):GND    I17 @BASEBOARD_FAB2_LIB.BASEBOARD_FAB2(SCH_1):PAGE124
  AJ68    GND @BASEBOARD_FAB2_LIB.BASEBOARD_FAB2(SCH_1):GND    I17 @BASEBOARD_FAB2_LIB.BASEBOARD_FAB2(SCH_1):PAGE124
   AJ7    GND @BASEBOARD_FAB2_LIB.BASEBOARD_FAB2(SCH_1):GND    I17 @BASEBOARD_FAB2_LIB.BASEBOARD_FAB2(SCH_1):PAGE124
  AK26    GND @BASEBOARD_FAB2_LIB.BASEBOARD_FAB2(SCH_1):GND    I17 @BASEBOARD_FAB2_LIB.BASEBOARD_FAB2(SCH_1):PAGE124
  AK41    GND @BASEBOARD_FAB2_LIB.BASEBOARD_FAB2(SCH_1):GND    I17 @BASEBOARD_FAB2_LIB.BASEBOARD_FAB2(SCH_1):PAGE124
  AK46    GND @BASEBOARD_FAB2_LIB.BASEBOARD_FAB2(SCH_1):GND    I17 @BASEBOARD_FAB2_LIB.BASEBOARD_FAB2(SCH_1):PAGE124
  AK48    GND @BASEBOARD_FAB2_LIB.BASEBOARD_FAB2(SCH_1):GND    I17 @BASEBOARD_FAB2_LIB.BASEBOARD_FAB2(SCH_1):PAGE124
  AK58    GND @BASEBOARD_FAB2_LIB.BASEBOARD_FAB2(SCH_1):GND    I17 @BASEBOARD_FAB2_LIB.BASEBOARD_FAB2(SCH_1):PAGE124
  AK61    GND @BASEBOARD_FAB2_LIB.BASEBOARD_FAB2(SCH_1):GND    I17 @BASEBOARD_FAB2_LIB.BASEBOARD_FAB2(SCH_1):PAGE124
  AK69    GND @BASEBOARD_FAB2_LIB.BASEBOARD_FAB2(SCH_1):GND    I17 @BASEBOARD_FAB2_LIB.BASEBOARD_FAB2(SCH_1):PAGE124
  AK71    GND @BASEBOARD_FAB2_LIB.BASEBOARD_FAB2(SCH_1):GND    I17 @BASEBOARD_FAB2_LIB.BASEBOARD_FAB2(SCH_1):PAGE124
  AL22    GND @BASEBOARD_FAB2_LIB.BASEBOARD_FAB2(SCH_1):GND    I17 @BASEBOARD_FAB2_LIB.BASEBOARD_FAB2(SCH_1):PAGE124
   AL5    GND @BASEBOARD_FAB2_LIB.BASEBOARD_FAB2(SCH_1):GND    I17 @BASEBOARD_FAB2_LIB.BASEBOARD_FAB2(SCH_1):PAGE124
  AL52    GND @BASEBOARD_FAB2_LIB.BASEBOARD_FAB2(SCH_1):GND    I17 @BASEBOARD_FAB2_LIB.BASEBOARD_FAB2(SCH_1):PAGE124
  AL59    GND @BASEBOARD_FAB2_LIB.BASEBOARD_FAB2(SCH_1):GND    I17 @BASEBOARD_FAB2_LIB.BASEBOARD_FAB2(SCH_1):PAGE124
  AL68    GND @BASEBOARD_FAB2_LIB.BASEBOARD_FAB2(SCH_1):GND    I16 @BASEBOARD_FAB2_LIB.BASEBOARD_FAB2(SCH_1):PAGE124
  AL70    GND @BASEBOARD_FAB2_LIB.BASEBOARD_FAB2(SCH_1):GND    I16 @BASEBOARD_FAB2_LIB.BASEBOARD_FAB2(SCH_1):PAGE124
  AL72    GND @BASEBOARD_FAB2_LIB.BASEBOARD_FAB2(SCH_1):GND    I16 @BASEBOARD_FAB2_LIB.BASEBOARD_FAB2(SCH_1):PAGE124
  AM26    GND @BASEBOARD_FAB2_LIB.BASEBOARD_FAB2(SCH_1):GND    I16 @BASEBOARD_FAB2_LIB.BASEBOARD_FAB2(SCH_1):PAGE124
  AM30    GND @BASEBOARD_FAB2_LIB.BASEBOARD_FAB2(SCH_1):GND    I16 @BASEBOARD_FAB2_LIB.BASEBOARD_FAB2(SCH_1):PAGE124
  AM41    GND @BASEBOARD_FAB2_LIB.BASEBOARD_FAB2(SCH_1):GND    I16 @BASEBOARD_FAB2_LIB.BASEBOARD_FAB2(SCH_1):PAGE124
  AM46    GND @BASEBOARD_FAB2_LIB.BASEBOARD_FAB2(SCH_1):GND    I16 @BASEBOARD_FAB2_LIB.BASEBOARD_FAB2(SCH_1):PAGE124
  AN13    GND @BASEBOARD_FAB2_LIB.BASEBOARD_FAB2(SCH_1):GND    I16 @BASEBOARD_FAB2_LIB.BASEBOARD_FAB2(SCH_1):PAGE124
  AN17    GND @BASEBOARD_FAB2_LIB.BASEBOARD_FAB2(SCH_1):GND    I16 @BASEBOARD_FAB2_LIB.BASEBOARD_FAB2(SCH_1):PAGE124
  AN68    GND @BASEBOARD_FAB2_LIB.BASEBOARD_FAB2(SCH_1):GND    I16 @BASEBOARD_FAB2_LIB.BASEBOARD_FAB2(SCH_1):PAGE124
  AP22    GND @BASEBOARD_FAB2_LIB.BASEBOARD_FAB2(SCH_1):GND    I16 @BASEBOARD_FAB2_LIB.BASEBOARD_FAB2(SCH_1):PAGE124
  AN20    GND @BASEBOARD_FAB2_LIB.BASEBOARD_FAB2(SCH_1):GND    I16 @BASEBOARD_FAB2_LIB.BASEBOARD_FAB2(SCH_1):PAGE124
   AN5    GND @BASEBOARD_FAB2_LIB.BASEBOARD_FAB2(SCH_1):GND    I16 @BASEBOARD_FAB2_LIB.BASEBOARD_FAB2(SCH_1):PAGE124
  AN58    GND @BASEBOARD_FAB2_LIB.BASEBOARD_FAB2(SCH_1):GND    I16 @BASEBOARD_FAB2_LIB.BASEBOARD_FAB2(SCH_1):PAGE124
   AN9    GND @BASEBOARD_FAB2_LIB.BASEBOARD_FAB2(SCH_1):GND    I16 @BASEBOARD_FAB2_LIB.BASEBOARD_FAB2(SCH_1):PAGE124
   AP2    GND @BASEBOARD_FAB2_LIB.BASEBOARD_FAB2(SCH_1):GND    I16 @BASEBOARD_FAB2_LIB.BASEBOARD_FAB2(SCH_1):PAGE124
  AP26    GND @BASEBOARD_FAB2_LIB.BASEBOARD_FAB2(SCH_1):GND    I16 @BASEBOARD_FAB2_LIB.BASEBOARD_FAB2(SCH_1):PAGE124
  AP30    GND @BASEBOARD_FAB2_LIB.BASEBOARD_FAB2(SCH_1):GND    I16 @BASEBOARD_FAB2_LIB.BASEBOARD_FAB2(SCH_1):PAGE124
   AP4    GND @BASEBOARD_FAB2_LIB.BASEBOARD_FAB2(SCH_1):GND    I16 @BASEBOARD_FAB2_LIB.BASEBOARD_FAB2(SCH_1):PAGE124
  AP41    GND @BASEBOARD_FAB2_LIB.BASEBOARD_FAB2(SCH_1):GND    I16 @BASEBOARD_FAB2_LIB.BASEBOARD_FAB2(SCH_1):PAGE124
  AP46    GND @BASEBOARD_FAB2_LIB.BASEBOARD_FAB2(SCH_1):GND    I16 @BASEBOARD_FAB2_LIB.BASEBOARD_FAB2(SCH_1):PAGE124
  AP52    GND @BASEBOARD_FAB2_LIB.BASEBOARD_FAB2(SCH_1):GND    I16 @BASEBOARD_FAB2_LIB.BASEBOARD_FAB2(SCH_1):PAGE124
  AP66    GND @BASEBOARD_FAB2_LIB.BASEBOARD_FAB2(SCH_1):GND    I16 @BASEBOARD_FAB2_LIB.BASEBOARD_FAB2(SCH_1):PAGE124
   AR5    GND @BASEBOARD_FAB2_LIB.BASEBOARD_FAB2(SCH_1):GND    I16 @BASEBOARD_FAB2_LIB.BASEBOARD_FAB2(SCH_1):PAGE124
  AR50    GND @BASEBOARD_FAB2_LIB.BASEBOARD_FAB2(SCH_1):GND    I16 @BASEBOARD_FAB2_LIB.BASEBOARD_FAB2(SCH_1):PAGE124
  AR58    GND @BASEBOARD_FAB2_LIB.BASEBOARD_FAB2(SCH_1):GND    I16 @BASEBOARD_FAB2_LIB.BASEBOARD_FAB2(SCH_1):PAGE124
  AR65    GND @BASEBOARD_FAB2_LIB.BASEBOARD_FAB2(SCH_1):GND    I16 @BASEBOARD_FAB2_LIB.BASEBOARD_FAB2(SCH_1):PAGE124
  AR68    GND @BASEBOARD_FAB2_LIB.BASEBOARD_FAB2(SCH_1):GND    I16 @BASEBOARD_FAB2_LIB.BASEBOARD_FAB2(SCH_1):PAGE124
  AR70    GND @BASEBOARD_FAB2_LIB.BASEBOARD_FAB2(SCH_1):GND    I16 @BASEBOARD_FAB2_LIB.BASEBOARD_FAB2(SCH_1):PAGE124
  AR72    GND @BASEBOARD_FAB2_LIB.BASEBOARD_FAB2(SCH_1):GND    I16 @BASEBOARD_FAB2_LIB.BASEBOARD_FAB2(SCH_1):PAGE124
   AT7    GND @BASEBOARD_FAB2_LIB.BASEBOARD_FAB2(SCH_1):GND    I16 @BASEBOARD_FAB2_LIB.BASEBOARD_FAB2(SCH_1):PAGE124
  AT11    GND @BASEBOARD_FAB2_LIB.BASEBOARD_FAB2(SCH_1):GND    I16 @BASEBOARD_FAB2_LIB.BASEBOARD_FAB2(SCH_1):PAGE124
  AT15    GND @BASEBOARD_FAB2_LIB.BASEBOARD_FAB2(SCH_1):GND    I16 @BASEBOARD_FAB2_LIB.BASEBOARD_FAB2(SCH_1):PAGE124
  AT18    GND @BASEBOARD_FAB2_LIB.BASEBOARD_FAB2(SCH_1):GND    I16 @BASEBOARD_FAB2_LIB.BASEBOARD_FAB2(SCH_1):PAGE124
  AT22    GND @BASEBOARD_FAB2_LIB.BASEBOARD_FAB2(SCH_1):GND    I16 @BASEBOARD_FAB2_LIB.BASEBOARD_FAB2(SCH_1):PAGE124
  AT26    GND @BASEBOARD_FAB2_LIB.BASEBOARD_FAB2(SCH_1):GND    I16 @BASEBOARD_FAB2_LIB.BASEBOARD_FAB2(SCH_1):PAGE124
  AT30    GND @BASEBOARD_FAB2_LIB.BASEBOARD_FAB2(SCH_1):GND    I16 @BASEBOARD_FAB2_LIB.BASEBOARD_FAB2(SCH_1):PAGE124
  AT41    GND @BASEBOARD_FAB2_LIB.BASEBOARD_FAB2(SCH_1):GND    I16 @BASEBOARD_FAB2_LIB.BASEBOARD_FAB2(SCH_1):PAGE124
  AT46    GND @BASEBOARD_FAB2_LIB.BASEBOARD_FAB2(SCH_1):GND    I16 @BASEBOARD_FAB2_LIB.BASEBOARD_FAB2(SCH_1):PAGE124
  AT59    GND @BASEBOARD_FAB2_LIB.BASEBOARD_FAB2(SCH_1):GND    I16 @BASEBOARD_FAB2_LIB.BASEBOARD_FAB2(SCH_1):PAGE124
  AU26    GND @BASEBOARD_FAB2_LIB.BASEBOARD_FAB2(SCH_1):GND    I16 @BASEBOARD_FAB2_LIB.BASEBOARD_FAB2(SCH_1):PAGE124
  AU30    GND @BASEBOARD_FAB2_LIB.BASEBOARD_FAB2(SCH_1):GND    I16 @BASEBOARD_FAB2_LIB.BASEBOARD_FAB2(SCH_1):PAGE124
  AE22    GND @BASEBOARD_FAB2_LIB.BASEBOARD_FAB2(SCH_1):GND    I16 @BASEBOARD_FAB2_LIB.BASEBOARD_FAB2(SCH_1):PAGE124
  AU41    GND @BASEBOARD_FAB2_LIB.BASEBOARD_FAB2(SCH_1):GND    I16 @BASEBOARD_FAB2_LIB.BASEBOARD_FAB2(SCH_1):PAGE124
  AU46    GND @BASEBOARD_FAB2_LIB.BASEBOARD_FAB2(SCH_1):GND    I16 @BASEBOARD_FAB2_LIB.BASEBOARD_FAB2(SCH_1):PAGE124
  AU50    GND @BASEBOARD_FAB2_LIB.BASEBOARD_FAB2(SCH_1):GND    I16 @BASEBOARD_FAB2_LIB.BASEBOARD_FAB2(SCH_1):PAGE124
  AU54    GND @BASEBOARD_FAB2_LIB.BASEBOARD_FAB2(SCH_1):GND    I16 @BASEBOARD_FAB2_LIB.BASEBOARD_FAB2(SCH_1):PAGE124
  AU61    GND @BASEBOARD_FAB2_LIB.BASEBOARD_FAB2(SCH_1):GND    I16 @BASEBOARD_FAB2_LIB.BASEBOARD_FAB2(SCH_1):PAGE124
   AV5    GND @BASEBOARD_FAB2_LIB.BASEBOARD_FAB2(SCH_1):GND    I16 @BASEBOARD_FAB2_LIB.BASEBOARD_FAB2(SCH_1):PAGE124
  AV22    GND @BASEBOARD_FAB2_LIB.BASEBOARD_FAB2(SCH_1):GND    I16 @BASEBOARD_FAB2_LIB.BASEBOARD_FAB2(SCH_1):PAGE124
  AV59    GND @BASEBOARD_FAB2_LIB.BASEBOARD_FAB2(SCH_1):GND    I16 @BASEBOARD_FAB2_LIB.BASEBOARD_FAB2(SCH_1):PAGE124
  AV68    GND @BASEBOARD_FAB2_LIB.BASEBOARD_FAB2(SCH_1):GND    I16 @BASEBOARD_FAB2_LIB.BASEBOARD_FAB2(SCH_1):PAGE124
   AW9    GND @BASEBOARD_FAB2_LIB.BASEBOARD_FAB2(SCH_1):GND    I16 @BASEBOARD_FAB2_LIB.BASEBOARD_FAB2(SCH_1):PAGE124
  AW13    GND @BASEBOARD_FAB2_LIB.BASEBOARD_FAB2(SCH_1):GND    I16 @BASEBOARD_FAB2_LIB.BASEBOARD_FAB2(SCH_1):PAGE124
  AW17    GND @BASEBOARD_FAB2_LIB.BASEBOARD_FAB2(SCH_1):GND    I16 @BASEBOARD_FAB2_LIB.BASEBOARD_FAB2(SCH_1):PAGE124
  AW26    GND @BASEBOARD_FAB2_LIB.BASEBOARD_FAB2(SCH_1):GND    I16 @BASEBOARD_FAB2_LIB.BASEBOARD_FAB2(SCH_1):PAGE124
  AW30    GND @BASEBOARD_FAB2_LIB.BASEBOARD_FAB2(SCH_1):GND    I16 @BASEBOARD_FAB2_LIB.BASEBOARD_FAB2(SCH_1):PAGE124
  AW32    GND @BASEBOARD_FAB2_LIB.BASEBOARD_FAB2(SCH_1):GND    I16 @BASEBOARD_FAB2_LIB.BASEBOARD_FAB2(SCH_1):PAGE124
  AW34    GND @BASEBOARD_FAB2_LIB.BASEBOARD_FAB2(SCH_1):GND    I16 @BASEBOARD_FAB2_LIB.BASEBOARD_FAB2(SCH_1):PAGE124
  AW36    GND @BASEBOARD_FAB2_LIB.BASEBOARD_FAB2(SCH_1):GND    I16 @BASEBOARD_FAB2_LIB.BASEBOARD_FAB2(SCH_1):PAGE124
  AW37    GND @BASEBOARD_FAB2_LIB.BASEBOARD_FAB2(SCH_1):GND    I16 @BASEBOARD_FAB2_LIB.BASEBOARD_FAB2(SCH_1):PAGE124
  AW39    GND @BASEBOARD_FAB2_LIB.BASEBOARD_FAB2(SCH_1):GND    I16 @BASEBOARD_FAB2_LIB.BASEBOARD_FAB2(SCH_1):PAGE124
  AW41    GND @BASEBOARD_FAB2_LIB.BASEBOARD_FAB2(SCH_1):GND    I16 @BASEBOARD_FAB2_LIB.BASEBOARD_FAB2(SCH_1):PAGE124
  AW46    GND @BASEBOARD_FAB2_LIB.BASEBOARD_FAB2(SCH_1):GND    I16 @BASEBOARD_FAB2_LIB.BASEBOARD_FAB2(SCH_1):PAGE124
  AW50    GND @BASEBOARD_FAB2_LIB.BASEBOARD_FAB2(SCH_1):GND    I16 @BASEBOARD_FAB2_LIB.BASEBOARD_FAB2(SCH_1):PAGE124
  AW58    GND @BASEBOARD_FAB2_LIB.BASEBOARD_FAB2(SCH_1):GND    I16 @BASEBOARD_FAB2_LIB.BASEBOARD_FAB2(SCH_1):PAGE124
  AW61    GND @BASEBOARD_FAB2_LIB.BASEBOARD_FAB2(SCH_1):GND    I16 @BASEBOARD_FAB2_LIB.BASEBOARD_FAB2(SCH_1):PAGE124
   AY5    GND @BASEBOARD_FAB2_LIB.BASEBOARD_FAB2(SCH_1):GND    I16 @BASEBOARD_FAB2_LIB.BASEBOARD_FAB2(SCH_1):PAGE124
  AY22    GND @BASEBOARD_FAB2_LIB.BASEBOARD_FAB2(SCH_1):GND    I16 @BASEBOARD_FAB2_LIB.BASEBOARD_FAB2(SCH_1):PAGE124
  AY56    GND @BASEBOARD_FAB2_LIB.BASEBOARD_FAB2(SCH_1):GND    I16 @BASEBOARD_FAB2_LIB.BASEBOARD_FAB2(SCH_1):PAGE124
  AY63    GND @BASEBOARD_FAB2_LIB.BASEBOARD_FAB2(SCH_1):GND    I16 @BASEBOARD_FAB2_LIB.BASEBOARD_FAB2(SCH_1):PAGE124
  AY68    GND @BASEBOARD_FAB2_LIB.BASEBOARD_FAB2(SCH_1):GND    I16 @BASEBOARD_FAB2_LIB.BASEBOARD_FAB2(SCH_1):PAGE124
  BA50    GND @BASEBOARD_FAB2_LIB.BASEBOARD_FAB2(SCH_1):GND    I16 @BASEBOARD_FAB2_LIB.BASEBOARD_FAB2(SCH_1):PAGE124
  BA54    GND @BASEBOARD_FAB2_LIB.BASEBOARD_FAB2(SCH_1):GND    I16 @BASEBOARD_FAB2_LIB.BASEBOARD_FAB2(SCH_1):PAGE124
  BA58    GND @BASEBOARD_FAB2_LIB.BASEBOARD_FAB2(SCH_1):GND    I16 @BASEBOARD_FAB2_LIB.BASEBOARD_FAB2(SCH_1):PAGE124
   BB5    GND @BASEBOARD_FAB2_LIB.BASEBOARD_FAB2(SCH_1):GND    I16 @BASEBOARD_FAB2_LIB.BASEBOARD_FAB2(SCH_1):PAGE124
   BB7    GND @BASEBOARD_FAB2_LIB.BASEBOARD_FAB2(SCH_1):GND    I16 @BASEBOARD_FAB2_LIB.BASEBOARD_FAB2(SCH_1):PAGE124
  BB11    GND @BASEBOARD_FAB2_LIB.BASEBOARD_FAB2(SCH_1):GND    I16 @BASEBOARD_FAB2_LIB.BASEBOARD_FAB2(SCH_1):PAGE124
  BB15    GND @BASEBOARD_FAB2_LIB.BASEBOARD_FAB2(SCH_1):GND    I16 @BASEBOARD_FAB2_LIB.BASEBOARD_FAB2(SCH_1):PAGE124
  BB18    GND @BASEBOARD_FAB2_LIB.BASEBOARD_FAB2(SCH_1):GND    I16 @BASEBOARD_FAB2_LIB.BASEBOARD_FAB2(SCH_1):PAGE124
  BB22    GND @BASEBOARD_FAB2_LIB.BASEBOARD_FAB2(SCH_1):GND    I16 @BASEBOARD_FAB2_LIB.BASEBOARD_FAB2(SCH_1):PAGE124
  BB44    GND @BASEBOARD_FAB2_LIB.BASEBOARD_FAB2(SCH_1):GND    I16 @BASEBOARD_FAB2_LIB.BASEBOARD_FAB2(SCH_1):PAGE124
  BB59    GND @BASEBOARD_FAB2_LIB.BASEBOARD_FAB2(SCH_1):GND    I16 @BASEBOARD_FAB2_LIB.BASEBOARD_FAB2(SCH_1):PAGE124
  BB66    GND @BASEBOARD_FAB2_LIB.BASEBOARD_FAB2(SCH_1):GND    I16 @BASEBOARD_FAB2_LIB.BASEBOARD_FAB2(SCH_1):PAGE124
  BB68    GND @BASEBOARD_FAB2_LIB.BASEBOARD_FAB2(SCH_1):GND    I16 @BASEBOARD_FAB2_LIB.BASEBOARD_FAB2(SCH_1):PAGE124
  BB70    GND @BASEBOARD_FAB2_LIB.BASEBOARD_FAB2(SCH_1):GND    I16 @BASEBOARD_FAB2_LIB.BASEBOARD_FAB2(SCH_1):PAGE124
  BB72    GND @BASEBOARD_FAB2_LIB.BASEBOARD_FAB2(SCH_1):GND    I16 @BASEBOARD_FAB2_LIB.BASEBOARD_FAB2(SCH_1):PAGE124
  BC69    GND @BASEBOARD_FAB2_LIB.BASEBOARD_FAB2(SCH_1):GND    I16 @BASEBOARD_FAB2_LIB.BASEBOARD_FAB2(SCH_1):PAGE124
  BC71    GND @BASEBOARD_FAB2_LIB.BASEBOARD_FAB2(SCH_1):GND    I16 @BASEBOARD_FAB2_LIB.BASEBOARD_FAB2(SCH_1):PAGE124
  BD24    GND @BASEBOARD_FAB2_LIB.BASEBOARD_FAB2(SCH_1):GND    I16 @BASEBOARD_FAB2_LIB.BASEBOARD_FAB2(SCH_1):PAGE124
  BD27    GND @BASEBOARD_FAB2_LIB.BASEBOARD_FAB2(SCH_1):GND    I16 @BASEBOARD_FAB2_LIB.BASEBOARD_FAB2(SCH_1):PAGE124
  BD31    GND @BASEBOARD_FAB2_LIB.BASEBOARD_FAB2(SCH_1):GND    I16 @BASEBOARD_FAB2_LIB.BASEBOARD_FAB2(SCH_1):PAGE124
  BD35    GND @BASEBOARD_FAB2_LIB.BASEBOARD_FAB2(SCH_1):GND    I16 @BASEBOARD_FAB2_LIB.BASEBOARD_FAB2(SCH_1):PAGE124
   BD5    GND @BASEBOARD_FAB2_LIB.BASEBOARD_FAB2(SCH_1):GND    I16 @BASEBOARD_FAB2_LIB.BASEBOARD_FAB2(SCH_1):PAGE124
  BD50    GND @BASEBOARD_FAB2_LIB.BASEBOARD_FAB2(SCH_1):GND    I16 @BASEBOARD_FAB2_LIB.BASEBOARD_FAB2(SCH_1):PAGE124
  BD54    GND @BASEBOARD_FAB2_LIB.BASEBOARD_FAB2(SCH_1):GND    I16 @BASEBOARD_FAB2_LIB.BASEBOARD_FAB2(SCH_1):PAGE124
  BD68    GND @BASEBOARD_FAB2_LIB.BASEBOARD_FAB2(SCH_1):GND    I16 @BASEBOARD_FAB2_LIB.BASEBOARD_FAB2(SCH_1):PAGE124
  BE29    GND @BASEBOARD_FAB2_LIB.BASEBOARD_FAB2(SCH_1):GND    I16 @BASEBOARD_FAB2_LIB.BASEBOARD_FAB2(SCH_1):PAGE124
  BE33    GND @BASEBOARD_FAB2_LIB.BASEBOARD_FAB2(SCH_1):GND    I16 @BASEBOARD_FAB2_LIB.BASEBOARD_FAB2(SCH_1):PAGE124
  BE37    GND @BASEBOARD_FAB2_LIB.BASEBOARD_FAB2(SCH_1):GND    I16 @BASEBOARD_FAB2_LIB.BASEBOARD_FAB2(SCH_1):PAGE124
  BE56    GND @BASEBOARD_FAB2_LIB.BASEBOARD_FAB2(SCH_1):GND    I16 @BASEBOARD_FAB2_LIB.BASEBOARD_FAB2(SCH_1):PAGE124
  BE59    GND @BASEBOARD_FAB2_LIB.BASEBOARD_FAB2(SCH_1):GND    I16 @BASEBOARD_FAB2_LIB.BASEBOARD_FAB2(SCH_1):PAGE124
  BE63    GND @BASEBOARD_FAB2_LIB.BASEBOARD_FAB2(SCH_1):GND    I16 @BASEBOARD_FAB2_LIB.BASEBOARD_FAB2(SCH_1):PAGE124
  BE66    GND @BASEBOARD_FAB2_LIB.BASEBOARD_FAB2(SCH_1):GND    I16 @BASEBOARD_FAB2_LIB.BASEBOARD_FAB2(SCH_1):PAGE124
  BF13    GND @BASEBOARD_FAB2_LIB.BASEBOARD_FAB2(SCH_1):GND    I16 @BASEBOARD_FAB2_LIB.BASEBOARD_FAB2(SCH_1):PAGE124
  BF17    GND @BASEBOARD_FAB2_LIB.BASEBOARD_FAB2(SCH_1):GND    I16 @BASEBOARD_FAB2_LIB.BASEBOARD_FAB2(SCH_1):PAGE124
  BF54    GND @BASEBOARD_FAB2_LIB.BASEBOARD_FAB2(SCH_1):GND    I16 @BASEBOARD_FAB2_LIB.BASEBOARD_FAB2(SCH_1):PAGE124
  BG44    GND @BASEBOARD_FAB2_LIB.BASEBOARD_FAB2(SCH_1):GND    I16 @BASEBOARD_FAB2_LIB.BASEBOARD_FAB2(SCH_1):PAGE124
  BF20    GND @BASEBOARD_FAB2_LIB.BASEBOARD_FAB2(SCH_1):GND    I16 @BASEBOARD_FAB2_LIB.BASEBOARD_FAB2(SCH_1):PAGE124
  BF24    GND @BASEBOARD_FAB2_LIB.BASEBOARD_FAB2(SCH_1):GND    I16 @BASEBOARD_FAB2_LIB.BASEBOARD_FAB2(SCH_1):PAGE124
  BF27    GND @BASEBOARD_FAB2_LIB.BASEBOARD_FAB2(SCH_1):GND    I16 @BASEBOARD_FAB2_LIB.BASEBOARD_FAB2(SCH_1):PAGE124
  BF38    GND @BASEBOARD_FAB2_LIB.BASEBOARD_FAB2(SCH_1):GND    I16 @BASEBOARD_FAB2_LIB.BASEBOARD_FAB2(SCH_1):PAGE124
  BF42    GND @BASEBOARD_FAB2_LIB.BASEBOARD_FAB2(SCH_1):GND    I16 @BASEBOARD_FAB2_LIB.BASEBOARD_FAB2(SCH_1):PAGE124
   BF5    GND @BASEBOARD_FAB2_LIB.BASEBOARD_FAB2(SCH_1):GND    I16 @BASEBOARD_FAB2_LIB.BASEBOARD_FAB2(SCH_1):PAGE124
  BF50    GND @BASEBOARD_FAB2_LIB.BASEBOARD_FAB2(SCH_1):GND    I16 @BASEBOARD_FAB2_LIB.BASEBOARD_FAB2(SCH_1):PAGE124
  BF58    GND @BASEBOARD_FAB2_LIB.BASEBOARD_FAB2(SCH_1):GND    I16 @BASEBOARD_FAB2_LIB.BASEBOARD_FAB2(SCH_1):PAGE124
  BF61    GND @BASEBOARD_FAB2_LIB.BASEBOARD_FAB2(SCH_1):GND    I16 @BASEBOARD_FAB2_LIB.BASEBOARD_FAB2(SCH_1):PAGE124
  BF65    GND @BASEBOARD_FAB2_LIB.BASEBOARD_FAB2(SCH_1):GND    I16 @BASEBOARD_FAB2_LIB.BASEBOARD_FAB2(SCH_1):PAGE124
  BF68    GND @BASEBOARD_FAB2_LIB.BASEBOARD_FAB2(SCH_1):GND    I16 @BASEBOARD_FAB2_LIB.BASEBOARD_FAB2(SCH_1):PAGE124
   BF9    GND @BASEBOARD_FAB2_LIB.BASEBOARD_FAB2(SCH_1):GND    I16 @BASEBOARD_FAB2_LIB.BASEBOARD_FAB2(SCH_1):PAGE124
  BG33    GND @BASEBOARD_FAB2_LIB.BASEBOARD_FAB2(SCH_1):GND    I16 @BASEBOARD_FAB2_LIB.BASEBOARD_FAB2(SCH_1):PAGE124
  BG48    GND @BASEBOARD_FAB2_LIB.BASEBOARD_FAB2(SCH_1):GND    I16 @BASEBOARD_FAB2_LIB.BASEBOARD_FAB2(SCH_1):PAGE124
  BG59    GND @BASEBOARD_FAB2_LIB.BASEBOARD_FAB2(SCH_1):GND    I16 @BASEBOARD_FAB2_LIB.BASEBOARD_FAB2(SCH_1):PAGE124
  BG63    GND @BASEBOARD_FAB2_LIB.BASEBOARD_FAB2(SCH_1):GND    I16 @BASEBOARD_FAB2_LIB.BASEBOARD_FAB2(SCH_1):PAGE124
  BH27    GND @BASEBOARD_FAB2_LIB.BASEBOARD_FAB2(SCH_1):GND    I16 @BASEBOARD_FAB2_LIB.BASEBOARD_FAB2(SCH_1):PAGE124
  BH38    GND @BASEBOARD_FAB2_LIB.BASEBOARD_FAB2(SCH_1):GND    I16 @BASEBOARD_FAB2_LIB.BASEBOARD_FAB2(SCH_1):PAGE124
  BH42    GND @BASEBOARD_FAB2_LIB.BASEBOARD_FAB2(SCH_1):GND    I16 @BASEBOARD_FAB2_LIB.BASEBOARD_FAB2(SCH_1):PAGE124
  BH46    GND @BASEBOARD_FAB2_LIB.BASEBOARD_FAB2(SCH_1):GND    I16 @BASEBOARD_FAB2_LIB.BASEBOARD_FAB2(SCH_1):PAGE124
  BH54    GND @BASEBOARD_FAB2_LIB.BASEBOARD_FAB2(SCH_1):GND    I16 @BASEBOARD_FAB2_LIB.BASEBOARD_FAB2(SCH_1):PAGE124
   BJ1    GND @BASEBOARD_FAB2_LIB.BASEBOARD_FAB2(SCH_1):GND    I16 @BASEBOARD_FAB2_LIB.BASEBOARD_FAB2(SCH_1):PAGE124
  BJ11    GND @BASEBOARD_FAB2_LIB.BASEBOARD_FAB2(SCH_1):GND    I16 @BASEBOARD_FAB2_LIB.BASEBOARD_FAB2(SCH_1):PAGE124
   BJ5    GND @BASEBOARD_FAB2_LIB.BASEBOARD_FAB2(SCH_1):GND    I16 @BASEBOARD_FAB2_LIB.BASEBOARD_FAB2(SCH_1):PAGE124
   BJ7    GND @BASEBOARD_FAB2_LIB.BASEBOARD_FAB2(SCH_1):GND    I16 @BASEBOARD_FAB2_LIB.BASEBOARD_FAB2(SCH_1):PAGE124
  BJ15    GND @BASEBOARD_FAB2_LIB.BASEBOARD_FAB2(SCH_1):GND    I16 @BASEBOARD_FAB2_LIB.BASEBOARD_FAB2(SCH_1):PAGE124
  BJ18    GND @BASEBOARD_FAB2_LIB.BASEBOARD_FAB2(SCH_1):GND    I16 @BASEBOARD_FAB2_LIB.BASEBOARD_FAB2(SCH_1):PAGE124
  BJ26    GND @BASEBOARD_FAB2_LIB.BASEBOARD_FAB2(SCH_1):GND    I16 @BASEBOARD_FAB2_LIB.BASEBOARD_FAB2(SCH_1):PAGE124
   BJ3    GND @BASEBOARD_FAB2_LIB.BASEBOARD_FAB2(SCH_1):GND    I16 @BASEBOARD_FAB2_LIB.BASEBOARD_FAB2(SCH_1):PAGE124
  BJ33    GND @BASEBOARD_FAB2_LIB.BASEBOARD_FAB2(SCH_1):GND    I16 @BASEBOARD_FAB2_LIB.BASEBOARD_FAB2(SCH_1):PAGE124
  BJ52    GND @BASEBOARD_FAB2_LIB.BASEBOARD_FAB2(SCH_1):GND    I16 @BASEBOARD_FAB2_LIB.BASEBOARD_FAB2(SCH_1):PAGE124
  BJ68    GND @BASEBOARD_FAB2_LIB.BASEBOARD_FAB2(SCH_1):GND    I16 @BASEBOARD_FAB2_LIB.BASEBOARD_FAB2(SCH_1):PAGE124
  BK24    GND @BASEBOARD_FAB2_LIB.BASEBOARD_FAB2(SCH_1):GND    I15 @BASEBOARD_FAB2_LIB.BASEBOARD_FAB2(SCH_1):PAGE124
  BK27    GND @BASEBOARD_FAB2_LIB.BASEBOARD_FAB2(SCH_1):GND    I15 @BASEBOARD_FAB2_LIB.BASEBOARD_FAB2(SCH_1):PAGE124
  BK31    GND @BASEBOARD_FAB2_LIB.BASEBOARD_FAB2(SCH_1):GND    I15 @BASEBOARD_FAB2_LIB.BASEBOARD_FAB2(SCH_1):PAGE124
  BK35    GND @BASEBOARD_FAB2_LIB.BASEBOARD_FAB2(SCH_1):GND    I15 @BASEBOARD_FAB2_LIB.BASEBOARD_FAB2(SCH_1):PAGE124
  BK38    GND @BASEBOARD_FAB2_LIB.BASEBOARD_FAB2(SCH_1):GND    I15 @BASEBOARD_FAB2_LIB.BASEBOARD_FAB2(SCH_1):PAGE124
  BK42    GND @BASEBOARD_FAB2_LIB.BASEBOARD_FAB2(SCH_1):GND    I15 @BASEBOARD_FAB2_LIB.BASEBOARD_FAB2(SCH_1):PAGE124
  BK50    GND @BASEBOARD_FAB2_LIB.BASEBOARD_FAB2(SCH_1):GND    I15 @BASEBOARD_FAB2_LIB.BASEBOARD_FAB2(SCH_1):PAGE124
  BL22    GND @BASEBOARD_FAB2_LIB.BASEBOARD_FAB2(SCH_1):GND    I15 @BASEBOARD_FAB2_LIB.BASEBOARD_FAB2(SCH_1):PAGE124
  BL40    GND @BASEBOARD_FAB2_LIB.BASEBOARD_FAB2(SCH_1):GND    I15 @BASEBOARD_FAB2_LIB.BASEBOARD_FAB2(SCH_1):PAGE124
  BL68    GND @BASEBOARD_FAB2_LIB.BASEBOARD_FAB2(SCH_1):GND    I15 @BASEBOARD_FAB2_LIB.BASEBOARD_FAB2(SCH_1):PAGE124
  BL37    GND @BASEBOARD_FAB2_LIB.BASEBOARD_FAB2(SCH_1):GND    I15 @BASEBOARD_FAB2_LIB.BASEBOARD_FAB2(SCH_1):PAGE124
   BL5    GND @BASEBOARD_FAB2_LIB.BASEBOARD_FAB2(SCH_1):GND    I15 @BASEBOARD_FAB2_LIB.BASEBOARD_FAB2(SCH_1):PAGE124
  BL63    GND @BASEBOARD_FAB2_LIB.BASEBOARD_FAB2(SCH_1):GND    I15 @BASEBOARD_FAB2_LIB.BASEBOARD_FAB2(SCH_1):PAGE124
  BL70    GND @BASEBOARD_FAB2_LIB.BASEBOARD_FAB2(SCH_1):GND    I15 @BASEBOARD_FAB2_LIB.BASEBOARD_FAB2(SCH_1):PAGE124
  BL72    GND @BASEBOARD_FAB2_LIB.BASEBOARD_FAB2(SCH_1):GND    I15 @BASEBOARD_FAB2_LIB.BASEBOARD_FAB2(SCH_1):PAGE124
  BM13    GND @BASEBOARD_FAB2_LIB.BASEBOARD_FAB2(SCH_1):GND    I15 @BASEBOARD_FAB2_LIB.BASEBOARD_FAB2(SCH_1):PAGE124
  BM17    GND @BASEBOARD_FAB2_LIB.BASEBOARD_FAB2(SCH_1):GND    I15 @BASEBOARD_FAB2_LIB.BASEBOARD_FAB2(SCH_1):PAGE124
  BN37    GND @BASEBOARD_FAB2_LIB.BASEBOARD_FAB2(SCH_1):GND    I15 @BASEBOARD_FAB2_LIB.BASEBOARD_FAB2(SCH_1):PAGE124
  BM46    GND @BASEBOARD_FAB2_LIB.BASEBOARD_FAB2(SCH_1):GND    I15 @BASEBOARD_FAB2_LIB.BASEBOARD_FAB2(SCH_1):PAGE124
  BM50    GND @BASEBOARD_FAB2_LIB.BASEBOARD_FAB2(SCH_1):GND    I15 @BASEBOARD_FAB2_LIB.BASEBOARD_FAB2(SCH_1):PAGE124
  BM58    GND @BASEBOARD_FAB2_LIB.BASEBOARD_FAB2(SCH_1):GND    I15 @BASEBOARD_FAB2_LIB.BASEBOARD_FAB2(SCH_1):PAGE124
  BM69    GND @BASEBOARD_FAB2_LIB.BASEBOARD_FAB2(SCH_1):GND    I15 @BASEBOARD_FAB2_LIB.BASEBOARD_FAB2(SCH_1):PAGE124
  BM71    GND @BASEBOARD_FAB2_LIB.BASEBOARD_FAB2(SCH_1):GND    I15 @BASEBOARD_FAB2_LIB.BASEBOARD_FAB2(SCH_1):PAGE124
   BM9    GND @BASEBOARD_FAB2_LIB.BASEBOARD_FAB2(SCH_1):GND    I15 @BASEBOARD_FAB2_LIB.BASEBOARD_FAB2(SCH_1):PAGE124
  BN22    GND @BASEBOARD_FAB2_LIB.BASEBOARD_FAB2(SCH_1):GND    I15 @BASEBOARD_FAB2_LIB.BASEBOARD_FAB2(SCH_1):PAGE124
  BN59    GND @BASEBOARD_FAB2_LIB.BASEBOARD_FAB2(SCH_1):GND    I15 @BASEBOARD_FAB2_LIB.BASEBOARD_FAB2(SCH_1):PAGE124
   BN5    GND @BASEBOARD_FAB2_LIB.BASEBOARD_FAB2(SCH_1):GND    I15 @BASEBOARD_FAB2_LIB.BASEBOARD_FAB2(SCH_1):PAGE124
  BN52    GND @BASEBOARD_FAB2_LIB.BASEBOARD_FAB2(SCH_1):GND    I15 @BASEBOARD_FAB2_LIB.BASEBOARD_FAB2(SCH_1):PAGE124
  BN66    GND @BASEBOARD_FAB2_LIB.BASEBOARD_FAB2(SCH_1):GND    I15 @BASEBOARD_FAB2_LIB.BASEBOARD_FAB2(SCH_1):PAGE124
  BR20    GND @BASEBOARD_FAB2_LIB.BASEBOARD_FAB2(SCH_1):GND    I15 @BASEBOARD_FAB2_LIB.BASEBOARD_FAB2(SCH_1):PAGE124
  BR50    GND @BASEBOARD_FAB2_LIB.BASEBOARD_FAB2(SCH_1):GND    I15 @BASEBOARD_FAB2_LIB.BASEBOARD_FAB2(SCH_1):PAGE124
   BT8    GND @BASEBOARD_FAB2_LIB.BASEBOARD_FAB2(SCH_1):GND    I15 @BASEBOARD_FAB2_LIB.BASEBOARD_FAB2(SCH_1):PAGE124
  BR54    GND @BASEBOARD_FAB2_LIB.BASEBOARD_FAB2(SCH_1):GND    I15 @BASEBOARD_FAB2_LIB.BASEBOARD_FAB2(SCH_1):PAGE124
  BR58    GND @BASEBOARD_FAB2_LIB.BASEBOARD_FAB2(SCH_1):GND    I15 @BASEBOARD_FAB2_LIB.BASEBOARD_FAB2(SCH_1):PAGE124
   BR6    GND @BASEBOARD_FAB2_LIB.BASEBOARD_FAB2(SCH_1):GND    I15 @BASEBOARD_FAB2_LIB.BASEBOARD_FAB2(SCH_1):PAGE124
  BT66    GND @BASEBOARD_FAB2_LIB.BASEBOARD_FAB2(SCH_1):GND    I15 @BASEBOARD_FAB2_LIB.BASEBOARD_FAB2(SCH_1):PAGE124
  BU13    GND @BASEBOARD_FAB2_LIB.BASEBOARD_FAB2(SCH_1):GND    I15 @BASEBOARD_FAB2_LIB.BASEBOARD_FAB2(SCH_1):PAGE124
  BU11    GND @BASEBOARD_FAB2_LIB.BASEBOARD_FAB2(SCH_1):GND    I15 @BASEBOARD_FAB2_LIB.BASEBOARD_FAB2(SCH_1):PAGE124
  BV49    GND @BASEBOARD_FAB2_LIB.BASEBOARD_FAB2(SCH_1):GND    I15 @BASEBOARD_FAB2_LIB.BASEBOARD_FAB2(SCH_1):PAGE124
  BU15    GND @BASEBOARD_FAB2_LIB.BASEBOARD_FAB2(SCH_1):GND    I15 @BASEBOARD_FAB2_LIB.BASEBOARD_FAB2(SCH_1):PAGE124
  BU18    GND @BASEBOARD_FAB2_LIB.BASEBOARD_FAB2(SCH_1):GND    I15 @BASEBOARD_FAB2_LIB.BASEBOARD_FAB2(SCH_1):PAGE124
  BU20    GND @BASEBOARD_FAB2_LIB.BASEBOARD_FAB2(SCH_1):GND    I15 @BASEBOARD_FAB2_LIB.BASEBOARD_FAB2(SCH_1):PAGE124
  BU22    GND @BASEBOARD_FAB2_LIB.BASEBOARD_FAB2(SCH_1):GND    I15 @BASEBOARD_FAB2_LIB.BASEBOARD_FAB2(SCH_1):PAGE124
  BU24    GND @BASEBOARD_FAB2_LIB.BASEBOARD_FAB2(SCH_1):GND    I15 @BASEBOARD_FAB2_LIB.BASEBOARD_FAB2(SCH_1):PAGE124
  BU26    GND @BASEBOARD_FAB2_LIB.BASEBOARD_FAB2(SCH_1):GND    I15 @BASEBOARD_FAB2_LIB.BASEBOARD_FAB2(SCH_1):PAGE124
  BU28    GND @BASEBOARD_FAB2_LIB.BASEBOARD_FAB2(SCH_1):GND    I15 @BASEBOARD_FAB2_LIB.BASEBOARD_FAB2(SCH_1):PAGE124
  BU30    GND @BASEBOARD_FAB2_LIB.BASEBOARD_FAB2(SCH_1):GND    I15 @BASEBOARD_FAB2_LIB.BASEBOARD_FAB2(SCH_1):PAGE124
  BU32    GND @BASEBOARD_FAB2_LIB.BASEBOARD_FAB2(SCH_1):GND    I15 @BASEBOARD_FAB2_LIB.BASEBOARD_FAB2(SCH_1):PAGE124
  BU34    GND @BASEBOARD_FAB2_LIB.BASEBOARD_FAB2(SCH_1):GND    I15 @BASEBOARD_FAB2_LIB.BASEBOARD_FAB2(SCH_1):PAGE124
  BU37    GND @BASEBOARD_FAB2_LIB.BASEBOARD_FAB2(SCH_1):GND    I15 @BASEBOARD_FAB2_LIB.BASEBOARD_FAB2(SCH_1):PAGE124
  BU39    GND @BASEBOARD_FAB2_LIB.BASEBOARD_FAB2(SCH_1):GND    I15 @BASEBOARD_FAB2_LIB.BASEBOARD_FAB2(SCH_1):PAGE124
  BU41    GND @BASEBOARD_FAB2_LIB.BASEBOARD_FAB2(SCH_1):GND    I15 @BASEBOARD_FAB2_LIB.BASEBOARD_FAB2(SCH_1):PAGE124
  BU43    GND @BASEBOARD_FAB2_LIB.BASEBOARD_FAB2(SCH_1):GND    I15 @BASEBOARD_FAB2_LIB.BASEBOARD_FAB2(SCH_1):PAGE124
  BU45    GND @BASEBOARD_FAB2_LIB.BASEBOARD_FAB2(SCH_1):GND    I15 @BASEBOARD_FAB2_LIB.BASEBOARD_FAB2(SCH_1):PAGE124
  BU48    GND @BASEBOARD_FAB2_LIB.BASEBOARD_FAB2(SCH_1):GND    I15 @BASEBOARD_FAB2_LIB.BASEBOARD_FAB2(SCH_1):PAGE124
  BU50    GND @BASEBOARD_FAB2_LIB.BASEBOARD_FAB2(SCH_1):GND    I15 @BASEBOARD_FAB2_LIB.BASEBOARD_FAB2(SCH_1):PAGE124
  BU52    GND @BASEBOARD_FAB2_LIB.BASEBOARD_FAB2(SCH_1):GND    I15 @BASEBOARD_FAB2_LIB.BASEBOARD_FAB2(SCH_1):PAGE124
  BU54    GND @BASEBOARD_FAB2_LIB.BASEBOARD_FAB2(SCH_1):GND    I15 @BASEBOARD_FAB2_LIB.BASEBOARD_FAB2(SCH_1):PAGE124
  BU57    GND @BASEBOARD_FAB2_LIB.BASEBOARD_FAB2(SCH_1):GND    I15 @BASEBOARD_FAB2_LIB.BASEBOARD_FAB2(SCH_1):PAGE124
  BU59    GND @BASEBOARD_FAB2_LIB.BASEBOARD_FAB2(SCH_1):GND    I15 @BASEBOARD_FAB2_LIB.BASEBOARD_FAB2(SCH_1):PAGE124
  BU61    GND @BASEBOARD_FAB2_LIB.BASEBOARD_FAB2(SCH_1):GND    I15 @BASEBOARD_FAB2_LIB.BASEBOARD_FAB2(SCH_1):PAGE124
  BU63    GND @BASEBOARD_FAB2_LIB.BASEBOARD_FAB2(SCH_1):GND    I15 @BASEBOARD_FAB2_LIB.BASEBOARD_FAB2(SCH_1):PAGE124
   BU9    GND @BASEBOARD_FAB2_LIB.BASEBOARD_FAB2(SCH_1):GND    I15 @BASEBOARD_FAB2_LIB.BASEBOARD_FAB2(SCH_1):PAGE124
  BV40    GND @BASEBOARD_FAB2_LIB.BASEBOARD_FAB2(SCH_1):GND    I15 @BASEBOARD_FAB2_LIB.BASEBOARD_FAB2(SCH_1):PAGE124
  BW15    GND @BASEBOARD_FAB2_LIB.BASEBOARD_FAB2(SCH_1):GND    I15 @BASEBOARD_FAB2_LIB.BASEBOARD_FAB2(SCH_1):PAGE124
  BW18    GND @BASEBOARD_FAB2_LIB.BASEBOARD_FAB2(SCH_1):GND    I15 @BASEBOARD_FAB2_LIB.BASEBOARD_FAB2(SCH_1):PAGE124
  BW26    GND @BASEBOARD_FAB2_LIB.BASEBOARD_FAB2(SCH_1):GND    I15 @BASEBOARD_FAB2_LIB.BASEBOARD_FAB2(SCH_1):PAGE124
  BW52    GND @BASEBOARD_FAB2_LIB.BASEBOARD_FAB2(SCH_1):GND    I15 @BASEBOARD_FAB2_LIB.BASEBOARD_FAB2(SCH_1):PAGE124
  BY40    GND @BASEBOARD_FAB2_LIB.BASEBOARD_FAB2(SCH_1):GND    I15 @BASEBOARD_FAB2_LIB.BASEBOARD_FAB2(SCH_1):PAGE124
  BY49    GND @BASEBOARD_FAB2_LIB.BASEBOARD_FAB2(SCH_1):GND    I15 @BASEBOARD_FAB2_LIB.BASEBOARD_FAB2(SCH_1):PAGE124
  CA15    GND @BASEBOARD_FAB2_LIB.BASEBOARD_FAB2(SCH_1):GND    I15 @BASEBOARD_FAB2_LIB.BASEBOARD_FAB2(SCH_1):PAGE124
  CA18    GND @BASEBOARD_FAB2_LIB.BASEBOARD_FAB2(SCH_1):GND    I15 @BASEBOARD_FAB2_LIB.BASEBOARD_FAB2(SCH_1):PAGE124
  CA26    GND @BASEBOARD_FAB2_LIB.BASEBOARD_FAB2(SCH_1):GND    I15 @BASEBOARD_FAB2_LIB.BASEBOARD_FAB2(SCH_1):PAGE124
  CA50    GND @BASEBOARD_FAB2_LIB.BASEBOARD_FAB2(SCH_1):GND    I15 @BASEBOARD_FAB2_LIB.BASEBOARD_FAB2(SCH_1):PAGE124
  CA52    GND @BASEBOARD_FAB2_LIB.BASEBOARD_FAB2(SCH_1):GND    I15 @BASEBOARD_FAB2_LIB.BASEBOARD_FAB2(SCH_1):PAGE124

U7D1 74CBTLV1G125_SMLF-IC,C88177-00A
     4 XDP_CPU_PWR_DEBUG_N @BASEBOARD_FAB2_LIB.BASEBOARD_FAB2(SCH_1):XDP_CPU_PWR_DEBUG_N   I142 @BASEBOARD_FAB2_LIB.BASEBOARD_FAB2(SCH_1):PAGE118
     1 PWRGD_PVCCIO_CPU0 @BASEBOARD_FAB2_LIB.BASEBOARD_FAB2(SCH_1):PWRGD_PVCCIO_CPU0   I142 @BASEBOARD_FAB2_LIB.BASEBOARD_FAB2(SCH_1):PAGE118
     2 XDP_PCH_PWR_DEBUG_N @BASEBOARD_FAB2_LIB.BASEBOARD_FAB2(SCH_1):XDP_PCH_PWR_DEBUG_N   I142 @BASEBOARD_FAB2_LIB.BASEBOARD_FAB2(SCH_1):PAGE118

U7D2 GTL2014_SM-IC,D66151-001
    13 FM_CPU_MSMI_LVT3_R_N @BASEBOARD_FAB2_LIB.BASEBOARD_FAB2(SCH_1):FM_CPU_MSMI_LVT3_R_N    I32 @BASEBOARD_FAB2_LIB.BASEBOARD_FAB2(SCH_1):PAGE92
    12 FM_CPU0_FIVR_FAULT_R_LVT3 @BASEBOARD_FAB2_LIB.BASEBOARD_FAB2(SCH_1):FM_CPU0_FIVR_FAULT_R_LVT3    I32 @BASEBOARD_FAB2_LIB.BASEBOARD_FAB2(SCH_1):PAGE92
    10 FM_CPU_ERR2_LVT3_R_N @BASEBOARD_FAB2_LIB.BASEBOARD_FAB2(SCH_1):FM_CPU_ERR2_LVT3_R_N    I32 @BASEBOARD_FAB2_LIB.BASEBOARD_FAB2(SCH_1):PAGE92
     9 FM_CPU0_THERMTRIP_LVT3_R_N @BASEBOARD_FAB2_LIB.BASEBOARD_FAB2(SCH_1):FM_CPU0_THERMTRIP_LVT3_R_N    I32 @BASEBOARD_FAB2_LIB.BASEBOARD_FAB2(SCH_1):PAGE92
     2 H_CPU_MSMI_G_N @BASEBOARD_FAB2_LIB.BASEBOARD_FAB2(SCH_1):H_CPU_MSMI_G_N    I32 @BASEBOARD_FAB2_LIB.BASEBOARD_FAB2(SCH_1):PAGE92
     3 H_CPU0_FIVR_FAULT_G @BASEBOARD_FAB2_LIB.BASEBOARD_FAB2(SCH_1):H_CPU0_FIVR_FAULT_G    I32 @BASEBOARD_FAB2_LIB.BASEBOARD_FAB2(SCH_1):PAGE92
     5 H_CPU_ERR2_GTL_N @BASEBOARD_FAB2_LIB.BASEBOARD_FAB2(SCH_1):H_CPU_ERR2_GTL_N    I32 @BASEBOARD_FAB2_LIB.BASEBOARD_FAB2(SCH_1):PAGE92
     6 H_CPU0_THERMTRIP_G_N @BASEBOARD_FAB2_LIB.BASEBOARD_FAB2(SCH_1):H_CPU0_THERMTRIP_G_N    I32 @BASEBOARD_FAB2_LIB.BASEBOARD_FAB2(SCH_1):PAGE92
     1 PD_GTL2104_DIR_0 @BASEBOARD_FAB2_LIB.BASEBOARD_FAB2(SCH_1):PD_GTL2104_DIR_0    I32 @BASEBOARD_FAB2_LIB.BASEBOARD_FAB2(SCH_1):PAGE92
    11    GND @BASEBOARD_FAB2_LIB.BASEBOARD_FAB2(SCH_1):GND    I32 @BASEBOARD_FAB2_LIB.BASEBOARD_FAB2(SCH_1):PAGE92
     8    GND @BASEBOARD_FAB2_LIB.BASEBOARD_FAB2(SCH_1):GND    I32 @BASEBOARD_FAB2_LIB.BASEBOARD_FAB2(SCH_1):PAGE92
     7    GND @BASEBOARD_FAB2_LIB.BASEBOARD_FAB2(SCH_1):GND    I32 @BASEBOARD_FAB2_LIB.BASEBOARD_FAB2(SCH_1):PAGE92
    14   P3V3 @BASEBOARD_FAB2_LIB.BASEBOARD_FAB2(SCH_1):P3V3    I32 @BASEBOARD_FAB2_LIB.BASEBOARD_FAB2(SCH_1):PAGE92
     4 P0V7_GTL2104_VREF_0 @BASEBOARD_FAB2_LIB.BASEBOARD_FAB2(SCH_1):P0V7_GTL2104_VREF_0    I32 @BASEBOARD_FAB2_LIB.BASEBOARD_FAB2(SCH_1):PAGE92

U7D3 ADM1085_SMT-IC,H46130-001
     5 A_ADM1085_CEXT @BASEBOARD_FAB2_LIB.BASEBOARD_FAB2(SCH_1):A_ADM1085_CEXT    I70 @BASEBOARD_FAB2_LIB.BASEBOARD_FAB2(SCH_1):PAGE196
     1 PWRGD_P3V3_STBY @BASEBOARD_FAB2_LIB.BASEBOARD_FAB2(SCH_1):PWRGD_P3V3_STBY    I70 @BASEBOARD_FAB2_LIB.BASEBOARD_FAB2(SCH_1):PAGE196
     4 PWRGD_DSW_PWROK @BASEBOARD_FAB2_LIB.BASEBOARD_FAB2(SCH_1):PWRGD_DSW_PWROK    I70 @BASEBOARD_FAB2_LIB.BASEBOARD_FAB2(SCH_1):PAGE196
     2    GND @BASEBOARD_FAB2_LIB.BASEBOARD_FAB2(SCH_1):GND    I70 @BASEBOARD_FAB2_LIB.BASEBOARD_FAB2(SCH_1):PAGE196
     6 P3V3_STBY @BASEBOARD_FAB2_LIB.BASEBOARD_FAB2(SCH_1):P3V3_STBY    I70 @BASEBOARD_FAB2_LIB.BASEBOARD_FAB2(SCH_1):PAGE196
     3 VSENSE_P12V_ADM1085 @BASEBOARD_FAB2_LIB.BASEBOARD_FAB2(SCH_1):VSENSE_P12V_ADM1085    I70 @BASEBOARD_FAB2_LIB.BASEBOARD_FAB2(SCH_1):PAGE196

U7E1 PCA9617_SSOP-IC,G81764-001-GNDA
     5 TP_SMB_DDR_DEF_EN @BASEBOARD_FAB2_LIB.BASEBOARD_FAB2(SCH_1):TP_SMB_DDR_DEF_EN    I61 @BASEBOARD_FAB2_LIB.BASEBOARD_FAB2(SCH_1):PAGE99
     2 SMB_DDR_DEF_SCL_G @BASEBOARD_FAB2_LIB.BASEBOARD_FAB2(SCH_1):SMB_DDR_DEF_SCL_G    I61 @BASEBOARD_FAB2_LIB.BASEBOARD_FAB2(SCH_1):PAGE99
     7 SMB_DDR_DEF_VPP_SCL_R @BASEBOARD_FAB2_LIB.BASEBOARD_FAB2(SCH_1):SMB_DDR_DEF_VPP_SCL_R    I61 @BASEBOARD_FAB2_LIB.BASEBOARD_FAB2(SCH_1):PAGE99
     3 SMB_DDR_DEF_SDA_G @BASEBOARD_FAB2_LIB.BASEBOARD_FAB2(SCH_1):SMB_DDR_DEF_SDA_G    I61 @BASEBOARD_FAB2_LIB.BASEBOARD_FAB2(SCH_1):PAGE99
     6 SMB_DDR_DEF_VPP_SDA_R @BASEBOARD_FAB2_LIB.BASEBOARD_FAB2(SCH_1):SMB_DDR_DEF_VPP_SDA_R    I61 @BASEBOARD_FAB2_LIB.BASEBOARD_FAB2(SCH_1):PAGE99
     1 PVCCIO_CPU0 @BASEBOARD_FAB2_LIB.BASEBOARD_FAB2(SCH_1):PVCCIO_CPU0    I61 @BASEBOARD_FAB2_LIB.BASEBOARD_FAB2(SCH_1):PAGE99
     8 PVPP_DEF @BASEBOARD_FAB2_LIB.BASEBOARD_FAB2(SCH_1):PVPP_DEF    I61 @BASEBOARD_FAB2_LIB.BASEBOARD_FAB2(SCH_1):PAGE99

U7E2 TTL1G08_SOTLF-NC7SZ08,IC,D1032B
     4 IRQ_CPU0_PROCHOT_G_N @BASEBOARD_FAB2_LIB.BASEBOARD_FAB2(SCH_1):IRQ_CPU0_PROCHOT_G_N   I117 @BASEBOARD_FAB2_LIB.BASEBOARD_FAB2(SCH_1):PAGE95
     1 FM_PVCCIN_CPU0_PWR_IN_ALERT_N @BASEBOARD_FAB2_LIB.BASEBOARD_FAB2(SCH_1):FM_PVCCIN_CPU0_PWR_IN_ALERT_N   I117 @BASEBOARD_FAB2_LIB.BASEBOARD_FAB2(SCH_1):PAGE95
     2 IRQ_PVCCIN_CPU0_VRHOT_LVC3_N @BASEBOARD_FAB2_LIB.BASEBOARD_FAB2(SCH_1):IRQ_PVCCIN_CPU0_VRHOT_LVC3_N   I117 @BASEBOARD_FAB2_LIB.BASEBOARD_FAB2(SCH_1):PAGE95

U7E3 TTL1G08_SOTLF-NC7SZ08,IC,D1032B
     4 IRQ_CPU1_PROCHOT_G_N @BASEBOARD_FAB2_LIB.BASEBOARD_FAB2(SCH_1):IRQ_CPU1_PROCHOT_G_N   I118 @BASEBOARD_FAB2_LIB.BASEBOARD_FAB2(SCH_1):PAGE95
     1 FM_PVCCIN_CPU1_PWR_IN_ALERT_N @BASEBOARD_FAB2_LIB.BASEBOARD_FAB2(SCH_1):FM_PVCCIN_CPU1_PWR_IN_ALERT_N   I118 @BASEBOARD_FAB2_LIB.BASEBOARD_FAB2(SCH_1):PAGE95
     2 IRQ_PVCCIN_CPU1_VRHOT_LVC3_N @BASEBOARD_FAB2_LIB.BASEBOARD_FAB2(SCH_1):IRQ_PVCCIN_CPU1_VRHOT_LVC3_N   I118 @BASEBOARD_FAB2_LIB.BASEBOARD_FAB2(SCH_1):PAGE95

U7F1 W25Q256_XSOI-IC,H25002-001
     9 PU_BIOS_SPI_WP0_N @BASEBOARD_FAB2_LIB.BASEBOARD_FAB2(SCH_1):PU_BIOS_SPI_WP0_N   I146 @BASEBOARD_FAB2_LIB.BASEBOARD_FAB2(SCH_1):PAGE153
    14 TP_SPI_0_0 @BASEBOARD_FAB2_LIB.BASEBOARD_FAB2(SCH_1):TP_SPI_0_0   I146 @BASEBOARD_FAB2_LIB.BASEBOARD_FAB2(SCH_1):PAGE153
    13 TP_SPI_0_1 @BASEBOARD_FAB2_LIB.BASEBOARD_FAB2(SCH_1):TP_SPI_0_1   I146 @BASEBOARD_FAB2_LIB.BASEBOARD_FAB2(SCH_1):PAGE153
    12 TP_SPI_0_2 @BASEBOARD_FAB2_LIB.BASEBOARD_FAB2(SCH_1):TP_SPI_0_2   I146 @BASEBOARD_FAB2_LIB.BASEBOARD_FAB2(SCH_1):PAGE153
    11 TP_SPI_0_3 @BASEBOARD_FAB2_LIB.BASEBOARD_FAB2(SCH_1):TP_SPI_0_3   I146 @BASEBOARD_FAB2_LIB.BASEBOARD_FAB2(SCH_1):PAGE153
     6 TP_SPI_0_4 @BASEBOARD_FAB2_LIB.BASEBOARD_FAB2(SCH_1):TP_SPI_0_4   I146 @BASEBOARD_FAB2_LIB.BASEBOARD_FAB2(SCH_1):PAGE153
     5 TP_SPI_0_5 @BASEBOARD_FAB2_LIB.BASEBOARD_FAB2(SCH_1):TP_SPI_0_5   I146 @BASEBOARD_FAB2_LIB.BASEBOARD_FAB2(SCH_1):PAGE153
     4 TP_SPI_0_6 @BASEBOARD_FAB2_LIB.BASEBOARD_FAB2(SCH_1):TP_SPI_0_6   I146 @BASEBOARD_FAB2_LIB.BASEBOARD_FAB2(SCH_1):PAGE153
    10    GND @BASEBOARD_FAB2_LIB.BASEBOARD_FAB2(SCH_1):GND   I146 @BASEBOARD_FAB2_LIB.BASEBOARD_FAB2(SCH_1):PAGE153
     8 SPI_MISO_R0 @BASEBOARD_FAB2_LIB.BASEBOARD_FAB2(SCH_1):SPI_MISO_R0   I146 @BASEBOARD_FAB2_LIB.BASEBOARD_FAB2(SCH_1):PAGE153
    16 SPI_CLK_R0 @BASEBOARD_FAB2_LIB.BASEBOARD_FAB2(SCH_1):SPI_CLK_R0   I146 @BASEBOARD_FAB2_LIB.BASEBOARD_FAB2(SCH_1):PAGE153
     2 P3V3_STBY @BASEBOARD_FAB2_LIB.BASEBOARD_FAB2(SCH_1):P3V3_STBY   I146 @BASEBOARD_FAB2_LIB.BASEBOARD_FAB2(SCH_1):PAGE153
     7 SPI_CS0_PRIMARY_R_N @BASEBOARD_FAB2_LIB.BASEBOARD_FAB2(SCH_1):SPI_CS0_PRIMARY_R_N   I146 @BASEBOARD_FAB2_LIB.BASEBOARD_FAB2(SCH_1):PAGE153
    15 SPI_SWITCH_MOSI_R0 @BASEBOARD_FAB2_LIB.BASEBOARD_FAB2(SCH_1):SPI_SWITCH_MOSI_R0   I146 @BASEBOARD_FAB2_LIB.BASEBOARD_FAB2(SCH_1):PAGE153
     3 PU_SPI0_RST @BASEBOARD_FAB2_LIB.BASEBOARD_FAB2(SCH_1):PU_SPI0_RST   I146 @BASEBOARD_FAB2_LIB.BASEBOARD_FAB2(SCH_1):PAGE153
     1 PU_BIOS_SPI_HOLD0_N @BASEBOARD_FAB2_LIB.BASEBOARD_FAB2(SCH_1):PU_BIOS_SPI_HOLD0_N   I146 @BASEBOARD_FAB2_LIB.BASEBOARD_FAB2(SCH_1):PAGE153

U8D2 TTL1G07_A_SOP-74LVC1G07,IC,C88B
     2 PWRGD_DSW_PWROK @BASEBOARD_FAB2_LIB.BASEBOARD_FAB2(SCH_1):PWRGD_DSW_PWROK   I374 @BASEBOARD_FAB2_LIB.BASEBOARD_FAB2(SCH_1):PAGE157
     4 RST_BMC_SRST_R2_N @BASEBOARD_FAB2_LIB.BASEBOARD_FAB2(SCH_1):RST_BMC_SRST_R2_N   I374 @BASEBOARD_FAB2_LIB.BASEBOARD_FAB2(SCH_1):PAGE157

U8D3 TTL1G07_A_SOP-74LVC1G07,IC,C88B
     2 IRQ_SML1_PMBUS_ALERT_BUF_N @BASEBOARD_FAB2_LIB.BASEBOARD_FAB2(SCH_1):IRQ_SML1_PMBUS_ALERT_BUF_N     I4 @BASEBOARD_FAB2_LIB.BASEBOARD_FAB2(SCH_1):PAGE170
     4 IRQ_FORCE_NM_THROTTLE_R_N @BASEBOARD_FAB2_LIB.BASEBOARD_FAB2(SCH_1):IRQ_FORCE_NM_THROTTLE_R_N     I4 @BASEBOARD_FAB2_LIB.BASEBOARD_FAB2(SCH_1):PAGE170

U8D4 AT24C64_SOICLF-IC,C47049-001-GA
     1    GND @BASEBOARD_FAB2_LIB.BASEBOARD_FAB2(SCH_1):GND    I49 @BASEBOARD_FAB2_LIB.BASEBOARD_FAB2(SCH_1):PAGE167
     2    GND @BASEBOARD_FAB2_LIB.BASEBOARD_FAB2(SCH_1):GND    I49 @BASEBOARD_FAB2_LIB.BASEBOARD_FAB2(SCH_1):PAGE167
     3 PU_AT24C64_A2 @BASEBOARD_FAB2_LIB.BASEBOARD_FAB2(SCH_1):PU_AT24C64_A2    I49 @BASEBOARD_FAB2_LIB.BASEBOARD_FAB2(SCH_1):PAGE167
     6 SMB_SENSOR_STBY_LVC3_SCL_R2 @BASEBOARD_FAB2_LIB.BASEBOARD_FAB2(SCH_1):SMB_SENSOR_STBY_LVC3_SCL_R2    I49 @BASEBOARD_FAB2_LIB.BASEBOARD_FAB2(SCH_1):PAGE167
     7 PD_FRU_WP @BASEBOARD_FAB2_LIB.BASEBOARD_FAB2(SCH_1):PD_FRU_WP    I49 @BASEBOARD_FAB2_LIB.BASEBOARD_FAB2(SCH_1):PAGE167
     5 SMB_SENSOR_STBY_LVC3_SDA_R2 @BASEBOARD_FAB2_LIB.BASEBOARD_FAB2(SCH_1):SMB_SENSOR_STBY_LVC3_SDA_R2    I49 @BASEBOARD_FAB2_LIB.BASEBOARD_FAB2(SCH_1):PAGE167

U8D5 TTL1G126_A_SOT-74HC1G126,IC,A7B
     1 FM_PMBUS_ALERT_BUF_EN @BASEBOARD_FAB2_LIB.BASEBOARD_FAB2(SCH_1):FM_PMBUS_ALERT_BUF_EN    I38 @BASEBOARD_FAB2_LIB.BASEBOARD_FAB2(SCH_1):PAGE170
     2 IRQ_SML1_PMBUS_ALERT_N @BASEBOARD_FAB2_LIB.BASEBOARD_FAB2(SCH_1):IRQ_SML1_PMBUS_ALERT_N    I38 @BASEBOARD_FAB2_LIB.BASEBOARD_FAB2(SCH_1):PAGE170
     4 IRQ_SML1_PMBUS_ALERT_BUF_N @BASEBOARD_FAB2_LIB.BASEBOARD_FAB2(SCH_1):IRQ_SML1_PMBUS_ALERT_BUF_N    I38 @BASEBOARD_FAB2_LIB.BASEBOARD_FAB2(SCH_1):PAGE170

U8D7 LCMXO2_A_256BGA-IC,H63395-001
    P4 FM_CPU1_RC_EN @BASEBOARD_FAB2_LIB.BASEBOARD_FAB2(SCH_1):FM_CPU1_RC_EN   I179 @BASEBOARD_FAB2_LIB.BASEBOARD_FAB2(SCH_1):PAGE190
    T4 PWRGD_PVSA_CPU1 @BASEBOARD_FAB2_LIB.BASEBOARD_FAB2(SCH_1):PWRGD_PVSA_CPU1   I179 @BASEBOARD_FAB2_LIB.BASEBOARD_FAB2(SCH_1):PAGE190
    T2 FM_ADR_MODE_SEL @BASEBOARD_FAB2_LIB.BASEBOARD_FAB2(SCH_1):FM_ADR_MODE_SEL   I179 @BASEBOARD_FAB2_LIB.BASEBOARD_FAB2(SCH_1):PAGE190
    R3 FM_CPU0_RC_EN @BASEBOARD_FAB2_LIB.BASEBOARD_FAB2(SCH_1):FM_CPU0_RC_EN   I179 @BASEBOARD_FAB2_LIB.BASEBOARD_FAB2(SCH_1):PAGE190
    R5 TP_CPLD1_PB5A_CSSPIN @BASEBOARD_FAB2_LIB.BASEBOARD_FAB2(SCH_1):TP_CPLD1_PB5A_CSSPIN   I179 @BASEBOARD_FAB2_LIB.BASEBOARD_FAB2(SCH_1):PAGE190
    P5 PWRGD_PVCCMCP_CPU0 @BASEBOARD_FAB2_LIB.BASEBOARD_FAB2(SCH_1):PWRGD_PVCCMCP_CPU0   I179 @BASEBOARD_FAB2_LIB.BASEBOARD_FAB2(SCH_1):PAGE190
    T5 PWRGD_PVCCIOMCP_CPU1 @BASEBOARD_FAB2_LIB.BASEBOARD_FAB2(SCH_1):PWRGD_PVCCIOMCP_CPU1   I179 @BASEBOARD_FAB2_LIB.BASEBOARD_FAB2(SCH_1):PAGE190
    R6 RST_PCIE_M2_DEV_N @BASEBOARD_FAB2_LIB.BASEBOARD_FAB2(SCH_1):RST_PCIE_M2_DEV_N   I179 @BASEBOARD_FAB2_LIB.BASEBOARD_FAB2(SCH_1):PAGE190
    T3 FM_DIS_ADR_DLY @BASEBOARD_FAB2_LIB.BASEBOARD_FAB2(SCH_1):FM_DIS_ADR_DLY   I179 @BASEBOARD_FAB2_LIB.BASEBOARD_FAB2(SCH_1):PAGE190
    R4 FM_BMC_CPLD_MP_RST_N @BASEBOARD_FAB2_LIB.BASEBOARD_FAB2(SCH_1):FM_BMC_CPLD_MP_RST_N   I179 @BASEBOARD_FAB2_LIB.BASEBOARD_FAB2(SCH_1):PAGE190
    P6 TP_CPLD1_PB8A_MCLK_CCLK @BASEBOARD_FAB2_LIB.BASEBOARD_FAB2(SCH_1):TP_CPLD1_PB8A_MCLK_CCLK   I179 @BASEBOARD_FAB2_LIB.BASEBOARD_FAB2(SCH_1):PAGE190
    T6 TP_CPLD1_PB8B_SO_SPISO @BASEBOARD_FAB2_LIB.BASEBOARD_FAB2(SCH_1):TP_CPLD1_PB8B_SO_SPISO   I179 @BASEBOARD_FAB2_LIB.BASEBOARD_FAB2(SCH_1):PAGE190
    N6 PWRGD_PVCCIOMCP_CPU0 @BASEBOARD_FAB2_LIB.BASEBOARD_FAB2(SCH_1):PWRGD_PVCCIOMCP_CPU0   I179 @BASEBOARD_FAB2_LIB.BASEBOARD_FAB2(SCH_1):PAGE190
    L7 TP_CPLD1_PB8D @BASEBOARD_FAB2_LIB.BASEBOARD_FAB2(SCH_1):TP_CPLD1_PB8D   I179 @BASEBOARD_FAB2_LIB.BASEBOARD_FAB2(SCH_1):PAGE190
    R7 PWRGD_PVTT_CPU1 @BASEBOARD_FAB2_LIB.BASEBOARD_FAB2(SCH_1):PWRGD_PVTT_CPU1   I179 @BASEBOARD_FAB2_LIB.BASEBOARD_FAB2(SCH_1):PAGE190
    P7 FM_PVCCIOMCP_CPU1_EN @BASEBOARD_FAB2_LIB.BASEBOARD_FAB2(SCH_1):FM_PVCCIOMCP_CPU1_EN   I179 @BASEBOARD_FAB2_LIB.BASEBOARD_FAB2(SCH_1):PAGE190
    M7 FM_PVCCIO_CPU0_EN @BASEBOARD_FAB2_LIB.BASEBOARD_FAB2(SCH_1):FM_PVCCIO_CPU0_EN   I179 @BASEBOARD_FAB2_LIB.BASEBOARD_FAB2(SCH_1):PAGE190
    N7 PWRGD_PVPP_ABC @BASEBOARD_FAB2_LIB.BASEBOARD_FAB2(SCH_1):PWRGD_PVPP_ABC   I179 @BASEBOARD_FAB2_LIB.BASEBOARD_FAB2(SCH_1):PAGE190
    T7 FM_PVCCIO_CPU1_EN @BASEBOARD_FAB2_LIB.BASEBOARD_FAB2(SCH_1):FM_PVCCIO_CPU1_EN   I179 @BASEBOARD_FAB2_LIB.BASEBOARD_FAB2(SCH_1):PAGE190
    R8 TP_CPLD1_PB11B_PCLKC2_0 @BASEBOARD_FAB2_LIB.BASEBOARD_FAB2(SCH_1):TP_CPLD1_PB11B_PCLKC2_0   I179 @BASEBOARD_FAB2_LIB.BASEBOARD_FAB2(SCH_1):PAGE190
    M6 PWRGD_PVPP_DEF @BASEBOARD_FAB2_LIB.BASEBOARD_FAB2(SCH_1):PWRGD_PVPP_DEF   I179 @BASEBOARD_FAB2_LIB.BASEBOARD_FAB2(SCH_1):PAGE190
    L8 PWRGD_PVCCIO_CPU0 @BASEBOARD_FAB2_LIB.BASEBOARD_FAB2(SCH_1):PWRGD_PVCCIO_CPU0   I179 @BASEBOARD_FAB2_LIB.BASEBOARD_FAB2(SCH_1):PAGE190
    P8 PWRGD_PVNN_P1V05_PCH @BASEBOARD_FAB2_LIB.BASEBOARD_FAB2(SCH_1):PWRGD_PVNN_P1V05_PCH   I179 @BASEBOARD_FAB2_LIB.BASEBOARD_FAB2(SCH_1):PAGE190
    T8 FM_CPLD_DBG_PWR_EN_N @BASEBOARD_FAB2_LIB.BASEBOARD_FAB2(SCH_1):FM_CPLD_DBG_PWR_EN_N   I179 @BASEBOARD_FAB2_LIB.BASEBOARD_FAB2(SCH_1):PAGE190
    N8 FM_156M_CPU1_BRD_OSC_EN @BASEBOARD_FAB2_LIB.BASEBOARD_FAB2(SCH_1):FM_156M_CPU1_BRD_OSC_EN   I179 @BASEBOARD_FAB2_LIB.BASEBOARD_FAB2(SCH_1):PAGE190
    L9 FM_IE_DISABLE_N @BASEBOARD_FAB2_LIB.BASEBOARD_FAB2(SCH_1):FM_IE_DISABLE_N   I179 @BASEBOARD_FAB2_LIB.BASEBOARD_FAB2(SCH_1):PAGE190
    T9 TP_CPLD1_PB16A_PCLKT2_1 @BASEBOARD_FAB2_LIB.BASEBOARD_FAB2(SCH_1):TP_CPLD1_PB16A_PCLKT2_1   I179 @BASEBOARD_FAB2_LIB.BASEBOARD_FAB2(SCH_1):PAGE190
    P9 TP_CPLD1_PB16B_PCLKC2_1 @BASEBOARD_FAB2_LIB.BASEBOARD_FAB2(SCH_1):TP_CPLD1_PB16B_PCLKC2_1   I179 @BASEBOARD_FAB2_LIB.BASEBOARD_FAB2(SCH_1):PAGE190
    M8 FM_PVCCMCP_CPU1_EN @BASEBOARD_FAB2_LIB.BASEBOARD_FAB2(SCH_1):FM_PVCCMCP_CPU1_EN   I179 @BASEBOARD_FAB2_LIB.BASEBOARD_FAB2(SCH_1):PAGE190
    N9 FM_CPLD_BMC_PWRDN_N @BASEBOARD_FAB2_LIB.BASEBOARD_FAB2(SCH_1):FM_CPLD_BMC_PWRDN_N   I179 @BASEBOARD_FAB2_LIB.BASEBOARD_FAB2(SCH_1):PAGE190
    R9 FM_UARTSW_LSB_N @BASEBOARD_FAB2_LIB.BASEBOARD_FAB2(SCH_1):FM_UARTSW_LSB_N   I179 @BASEBOARD_FAB2_LIB.BASEBOARD_FAB2(SCH_1):PAGE190
   T10 FM_156M_CPU0_BRD_OSC_EN @BASEBOARD_FAB2_LIB.BASEBOARD_FAB2(SCH_1):FM_156M_CPU0_BRD_OSC_EN   I179 @BASEBOARD_FAB2_LIB.BASEBOARD_FAB2(SCH_1):PAGE190
    M9 FM_CPLD_UART_CH_LOCK_N @BASEBOARD_FAB2_LIB.BASEBOARD_FAB2(SCH_1):FM_CPLD_UART_CH_LOCK_N   I179 @BASEBOARD_FAB2_LIB.BASEBOARD_FAB2(SCH_1):PAGE190
   L10 FM_SOL_UART_CH_SEL @BASEBOARD_FAB2_LIB.BASEBOARD_FAB2(SCH_1):FM_SOL_UART_CH_SEL   I179 @BASEBOARD_FAB2_LIB.BASEBOARD_FAB2(SCH_1):PAGE190
   P10 RST_CD_CPU1_POR_N @BASEBOARD_FAB2_LIB.BASEBOARD_FAB2(SCH_1):RST_CD_CPU1_POR_N   I179 @BASEBOARD_FAB2_LIB.BASEBOARD_FAB2(SCH_1):PAGE190
   R10 RST_CPU0_LVC3_R1_N @BASEBOARD_FAB2_LIB.BASEBOARD_FAB2(SCH_1):RST_CPU0_LVC3_R1_N   I179 @BASEBOARD_FAB2_LIB.BASEBOARD_FAB2(SCH_1):PAGE190
   N10 RST_CPU1_LVC3_R1_N @BASEBOARD_FAB2_LIB.BASEBOARD_FAB2(SCH_1):RST_CPU1_LVC3_R1_N   I179 @BASEBOARD_FAB2_LIB.BASEBOARD_FAB2(SCH_1):PAGE190
   M11 XDP_PWRGD_RST_N @BASEBOARD_FAB2_LIB.BASEBOARD_FAB2(SCH_1):XDP_PWRGD_RST_N   I179 @BASEBOARD_FAB2_LIB.BASEBOARD_FAB2(SCH_1):PAGE190
   T11 FM_CPU1_PKGID2 @BASEBOARD_FAB2_LIB.BASEBOARD_FAB2(SCH_1):FM_CPU1_PKGID2   I179 @BASEBOARD_FAB2_LIB.BASEBOARD_FAB2(SCH_1):PAGE190
   P11 FM_UARTSW_MSB_N @BASEBOARD_FAB2_LIB.BASEBOARD_FAB2(SCH_1):FM_UARTSW_MSB_N   I179 @BASEBOARD_FAB2_LIB.BASEBOARD_FAB2(SCH_1):PAGE190
   M10 PWRGD_CPU1_LVC3 @BASEBOARD_FAB2_LIB.BASEBOARD_FAB2(SCH_1):PWRGD_CPU1_LVC3   I179 @BASEBOARD_FAB2_LIB.BASEBOARD_FAB2(SCH_1):PAGE190
   N11 XDP_SYSPWROK @BASEBOARD_FAB2_LIB.BASEBOARD_FAB2(SCH_1):XDP_SYSPWROK   I179 @BASEBOARD_FAB2_LIB.BASEBOARD_FAB2(SCH_1):PAGE190
   R11 FM_DB1200ZL_BCLKS_EN_N @BASEBOARD_FAB2_LIB.BASEBOARD_FAB2(SCH_1):FM_DB1200ZL_BCLKS_EN_N   I179 @BASEBOARD_FAB2_LIB.BASEBOARD_FAB2(SCH_1):PAGE190
   T12 FM_CPU1_SKTOCC_LVT3_N @BASEBOARD_FAB2_LIB.BASEBOARD_FAB2(SCH_1):FM_CPU1_SKTOCC_LVT3_N   I179 @BASEBOARD_FAB2_LIB.BASEBOARD_FAB2(SCH_1):PAGE190
   R13 FM_CPU0_VRM_OSC_EN @BASEBOARD_FAB2_LIB.BASEBOARD_FAB2(SCH_1):FM_CPU0_VRM_OSC_EN   I179 @BASEBOARD_FAB2_LIB.BASEBOARD_FAB2(SCH_1):PAGE190
   T14 FM_CPU0_SKTOCC_LVT3_N @BASEBOARD_FAB2_LIB.BASEBOARD_FAB2(SCH_1):FM_CPU0_SKTOCC_LVT3_N   I179 @BASEBOARD_FAB2_LIB.BASEBOARD_FAB2(SCH_1):PAGE190
   P12 FM_CPU1_PKGID1 @BASEBOARD_FAB2_LIB.BASEBOARD_FAB2(SCH_1):FM_CPU1_PKGID1   I179 @BASEBOARD_FAB2_LIB.BASEBOARD_FAB2(SCH_1):PAGE190
   T13 FM_CPU_MSMI_LVT3_N @BASEBOARD_FAB2_LIB.BASEBOARD_FAB2(SCH_1):FM_CPU_MSMI_LVT3_N   I179 @BASEBOARD_FAB2_LIB.BASEBOARD_FAB2(SCH_1):PAGE190
   R12 FM_CPU1_PKGID0 @BASEBOARD_FAB2_LIB.BASEBOARD_FAB2(SCH_1):FM_CPU1_PKGID0   I179 @BASEBOARD_FAB2_LIB.BASEBOARD_FAB2(SCH_1):PAGE190
   P13 TP_CPLD1_PB25B_SI_SISPI @BASEBOARD_FAB2_LIB.BASEBOARD_FAB2(SCH_1):TP_CPLD1_PB25B_SI_SISPI   I179 @BASEBOARD_FAB2_LIB.BASEBOARD_FAB2(SCH_1):PAGE190
   T15 PWRGD_DRAMPWRGD @BASEBOARD_FAB2_LIB.BASEBOARD_FAB2(SCH_1):PWRGD_DRAMPWRGD   I179 @BASEBOARD_FAB2_LIB.BASEBOARD_FAB2(SCH_1):PAGE190
   R14 FM_CPU_CATERR_LVT3_N @BASEBOARD_FAB2_LIB.BASEBOARD_FAB2(SCH_1):FM_CPU_CATERR_LVT3_N   I179 @BASEBOARD_FAB2_LIB.BASEBOARD_FAB2(SCH_1):PAGE190
    D3 TP_CPLD1_PL1A_L_GPLLT_FB @BASEBOARD_FAB2_LIB.BASEBOARD_FAB2(SCH_1):TP_CPLD1_PL1A_L_GPLLT_FB   I179 @BASEBOARD_FAB2_LIB.BASEBOARD_FAB2(SCH_1):PAGE190
    D1 TP_CPLD1_PL1B_L_GPLLC_FB @BASEBOARD_FAB2_LIB.BASEBOARD_FAB2(SCH_1):TP_CPLD1_PL1B_L_GPLLC_FB   I179 @BASEBOARD_FAB2_LIB.BASEBOARD_FAB2(SCH_1):PAGE190
    B1 RST_PCIE_PCH_PERST_N @BASEBOARD_FAB2_LIB.BASEBOARD_FAB2(SCH_1):RST_PCIE_PCH_PERST_N   I179 @BASEBOARD_FAB2_LIB.BASEBOARD_FAB2(SCH_1):PAGE190
    C2 FM_PCH_PLD_DATA @BASEBOARD_FAB2_LIB.BASEBOARD_FAB2(SCH_1):FM_PCH_PLD_DATA   I179 @BASEBOARD_FAB2_LIB.BASEBOARD_FAB2(SCH_1):PAGE190
    E2 FM_CPU_CATERR_DLY_LVT3_N @BASEBOARD_FAB2_LIB.BASEBOARD_FAB2(SCH_1):FM_CPU_CATERR_DLY_LVT3_N   I179 @BASEBOARD_FAB2_LIB.BASEBOARD_FAB2(SCH_1):PAGE190
    E3 TP_CPLD1_PL2B_L_GPLLC_IN @BASEBOARD_FAB2_LIB.BASEBOARD_FAB2(SCH_1):TP_CPLD1_PL2B_L_GPLLC_IN   I179 @BASEBOARD_FAB2_LIB.BASEBOARD_FAB2(SCH_1):PAGE190
    C1 RST_PCIE_CPU_DEV1_N @BASEBOARD_FAB2_LIB.BASEBOARD_FAB2(SCH_1):RST_PCIE_CPU_DEV1_N   I179 @BASEBOARD_FAB2_LIB.BASEBOARD_FAB2(SCH_1):PAGE190
    D2 FM_MEM_EVENT_FUNC @BASEBOARD_FAB2_LIB.BASEBOARD_FAB2(SCH_1):FM_MEM_EVENT_FUNC   I179 @BASEBOARD_FAB2_LIB.BASEBOARD_FAB2(SCH_1):PAGE190
    E1 CLK_32K_SUSCLK_PLD @BASEBOARD_FAB2_LIB.BASEBOARD_FAB2(SCH_1):CLK_32K_SUSCLK_PLD   I179 @BASEBOARD_FAB2_LIB.BASEBOARD_FAB2(SCH_1):PAGE190
    F2 FM_CPU0_PKGID0 @BASEBOARD_FAB2_LIB.BASEBOARD_FAB2(SCH_1):FM_CPU0_PKGID0   I179 @BASEBOARD_FAB2_LIB.BASEBOARD_FAB2(SCH_1):PAGE190
    F4 PU_RST_PERST_BIT0 @BASEBOARD_FAB2_LIB.BASEBOARD_FAB2(SCH_1):PU_RST_PERST_BIT0   I179 @BASEBOARD_FAB2_LIB.BASEBOARD_FAB2(SCH_1):PAGE190
    G6 FM_PWR_BTN_N @BASEBOARD_FAB2_LIB.BASEBOARD_FAB2(SCH_1):FM_PWR_BTN_N   I179 @BASEBOARD_FAB2_LIB.BASEBOARD_FAB2(SCH_1):PAGE190
    F3 FM_CPU0_PROC_ID1 @BASEBOARD_FAB2_LIB.BASEBOARD_FAB2(SCH_1):FM_CPU0_PROC_ID1   I179 @BASEBOARD_FAB2_LIB.BASEBOARD_FAB2(SCH_1):PAGE190
    F1 FM_CPU0_PROC_ID0 @BASEBOARD_FAB2_LIB.BASEBOARD_FAB2(SCH_1):FM_CPU0_PROC_ID0   I179 @BASEBOARD_FAB2_LIB.BASEBOARD_FAB2(SCH_1):PAGE190
    G5 FM_DEBUG_RST_BTN_N @BASEBOARD_FAB2_LIB.BASEBOARD_FAB2(SCH_1):FM_DEBUG_RST_BTN_N   I179 @BASEBOARD_FAB2_LIB.BASEBOARD_FAB2(SCH_1):PAGE190
    G4 RST_RSMRST_R_N @BASEBOARD_FAB2_LIB.BASEBOARD_FAB2(SCH_1):RST_RSMRST_R_N   I179 @BASEBOARD_FAB2_LIB.BASEBOARD_FAB2(SCH_1):PAGE190
    G2 FM_CPU0_PKGID2 @BASEBOARD_FAB2_LIB.BASEBOARD_FAB2(SCH_1):FM_CPU0_PKGID2   I179 @BASEBOARD_FAB2_LIB.BASEBOARD_FAB2(SCH_1):PAGE190
    G3 FM_CPU0_PKGID1 @BASEBOARD_FAB2_LIB.BASEBOARD_FAB2(SCH_1):FM_CPU0_PKGID1   I179 @BASEBOARD_FAB2_LIB.BASEBOARD_FAB2(SCH_1):PAGE190
    F5 FM_CPU0_FIVR_FAULT_LVT3_N @BASEBOARD_FAB2_LIB.BASEBOARD_FAB2(SCH_1):FM_CPU0_FIVR_FAULT_LVT3_N   I179 @BASEBOARD_FAB2_LIB.BASEBOARD_FAB2(SCH_1):PAGE190
    H6 PWRGD_P3V3 @BASEBOARD_FAB2_LIB.BASEBOARD_FAB2(SCH_1):PWRGD_P3V3   I179 @BASEBOARD_FAB2_LIB.BASEBOARD_FAB2(SCH_1):PAGE190
    G1 FM_SLPS3_N @BASEBOARD_FAB2_LIB.BASEBOARD_FAB2(SCH_1):FM_SLPS3_N   I179 @BASEBOARD_FAB2_LIB.BASEBOARD_FAB2(SCH_1):PAGE190
    H2 FM_PVCCMCP_CPU0_EN @BASEBOARD_FAB2_LIB.BASEBOARD_FAB2(SCH_1):FM_PVCCMCP_CPU0_EN   I179 @BASEBOARD_FAB2_LIB.BASEBOARD_FAB2(SCH_1):PAGE190
    H4 FM_MP_PS_FAIL_N @BASEBOARD_FAB2_LIB.BASEBOARD_FAB2(SCH_1):FM_MP_PS_FAIL_N   I179 @BASEBOARD_FAB2_LIB.BASEBOARD_FAB2(SCH_1):PAGE190
    J6 PWRGD_P5V @BASEBOARD_FAB2_LIB.BASEBOARD_FAB2(SCH_1):PWRGD_P5V   I179 @BASEBOARD_FAB2_LIB.BASEBOARD_FAB2(SCH_1):PAGE190
    H3 RST_PCIE_CPU_DEV2_N @BASEBOARD_FAB2_LIB.BASEBOARD_FAB2(SCH_1):RST_PCIE_CPU_DEV2_N   I179 @BASEBOARD_FAB2_LIB.BASEBOARD_FAB2(SCH_1):PAGE190
    H1 RST_PCIE_CPU_DEV3_N @BASEBOARD_FAB2_LIB.BASEBOARD_FAB2(SCH_1):RST_PCIE_CPU_DEV3_N   I179 @BASEBOARD_FAB2_LIB.BASEBOARD_FAB2(SCH_1):PAGE190
    J1 SGPIO_BMC_CLK @BASEBOARD_FAB2_LIB.BASEBOARD_FAB2(SCH_1):SGPIO_BMC_CLK   I179 @BASEBOARD_FAB2_LIB.BASEBOARD_FAB2(SCH_1):PAGE190
    J3 TP_CPLD1_PL7D_PCLKT4_0 @BASEBOARD_FAB2_LIB.BASEBOARD_FAB2(SCH_1):TP_CPLD1_PL7D_PCLKT4_0   I179 @BASEBOARD_FAB2_LIB.BASEBOARD_FAB2(SCH_1):PAGE190
    J2 SGPIO_BMC_DOUT @BASEBOARD_FAB2_LIB.BASEBOARD_FAB2(SCH_1):SGPIO_BMC_DOUT   I179 @BASEBOARD_FAB2_LIB.BASEBOARD_FAB2(SCH_1):PAGE190
    K1 FM_PVCCIOMCP_CPU0_EN @BASEBOARD_FAB2_LIB.BASEBOARD_FAB2(SCH_1):FM_PVCCIOMCP_CPU0_EN   I179 @BASEBOARD_FAB2_LIB.BASEBOARD_FAB2(SCH_1):PAGE190
    H5 SMB_SLOTX24_PCH_STBY_LVC3_SCL @BASEBOARD_FAB2_LIB.BASEBOARD_FAB2(SCH_1):SMB_SLOTX24_PCH_STBY_LVC3_SCL   I179 @BASEBOARD_FAB2_LIB.BASEBOARD_FAB2(SCH_1):PAGE190
    J4 SMB_SLOTX24_PCH_STBY_LVC3_SDA @BASEBOARD_FAB2_LIB.BASEBOARD_FAB2(SCH_1):SMB_SLOTX24_PCH_STBY_LVC3_SDA   I179 @BASEBOARD_FAB2_LIB.BASEBOARD_FAB2(SCH_1):PAGE190
    K3 SP1_BMC_HOST_UART_RX @BASEBOARD_FAB2_LIB.BASEBOARD_FAB2(SCH_1):SP1_BMC_HOST_UART_RX   I179 @BASEBOARD_FAB2_LIB.BASEBOARD_FAB2(SCH_1):PAGE190
    K2 SP1_BMC_HOST_UART_TX @BASEBOARD_FAB2_LIB.BASEBOARD_FAB2(SCH_1):SP1_BMC_HOST_UART_TX   I179 @BASEBOARD_FAB2_LIB.BASEBOARD_FAB2(SCH_1):PAGE190
    J5 UART_BMC_RXD5 @BASEBOARD_FAB2_LIB.BASEBOARD_FAB2(SCH_1):UART_BMC_RXD5   I179 @BASEBOARD_FAB2_LIB.BASEBOARD_FAB2(SCH_1):PAGE190
    K6 UART_BMC_TXD5 @BASEBOARD_FAB2_LIB.BASEBOARD_FAB2(SCH_1):UART_BMC_TXD5   I179 @BASEBOARD_FAB2_LIB.BASEBOARD_FAB2(SCH_1):PAGE190
    L1 PWRGD_PVSA_CPU0 @BASEBOARD_FAB2_LIB.BASEBOARD_FAB2(SCH_1):PWRGD_PVSA_CPU0   I179 @BASEBOARD_FAB2_LIB.BASEBOARD_FAB2(SCH_1):PAGE190
    L3 TP_CPLD1_PL11A @BASEBOARD_FAB2_LIB.BASEBOARD_FAB2(SCH_1):TP_CPLD1_PL11A   I179 @BASEBOARD_FAB2_LIB.BASEBOARD_FAB2(SCH_1):PAGE190
    K4 SGPIO_BMC_LD_N @BASEBOARD_FAB2_LIB.BASEBOARD_FAB2(SCH_1):SGPIO_BMC_LD_N   I179 @BASEBOARD_FAB2_LIB.BASEBOARD_FAB2(SCH_1):PAGE190
    L5 PWRGD_CPU0_LVC3 @BASEBOARD_FAB2_LIB.BASEBOARD_FAB2(SCH_1):PWRGD_CPU0_LVC3   I179 @BASEBOARD_FAB2_LIB.BASEBOARD_FAB2(SCH_1):PAGE190
    L2 CLK_25M_CPLD @BASEBOARD_FAB2_LIB.BASEBOARD_FAB2(SCH_1):CLK_25M_CPLD   I179 @BASEBOARD_FAB2_LIB.BASEBOARD_FAB2(SCH_1):PAGE190
    M1 RST_RSMRST_DLY @BASEBOARD_FAB2_LIB.BASEBOARD_FAB2(SCH_1):RST_RSMRST_DLY   I179 @BASEBOARD_FAB2_LIB.BASEBOARD_FAB2(SCH_1):PAGE190
    K5 PWRGD_PVCCIN_CPU0 @BASEBOARD_FAB2_LIB.BASEBOARD_FAB2(SCH_1):PWRGD_PVCCIN_CPU0   I179 @BASEBOARD_FAB2_LIB.BASEBOARD_FAB2(SCH_1):PAGE190
    L4 PWRGD_PVCCMCP_CPU1 @BASEBOARD_FAB2_LIB.BASEBOARD_FAB2(SCH_1):PWRGD_PVCCMCP_CPU1   I179 @BASEBOARD_FAB2_LIB.BASEBOARD_FAB2(SCH_1):PAGE190
    M3 RST_PCIE_RISER1_PERST_N @BASEBOARD_FAB2_LIB.BASEBOARD_FAB2(SCH_1):RST_PCIE_RISER1_PERST_N   I179 @BASEBOARD_FAB2_LIB.BASEBOARD_FAB2(SCH_1):PAGE190
    N1 PWRGD_PVCCIN_CPU1 @BASEBOARD_FAB2_LIB.BASEBOARD_FAB2(SCH_1):PWRGD_PVCCIN_CPU1   I179 @BASEBOARD_FAB2_LIB.BASEBOARD_FAB2(SCH_1):PAGE190
    N2 PWRGD_PVPP_KLM @BASEBOARD_FAB2_LIB.BASEBOARD_FAB2(SCH_1):PWRGD_PVPP_KLM   I179 @BASEBOARD_FAB2_LIB.BASEBOARD_FAB2(SCH_1):PAGE190
    P1 FM_GLOBAL_RST_WARN_N @BASEBOARD_FAB2_LIB.BASEBOARD_FAB2(SCH_1):FM_GLOBAL_RST_WARN_N   I179 @BASEBOARD_FAB2_LIB.BASEBOARD_FAB2(SCH_1):PAGE190
    M2 PWRGD_PVPP_GHJ @BASEBOARD_FAB2_LIB.BASEBOARD_FAB2(SCH_1):PWRGD_PVPP_GHJ   I179 @BASEBOARD_FAB2_LIB.BASEBOARD_FAB2(SCH_1):PAGE190
    N3 RST_CD_CPU0_POR_N @BASEBOARD_FAB2_LIB.BASEBOARD_FAB2(SCH_1):RST_CD_CPU0_POR_N   I179 @BASEBOARD_FAB2_LIB.BASEBOARD_FAB2(SCH_1):PAGE190
    R1 FM_BMC_CPLD_GPO @BASEBOARD_FAB2_LIB.BASEBOARD_FAB2(SCH_1):FM_BMC_CPLD_GPO   I179 @BASEBOARD_FAB2_LIB.BASEBOARD_FAB2(SCH_1):PAGE190
    P2 FM_UART_ALERT_N @BASEBOARD_FAB2_LIB.BASEBOARD_FAB2(SCH_1):FM_UART_ALERT_N   I179 @BASEBOARD_FAB2_LIB.BASEBOARD_FAB2(SCH_1):PAGE190
   D14 PWRGD_SYS_PWROK @BASEBOARD_FAB2_LIB.BASEBOARD_FAB2(SCH_1):PWRGD_SYS_PWROK    I59 @BASEBOARD_FAB2_LIB.BASEBOARD_FAB2(SCH_1):PAGE191
   E15 RST_PLTRST_N @BASEBOARD_FAB2_LIB.BASEBOARD_FAB2(SCH_1):RST_PLTRST_N    I59 @BASEBOARD_FAB2_LIB.BASEBOARD_FAB2(SCH_1):PAGE191
   C15 FM_DB1200_PWRGD @BASEBOARD_FAB2_LIB.BASEBOARD_FAB2(SCH_1):FM_DB1200_PWRGD    I59 @BASEBOARD_FAB2_LIB.BASEBOARD_FAB2(SCH_1):PAGE191
   B16 FM_ADR_COMPLETE_DLY @BASEBOARD_FAB2_LIB.BASEBOARD_FAB2(SCH_1):FM_ADR_COMPLETE_DLY    I59 @BASEBOARD_FAB2_LIB.BASEBOARD_FAB2(SCH_1):PAGE191
   D16 PWRGD_P1V8MCP_CPU1 @BASEBOARD_FAB2_LIB.BASEBOARD_FAB2(SCH_1):PWRGD_P1V8MCP_CPU1    I59 @BASEBOARD_FAB2_LIB.BASEBOARD_FAB2(SCH_1):PAGE191
   E14 FM_CPLD_ADR_TRIGGER_N @BASEBOARD_FAB2_LIB.BASEBOARD_FAB2(SCH_1):FM_CPLD_ADR_TRIGGER_N    I59 @BASEBOARD_FAB2_LIB.BASEBOARD_FAB2(SCH_1):PAGE191
   C16 PWRGD_PCH_PWROK @BASEBOARD_FAB2_LIB.BASEBOARD_FAB2(SCH_1):PWRGD_PCH_PWROK    I59 @BASEBOARD_FAB2_LIB.BASEBOARD_FAB2(SCH_1):PAGE191
   D15 PWRGD_P1V8MCP_CPU0 @BASEBOARD_FAB2_LIB.BASEBOARD_FAB2(SCH_1):PWRGD_P1V8MCP_CPU0    I59 @BASEBOARD_FAB2_LIB.BASEBOARD_FAB2(SCH_1):PAGE191
   E16 FM_P1V8MCP_CPU0_EN @BASEBOARD_FAB2_LIB.BASEBOARD_FAB2(SCH_1):FM_P1V8MCP_CPU0_EN    I59 @BASEBOARD_FAB2_LIB.BASEBOARD_FAB2(SCH_1):PAGE191
   F15 FM_CPU0_MCP_CLK_EN_N @BASEBOARD_FAB2_LIB.BASEBOARD_FAB2(SCH_1):FM_CPU0_MCP_CLK_EN_N    I59 @BASEBOARD_FAB2_LIB.BASEBOARD_FAB2(SCH_1):PAGE191
   F13 PWRGD_CPUPWRGD @BASEBOARD_FAB2_LIB.BASEBOARD_FAB2(SCH_1):PWRGD_CPUPWRGD    I59 @BASEBOARD_FAB2_LIB.BASEBOARD_FAB2(SCH_1):PAGE191
   G12 FM_CPU0_THERMTRIP_LATCH_LVT3_N @BASEBOARD_FAB2_LIB.BASEBOARD_FAB2(SCH_1):FM_CPU0_THERMTRIP_LATCH_LVT3_N    I59 @BASEBOARD_FAB2_LIB.BASEBOARD_FAB2(SCH_1):PAGE191
   F14 RST_BMC_SYSRST_BTN_OUT_B_N @BASEBOARD_FAB2_LIB.BASEBOARD_FAB2(SCH_1):RST_BMC_SYSRST_BTN_OUT_B_N    I59 @BASEBOARD_FAB2_LIB.BASEBOARD_FAB2(SCH_1):PAGE191
   F16 FM_CPU1_MCP_CLK_EN_N @BASEBOARD_FAB2_LIB.BASEBOARD_FAB2(SCH_1):FM_CPU1_MCP_CLK_EN_N    I59 @BASEBOARD_FAB2_LIB.BASEBOARD_FAB2(SCH_1):PAGE191
   F12 FM_P1V8MCP_CPU1_EN @BASEBOARD_FAB2_LIB.BASEBOARD_FAB2(SCH_1):FM_P1V8MCP_CPU1_EN    I59 @BASEBOARD_FAB2_LIB.BASEBOARD_FAB2(SCH_1):PAGE191
   G13 FM_CPU1_FIVR_FAULT_LVT3 @BASEBOARD_FAB2_LIB.BASEBOARD_FAB2(SCH_1):FM_CPU1_FIVR_FAULT_LVT3    I59 @BASEBOARD_FAB2_LIB.BASEBOARD_FAB2(SCH_1):PAGE191
   G15 FM_UV_ADR_TRIGGER_N @BASEBOARD_FAB2_LIB.BASEBOARD_FAB2(SCH_1):FM_UV_ADR_TRIGGER_N    I59 @BASEBOARD_FAB2_LIB.BASEBOARD_FAB2(SCH_1):PAGE191
   G14 FM_CPU1_THERMTRIP_LVT3_N @BASEBOARD_FAB2_LIB.BASEBOARD_FAB2(SCH_1):FM_CPU1_THERMTRIP_LVT3_N    I59 @BASEBOARD_FAB2_LIB.BASEBOARD_FAB2(SCH_1):PAGE191
   G11 FM_WBG_PRSNT_N @BASEBOARD_FAB2_LIB.BASEBOARD_FAB2(SCH_1):FM_WBG_PRSNT_N    I59 @BASEBOARD_FAB2_LIB.BASEBOARD_FAB2(SCH_1):PAGE191
   H12 FM_UV_ADR_TRIGGER_EN @BASEBOARD_FAB2_LIB.BASEBOARD_FAB2(SCH_1):FM_UV_ADR_TRIGGER_EN    I59 @BASEBOARD_FAB2_LIB.BASEBOARD_FAB2(SCH_1):PAGE191
   G16 FM_FAST_PROCHOT_THROTTLE_IN_N @BASEBOARD_FAB2_LIB.BASEBOARD_FAB2(SCH_1):FM_FAST_PROCHOT_THROTTLE_IN_N    I59 @BASEBOARD_FAB2_LIB.BASEBOARD_FAB2(SCH_1):PAGE191
   H15 FM_PVDDQ_KLM_EN @BASEBOARD_FAB2_LIB.BASEBOARD_FAB2(SCH_1):FM_PVDDQ_KLM_EN    I59 @BASEBOARD_FAB2_LIB.BASEBOARD_FAB2(SCH_1):PAGE191
   H13 FM_PVDDQ_GHJ_EN @BASEBOARD_FAB2_LIB.BASEBOARD_FAB2(SCH_1):FM_PVDDQ_GHJ_EN    I59 @BASEBOARD_FAB2_LIB.BASEBOARD_FAB2(SCH_1):PAGE191
   J12 FM_FAST_PROCHOT_THROTTLE_DLY_N @BASEBOARD_FAB2_LIB.BASEBOARD_FAB2(SCH_1):FM_FAST_PROCHOT_THROTTLE_DLY_N    I59 @BASEBOARD_FAB2_LIB.BASEBOARD_FAB2(SCH_1):PAGE191
   H14 TP_CPLD1_PR7A_PCLKT1_0 @BASEBOARD_FAB2_LIB.BASEBOARD_FAB2(SCH_1):TP_CPLD1_PR7A_PCLKT1_0    I59 @BASEBOARD_FAB2_LIB.BASEBOARD_FAB2(SCH_1):PAGE191
   H16 TP_CPLD1_PR7B_PCLKC1_0 @BASEBOARD_FAB2_LIB.BASEBOARD_FAB2(SCH_1):TP_CPLD1_PR7B_PCLKC1_0    I59 @BASEBOARD_FAB2_LIB.BASEBOARD_FAB2(SCH_1):PAGE191
   J16 TP_CPLD1_PR7C @BASEBOARD_FAB2_LIB.BASEBOARD_FAB2(SCH_1):TP_CPLD1_PR7C    I59 @BASEBOARD_FAB2_LIB.BASEBOARD_FAB2(SCH_1):PAGE191
   J14 TP_CPLD1_PR7D @BASEBOARD_FAB2_LIB.BASEBOARD_FAB2(SCH_1):TP_CPLD1_PR7D    I59 @BASEBOARD_FAB2_LIB.BASEBOARD_FAB2(SCH_1):PAGE191
   J15 TP_CPLD1_PR9A @BASEBOARD_FAB2_LIB.BASEBOARD_FAB2(SCH_1):TP_CPLD1_PR9A    I59 @BASEBOARD_FAB2_LIB.BASEBOARD_FAB2(SCH_1):PAGE191
   K16 PU_FAB2_MARKER_CPLD @BASEBOARD_FAB2_LIB.BASEBOARD_FAB2(SCH_1):PU_FAB2_MARKER_CPLD    I59 @BASEBOARD_FAB2_LIB.BASEBOARD_FAB2(SCH_1):PAGE191
   H11 TP_CPLD1_PR9C @BASEBOARD_FAB2_LIB.BASEBOARD_FAB2(SCH_1):TP_CPLD1_PR9C    I59 @BASEBOARD_FAB2_LIB.BASEBOARD_FAB2(SCH_1):PAGE191
   J13 TP_CPLD1_PR9D @BASEBOARD_FAB2_LIB.BASEBOARD_FAB2(SCH_1):TP_CPLD1_PR9D    I59 @BASEBOARD_FAB2_LIB.BASEBOARD_FAB2(SCH_1):PAGE191
   K14 FM_PVDDQ_ABC_EN @BASEBOARD_FAB2_LIB.BASEBOARD_FAB2(SCH_1):FM_PVDDQ_ABC_EN    I59 @BASEBOARD_FAB2_LIB.BASEBOARD_FAB2(SCH_1):PAGE191
   K15 FM_PVDDQ_DEF_EN @BASEBOARD_FAB2_LIB.BASEBOARD_FAB2(SCH_1):FM_PVDDQ_DEF_EN    I59 @BASEBOARD_FAB2_LIB.BASEBOARD_FAB2(SCH_1):PAGE191
   J11 TP_CPLD1_PR10C @BASEBOARD_FAB2_LIB.BASEBOARD_FAB2(SCH_1):TP_CPLD1_PR10C    I59 @BASEBOARD_FAB2_LIB.BASEBOARD_FAB2(SCH_1):PAGE191
   L12 PWRGD_P3V3_STBY @BASEBOARD_FAB2_LIB.BASEBOARD_FAB2(SCH_1):PWRGD_P3V3_STBY    I59 @BASEBOARD_FAB2_LIB.BASEBOARD_FAB2(SCH_1):PAGE191
   L16 PWRGD_PVCCIO_CPU1 @BASEBOARD_FAB2_LIB.BASEBOARD_FAB2(SCH_1):PWRGD_PVCCIO_CPU1    I59 @BASEBOARD_FAB2_LIB.BASEBOARD_FAB2(SCH_1):PAGE191
   L14 TP_CPLD1_PR11B @BASEBOARD_FAB2_LIB.BASEBOARD_FAB2(SCH_1):TP_CPLD1_PR11B    I59 @BASEBOARD_FAB2_LIB.BASEBOARD_FAB2(SCH_1):PAGE191
   K13 FM_MEM_THERM_EVENT_LVT3_N @BASEBOARD_FAB2_LIB.BASEBOARD_FAB2(SCH_1):FM_MEM_THERM_EVENT_LVT3_N    I59 @BASEBOARD_FAB2_LIB.BASEBOARD_FAB2(SCH_1):PAGE191
   K12 FM_MEM_THERM_EVENT_PCH_N @BASEBOARD_FAB2_LIB.BASEBOARD_FAB2(SCH_1):FM_MEM_THERM_EVENT_PCH_N    I59 @BASEBOARD_FAB2_LIB.BASEBOARD_FAB2(SCH_1):PAGE191
   L15 FM_THERMTRIP_DLY @BASEBOARD_FAB2_LIB.BASEBOARD_FAB2(SCH_1):FM_THERMTRIP_DLY    I59 @BASEBOARD_FAB2_LIB.BASEBOARD_FAB2(SCH_1):PAGE191
   M16 FM_CPU0_FIVR_FAULT_LVT3 @BASEBOARD_FAB2_LIB.BASEBOARD_FAB2(SCH_1):FM_CPU0_FIVR_FAULT_LVT3    I59 @BASEBOARD_FAB2_LIB.BASEBOARD_FAB2(SCH_1):PAGE191
   K11 RST_PLTRST_BUF_N @BASEBOARD_FAB2_LIB.BASEBOARD_FAB2(SCH_1):RST_PLTRST_BUF_N    I59 @BASEBOARD_FAB2_LIB.BASEBOARD_FAB2(SCH_1):PAGE191
   L13 TP_CPLD1_PR12D @BASEBOARD_FAB2_LIB.BASEBOARD_FAB2(SCH_1):TP_CPLD1_PR12D    I59 @BASEBOARD_FAB2_LIB.BASEBOARD_FAB2(SCH_1):PAGE191
   M14 FM_CPU1_PROC_ID1 @BASEBOARD_FAB2_LIB.BASEBOARD_FAB2(SCH_1):FM_CPU1_PROC_ID1    I59 @BASEBOARD_FAB2_LIB.BASEBOARD_FAB2(SCH_1):PAGE191
   M15 FM_CPU1_PROC_ID0 @BASEBOARD_FAB2_LIB.BASEBOARD_FAB2(SCH_1):FM_CPU1_PROC_ID0    I59 @BASEBOARD_FAB2_LIB.BASEBOARD_FAB2(SCH_1):PAGE191
   N15 FM_CPU0_THERMTRIP_LVT3_N @BASEBOARD_FAB2_LIB.BASEBOARD_FAB2(SCH_1):FM_CPU0_THERMTRIP_LVT3_N    I59 @BASEBOARD_FAB2_LIB.BASEBOARD_FAB2(SCH_1):PAGE191
   P16 FM_PVPP_CPU1_EN @BASEBOARD_FAB2_LIB.BASEBOARD_FAB2(SCH_1):FM_PVPP_CPU1_EN    I59 @BASEBOARD_FAB2_LIB.BASEBOARD_FAB2(SCH_1):PAGE191
   N16 FM_PVCCIN_PVCCSA_CPU1_EN_LVC1 @BASEBOARD_FAB2_LIB.BASEBOARD_FAB2(SCH_1):FM_PVCCIN_PVCCSA_CPU1_EN_LVC1    I59 @BASEBOARD_FAB2_LIB.BASEBOARD_FAB2(SCH_1):PAGE191
   N14 FM_CPU1_VRM_OSC_EN @BASEBOARD_FAB2_LIB.BASEBOARD_FAB2(SCH_1):FM_CPU1_VRM_OSC_EN    I59 @BASEBOARD_FAB2_LIB.BASEBOARD_FAB2(SCH_1):PAGE191
   P15 FM_PVPP_CPU0_EN @BASEBOARD_FAB2_LIB.BASEBOARD_FAB2(SCH_1):FM_PVPP_CPU0_EN    I59 @BASEBOARD_FAB2_LIB.BASEBOARD_FAB2(SCH_1):PAGE191
   R16 FM_P12V_MAIN_SW_EN @BASEBOARD_FAB2_LIB.BASEBOARD_FAB2(SCH_1):FM_P12V_MAIN_SW_EN    I59 @BASEBOARD_FAB2_LIB.BASEBOARD_FAB2(SCH_1):PAGE191
    C4 FM_ADR_SMI_GPIO_R_N @BASEBOARD_FAB2_LIB.BASEBOARD_FAB2(SCH_1):FM_ADR_SMI_GPIO_R_N    I59 @BASEBOARD_FAB2_LIB.BASEBOARD_FAB2(SCH_1):PAGE191
    B5 PWRGD_P12V_MAIN @BASEBOARD_FAB2_LIB.BASEBOARD_FAB2(SCH_1):PWRGD_P12V_MAIN    I59 @BASEBOARD_FAB2_LIB.BASEBOARD_FAB2(SCH_1):PAGE191
    B3 FM_CTNR_PS_ON @BASEBOARD_FAB2_LIB.BASEBOARD_FAB2(SCH_1):FM_CTNR_PS_ON    I59 @BASEBOARD_FAB2_LIB.BASEBOARD_FAB2(SCH_1):PAGE191
    A4 FM_P3V3_CPLD_EN @BASEBOARD_FAB2_LIB.BASEBOARD_FAB2(SCH_1):FM_P3V3_CPLD_EN    I59 @BASEBOARD_FAB2_LIB.BASEBOARD_FAB2(SCH_1):PAGE191
    C5 FM_CPU1_THERMTRIP_LATCH_LVT3_N @BASEBOARD_FAB2_LIB.BASEBOARD_FAB2(SCH_1):FM_CPU1_THERMTRIP_LATCH_LVT3_N    I59 @BASEBOARD_FAB2_LIB.BASEBOARD_FAB2(SCH_1):PAGE191
    A5 TP_CPLD1_PT11A @BASEBOARD_FAB2_LIB.BASEBOARD_FAB2(SCH_1):TP_CPLD1_PT11A    I59 @BASEBOARD_FAB2_LIB.BASEBOARD_FAB2(SCH_1):PAGE191
    B6 TP_CPLD1_PT11B @BASEBOARD_FAB2_LIB.BASEBOARD_FAB2(SCH_1):TP_CPLD1_PT11B    I59 @BASEBOARD_FAB2_LIB.BASEBOARD_FAB2(SCH_1):PAGE191
    A3 FM_PCH_PRSNT_N @BASEBOARD_FAB2_LIB.BASEBOARD_FAB2(SCH_1):FM_PCH_PRSNT_N    I59 @BASEBOARD_FAB2_LIB.BASEBOARD_FAB2(SCH_1):PAGE191
    B4 PWRGD_PVTT_CPU0 @BASEBOARD_FAB2_LIB.BASEBOARD_FAB2(SCH_1):PWRGD_PVTT_CPU0    I59 @BASEBOARD_FAB2_LIB.BASEBOARD_FAB2(SCH_1):PAGE191
    D6 RST_PCIE_CPU_DEV0_N @BASEBOARD_FAB2_LIB.BASEBOARD_FAB2(SCH_1):RST_PCIE_CPU_DEV0_N    I59 @BASEBOARD_FAB2_LIB.BASEBOARD_FAB2(SCH_1):PAGE191
    E7 PWRGD_P1V26_BMC_STBY @BASEBOARD_FAB2_LIB.BASEBOARD_FAB2(SCH_1):PWRGD_P1V26_BMC_STBY    I59 @BASEBOARD_FAB2_LIB.BASEBOARD_FAB2(SCH_1):PAGE191
    C6 JTAG_PLD_TDO @BASEBOARD_FAB2_LIB.BASEBOARD_FAB2(SCH_1):JTAG_PLD_TDO    I59 @BASEBOARD_FAB2_LIB.BASEBOARD_FAB2(SCH_1):PAGE191
    A6 JTAG_PLD_TDI @BASEBOARD_FAB2_LIB.BASEBOARD_FAB2(SCH_1):JTAG_PLD_TDI    I59 @BASEBOARD_FAB2_LIB.BASEBOARD_FAB2(SCH_1):PAGE191
    B7 TP_CPLD1_PT13A @BASEBOARD_FAB2_LIB.BASEBOARD_FAB2(SCH_1):TP_CPLD1_PT13A    I59 @BASEBOARD_FAB2_LIB.BASEBOARD_FAB2(SCH_1):PAGE191
    C7 FM_BMC_ONCTL_N @BASEBOARD_FAB2_LIB.BASEBOARD_FAB2(SCH_1):FM_BMC_ONCTL_N    I59 @BASEBOARD_FAB2_LIB.BASEBOARD_FAB2(SCH_1):PAGE191
    E6 FM_CPU1_FIVR_FAULT_LVT3_N @BASEBOARD_FAB2_LIB.BASEBOARD_FAB2(SCH_1):FM_CPU1_FIVR_FAULT_LVT3_N    I59 @BASEBOARD_FAB2_LIB.BASEBOARD_FAB2(SCH_1):PAGE191
    D7 FM_FORCE_ADR_N @BASEBOARD_FAB2_LIB.BASEBOARD_FAB2(SCH_1):FM_FORCE_ADR_N    I59 @BASEBOARD_FAB2_LIB.BASEBOARD_FAB2(SCH_1):PAGE191
    F7 FM_PLD_DEBUG_MODE_N @BASEBOARD_FAB2_LIB.BASEBOARD_FAB2(SCH_1):FM_PLD_DEBUG_MODE_N    I59 @BASEBOARD_FAB2_LIB.BASEBOARD_FAB2(SCH_1):PAGE191
    E8 TP_CPLD1_PT16B @BASEBOARD_FAB2_LIB.BASEBOARD_FAB2(SCH_1):TP_CPLD1_PT16B    I59 @BASEBOARD_FAB2_LIB.BASEBOARD_FAB2(SCH_1):PAGE191
    A7 JTAG_PLD_TCK @BASEBOARD_FAB2_LIB.BASEBOARD_FAB2(SCH_1):JTAG_PLD_TCK    I59 @BASEBOARD_FAB2_LIB.BASEBOARD_FAB2(SCH_1):PAGE191
    B8 JTAG_PLD_TMS @BASEBOARD_FAB2_LIB.BASEBOARD_FAB2(SCH_1):JTAG_PLD_TMS    I59 @BASEBOARD_FAB2_LIB.BASEBOARD_FAB2(SCH_1):PAGE191
    C8 FM_ADR_COMPLETE @BASEBOARD_FAB2_LIB.BASEBOARD_FAB2(SCH_1):FM_ADR_COMPLETE    I59 @BASEBOARD_FAB2_LIB.BASEBOARD_FAB2(SCH_1):PAGE191
    A8 TP_CPLD1_PT17B_PCLKC0_1 @BASEBOARD_FAB2_LIB.BASEBOARD_FAB2(SCH_1):TP_CPLD1_PT17B_PCLKC0_1    I59 @BASEBOARD_FAB2_LIB.BASEBOARD_FAB2(SCH_1):PAGE191
    D8 TP_CPLD1_PT17C @BASEBOARD_FAB2_LIB.BASEBOARD_FAB2(SCH_1):TP_CPLD1_PT17C    I59 @BASEBOARD_FAB2_LIB.BASEBOARD_FAB2(SCH_1):PAGE191
    E9 FM_SLP_SUS_N @BASEBOARD_FAB2_LIB.BASEBOARD_FAB2(SCH_1):FM_SLP_SUS_N    I59 @BASEBOARD_FAB2_LIB.BASEBOARD_FAB2(SCH_1):PAGE191
    F8 SGPIO_BMC_DIN_R @BASEBOARD_FAB2_LIB.BASEBOARD_FAB2(SCH_1):SGPIO_BMC_DIN_R    I59 @BASEBOARD_FAB2_LIB.BASEBOARD_FAB2(SCH_1):PAGE191
    D9 RST_PCIE_MIDPLANE_N @BASEBOARD_FAB2_LIB.BASEBOARD_FAB2(SCH_1):RST_PCIE_MIDPLANE_N    I59 @BASEBOARD_FAB2_LIB.BASEBOARD_FAB2(SCH_1):PAGE191
    A9 SMB_SENSOR_STBY_LVC3_SCL @BASEBOARD_FAB2_LIB.BASEBOARD_FAB2(SCH_1):SMB_SENSOR_STBY_LVC3_SCL    I59 @BASEBOARD_FAB2_LIB.BASEBOARD_FAB2(SCH_1):PAGE191
    C9 SMB_SENSOR_STBY_LVC3_SDA @BASEBOARD_FAB2_LIB.BASEBOARD_FAB2(SCH_1):SMB_SENSOR_STBY_LVC3_SDA    I59 @BASEBOARD_FAB2_LIB.BASEBOARD_FAB2(SCH_1):PAGE191
    B9 PU_RST_PERST_BIT1 @BASEBOARD_FAB2_LIB.BASEBOARD_FAB2(SCH_1):PU_RST_PERST_BIT1    I59 @BASEBOARD_FAB2_LIB.BASEBOARD_FAB2(SCH_1):PAGE191
   A10 FM_PVCCIN_PVCCSA_CPU0_EN_LVC1 @BASEBOARD_FAB2_LIB.BASEBOARD_FAB2(SCH_1):FM_PVCCIN_PVCCSA_CPU0_EN_LVC1    I59 @BASEBOARD_FAB2_LIB.BASEBOARD_FAB2(SCH_1):PAGE191
    F9 FM_PS_EN @BASEBOARD_FAB2_LIB.BASEBOARD_FAB2(SCH_1):FM_PS_EN    I59 @BASEBOARD_FAB2_LIB.BASEBOARD_FAB2(SCH_1):PAGE191
   E11 TP_CPLD1_PT19D @BASEBOARD_FAB2_LIB.BASEBOARD_FAB2(SCH_1):TP_CPLD1_PT19D    I59 @BASEBOARD_FAB2_LIB.BASEBOARD_FAB2(SCH_1):PAGE191
   D10 TP_CPLD1_PT20A @BASEBOARD_FAB2_LIB.BASEBOARD_FAB2(SCH_1):TP_CPLD1_PT20A    I59 @BASEBOARD_FAB2_LIB.BASEBOARD_FAB2(SCH_1):PAGE191
   E10 TP_CPLD1_PT20B @BASEBOARD_FAB2_LIB.BASEBOARD_FAB2(SCH_1):TP_CPLD1_PT20B    I59 @BASEBOARD_FAB2_LIB.BASEBOARD_FAB2(SCH_1):PAGE191
   C10 FM_JTAG_PLD_EN_DEBUG @BASEBOARD_FAB2_LIB.BASEBOARD_FAB2(SCH_1):FM_JTAG_PLD_EN_DEBUG    I59 @BASEBOARD_FAB2_LIB.BASEBOARD_FAB2(SCH_1):PAGE191
   B10 TP_CPLD1_PT20D_PROGRAMN @BASEBOARD_FAB2_LIB.BASEBOARD_FAB2(SCH_1):TP_CPLD1_PT20D_PROGRAMN    I59 @BASEBOARD_FAB2_LIB.BASEBOARD_FAB2(SCH_1):PAGE191
   A11 FM_CPU0_OR_CPU1_MCP_PRES @BASEBOARD_FAB2_LIB.BASEBOARD_FAB2(SCH_1):FM_CPU0_OR_CPU1_MCP_PRES    I59 @BASEBOARD_FAB2_LIB.BASEBOARD_FAB2(SCH_1):PAGE191
   C11 FM_CPU0_CD_PRES @BASEBOARD_FAB2_LIB.BASEBOARD_FAB2(SCH_1):FM_CPU0_CD_PRES    I59 @BASEBOARD_FAB2_LIB.BASEBOARD_FAB2(SCH_1):PAGE191
   F10 FM_CPU1_CD_PRES @BASEBOARD_FAB2_LIB.BASEBOARD_FAB2(SCH_1):FM_CPU1_CD_PRES    I59 @BASEBOARD_FAB2_LIB.BASEBOARD_FAB2(SCH_1):PAGE191
   D11 FM_CPU0_AND_CPU1_MCP_PRES @BASEBOARD_FAB2_LIB.BASEBOARD_FAB2(SCH_1):FM_CPU0_AND_CPU1_MCP_PRES    I59 @BASEBOARD_FAB2_LIB.BASEBOARD_FAB2(SCH_1):PAGE191
   B11 PWRGD_DSW_PWROK @BASEBOARD_FAB2_LIB.BASEBOARD_FAB2(SCH_1):PWRGD_DSW_PWROK    I59 @BASEBOARD_FAB2_LIB.BASEBOARD_FAB2(SCH_1):PAGE191
   A12 PU_THERMTRIP_FORCE_N @BASEBOARD_FAB2_LIB.BASEBOARD_FAB2(SCH_1):PU_THERMTRIP_FORCE_N    I59 @BASEBOARD_FAB2_LIB.BASEBOARD_FAB2(SCH_1):PAGE191
   B13 TP_CPLD1_PT22C @BASEBOARD_FAB2_LIB.BASEBOARD_FAB2(SCH_1):TP_CPLD1_PT22C    I59 @BASEBOARD_FAB2_LIB.BASEBOARD_FAB2(SCH_1):PAGE191
   A14 TP_CPLD1_PT22D @BASEBOARD_FAB2_LIB.BASEBOARD_FAB2(SCH_1):TP_CPLD1_PT22D    I59 @BASEBOARD_FAB2_LIB.BASEBOARD_FAB2(SCH_1):PAGE191
   C12 FM_SLPS4_N @BASEBOARD_FAB2_LIB.BASEBOARD_FAB2(SCH_1):FM_SLPS4_N    I59 @BASEBOARD_FAB2_LIB.BASEBOARD_FAB2(SCH_1):PAGE191
   B12 FM_PCH_PWRBTN_N @BASEBOARD_FAB2_LIB.BASEBOARD_FAB2(SCH_1):FM_PCH_PWRBTN_N    I59 @BASEBOARD_FAB2_LIB.BASEBOARD_FAB2(SCH_1):PAGE191
   B14 FM_SINT_PRSNT_N @BASEBOARD_FAB2_LIB.BASEBOARD_FAB2(SCH_1):FM_SINT_PRSNT_N    I59 @BASEBOARD_FAB2_LIB.BASEBOARD_FAB2(SCH_1):PAGE191
   A15 TP_CPLD1_PT24B @BASEBOARD_FAB2_LIB.BASEBOARD_FAB2(SCH_1):TP_CPLD1_PT24B    I59 @BASEBOARD_FAB2_LIB.BASEBOARD_FAB2(SCH_1):PAGE191
   A13 TP_CPLD1_PT24C_INITN @BASEBOARD_FAB2_LIB.BASEBOARD_FAB2(SCH_1):TP_CPLD1_PT24C_INITN    I59 @BASEBOARD_FAB2_LIB.BASEBOARD_FAB2(SCH_1):PAGE191
   C13 TP_CPLD1_PT24D_DONE @BASEBOARD_FAB2_LIB.BASEBOARD_FAB2(SCH_1):TP_CPLD1_PT24D_DONE    I59 @BASEBOARD_FAB2_LIB.BASEBOARD_FAB2(SCH_1):PAGE191
    B2    GND @BASEBOARD_FAB2_LIB.BASEBOARD_FAB2(SCH_1):GND    I14 @BASEBOARD_FAB2_LIB.BASEBOARD_FAB2(SCH_1):PAGE192
   B15    GND @BASEBOARD_FAB2_LIB.BASEBOARD_FAB2(SCH_1):GND    I14 @BASEBOARD_FAB2_LIB.BASEBOARD_FAB2(SCH_1):PAGE192
    C3    GND @BASEBOARD_FAB2_LIB.BASEBOARD_FAB2(SCH_1):GND    I14 @BASEBOARD_FAB2_LIB.BASEBOARD_FAB2(SCH_1):PAGE192
   C14    GND @BASEBOARD_FAB2_LIB.BASEBOARD_FAB2(SCH_1):GND    I14 @BASEBOARD_FAB2_LIB.BASEBOARD_FAB2(SCH_1):PAGE192
    D4    GND @BASEBOARD_FAB2_LIB.BASEBOARD_FAB2(SCH_1):GND    I14 @BASEBOARD_FAB2_LIB.BASEBOARD_FAB2(SCH_1):PAGE192
   D13    GND @BASEBOARD_FAB2_LIB.BASEBOARD_FAB2(SCH_1):GND    I14 @BASEBOARD_FAB2_LIB.BASEBOARD_FAB2(SCH_1):PAGE192
    E5    GND @BASEBOARD_FAB2_LIB.BASEBOARD_FAB2(SCH_1):GND    I14 @BASEBOARD_FAB2_LIB.BASEBOARD_FAB2(SCH_1):PAGE192
   E12    GND @BASEBOARD_FAB2_LIB.BASEBOARD_FAB2(SCH_1):GND    I14 @BASEBOARD_FAB2_LIB.BASEBOARD_FAB2(SCH_1):PAGE192
    F6    GND @BASEBOARD_FAB2_LIB.BASEBOARD_FAB2(SCH_1):GND    I14 @BASEBOARD_FAB2_LIB.BASEBOARD_FAB2(SCH_1):PAGE192
   F11    GND @BASEBOARD_FAB2_LIB.BASEBOARD_FAB2(SCH_1):GND    I14 @BASEBOARD_FAB2_LIB.BASEBOARD_FAB2(SCH_1):PAGE192
    H8    GND @BASEBOARD_FAB2_LIB.BASEBOARD_FAB2(SCH_1):GND    I14 @BASEBOARD_FAB2_LIB.BASEBOARD_FAB2(SCH_1):PAGE192
    H9    GND @BASEBOARD_FAB2_LIB.BASEBOARD_FAB2(SCH_1):GND    I14 @BASEBOARD_FAB2_LIB.BASEBOARD_FAB2(SCH_1):PAGE192
    J8    GND @BASEBOARD_FAB2_LIB.BASEBOARD_FAB2(SCH_1):GND    I14 @BASEBOARD_FAB2_LIB.BASEBOARD_FAB2(SCH_1):PAGE192
    J9    GND @BASEBOARD_FAB2_LIB.BASEBOARD_FAB2(SCH_1):GND    I14 @BASEBOARD_FAB2_LIB.BASEBOARD_FAB2(SCH_1):PAGE192
    L6    GND @BASEBOARD_FAB2_LIB.BASEBOARD_FAB2(SCH_1):GND    I14 @BASEBOARD_FAB2_LIB.BASEBOARD_FAB2(SCH_1):PAGE192
   L11    GND @BASEBOARD_FAB2_LIB.BASEBOARD_FAB2(SCH_1):GND    I14 @BASEBOARD_FAB2_LIB.BASEBOARD_FAB2(SCH_1):PAGE192
    M5    GND @BASEBOARD_FAB2_LIB.BASEBOARD_FAB2(SCH_1):GND    I14 @BASEBOARD_FAB2_LIB.BASEBOARD_FAB2(SCH_1):PAGE192
   M12    GND @BASEBOARD_FAB2_LIB.BASEBOARD_FAB2(SCH_1):GND    I14 @BASEBOARD_FAB2_LIB.BASEBOARD_FAB2(SCH_1):PAGE192
    N4    GND @BASEBOARD_FAB2_LIB.BASEBOARD_FAB2(SCH_1):GND    I14 @BASEBOARD_FAB2_LIB.BASEBOARD_FAB2(SCH_1):PAGE192
   N13    GND @BASEBOARD_FAB2_LIB.BASEBOARD_FAB2(SCH_1):GND    I14 @BASEBOARD_FAB2_LIB.BASEBOARD_FAB2(SCH_1):PAGE192
    P3    GND @BASEBOARD_FAB2_LIB.BASEBOARD_FAB2(SCH_1):GND    I14 @BASEBOARD_FAB2_LIB.BASEBOARD_FAB2(SCH_1):PAGE192
   P14    GND @BASEBOARD_FAB2_LIB.BASEBOARD_FAB2(SCH_1):GND    I14 @BASEBOARD_FAB2_LIB.BASEBOARD_FAB2(SCH_1):PAGE192
    R2    GND @BASEBOARD_FAB2_LIB.BASEBOARD_FAB2(SCH_1):GND    I14 @BASEBOARD_FAB2_LIB.BASEBOARD_FAB2(SCH_1):PAGE192
   R15    GND @BASEBOARD_FAB2_LIB.BASEBOARD_FAB2(SCH_1):GND    I14 @BASEBOARD_FAB2_LIB.BASEBOARD_FAB2(SCH_1):PAGE192
    A1 P3V3_STBY @BASEBOARD_FAB2_LIB.BASEBOARD_FAB2(SCH_1):P3V3_STBY    I14 @BASEBOARD_FAB2_LIB.BASEBOARD_FAB2(SCH_1):PAGE192
   A16 P3V3_STBY @BASEBOARD_FAB2_LIB.BASEBOARD_FAB2(SCH_1):P3V3_STBY    I14 @BASEBOARD_FAB2_LIB.BASEBOARD_FAB2(SCH_1):PAGE192
    T1 P3V3_STBY @BASEBOARD_FAB2_LIB.BASEBOARD_FAB2(SCH_1):P3V3_STBY    I14 @BASEBOARD_FAB2_LIB.BASEBOARD_FAB2(SCH_1):PAGE192
   T16 P3V3_STBY @BASEBOARD_FAB2_LIB.BASEBOARD_FAB2(SCH_1):P3V3_STBY    I14 @BASEBOARD_FAB2_LIB.BASEBOARD_FAB2(SCH_1):PAGE192
    G7 P3V3_STBY @BASEBOARD_FAB2_LIB.BASEBOARD_FAB2(SCH_1):P3V3_STBY    I14 @BASEBOARD_FAB2_LIB.BASEBOARD_FAB2(SCH_1):PAGE192
   G10 P3V3_STBY @BASEBOARD_FAB2_LIB.BASEBOARD_FAB2(SCH_1):P3V3_STBY    I14 @BASEBOARD_FAB2_LIB.BASEBOARD_FAB2(SCH_1):PAGE192
    K7 P3V3_STBY @BASEBOARD_FAB2_LIB.BASEBOARD_FAB2(SCH_1):P3V3_STBY    I14 @BASEBOARD_FAB2_LIB.BASEBOARD_FAB2(SCH_1):PAGE192
   K10 P3V3_STBY @BASEBOARD_FAB2_LIB.BASEBOARD_FAB2(SCH_1):P3V3_STBY    I14 @BASEBOARD_FAB2_LIB.BASEBOARD_FAB2(SCH_1):PAGE192
    G8 P3V3_STBY @BASEBOARD_FAB2_LIB.BASEBOARD_FAB2(SCH_1):P3V3_STBY    I14 @BASEBOARD_FAB2_LIB.BASEBOARD_FAB2(SCH_1):PAGE192
   D12 P3V3_STBY @BASEBOARD_FAB2_LIB.BASEBOARD_FAB2(SCH_1):P3V3_STBY    I14 @BASEBOARD_FAB2_LIB.BASEBOARD_FAB2(SCH_1):PAGE192
    G9 P3V3_STBY @BASEBOARD_FAB2_LIB.BASEBOARD_FAB2(SCH_1):P3V3_STBY    I14 @BASEBOARD_FAB2_LIB.BASEBOARD_FAB2(SCH_1):PAGE192
   E13 P3V3_STBY @BASEBOARD_FAB2_LIB.BASEBOARD_FAB2(SCH_1):P3V3_STBY    I14 @BASEBOARD_FAB2_LIB.BASEBOARD_FAB2(SCH_1):PAGE192
   H10 P3V3_STBY @BASEBOARD_FAB2_LIB.BASEBOARD_FAB2(SCH_1):P3V3_STBY    I14 @BASEBOARD_FAB2_LIB.BASEBOARD_FAB2(SCH_1):PAGE192
   J10 P3V3_STBY @BASEBOARD_FAB2_LIB.BASEBOARD_FAB2(SCH_1):P3V3_STBY    I14 @BASEBOARD_FAB2_LIB.BASEBOARD_FAB2(SCH_1):PAGE192
   M13 P3V3_STBY @BASEBOARD_FAB2_LIB.BASEBOARD_FAB2(SCH_1):P3V3_STBY    I14 @BASEBOARD_FAB2_LIB.BASEBOARD_FAB2(SCH_1):PAGE192
    K9 P3V3_STBY @BASEBOARD_FAB2_LIB.BASEBOARD_FAB2(SCH_1):P3V3_STBY    I14 @BASEBOARD_FAB2_LIB.BASEBOARD_FAB2(SCH_1):PAGE192
   N12 P3V3_STBY @BASEBOARD_FAB2_LIB.BASEBOARD_FAB2(SCH_1):P3V3_STBY    I14 @BASEBOARD_FAB2_LIB.BASEBOARD_FAB2(SCH_1):PAGE192
    K8 P3V3_STBY @BASEBOARD_FAB2_LIB.BASEBOARD_FAB2(SCH_1):P3V3_STBY    I14 @BASEBOARD_FAB2_LIB.BASEBOARD_FAB2(SCH_1):PAGE192
    N5 P3V3_STBY @BASEBOARD_FAB2_LIB.BASEBOARD_FAB2(SCH_1):P3V3_STBY    I14 @BASEBOARD_FAB2_LIB.BASEBOARD_FAB2(SCH_1):PAGE192
    J7 P3V3_STBY @BASEBOARD_FAB2_LIB.BASEBOARD_FAB2(SCH_1):P3V3_STBY    I14 @BASEBOARD_FAB2_LIB.BASEBOARD_FAB2(SCH_1):PAGE192
    H7 P3V3_STBY @BASEBOARD_FAB2_LIB.BASEBOARD_FAB2(SCH_1):P3V3_STBY    I14 @BASEBOARD_FAB2_LIB.BASEBOARD_FAB2(SCH_1):PAGE192
    E4 P3V3_STBY @BASEBOARD_FAB2_LIB.BASEBOARD_FAB2(SCH_1):P3V3_STBY    I14 @BASEBOARD_FAB2_LIB.BASEBOARD_FAB2(SCH_1):PAGE192
    D5 P3V3_STBY @BASEBOARD_FAB2_LIB.BASEBOARD_FAB2(SCH_1):P3V3_STBY    I14 @BASEBOARD_FAB2_LIB.BASEBOARD_FAB2(SCH_1):PAGE192
    A2 NC_CPLD1 @BASEBOARD_FAB2_LIB.BASEBOARD_FAB2(SCH_1):NC_CPLD1    I14 @BASEBOARD_FAB2_LIB.BASEBOARD_FAB2(SCH_1):PAGE192
    M4 P3V3_STBY @BASEBOARD_FAB2_LIB.BASEBOARD_FAB2(SCH_1):P3V3_STBY    I14 @BASEBOARD_FAB2_LIB.BASEBOARD_FAB2(SCH_1):PAGE192

U8D8 TPS3700_SM-IC,H69492-001
     5    GND @BASEBOARD_FAB2_LIB.BASEBOARD_FAB2(SCH_1):GND   I104 @BASEBOARD_FAB2_LIB.BASEBOARD_FAB2(SCH_1):PAGE196
     4 A_PG_P12V_MAIN @BASEBOARD_FAB2_LIB.BASEBOARD_FAB2(SCH_1):A_PG_P12V_MAIN   I104 @BASEBOARD_FAB2_LIB.BASEBOARD_FAB2(SCH_1):PAGE196
     3 A_PG_P5V @BASEBOARD_FAB2_LIB.BASEBOARD_FAB2(SCH_1):A_PG_P5V   I104 @BASEBOARD_FAB2_LIB.BASEBOARD_FAB2(SCH_1):PAGE196
     6 PWRGD_P12V_MAIN_R @BASEBOARD_FAB2_LIB.BASEBOARD_FAB2(SCH_1):PWRGD_P12V_MAIN_R   I104 @BASEBOARD_FAB2_LIB.BASEBOARD_FAB2(SCH_1):PAGE196
     1 PWRGD_P5V_N @BASEBOARD_FAB2_LIB.BASEBOARD_FAB2(SCH_1):PWRGD_P5V_N   I104 @BASEBOARD_FAB2_LIB.BASEBOARD_FAB2(SCH_1):PAGE196
     2 P3V3_STBY @BASEBOARD_FAB2_LIB.BASEBOARD_FAB2(SCH_1):P3V3_STBY   I104 @BASEBOARD_FAB2_LIB.BASEBOARD_FAB2(SCH_1):PAGE196

U8E1 TTL08_QFN15-74LVC08A,IC,D90404B
    11 FM_FAST_PROCHOT_THROTTLE_IN_N @BASEBOARD_FAB2_LIB.BASEBOARD_FAB2(SCH_1):FM_FAST_PROCHOT_THROTTLE_IN_N    I12 @BASEBOARD_FAB2_LIB.BASEBOARD_FAB2(SCH_1):PAGE170
    13 FM_FAST_PROCHOT_AND_OUT_1_N @BASEBOARD_FAB2_LIB.BASEBOARD_FAB2(SCH_1):FM_FAST_PROCHOT_AND_OUT_1_N    I12 @BASEBOARD_FAB2_LIB.BASEBOARD_FAB2(SCH_1):PAGE170
    12 FM_FAST_PROCHOT_AND_OUT_0_N @BASEBOARD_FAB2_LIB.BASEBOARD_FAB2(SCH_1):FM_FAST_PROCHOT_AND_OUT_0_N    I12 @BASEBOARD_FAB2_LIB.BASEBOARD_FAB2(SCH_1):PAGE170
     8 FM_CTNR_PS_ON_R @BASEBOARD_FAB2_LIB.BASEBOARD_FAB2(SCH_1):FM_CTNR_PS_ON_R   I243 @BASEBOARD_FAB2_LIB.BASEBOARD_FAB2(SCH_1):PAGE181
    10 PWRGD_P12V_HSC_DLY @BASEBOARD_FAB2_LIB.BASEBOARD_FAB2(SCH_1):PWRGD_P12V_HSC_DLY   I243 @BASEBOARD_FAB2_LIB.BASEBOARD_FAB2(SCH_1):PAGE181
     9 FM_PS_EN @BASEBOARD_FAB2_LIB.BASEBOARD_FAB2(SCH_1):FM_PS_EN   I243 @BASEBOARD_FAB2_LIB.BASEBOARD_FAB2(SCH_1):PAGE181
     6 FM_FAST_PROCHOT_AND_OUT_1_N @BASEBOARD_FAB2_LIB.BASEBOARD_FAB2(SCH_1):FM_FAST_PROCHOT_AND_OUT_1_N    I11 @BASEBOARD_FAB2_LIB.BASEBOARD_FAB2(SCH_1):PAGE170
     5 FM_HSC_TIMER_EXP_N @BASEBOARD_FAB2_LIB.BASEBOARD_FAB2(SCH_1):FM_HSC_TIMER_EXP_N    I11 @BASEBOARD_FAB2_LIB.BASEBOARD_FAB2(SCH_1):PAGE170
     4 IRQ_UV_DETECT_N @BASEBOARD_FAB2_LIB.BASEBOARD_FAB2(SCH_1):IRQ_UV_DETECT_N    I11 @BASEBOARD_FAB2_LIB.BASEBOARD_FAB2(SCH_1):PAGE170
     3 FM_FAST_PROCHOT_AND_OUT_0_N @BASEBOARD_FAB2_LIB.BASEBOARD_FAB2(SCH_1):FM_FAST_PROCHOT_AND_OUT_0_N    I10 @BASEBOARD_FAB2_LIB.BASEBOARD_FAB2(SCH_1):PAGE170
     2 FM_OC_DETECT_N @BASEBOARD_FAB2_LIB.BASEBOARD_FAB2(SCH_1):FM_OC_DETECT_N    I10 @BASEBOARD_FAB2_LIB.BASEBOARD_FAB2(SCH_1):PAGE170
     1 IRQ_FORCE_NM_THROTTLE_N @BASEBOARD_FAB2_LIB.BASEBOARD_FAB2(SCH_1):IRQ_FORCE_NM_THROTTLE_N    I10 @BASEBOARD_FAB2_LIB.BASEBOARD_FAB2(SCH_1):PAGE170

U8E2 ADM809_SMLF-IC,D23047-001-GND=A
     3 PWRGD_P12V_HSC @BASEBOARD_FAB2_LIB.BASEBOARD_FAB2(SCH_1):PWRGD_P12V_HSC    I89 @BASEBOARD_FAB2_LIB.BASEBOARD_FAB2(SCH_1):PAGE196
     2 PWRGD_P12V_HSC_DLY_R @BASEBOARD_FAB2_LIB.BASEBOARD_FAB2(SCH_1):PWRGD_P12V_HSC_DLY_R    I89 @BASEBOARD_FAB2_LIB.BASEBOARD_FAB2(SCH_1):PAGE196

U8E3 TTL1G126_A_SOT-74HC1G126,IC,A7B
     1 RST_PLTRST_TOP_SWAP @BASEBOARD_FAB2_LIB.BASEBOARD_FAB2(SCH_1):RST_PLTRST_TOP_SWAP   I130 @BASEBOARD_FAB2_LIB.BASEBOARD_FAB2(SCH_1):PAGE136
     2 FM_BIOS_TOP_SWAP @BASEBOARD_FAB2_LIB.BASEBOARD_FAB2(SCH_1):FM_BIOS_TOP_SWAP   I130 @BASEBOARD_FAB2_LIB.BASEBOARD_FAB2(SCH_1):PAGE136
     4 FM_BIOS_TOP_SWAP_SPKR_R @BASEBOARD_FAB2_LIB.BASEBOARD_FAB2(SCH_1):FM_BIOS_TOP_SWAP_SPKR_R   I130 @BASEBOARD_FAB2_LIB.BASEBOARD_FAB2(SCH_1):PAGE136

U8E4 TTL1G126_A_SOT-74HC1G126,IC,A7B
     1 PU_TRI_STATE_EN @BASEBOARD_FAB2_LIB.BASEBOARD_FAB2(SCH_1):PU_TRI_STATE_EN     I1 @BASEBOARD_FAB2_LIB.BASEBOARD_FAB2(SCH_1):PAGE142
     2 FM_ALL_WAKE_N @BASEBOARD_FAB2_LIB.BASEBOARD_FAB2(SCH_1):FM_ALL_WAKE_N     I1 @BASEBOARD_FAB2_LIB.BASEBOARD_FAB2(SCH_1):PAGE142
     4 IRQ_LVC3_WAKE_R_N @BASEBOARD_FAB2_LIB.BASEBOARD_FAB2(SCH_1):IRQ_LVC3_WAKE_R_N     I1 @BASEBOARD_FAB2_LIB.BASEBOARD_FAB2(SCH_1):PAGE142

U8F1 PI3B3257A_TSSOPLF-IC,E16801-001
    16 P3V3_STBY @BASEBOARD_FAB2_LIB.BASEBOARD_FAB2(SCH_1):P3V3_STBY    I74 @BASEBOARD_FAB2_LIB.BASEBOARD_FAB2(SCH_1):PAGE154
     8    GND @BASEBOARD_FAB2_LIB.BASEBOARD_FAB2(SCH_1):GND    I74 @BASEBOARD_FAB2_LIB.BASEBOARD_FAB2(SCH_1):PAGE154
    15    GND @BASEBOARD_FAB2_LIB.BASEBOARD_FAB2(SCH_1):GND    I74 @BASEBOARD_FAB2_LIB.BASEBOARD_FAB2(SCH_1):PAGE154
     1 FM_BIOS_SPI_BMC_CTRL @BASEBOARD_FAB2_LIB.BASEBOARD_FAB2(SCH_1):FM_BIOS_SPI_BMC_CTRL    I74 @BASEBOARD_FAB2_LIB.BASEBOARD_FAB2(SCH_1):PAGE154
     4 SPI_SWITCH_CLK @BASEBOARD_FAB2_LIB.BASEBOARD_FAB2(SCH_1):SPI_SWITCH_CLK    I74 @BASEBOARD_FAB2_LIB.BASEBOARD_FAB2(SCH_1):PAGE154
     7 SPI_SWITCH_MOSI @BASEBOARD_FAB2_LIB.BASEBOARD_FAB2(SCH_1):SPI_SWITCH_MOSI    I74 @BASEBOARD_FAB2_LIB.BASEBOARD_FAB2(SCH_1):PAGE154
     9 SPI_SWITCH_CS0_N @BASEBOARD_FAB2_LIB.BASEBOARD_FAB2(SCH_1):SPI_SWITCH_CS0_N    I74 @BASEBOARD_FAB2_LIB.BASEBOARD_FAB2(SCH_1):PAGE154
    12 SPI_SWITCH_MISO @BASEBOARD_FAB2_LIB.BASEBOARD_FAB2(SCH_1):SPI_SWITCH_MISO    I74 @BASEBOARD_FAB2_LIB.BASEBOARD_FAB2(SCH_1):PAGE154
     2 SPI_PCH_CLK @BASEBOARD_FAB2_LIB.BASEBOARD_FAB2(SCH_1):SPI_PCH_CLK    I74 @BASEBOARD_FAB2_LIB.BASEBOARD_FAB2(SCH_1):PAGE154
     3 SPI_BMC_CLK @BASEBOARD_FAB2_LIB.BASEBOARD_FAB2(SCH_1):SPI_BMC_CLK    I74 @BASEBOARD_FAB2_LIB.BASEBOARD_FAB2(SCH_1):PAGE154
     5 SPI_PCH_MOSI @BASEBOARD_FAB2_LIB.BASEBOARD_FAB2(SCH_1):SPI_PCH_MOSI    I74 @BASEBOARD_FAB2_LIB.BASEBOARD_FAB2(SCH_1):PAGE154
     6 SPI_BMC_DO @BASEBOARD_FAB2_LIB.BASEBOARD_FAB2(SCH_1):SPI_BMC_DO    I74 @BASEBOARD_FAB2_LIB.BASEBOARD_FAB2(SCH_1):PAGE154
    11 SPI_PCH_CS0_N @BASEBOARD_FAB2_LIB.BASEBOARD_FAB2(SCH_1):SPI_PCH_CS0_N    I74 @BASEBOARD_FAB2_LIB.BASEBOARD_FAB2(SCH_1):PAGE154
    10 SPI_BMC_CS0_N @BASEBOARD_FAB2_LIB.BASEBOARD_FAB2(SCH_1):SPI_BMC_CS0_N    I74 @BASEBOARD_FAB2_LIB.BASEBOARD_FAB2(SCH_1):PAGE154
    14 SPI_PCH_MISO_R @BASEBOARD_FAB2_LIB.BASEBOARD_FAB2(SCH_1):SPI_PCH_MISO_R    I74 @BASEBOARD_FAB2_LIB.BASEBOARD_FAB2(SCH_1):PAGE154
    13 SPI_BMC_DI @BASEBOARD_FAB2_LIB.BASEBOARD_FAB2(SCH_1):SPI_BMC_DI    I74 @BASEBOARD_FAB2_LIB.BASEBOARD_FAB2(SCH_1):PAGE154

U8F2 W25Q128_SKT16-IC,H12709-001
     1 PU_SPI_BMC_BT_HOLD_N @BASEBOARD_FAB2_LIB.BASEBOARD_FAB2(SCH_1):PU_SPI_BMC_BT_HOLD_N    I32 @BASEBOARD_FAB2_LIB.BASEBOARD_FAB2(SCH_1):PAGE162
     2 P3V3_STBY @BASEBOARD_FAB2_LIB.BASEBOARD_FAB2(SCH_1):P3V3_STBY    I32 @BASEBOARD_FAB2_LIB.BASEBOARD_FAB2(SCH_1):PAGE162
     3 PU_SPI_FLASH_RESET_2_N @BASEBOARD_FAB2_LIB.BASEBOARD_FAB2(SCH_1):PU_SPI_FLASH_RESET_2_N    I32 @BASEBOARD_FAB2_LIB.BASEBOARD_FAB2(SCH_1):PAGE162
     4 TP_SPI_2_0 @BASEBOARD_FAB2_LIB.BASEBOARD_FAB2(SCH_1):TP_SPI_2_0    I32 @BASEBOARD_FAB2_LIB.BASEBOARD_FAB2(SCH_1):PAGE162
     5 TP_SPI_2_1 @BASEBOARD_FAB2_LIB.BASEBOARD_FAB2(SCH_1):TP_SPI_2_1    I32 @BASEBOARD_FAB2_LIB.BASEBOARD_FAB2(SCH_1):PAGE162
     6 TP_SPI_2_2 @BASEBOARD_FAB2_LIB.BASEBOARD_FAB2(SCH_1):TP_SPI_2_2    I32 @BASEBOARD_FAB2_LIB.BASEBOARD_FAB2(SCH_1):PAGE162
     7 SPI_BMC_BT_CS_N @BASEBOARD_FAB2_LIB.BASEBOARD_FAB2(SCH_1):SPI_BMC_BT_CS_N    I32 @BASEBOARD_FAB2_LIB.BASEBOARD_FAB2(SCH_1):PAGE162
     8 SPI_BMC_BT_DI_R @BASEBOARD_FAB2_LIB.BASEBOARD_FAB2(SCH_1):SPI_BMC_BT_DI_R    I32 @BASEBOARD_FAB2_LIB.BASEBOARD_FAB2(SCH_1):PAGE162
     9 PU_SPI_BMC_BT_WP_N @BASEBOARD_FAB2_LIB.BASEBOARD_FAB2(SCH_1):PU_SPI_BMC_BT_WP_N    I32 @BASEBOARD_FAB2_LIB.BASEBOARD_FAB2(SCH_1):PAGE162
    10    GND @BASEBOARD_FAB2_LIB.BASEBOARD_FAB2(SCH_1):GND    I32 @BASEBOARD_FAB2_LIB.BASEBOARD_FAB2(SCH_1):PAGE162
    11 TP_SPI_2_3 @BASEBOARD_FAB2_LIB.BASEBOARD_FAB2(SCH_1):TP_SPI_2_3    I32 @BASEBOARD_FAB2_LIB.BASEBOARD_FAB2(SCH_1):PAGE162
    12 TP_SPI_2_4 @BASEBOARD_FAB2_LIB.BASEBOARD_FAB2(SCH_1):TP_SPI_2_4    I32 @BASEBOARD_FAB2_LIB.BASEBOARD_FAB2(SCH_1):PAGE162
    13 TP_SPI_2_5 @BASEBOARD_FAB2_LIB.BASEBOARD_FAB2(SCH_1):TP_SPI_2_5    I32 @BASEBOARD_FAB2_LIB.BASEBOARD_FAB2(SCH_1):PAGE162
    14 TP_SPI_2_6 @BASEBOARD_FAB2_LIB.BASEBOARD_FAB2(SCH_1):TP_SPI_2_6    I32 @BASEBOARD_FAB2_LIB.BASEBOARD_FAB2(SCH_1):PAGE162
    15 SPI_BMC_BT_DO @BASEBOARD_FAB2_LIB.BASEBOARD_FAB2(SCH_1):SPI_BMC_BT_DO    I32 @BASEBOARD_FAB2_LIB.BASEBOARD_FAB2(SCH_1):PAGE162
    16 SPI_BMC_BT_CLK @BASEBOARD_FAB2_LIB.BASEBOARD_FAB2(SCH_1):SPI_BMC_BT_CLK    I32 @BASEBOARD_FAB2_LIB.BASEBOARD_FAB2(SCH_1):PAGE162

U8F3 TTL2G07_SOT23LF-74LVC2G07,IC,DB
     1 RST_BMC_SYSRST_BTN_OUT_N @BASEBOARD_FAB2_LIB.BASEBOARD_FAB2(SCH_1):RST_BMC_SYSRST_BTN_OUT_N   I201 @BASEBOARD_FAB2_LIB.BASEBOARD_FAB2(SCH_1):PAGE156
     3 FM_BMC_PWRBTN_OUT_N @BASEBOARD_FAB2_LIB.BASEBOARD_FAB2(SCH_1):FM_BMC_PWRBTN_OUT_N   I201 @BASEBOARD_FAB2_LIB.BASEBOARD_FAB2(SCH_1):PAGE156
     4 FM_PCH_PWRBTN_R_N @BASEBOARD_FAB2_LIB.BASEBOARD_FAB2(SCH_1):FM_PCH_PWRBTN_R_N   I201 @BASEBOARD_FAB2_LIB.BASEBOARD_FAB2(SCH_1):PAGE156
     6 RST_BMC_SYSRST_BTN_OUT_B_R_N @BASEBOARD_FAB2_LIB.BASEBOARD_FAB2(SCH_1):RST_BMC_SYSRST_BTN_OUT_B_R_N   I201 @BASEBOARD_FAB2_LIB.BASEBOARD_FAB2(SCH_1):PAGE156

U8G1 TTL2G07_SOT23LF-74LVC2G07,IC,DB
     1 RST_PCH_SYSRST_BTN_OUT_N @BASEBOARD_FAB2_LIB.BASEBOARD_FAB2(SCH_1):RST_PCH_SYSRST_BTN_OUT_N   I269 @BASEBOARD_FAB2_LIB.BASEBOARD_FAB2(SCH_1):PAGE156
     3 FM_PCH_PWRBTN_OUT_N @BASEBOARD_FAB2_LIB.BASEBOARD_FAB2(SCH_1):FM_PCH_PWRBTN_OUT_N   I269 @BASEBOARD_FAB2_LIB.BASEBOARD_FAB2(SCH_1):PAGE156
     4 FM_PCH_PWRBTN_R_N @BASEBOARD_FAB2_LIB.BASEBOARD_FAB2(SCH_1):FM_PCH_PWRBTN_R_N   I269 @BASEBOARD_FAB2_LIB.BASEBOARD_FAB2(SCH_1):PAGE156
     6 RST_BMC_SYSRST_BTN_OUT_B_R_N @BASEBOARD_FAB2_LIB.BASEBOARD_FAB2(SCH_1):RST_BMC_SYSRST_BTN_OUT_B_R_N   I269 @BASEBOARD_FAB2_LIB.BASEBOARD_FAB2(SCH_1):PAGE156

U8G2 TTL1G07_A_SOP-74LVC1G07,IC,C88B
     2 FAN_PWM_OUT_SYS0 @BASEBOARD_FAB2_LIB.BASEBOARD_FAB2(SCH_1):FAN_PWM_OUT_SYS0    I88 @BASEBOARD_FAB2_LIB.BASEBOARD_FAB2(SCH_1):PAGE161
     4 FAN_PWM_OUT_SYS0_BUF @BASEBOARD_FAB2_LIB.BASEBOARD_FAB2(SCH_1):FAN_PWM_OUT_SYS0_BUF    I88 @BASEBOARD_FAB2_LIB.BASEBOARD_FAB2(SCH_1):PAGE161

U8G3 TTL1G07_A_SOP-74LVC1G07,IC,C88B
     2 FAN_PWM_OUT_SYS1 @BASEBOARD_FAB2_LIB.BASEBOARD_FAB2(SCH_1):FAN_PWM_OUT_SYS1    I92 @BASEBOARD_FAB2_LIB.BASEBOARD_FAB2(SCH_1):PAGE161
     4 FAN_PWM_OUT_SYS1_BUF @BASEBOARD_FAB2_LIB.BASEBOARD_FAB2(SCH_1):FAN_PWM_OUT_SYS1_BUF    I92 @BASEBOARD_FAB2_LIB.BASEBOARD_FAB2(SCH_1):PAGE161

U9A1 TTL1G07_A_SOP-74LVC1G07,IC,C88B
     2 SPA_5V_SIN_SW @BASEBOARD_FAB2_LIB.BASEBOARD_FAB2(SCH_1):SPA_5V_SIN_SW   I178 @BASEBOARD_FAB2_LIB.BASEBOARD_FAB2(SCH_1):PAGE155
     4 SPA_SIN_SW_R @BASEBOARD_FAB2_LIB.BASEBOARD_FAB2(SCH_1):SPA_SIN_SW_R   I178 @BASEBOARD_FAB2_LIB.BASEBOARD_FAB2(SCH_1):PAGE155

U9A3 TTL2G14_SMLF-74LVC2G14,IC,D184B
     1 FP_RST_BTN_R_N @BASEBOARD_FAB2_LIB.BASEBOARD_FAB2(SCH_1):FP_RST_BTN_R_N    I18 @BASEBOARD_FAB2_LIB.BASEBOARD_FAB2(SCH_1):PAGE175
     6 FP_RST_BTN_BUF1_N @BASEBOARD_FAB2_LIB.BASEBOARD_FAB2(SCH_1):FP_RST_BTN_BUF1_N    I18 @BASEBOARD_FAB2_LIB.BASEBOARD_FAB2(SCH_1):PAGE175
     3 FP_RST_BTN_BUF1_N @BASEBOARD_FAB2_LIB.BASEBOARD_FAB2(SCH_1):FP_RST_BTN_BUF1_N    I15 @BASEBOARD_FAB2_LIB.BASEBOARD_FAB2(SCH_1):PAGE175
     4 RST_SYSTEM_BTN_BUF_N @BASEBOARD_FAB2_LIB.BASEBOARD_FAB2(SCH_1):RST_SYSTEM_BTN_BUF_N    I15 @BASEBOARD_FAB2_LIB.BASEBOARD_FAB2(SCH_1):PAGE175

U9A4 TTL2G14_SMLF-74LVC2G14,IC,D184B
     1 FP_PWR_BTN_R1_N @BASEBOARD_FAB2_LIB.BASEBOARD_FAB2(SCH_1):FP_PWR_BTN_R1_N     I9 @BASEBOARD_FAB2_LIB.BASEBOARD_FAB2(SCH_1):PAGE175
     6 FP_PWR_BTN_BUF1_N @BASEBOARD_FAB2_LIB.BASEBOARD_FAB2(SCH_1):FP_PWR_BTN_BUF1_N     I9 @BASEBOARD_FAB2_LIB.BASEBOARD_FAB2(SCH_1):PAGE175
     3 FP_PWR_BTN_BUF1_N @BASEBOARD_FAB2_LIB.BASEBOARD_FAB2(SCH_1):FP_PWR_BTN_BUF1_N    I10 @BASEBOARD_FAB2_LIB.BASEBOARD_FAB2(SCH_1):PAGE175
     4 FM_PWR_BTN_R_N @BASEBOARD_FAB2_LIB.BASEBOARD_FAB2(SCH_1):FM_PWR_BTN_R_N    I10 @BASEBOARD_FAB2_LIB.BASEBOARD_FAB2(SCH_1):PAGE175

U9A5 74CBTLV1G125_SMLF-IC,C88177-00A
     4    GND @BASEBOARD_FAB2_LIB.BASEBOARD_FAB2(SCH_1):GND   I185 @BASEBOARD_FAB2_LIB.BASEBOARD_FAB2(SCH_1):PAGE113
     1 FM_CPU0_OR_CPU1_MCP_PRES @BASEBOARD_FAB2_LIB.BASEBOARD_FAB2(SCH_1):FM_CPU0_OR_CPU1_MCP_PRES   I185 @BASEBOARD_FAB2_LIB.BASEBOARD_FAB2(SCH_1):PAGE113
     2 JTAG_MCP_TCK_R @BASEBOARD_FAB2_LIB.BASEBOARD_FAB2(SCH_1):JTAG_MCP_TCK_R   I185 @BASEBOARD_FAB2_LIB.BASEBOARD_FAB2(SCH_1):PAGE113

U9B4 TMP421_TSSOP-IC,G62962-001
     3 PU_TMP421_1_A1 @BASEBOARD_FAB2_LIB.BASEBOARD_FAB2(SCH_1):PU_TMP421_1_A1     I1 @BASEBOARD_FAB2_LIB.BASEBOARD_FAB2(SCH_1):PAGE167
     4 PD_TMP421_1_A0 @BASEBOARD_FAB2_LIB.BASEBOARD_FAB2(SCH_1):PD_TMP421_1_A0     I1 @BASEBOARD_FAB2_LIB.BASEBOARD_FAB2(SCH_1):PAGE167
     2 ISENSE_TMP421_1_DXN @BASEBOARD_FAB2_LIB.BASEBOARD_FAB2(SCH_1):ISENSE_TMP421_1_DXN     I1 @BASEBOARD_FAB2_LIB.BASEBOARD_FAB2(SCH_1):PAGE167
     1 ISENSE_TMP421_1_DXP @BASEBOARD_FAB2_LIB.BASEBOARD_FAB2(SCH_1):ISENSE_TMP421_1_DXP     I1 @BASEBOARD_FAB2_LIB.BASEBOARD_FAB2(SCH_1):PAGE167
     5    GND @BASEBOARD_FAB2_LIB.BASEBOARD_FAB2(SCH_1):GND     I1 @BASEBOARD_FAB2_LIB.BASEBOARD_FAB2(SCH_1):PAGE167
     7 SMB_SENSOR_TMP421_1_SCL @BASEBOARD_FAB2_LIB.BASEBOARD_FAB2(SCH_1):SMB_SENSOR_TMP421_1_SCL     I1 @BASEBOARD_FAB2_LIB.BASEBOARD_FAB2(SCH_1):PAGE167
     6 SMB_SENSOR_TMP421_1_SDA @BASEBOARD_FAB2_LIB.BASEBOARD_FAB2(SCH_1):SMB_SENSOR_TMP421_1_SDA     I1 @BASEBOARD_FAB2_LIB.BASEBOARD_FAB2(SCH_1):PAGE167
     8 P3V3_STBY @BASEBOARD_FAB2_LIB.BASEBOARD_FAB2(SCH_1):P3V3_STBY     I1 @BASEBOARD_FAB2_LIB.BASEBOARD_FAB2(SCH_1):PAGE167

U9E1 M25PE16_SM-IC,H77797-001
     1 SPI_NIC_CS_N @BASEBOARD_FAB2_LIB.BASEBOARD_FAB2(SCH_1):SPI_NIC_CS_N     I1 @BASEBOARD_FAB2_LIB.BASEBOARD_FAB2(SCH_1):PAGE140
     7 PU_NV_HOLD_N @BASEBOARD_FAB2_LIB.BASEBOARD_FAB2(SCH_1):PU_NV_HOLD_N     I1 @BASEBOARD_FAB2_LIB.BASEBOARD_FAB2(SCH_1):PAGE140
     6 SPI_NIC_SCLK @BASEBOARD_FAB2_LIB.BASEBOARD_FAB2(SCH_1):SPI_NIC_SCLK     I1 @BASEBOARD_FAB2_LIB.BASEBOARD_FAB2(SCH_1):PAGE140
     5 SPI_NIC_MOSI @BASEBOARD_FAB2_LIB.BASEBOARD_FAB2(SCH_1):SPI_NIC_MOSI     I1 @BASEBOARD_FAB2_LIB.BASEBOARD_FAB2(SCH_1):PAGE140
     2 SPI_NIC_MISO_R @BASEBOARD_FAB2_LIB.BASEBOARD_FAB2(SCH_1):SPI_NIC_MISO_R     I1 @BASEBOARD_FAB2_LIB.BASEBOARD_FAB2(SCH_1):PAGE140
     8 P3V3_STBY @BASEBOARD_FAB2_LIB.BASEBOARD_FAB2(SCH_1):P3V3_STBY     I1 @BASEBOARD_FAB2_LIB.BASEBOARD_FAB2(SCH_1):PAGE140
     4    GND @BASEBOARD_FAB2_LIB.BASEBOARD_FAB2(SCH_1):GND     I1 @BASEBOARD_FAB2_LIB.BASEBOARD_FAB2(SCH_1):PAGE140
     3 PU_NV_WP_N @BASEBOARD_FAB2_LIB.BASEBOARD_FAB2(SCH_1):PU_NV_WP_N     I1 @BASEBOARD_FAB2_LIB.BASEBOARD_FAB2(SCH_1):PAGE140

U9F1 FSA3357_SM-IC,C63273-001
     7 UART_MUX_IN_R @BASEBOARD_FAB2_LIB.BASEBOARD_FAB2(SCH_1):UART_MUX_IN_R    I75 @BASEBOARD_FAB2_LIB.BASEBOARD_FAB2(SCH_1):PAGE158
     1 SP2_BMC_CM_UART_RX_R @BASEBOARD_FAB2_LIB.BASEBOARD_FAB2(SCH_1):SP2_BMC_CM_UART_RX_R    I75 @BASEBOARD_FAB2_LIB.BASEBOARD_FAB2(SCH_1):PAGE158
     2 UART_BMC_RXD5 @BASEBOARD_FAB2_LIB.BASEBOARD_FAB2(SCH_1):UART_BMC_RXD5    I75 @BASEBOARD_FAB2_LIB.BASEBOARD_FAB2(SCH_1):PAGE158
     3 SP1_BMC_HOST_UART_RX @BASEBOARD_FAB2_LIB.BASEBOARD_FAB2(SCH_1):SP1_BMC_HOST_UART_RX    I75 @BASEBOARD_FAB2_LIB.BASEBOARD_FAB2(SCH_1):PAGE158
     4    GND @BASEBOARD_FAB2_LIB.BASEBOARD_FAB2(SCH_1):GND    I75 @BASEBOARD_FAB2_LIB.BASEBOARD_FAB2(SCH_1):PAGE158
     6 FM_UARTSW_LSB_N @BASEBOARD_FAB2_LIB.BASEBOARD_FAB2(SCH_1):FM_UARTSW_LSB_N    I75 @BASEBOARD_FAB2_LIB.BASEBOARD_FAB2(SCH_1):PAGE158
     5 FM_UARTSW_MSB_N @BASEBOARD_FAB2_LIB.BASEBOARD_FAB2(SCH_1):FM_UARTSW_MSB_N    I75 @BASEBOARD_FAB2_LIB.BASEBOARD_FAB2(SCH_1):PAGE158
     8 P3V3_STBY @BASEBOARD_FAB2_LIB.BASEBOARD_FAB2(SCH_1):P3V3_STBY    I75 @BASEBOARD_FAB2_LIB.BASEBOARD_FAB2(SCH_1):PAGE158

U9F2 FSA3357_SM-IC,C63273-001
     7 UART_MUX_OUT_R @BASEBOARD_FAB2_LIB.BASEBOARD_FAB2(SCH_1):UART_MUX_OUT_R    I74 @BASEBOARD_FAB2_LIB.BASEBOARD_FAB2(SCH_1):PAGE158
     1 SP2_BMC_CM_UART_TX_R @BASEBOARD_FAB2_LIB.BASEBOARD_FAB2(SCH_1):SP2_BMC_CM_UART_TX_R    I74 @BASEBOARD_FAB2_LIB.BASEBOARD_FAB2(SCH_1):PAGE158
     2 UART_BMC_TXD5 @BASEBOARD_FAB2_LIB.BASEBOARD_FAB2(SCH_1):UART_BMC_TXD5    I74 @BASEBOARD_FAB2_LIB.BASEBOARD_FAB2(SCH_1):PAGE158
     3 SP1_BMC_HOST_UART_TX @BASEBOARD_FAB2_LIB.BASEBOARD_FAB2(SCH_1):SP1_BMC_HOST_UART_TX    I74 @BASEBOARD_FAB2_LIB.BASEBOARD_FAB2(SCH_1):PAGE158
     4    GND @BASEBOARD_FAB2_LIB.BASEBOARD_FAB2(SCH_1):GND    I74 @BASEBOARD_FAB2_LIB.BASEBOARD_FAB2(SCH_1):PAGE158
     6 FM_UARTSW_LSB_N @BASEBOARD_FAB2_LIB.BASEBOARD_FAB2(SCH_1):FM_UARTSW_LSB_N    I74 @BASEBOARD_FAB2_LIB.BASEBOARD_FAB2(SCH_1):PAGE158
     5 FM_UARTSW_MSB_N @BASEBOARD_FAB2_LIB.BASEBOARD_FAB2(SCH_1):FM_UARTSW_MSB_N    I74 @BASEBOARD_FAB2_LIB.BASEBOARD_FAB2(SCH_1):PAGE158
     8 P3V3_STBY @BASEBOARD_FAB2_LIB.BASEBOARD_FAB2(SCH_1):P3V3_STBY    I74 @BASEBOARD_FAB2_LIB.BASEBOARD_FAB2(SCH_1):PAGE158

U9F3 TTL1G07_A_SOP-74LVC1G07,IC,C88B
     2 RST_BMC_DDR3_BUF_IN_N @BASEBOARD_FAB2_LIB.BASEBOARD_FAB2(SCH_1):RST_BMC_DDR3_BUF_IN_N    I34 @BASEBOARD_FAB2_LIB.BASEBOARD_FAB2(SCH_1):PAGE149
     4 RST_BMC_DDR3_R_N @BASEBOARD_FAB2_LIB.BASEBOARD_FAB2(SCH_1):RST_BMC_DDR3_R_N    I34 @BASEBOARD_FAB2_LIB.BASEBOARD_FAB2(SCH_1):PAGE149

U9G1 GTL2014_SM-IC,D66151-001
    13 H_CPU1_KLM_MEMHOT_LVT3_R_N @BASEBOARD_FAB2_LIB.BASEBOARD_FAB2(SCH_1):H_CPU1_KLM_MEMHOT_LVT3_R_N     I1 @BASEBOARD_FAB2_LIB.BASEBOARD_FAB2(SCH_1):PAGE152
    12 H_CPU1_GHJ_MEMHOT_LVT3_R_N @BASEBOARD_FAB2_LIB.BASEBOARD_FAB2(SCH_1):H_CPU1_GHJ_MEMHOT_LVT3_R_N     I1 @BASEBOARD_FAB2_LIB.BASEBOARD_FAB2(SCH_1):PAGE152
    10 H_CPU0_DEF_MEMHOT_LVT3_R_N @BASEBOARD_FAB2_LIB.BASEBOARD_FAB2(SCH_1):H_CPU0_DEF_MEMHOT_LVT3_R_N     I1 @BASEBOARD_FAB2_LIB.BASEBOARD_FAB2(SCH_1):PAGE152
     9 H_CPU0_ABC_MEMHOT_LVT3_R_N @BASEBOARD_FAB2_LIB.BASEBOARD_FAB2(SCH_1):H_CPU0_ABC_MEMHOT_LVT3_R_N     I1 @BASEBOARD_FAB2_LIB.BASEBOARD_FAB2(SCH_1):PAGE152
     2 H_CPU1_MEMKLM_MEMHOT_G_R_N @BASEBOARD_FAB2_LIB.BASEBOARD_FAB2(SCH_1):H_CPU1_MEMKLM_MEMHOT_G_R_N     I1 @BASEBOARD_FAB2_LIB.BASEBOARD_FAB2(SCH_1):PAGE152
     3 H_CPU1_MEMGHJ_MEMHOT_G_R_N @BASEBOARD_FAB2_LIB.BASEBOARD_FAB2(SCH_1):H_CPU1_MEMGHJ_MEMHOT_G_R_N     I1 @BASEBOARD_FAB2_LIB.BASEBOARD_FAB2(SCH_1):PAGE152
     5 H_CPU0_MEMDEF_MEMHOT_G_R_N @BASEBOARD_FAB2_LIB.BASEBOARD_FAB2(SCH_1):H_CPU0_MEMDEF_MEMHOT_G_R_N     I1 @BASEBOARD_FAB2_LIB.BASEBOARD_FAB2(SCH_1):PAGE152
     6 H_CPU0_MEMABC_MEMHOT_G_R_N @BASEBOARD_FAB2_LIB.BASEBOARD_FAB2(SCH_1):H_CPU0_MEMABC_MEMHOT_G_R_N     I1 @BASEBOARD_FAB2_LIB.BASEBOARD_FAB2(SCH_1):PAGE152
     1 PD_DIR_2 @BASEBOARD_FAB2_LIB.BASEBOARD_FAB2(SCH_1):PD_DIR_2     I1 @BASEBOARD_FAB2_LIB.BASEBOARD_FAB2(SCH_1):PAGE152
    11    GND @BASEBOARD_FAB2_LIB.BASEBOARD_FAB2(SCH_1):GND     I1 @BASEBOARD_FAB2_LIB.BASEBOARD_FAB2(SCH_1):PAGE152
     8    GND @BASEBOARD_FAB2_LIB.BASEBOARD_FAB2(SCH_1):GND     I1 @BASEBOARD_FAB2_LIB.BASEBOARD_FAB2(SCH_1):PAGE152
     7    GND @BASEBOARD_FAB2_LIB.BASEBOARD_FAB2(SCH_1):GND     I1 @BASEBOARD_FAB2_LIB.BASEBOARD_FAB2(SCH_1):PAGE152
    14   P3V3 @BASEBOARD_FAB2_LIB.BASEBOARD_FAB2(SCH_1):P3V3     I1 @BASEBOARD_FAB2_LIB.BASEBOARD_FAB2(SCH_1):PAGE152
     4 P0V7_GTL2014_2 @BASEBOARD_FAB2_LIB.BASEBOARD_FAB2(SCH_1):P0V7_GTL2014_2     I1 @BASEBOARD_FAB2_LIB.BASEBOARD_FAB2(SCH_1):PAGE152

U9P1 TPS3700_SM-IC,H69492-001
     5    GND @BASEBOARD_FAB2_LIB.BASEBOARD_FAB2(SCH_1):GND   I163 @BASEBOARD_FAB2_LIB.BASEBOARD_FAB2(SCH_1):PAGE200
     4 A_P12V_STBY_ADR_TRIGGER @BASEBOARD_FAB2_LIB.BASEBOARD_FAB2(SCH_1):A_P12V_STBY_ADR_TRIGGER   I163 @BASEBOARD_FAB2_LIB.BASEBOARD_FAB2(SCH_1):PAGE200
     3 A_P12V_STBY_FP_TRIGGER @BASEBOARD_FAB2_LIB.BASEBOARD_FAB2(SCH_1):A_P12V_STBY_FP_TRIGGER   I163 @BASEBOARD_FAB2_LIB.BASEBOARD_FAB2(SCH_1):PAGE200
     6 FM_UV_ADR_TRIGGER_N @BASEBOARD_FAB2_LIB.BASEBOARD_FAB2(SCH_1):FM_UV_ADR_TRIGGER_N   I163 @BASEBOARD_FAB2_LIB.BASEBOARD_FAB2(SCH_1):PAGE200
     1 A_P12V_STBY_FPH_GATE @BASEBOARD_FAB2_LIB.BASEBOARD_FAB2(SCH_1):A_P12V_STBY_FPH_GATE   I163 @BASEBOARD_FAB2_LIB.BASEBOARD_FAB2(SCH_1):PAGE200
     2 P12V_STBY @BASEBOARD_FAB2_LIB.BASEBOARD_FAB2(SCH_1):P12V_STBY   I163 @BASEBOARD_FAB2_LIB.BASEBOARD_FAB2(SCH_1):PAGE200

U9P2 TPS3700_SM-IC,H69492-001
     5    GND @BASEBOARD_FAB2_LIB.BASEBOARD_FAB2(SCH_1):GND   I200 @BASEBOARD_FAB2_LIB.BASEBOARD_FAB2(SCH_1):PAGE200
     4 A_HSC_INAP @BASEBOARD_FAB2_LIB.BASEBOARD_FAB2(SCH_1):A_HSC_INAP   I200 @BASEBOARD_FAB2_LIB.BASEBOARD_FAB2(SCH_1):PAGE200
     3 A_HSC_TIMER_R @BASEBOARD_FAB2_LIB.BASEBOARD_FAB2(SCH_1):A_HSC_TIMER_R   I200 @BASEBOARD_FAB2_LIB.BASEBOARD_FAB2(SCH_1):PAGE200
     6 PWRGD_DSW_PWROK @BASEBOARD_FAB2_LIB.BASEBOARD_FAB2(SCH_1):PWRGD_DSW_PWROK   I200 @BASEBOARD_FAB2_LIB.BASEBOARD_FAB2(SCH_1):PAGE200
     1 FM_HSC_TIMER_EXP_N @BASEBOARD_FAB2_LIB.BASEBOARD_FAB2(SCH_1):FM_HSC_TIMER_EXP_N   I200 @BASEBOARD_FAB2_LIB.BASEBOARD_FAB2(SCH_1):PAGE200
     2 P3V3_STBY @BASEBOARD_FAB2_LIB.BASEBOARD_FAB2(SCH_1):P3V3_STBY   I200 @BASEBOARD_FAB2_LIB.BASEBOARD_FAB2(SCH_1):PAGE200

U25W4 AST2520A1-GP-GP_ASIC2-GB1-AST2A
    U9 BMC_M_DQ4 @BASEBOARD_FAB2_LIB.BASEBOARD_FAB2(SCH_1):BMC_M_DQ4    I63 @BASEBOARD_FAB2_LIB.BASEBOARD_FAB2(SCH_1):PAGE143
  AA10 BMC_M_DQ3 @BASEBOARD_FAB2_LIB.BASEBOARD_FAB2(SCH_1):BMC_M_DQ3    I63 @BASEBOARD_FAB2_LIB.BASEBOARD_FAB2(SCH_1):PAGE143
   Y10 BMC_M_DQ2 @BASEBOARD_FAB2_LIB.BASEBOARD_FAB2(SCH_1):BMC_M_DQ2    I63 @BASEBOARD_FAB2_LIB.BASEBOARD_FAB2(SCH_1):PAGE143
   W10 BMC_M_DQ1 @BASEBOARD_FAB2_LIB.BASEBOARD_FAB2(SCH_1):BMC_M_DQ1    I63 @BASEBOARD_FAB2_LIB.BASEBOARD_FAB2(SCH_1):PAGE143
   U10 BMC_M_DQ0 @BASEBOARD_FAB2_LIB.BASEBOARD_FAB2(SCH_1):BMC_M_DQ0    I63 @BASEBOARD_FAB2_LIB.BASEBOARD_FAB2(SCH_1):PAGE143
   U15 TP_BMC_M_A15 @BASEBOARD_FAB2_LIB.BASEBOARD_FAB2(SCH_1):TP_BMC_M_A15    I63 @BASEBOARD_FAB2_LIB.BASEBOARD_FAB2(SCH_1):PAGE143
    U7 BMC_M_DQ15 @BASEBOARD_FAB2_LIB.BASEBOARD_FAB2(SCH_1):BMC_M_DQ15    I63 @BASEBOARD_FAB2_LIB.BASEBOARD_FAB2(SCH_1):PAGE143
    V7 BMC_M_DQ14 @BASEBOARD_FAB2_LIB.BASEBOARD_FAB2(SCH_1):BMC_M_DQ14    I63 @BASEBOARD_FAB2_LIB.BASEBOARD_FAB2(SCH_1):PAGE143
   AB8 BMC_M_DM1 @BASEBOARD_FAB2_LIB.BASEBOARD_FAB2(SCH_1):BMC_M_DM1    I63 @BASEBOARD_FAB2_LIB.BASEBOARD_FAB2(SCH_1):PAGE143
   W11 BMC_MIOZ @BASEBOARD_FAB2_LIB.BASEBOARD_FAB2(SCH_1):BMC_MIOZ    I63 @BASEBOARD_FAB2_LIB.BASEBOARD_FAB2(SCH_1):PAGE143
  AB13 BMC_M_CAS_N @BASEBOARD_FAB2_LIB.BASEBOARD_FAB2(SCH_1):BMC_M_CAS_N    I63 @BASEBOARD_FAB2_LIB.BASEBOARD_FAB2(SCH_1):PAGE143
   U13 BMC_M_A10 @BASEBOARD_FAB2_LIB.BASEBOARD_FAB2(SCH_1):BMC_M_A10    I63 @BASEBOARD_FAB2_LIB.BASEBOARD_FAB2(SCH_1):PAGE143
  AA14 BMC_M_A11 @BASEBOARD_FAB2_LIB.BASEBOARD_FAB2(SCH_1):BMC_M_A11    I63 @BASEBOARD_FAB2_LIB.BASEBOARD_FAB2(SCH_1):PAGE143
    T9 BMC_M_VREFCA @BASEBOARD_FAB2_LIB.BASEBOARD_FAB2(SCH_1):BMC_M_VREFCA    I63 @BASEBOARD_FAB2_LIB.BASEBOARD_FAB2(SCH_1):PAGE143
    Y8 BMC_M_DQ9 @BASEBOARD_FAB2_LIB.BASEBOARD_FAB2(SCH_1):BMC_M_DQ9    I63 @BASEBOARD_FAB2_LIB.BASEBOARD_FAB2(SCH_1):PAGE143
   V11 BMC_M_ODT @BASEBOARD_FAB2_LIB.BASEBOARD_FAB2(SCH_1):BMC_M_ODT    I63 @BASEBOARD_FAB2_LIB.BASEBOARD_FAB2(SCH_1):PAGE143
   Y11 BMC_M_CKE @BASEBOARD_FAB2_LIB.BASEBOARD_FAB2(SCH_1):BMC_M_CKE    I63 @BASEBOARD_FAB2_LIB.BASEBOARD_FAB2(SCH_1):PAGE143
  AB12 BMC_M_CLK_DN @BASEBOARD_FAB2_LIB.BASEBOARD_FAB2(SCH_1):BMC_M_CLK_DN    I63 @BASEBOARD_FAB2_LIB.BASEBOARD_FAB2(SCH_1):PAGE143
   W13 BMC_M_BG0 @BASEBOARD_FAB2_LIB.BASEBOARD_FAB2(SCH_1):BMC_M_BG0    I63 @BASEBOARD_FAB2_LIB.BASEBOARD_FAB2(SCH_1):PAGE143
   Y13 BMC_M_BA1 @BASEBOARD_FAB2_LIB.BASEBOARD_FAB2(SCH_1):BMC_M_BA1    I63 @BASEBOARD_FAB2_LIB.BASEBOARD_FAB2(SCH_1):PAGE143
   U12 BMC_M_BA0 @BASEBOARD_FAB2_LIB.BASEBOARD_FAB2(SCH_1):BMC_M_BA0    I63 @BASEBOARD_FAB2_LIB.BASEBOARD_FAB2(SCH_1):PAGE143
   Y16 BMC_M_A9 @BASEBOARD_FAB2_LIB.BASEBOARD_FAB2(SCH_1):BMC_M_A9    I63 @BASEBOARD_FAB2_LIB.BASEBOARD_FAB2(SCH_1):PAGE143
   W16 BMC_M_A8 @BASEBOARD_FAB2_LIB.BASEBOARD_FAB2(SCH_1):BMC_M_A8    I63 @BASEBOARD_FAB2_LIB.BASEBOARD_FAB2(SCH_1):PAGE143
  AA16 BMC_M_A7 @BASEBOARD_FAB2_LIB.BASEBOARD_FAB2(SCH_1):BMC_M_A7    I63 @BASEBOARD_FAB2_LIB.BASEBOARD_FAB2(SCH_1):PAGE143
  AB16 BMC_M_A6 @BASEBOARD_FAB2_LIB.BASEBOARD_FAB2(SCH_1):BMC_M_A6    I63 @BASEBOARD_FAB2_LIB.BASEBOARD_FAB2(SCH_1):PAGE143
   V15 BMC_M_A5 @BASEBOARD_FAB2_LIB.BASEBOARD_FAB2(SCH_1):BMC_M_A5    I63 @BASEBOARD_FAB2_LIB.BASEBOARD_FAB2(SCH_1):PAGE143
   W15 BMC_M_A4 @BASEBOARD_FAB2_LIB.BASEBOARD_FAB2(SCH_1):BMC_M_A4    I63 @BASEBOARD_FAB2_LIB.BASEBOARD_FAB2(SCH_1):PAGE143
   U14 BMC_M_A3 @BASEBOARD_FAB2_LIB.BASEBOARD_FAB2(SCH_1):BMC_M_A3    I63 @BASEBOARD_FAB2_LIB.BASEBOARD_FAB2(SCH_1):PAGE143
   W14 BMC_M_A2 @BASEBOARD_FAB2_LIB.BASEBOARD_FAB2(SCH_1):BMC_M_A2    I63 @BASEBOARD_FAB2_LIB.BASEBOARD_FAB2(SCH_1):PAGE143
   Y14 BMC_M_A12 @BASEBOARD_FAB2_LIB.BASEBOARD_FAB2(SCH_1):BMC_M_A12    I63 @BASEBOARD_FAB2_LIB.BASEBOARD_FAB2(SCH_1):PAGE143
  AB14 BMC_M_A1 @BASEBOARD_FAB2_LIB.BASEBOARD_FAB2(SCH_1):BMC_M_A1    I63 @BASEBOARD_FAB2_LIB.BASEBOARD_FAB2(SCH_1):PAGE143
   V13 BMC_M_A0 @BASEBOARD_FAB2_LIB.BASEBOARD_FAB2(SCH_1):BMC_M_A0    I63 @BASEBOARD_FAB2_LIB.BASEBOARD_FAB2(SCH_1):PAGE143
   AB7 BMC_M_DQS1_DP @BASEBOARD_FAB2_LIB.BASEBOARD_FAB2(SCH_1):BMC_M_DQS1_DP    I63 @BASEBOARD_FAB2_LIB.BASEBOARD_FAB2(SCH_1):PAGE143
   AB6 BMC_M_DQS1_DN @BASEBOARD_FAB2_LIB.BASEBOARD_FAB2(SCH_1):BMC_M_DQS1_DN    I63 @BASEBOARD_FAB2_LIB.BASEBOARD_FAB2(SCH_1):PAGE143
   AB9 BMC_M_DQS0_DP @BASEBOARD_FAB2_LIB.BASEBOARD_FAB2(SCH_1):BMC_M_DQS0_DP    I63 @BASEBOARD_FAB2_LIB.BASEBOARD_FAB2(SCH_1):PAGE143
  AB10 BMC_M_DQS0_DN @BASEBOARD_FAB2_LIB.BASEBOARD_FAB2(SCH_1):BMC_M_DQS0_DN    I63 @BASEBOARD_FAB2_LIB.BASEBOARD_FAB2(SCH_1):PAGE143
    W9 BMC_M_DQ6 @BASEBOARD_FAB2_LIB.BASEBOARD_FAB2(SCH_1):BMC_M_DQ6    I63 @BASEBOARD_FAB2_LIB.BASEBOARD_FAB2(SCH_1):PAGE143
    Y9 BMC_M_DQ5 @BASEBOARD_FAB2_LIB.BASEBOARD_FAB2(SCH_1):BMC_M_DQ5    I63 @BASEBOARD_FAB2_LIB.BASEBOARD_FAB2(SCH_1):PAGE143
    W7 BMC_M_DQ13 @BASEBOARD_FAB2_LIB.BASEBOARD_FAB2(SCH_1):BMC_M_DQ13    I63 @BASEBOARD_FAB2_LIB.BASEBOARD_FAB2(SCH_1):PAGE143
   AA6 BMC_M_DQ12 @BASEBOARD_FAB2_LIB.BASEBOARD_FAB2(SCH_1):BMC_M_DQ12    I63 @BASEBOARD_FAB2_LIB.BASEBOARD_FAB2(SCH_1):PAGE143
    U8 BMC_M_DM0 @BASEBOARD_FAB2_LIB.BASEBOARD_FAB2(SCH_1):BMC_M_DM0    I63 @BASEBOARD_FAB2_LIB.BASEBOARD_FAB2(SCH_1):PAGE143
  AB15 BMC_M_A13 @BASEBOARD_FAB2_LIB.BASEBOARD_FAB2(SCH_1):BMC_M_A13    I63 @BASEBOARD_FAB2_LIB.BASEBOARD_FAB2(SCH_1):PAGE143
   Y15 BMC_M_MACT_N @BASEBOARD_FAB2_LIB.BASEBOARD_FAB2(SCH_1):BMC_M_MACT_N    I63 @BASEBOARD_FAB2_LIB.BASEBOARD_FAB2(SCH_1):PAGE143
    W8 BMC_M_DQ11 @BASEBOARD_FAB2_LIB.BASEBOARD_FAB2(SCH_1):BMC_M_DQ11    I63 @BASEBOARD_FAB2_LIB.BASEBOARD_FAB2(SCH_1):PAGE143
    Y7 BMC_M_DQ10 @BASEBOARD_FAB2_LIB.BASEBOARD_FAB2(SCH_1):BMC_M_DQ10    I63 @BASEBOARD_FAB2_LIB.BASEBOARD_FAB2(SCH_1):PAGE143
   Y12 BMC_M_WE_N @BASEBOARD_FAB2_LIB.BASEBOARD_FAB2(SCH_1):BMC_M_WE_N    I63 @BASEBOARD_FAB2_LIB.BASEBOARD_FAB2(SCH_1):PAGE143
   W12 BMC_M_RAS_N @BASEBOARD_FAB2_LIB.BASEBOARD_FAB2(SCH_1):BMC_M_RAS_N    I63 @BASEBOARD_FAB2_LIB.BASEBOARD_FAB2(SCH_1):PAGE143
    V9 BMC_M_DQ7 @BASEBOARD_FAB2_LIB.BASEBOARD_FAB2(SCH_1):BMC_M_DQ7    I63 @BASEBOARD_FAB2_LIB.BASEBOARD_FAB2(SCH_1):PAGE143
   AA8 BMC_M_DQ8 @BASEBOARD_FAB2_LIB.BASEBOARD_FAB2(SCH_1):BMC_M_DQ8    I63 @BASEBOARD_FAB2_LIB.BASEBOARD_FAB2(SCH_1):PAGE143
  AB11 BMC_M_CLK_DP @BASEBOARD_FAB2_LIB.BASEBOARD_FAB2(SCH_1):BMC_M_CLK_DP    I63 @BASEBOARD_FAB2_LIB.BASEBOARD_FAB2(SCH_1):PAGE143
  AA12 BMC_M_CS_N @BASEBOARD_FAB2_LIB.BASEBOARD_FAB2(SCH_1):BMC_M_CS_N    I63 @BASEBOARD_FAB2_LIB.BASEBOARD_FAB2(SCH_1):PAGE143
   H22 PWRGD_SYS_PWROK @BASEBOARD_FAB2_LIB.BASEBOARD_FAB2(SCH_1):PWRGD_SYS_PWROK    I95 @BASEBOARD_FAB2_LIB.BASEBOARD_FAB2(SCH_1):PAGE144
   J20 CLK_48M_USB_BMC @BASEBOARD_FAB2_LIB.BASEBOARD_FAB2(SCH_1):CLK_48M_USB_BMC    I95 @BASEBOARD_FAB2_LIB.BASEBOARD_FAB2(SCH_1):PAGE144
   M18 SMB_IPMB_3V3AUX_SCL_R @BASEBOARD_FAB2_LIB.BASEBOARD_FAB2(SCH_1):SMB_IPMB_3V3AUX_SCL_R    I95 @BASEBOARD_FAB2_LIB.BASEBOARD_FAB2(SCH_1):PAGE144
   A15 IRQ_PVDDQ_DEF_VRHOT_LVT3_N @BASEBOARD_FAB2_LIB.BASEBOARD_FAB2(SCH_1):IRQ_PVDDQ_DEF_VRHOT_LVT3_N    I95 @BASEBOARD_FAB2_LIB.BASEBOARD_FAB2(SCH_1):PAGE144
    K4 A_DACRSET @BASEBOARD_FAB2_LIB.BASEBOARD_FAB2(SCH_1):A_DACRSET    I95 @BASEBOARD_FAB2_LIB.BASEBOARD_FAB2(SCH_1):PAGE144
    J4 TP_DACR @BASEBOARD_FAB2_LIB.BASEBOARD_FAB2(SCH_1):TP_DACR    I95 @BASEBOARD_FAB2_LIB.BASEBOARD_FAB2(SCH_1):PAGE144
    J3 TP_DACG @BASEBOARD_FAB2_LIB.BASEBOARD_FAB2(SCH_1):TP_DACG    I95 @BASEBOARD_FAB2_LIB.BASEBOARD_FAB2(SCH_1):PAGE144
    C8 JTAG_BMC_TMS @BASEBOARD_FAB2_LIB.BASEBOARD_FAB2(SCH_1):JTAG_BMC_TMS    I95 @BASEBOARD_FAB2_LIB.BASEBOARD_FAB2(SCH_1):PAGE144
   D12 JTAG_BMC_TDI @BASEBOARD_FAB2_LIB.BASEBOARD_FAB2(SCH_1):JTAG_BMC_TDI    I95 @BASEBOARD_FAB2_LIB.BASEBOARD_FAB2(SCH_1):PAGE144
   C10 JTAG_BMC_TCK @BASEBOARD_FAB2_LIB.BASEBOARD_FAB2(SCH_1):JTAG_BMC_TCK    I95 @BASEBOARD_FAB2_LIB.BASEBOARD_FAB2(SCH_1):PAGE144
    C9 TP_JTAG_BMC_RTCK @BASEBOARD_FAB2_LIB.BASEBOARD_FAB2(SCH_1):TP_JTAG_BMC_RTCK    I95 @BASEBOARD_FAB2_LIB.BASEBOARD_FAB2(SCH_1):PAGE144
   E11 JTAG_BMC_TRST_N @BASEBOARD_FAB2_LIB.BASEBOARD_FAB2(SCH_1):JTAG_BMC_TRST_N    I95 @BASEBOARD_FAB2_LIB.BASEBOARD_FAB2(SCH_1):PAGE144
   E15 FM_BIOS_MRC_DEBUG_MSG_DIS_N @BASEBOARD_FAB2_LIB.BASEBOARD_FAB2(SCH_1):FM_BIOS_MRC_DEBUG_MSG_DIS_N    I95 @BASEBOARD_FAB2_LIB.BASEBOARD_FAB2(SCH_1):PAGE144
   C18 IRQ_HSC_FAULT_N @BASEBOARD_FAB2_LIB.BASEBOARD_FAB2(SCH_1):IRQ_HSC_FAULT_N    I95 @BASEBOARD_FAB2_LIB.BASEBOARD_FAB2(SCH_1):PAGE144
   C15 FM_SOL_UART_CH_SEL @BASEBOARD_FAB2_LIB.BASEBOARD_FAB2(SCH_1):FM_SOL_UART_CH_SEL    I95 @BASEBOARD_FAB2_LIB.BASEBOARD_FAB2(SCH_1):PAGE144
   B15 FM_CPU_BMC_INIT @BASEBOARD_FAB2_LIB.BASEBOARD_FAB2(SCH_1):FM_CPU_BMC_INIT    I95 @BASEBOARD_FAB2_LIB.BASEBOARD_FAB2(SCH_1):PAGE144
   A14 IRQ_DIMM_SAVE_LVT3_N @BASEBOARD_FAB2_LIB.BASEBOARD_FAB2(SCH_1):IRQ_DIMM_SAVE_LVT3_N    I95 @BASEBOARD_FAB2_LIB.BASEBOARD_FAB2(SCH_1):PAGE144
    L2 SGPIO_BMC_LD_R_N @BASEBOARD_FAB2_LIB.BASEBOARD_FAB2(SCH_1):SGPIO_BMC_LD_R_N    I95 @BASEBOARD_FAB2_LIB.BASEBOARD_FAB2(SCH_1):PAGE144
    R2 SGPIO_BMC_CLK_R @BASEBOARD_FAB2_LIB.BASEBOARD_FAB2(SCH_1):SGPIO_BMC_CLK_R    I95 @BASEBOARD_FAB2_LIB.BASEBOARD_FAB2(SCH_1):PAGE144
    N3 SGPIO_BMC_DOUT_R @BASEBOARD_FAB2_LIB.BASEBOARD_FAB2(SCH_1):SGPIO_BMC_DOUT_R    I95 @BASEBOARD_FAB2_LIB.BASEBOARD_FAB2(SCH_1):PAGE144
   E16 FM_FAST_PROCHOT_EN_N @BASEBOARD_FAB2_LIB.BASEBOARD_FAB2(SCH_1):FM_FAST_PROCHOT_EN_N    I95 @BASEBOARD_FAB2_LIB.BASEBOARD_FAB2(SCH_1):PAGE144
   C19 FM_PCH_BMC_THERMTRIP_N @BASEBOARD_FAB2_LIB.BASEBOARD_FAB2(SCH_1):FM_PCH_BMC_THERMTRIP_N    I95 @BASEBOARD_FAB2_LIB.BASEBOARD_FAB2(SCH_1):PAGE144
    J2 TP_DACB @BASEBOARD_FAB2_LIB.BASEBOARD_FAB2(SCH_1):TP_DACB    I95 @BASEBOARD_FAB2_LIB.BASEBOARD_FAB2(SCH_1):PAGE144
   M19 SMB_IPMB_3V3AUX_SDA_R @BASEBOARD_FAB2_LIB.BASEBOARD_FAB2(SCH_1):SMB_IPMB_3V3AUX_SDA_R    I95 @BASEBOARD_FAB2_LIB.BASEBOARD_FAB2(SCH_1):PAGE144
   D11 JTAG_BMC_TDO @BASEBOARD_FAB2_LIB.BASEBOARD_FAB2(SCH_1):JTAG_BMC_TDO    I95 @BASEBOARD_FAB2_LIB.BASEBOARD_FAB2(SCH_1):PAGE144
   K19 PWRGD_PCH_PWROK @BASEBOARD_FAB2_LIB.BASEBOARD_FAB2(SCH_1):PWRGD_PCH_PWROK    I95 @BASEBOARD_FAB2_LIB.BASEBOARD_FAB2(SCH_1):PAGE144
   L19 FM_CPU1_SKTOCC_LVT3_N @BASEBOARD_FAB2_LIB.BASEBOARD_FAB2(SCH_1):FM_CPU1_SKTOCC_LVT3_N    I95 @BASEBOARD_FAB2_LIB.BASEBOARD_FAB2(SCH_1):PAGE144
   L18 FM_MP_PS_FAIL_N @BASEBOARD_FAB2_LIB.BASEBOARD_FAB2(SCH_1):FM_MP_PS_FAIL_N    I95 @BASEBOARD_FAB2_LIB.BASEBOARD_FAB2(SCH_1):PAGE144
   K18 FM_CPU0_SKTOCC_LVT3_N @BASEBOARD_FAB2_LIB.BASEBOARD_FAB2(SCH_1):FM_CPU0_SKTOCC_LVT3_N    I95 @BASEBOARD_FAB2_LIB.BASEBOARD_FAB2(SCH_1):PAGE144
   H20 IRQ_PVDDQ_GHJ_VRHOT_LVT3_N @BASEBOARD_FAB2_LIB.BASEBOARD_FAB2(SCH_1):IRQ_PVDDQ_GHJ_VRHOT_LVT3_N    I95 @BASEBOARD_FAB2_LIB.BASEBOARD_FAB2(SCH_1):PAGE144
   M20 TP_SMB_STORAGE_BP_3V3AUX_SCL @BASEBOARD_FAB2_LIB.BASEBOARD_FAB2(SCH_1):TP_SMB_STORAGE_BP_3V3AUX_SCL    I95 @BASEBOARD_FAB2_LIB.BASEBOARD_FAB2(SCH_1):PAGE144
   P20 TP_SMB_STORAGE_BP_3V3AUX_SDA @BASEBOARD_FAB2_LIB.BASEBOARD_FAB2(SCH_1):TP_SMB_STORAGE_BP_3V3AUX_SDA    I95 @BASEBOARD_FAB2_LIB.BASEBOARD_FAB2(SCH_1):PAGE144
   A11 SMB_VR_STBY_LVC3_SCL_R @BASEBOARD_FAB2_LIB.BASEBOARD_FAB2(SCH_1):SMB_VR_STBY_LVC3_SCL_R    I95 @BASEBOARD_FAB2_LIB.BASEBOARD_FAB2(SCH_1):PAGE144
   A10 SMB_VR_STBY_LVC3_SDA_R @BASEBOARD_FAB2_LIB.BASEBOARD_FAB2(SCH_1):SMB_VR_STBY_LVC3_SDA_R    I95 @BASEBOARD_FAB2_LIB.BASEBOARD_FAB2(SCH_1):PAGE144
    A9 SMB_HOST_STBY_LVC3_SCL_R @BASEBOARD_FAB2_LIB.BASEBOARD_FAB2(SCH_1):SMB_HOST_STBY_LVC3_SCL_R    I95 @BASEBOARD_FAB2_LIB.BASEBOARD_FAB2(SCH_1):PAGE144
    B9 SMB_HOST_STBY_LVC3_SDA_R @BASEBOARD_FAB2_LIB.BASEBOARD_FAB2(SCH_1):SMB_HOST_STBY_LVC3_SDA_R    I95 @BASEBOARD_FAB2_LIB.BASEBOARD_FAB2(SCH_1):PAGE144
    L3 SMB_SENSOR_BMC_STBY_LVC3_SCL @BASEBOARD_FAB2_LIB.BASEBOARD_FAB2(SCH_1):SMB_SENSOR_BMC_STBY_LVC3_SCL    I95 @BASEBOARD_FAB2_LIB.BASEBOARD_FAB2(SCH_1):PAGE144
    L4 SMB_SENSOR_BMC_STBY_LVC3_SDA @BASEBOARD_FAB2_LIB.BASEBOARD_FAB2(SCH_1):SMB_SENSOR_BMC_STBY_LVC3_SDA    I95 @BASEBOARD_FAB2_LIB.BASEBOARD_FAB2(SCH_1):PAGE144
    L1 SMB_SMLINK0_STBY_LVC3_SCL_R @BASEBOARD_FAB2_LIB.BASEBOARD_FAB2(SCH_1):SMB_SMLINK0_STBY_LVC3_SCL_R    I95 @BASEBOARD_FAB2_LIB.BASEBOARD_FAB2(SCH_1):PAGE144
    N2 SMB_SMLINK0_STBY_LVC3_SDA_R @BASEBOARD_FAB2_LIB.BASEBOARD_FAB2(SCH_1):SMB_SMLINK0_STBY_LVC3_SDA_R    I95 @BASEBOARD_FAB2_LIB.BASEBOARD_FAB2(SCH_1):PAGE144
   E19 FM_CPU_CATERR_LVT3_N @BASEBOARD_FAB2_LIB.BASEBOARD_FAB2(SCH_1):FM_CPU_CATERR_LVT3_N    I95 @BASEBOARD_FAB2_LIB.BASEBOARD_FAB2(SCH_1):PAGE144
   A19 FM_CPU_ERR2_LVT3_N @BASEBOARD_FAB2_LIB.BASEBOARD_FAB2(SCH_1):FM_CPU_ERR2_LVT3_N    I95 @BASEBOARD_FAB2_LIB.BASEBOARD_FAB2(SCH_1):PAGE144
    N4 SGPIO_BMC_DIN @BASEBOARD_FAB2_LIB.BASEBOARD_FAB2(SCH_1):SGPIO_BMC_DIN    I95 @BASEBOARD_FAB2_LIB.BASEBOARD_FAB2(SCH_1):PAGE144
   B16 FM_BMC_CPLD_GPO @BASEBOARD_FAB2_LIB.BASEBOARD_FAB2(SCH_1):FM_BMC_CPLD_GPO    I95 @BASEBOARD_FAB2_LIB.BASEBOARD_FAB2(SCH_1):PAGE144
   C16 FM_FLASH_DESC_OVERRIDE_R @BASEBOARD_FAB2_LIB.BASEBOARD_FAB2(SCH_1):FM_FLASH_DESC_OVERRIDE_R    I95 @BASEBOARD_FAB2_LIB.BASEBOARD_FAB2(SCH_1):PAGE144
   A13 SMB_SLOTX24_STBY_LVC3_SDA_R @BASEBOARD_FAB2_LIB.BASEBOARD_FAB2(SCH_1):SMB_SLOTX24_STBY_LVC3_SDA_R    I95 @BASEBOARD_FAB2_LIB.BASEBOARD_FAB2(SCH_1):PAGE144
   C14 SMB_SLOTX24_STBY_LVC3_SCL_R @BASEBOARD_FAB2_LIB.BASEBOARD_FAB2(SCH_1):SMB_SLOTX24_STBY_LVC3_SCL_R    I95 @BASEBOARD_FAB2_LIB.BASEBOARD_FAB2(SCH_1):PAGE144
    R1 SMB_BMC_PMBUS_STBY_LVC3_SDA_R @BASEBOARD_FAB2_LIB.BASEBOARD_FAB2(SCH_1):SMB_BMC_PMBUS_STBY_LVC3_SDA_R    I95 @BASEBOARD_FAB2_LIB.BASEBOARD_FAB2(SCH_1):PAGE144
    P2 SMB_BMC_PMBUS_STBY_LVC3_SCL_R @BASEBOARD_FAB2_LIB.BASEBOARD_FAB2(SCH_1):SMB_BMC_PMBUS_STBY_LVC3_SCL_R    I95 @BASEBOARD_FAB2_LIB.BASEBOARD_FAB2(SCH_1):PAGE144
    P1 SMB_OCP_FRU_STBY_LVC3_SDA_R @BASEBOARD_FAB2_LIB.BASEBOARD_FAB2(SCH_1):SMB_OCP_FRU_STBY_LVC3_SDA_R    I95 @BASEBOARD_FAB2_LIB.BASEBOARD_FAB2(SCH_1):PAGE144
    N1 SMB_OCP_FRU_STBY_LVC3_SCL_R @BASEBOARD_FAB2_LIB.BASEBOARD_FAB2(SCH_1):SMB_OCP_FRU_STBY_LVC3_SCL_R    I95 @BASEBOARD_FAB2_LIB.BASEBOARD_FAB2(SCH_1):PAGE144
   H21 IRQ_BMC_PCH_SMI_LPC_N @BASEBOARD_FAB2_LIB.BASEBOARD_FAB2(SCH_1):IRQ_BMC_PCH_SMI_LPC_N    I95 @BASEBOARD_FAB2_LIB.BASEBOARD_FAB2(SCH_1):PAGE144
   N21 SMB_OCP_LAN_STBY_LVC3_SCL_R @BASEBOARD_FAB2_LIB.BASEBOARD_FAB2(SCH_1):SMB_OCP_LAN_STBY_LVC3_SCL_R    I95 @BASEBOARD_FAB2_LIB.BASEBOARD_FAB2(SCH_1):PAGE144
   N22 SMB_OCP_LAN_STBY_LVC3_SDA_R @BASEBOARD_FAB2_LIB.BASEBOARD_FAB2(SCH_1):SMB_OCP_LAN_STBY_LVC3_SDA_R    I95 @BASEBOARD_FAB2_LIB.BASEBOARD_FAB2(SCH_1):PAGE144
   B12 TP_SMB_BUS11_SCL @BASEBOARD_FAB2_LIB.BASEBOARD_FAB2(SCH_1):TP_SMB_BUS11_SCL   I117 @BASEBOARD_FAB2_LIB.BASEBOARD_FAB2(SCH_1):PAGE145
    D9 TP_SMB_BUS11_SDA @BASEBOARD_FAB2_LIB.BASEBOARD_FAB2(SCH_1):TP_SMB_BUS11_SDA   I117 @BASEBOARD_FAB2_LIB.BASEBOARD_FAB2(SCH_1):PAGE145
   A12 SMB_PCIE_SSD_3V3AUX_SDA @BASEBOARD_FAB2_LIB.BASEBOARD_FAB2(SCH_1):SMB_PCIE_SSD_3V3AUX_SDA   I117 @BASEBOARD_FAB2_LIB.BASEBOARD_FAB2(SCH_1):PAGE145
   C12 SMB_PCIE_SSD_3V3AUX_SCL @BASEBOARD_FAB2_LIB.BASEBOARD_FAB2(SCH_1):SMB_PCIE_SSD_3V3AUX_SCL   I117 @BASEBOARD_FAB2_LIB.BASEBOARD_FAB2(SCH_1):PAGE145
   B14 FM_BMC_HEARTBEAT_N @BASEBOARD_FAB2_LIB.BASEBOARD_FAB2(SCH_1):FM_BMC_HEARTBEAT_N   I117 @BASEBOARD_FAB2_LIB.BASEBOARD_FAB2(SCH_1):PAGE145
   D14 FM_BMC_FAULT_LED_N @BASEBOARD_FAB2_LIB.BASEBOARD_FAB2(SCH_1):FM_BMC_FAULT_LED_N   I117 @BASEBOARD_FAB2_LIB.BASEBOARD_FAB2(SCH_1):PAGE145
   P21 FM_BMC_ONCTL_R_N @BASEBOARD_FAB2_LIB.BASEBOARD_FAB2(SCH_1):FM_BMC_ONCTL_R_N   I117 @BASEBOARD_FAB2_LIB.BASEBOARD_FAB2(SCH_1):PAGE145
   D15 H_CPU1_MEMGHJ_MEMHOT_LVT3_BMC_N @BASEBOARD_FAB2_LIB.BASEBOARD_FAB2(SCH_1):H_CPU1_MEMGHJ_MEMHOT_LVT3_BMC_N   I117 @BASEBOARD_FAB2_LIB.BASEBOARD_FAB2(SCH_1):PAGE145
   C11 SMB_IE_3V3AUX_SCL @BASEBOARD_FAB2_LIB.BASEBOARD_FAB2(SCH_1):SMB_IE_3V3AUX_SCL   I117 @BASEBOARD_FAB2_LIB.BASEBOARD_FAB2(SCH_1):PAGE145
   D10 SMB_LAN_STBY_LVC3_SCL_R @BASEBOARD_FAB2_LIB.BASEBOARD_FAB2(SCH_1):SMB_LAN_STBY_LVC3_SCL_R   I117 @BASEBOARD_FAB2_LIB.BASEBOARD_FAB2(SCH_1):PAGE145
   E14 FM_BIOS_SMI_ACTIVE_N @BASEBOARD_FAB2_LIB.BASEBOARD_FAB2(SCH_1):FM_BIOS_SMI_ACTIVE_N   I117 @BASEBOARD_FAB2_LIB.BASEBOARD_FAB2(SCH_1):PAGE145
   D13 FM_OCP_MEZZA_PRES_N @BASEBOARD_FAB2_LIB.BASEBOARD_FAB2(SCH_1):FM_OCP_MEZZA_PRES_N   I117 @BASEBOARD_FAB2_LIB.BASEBOARD_FAB2(SCH_1):PAGE145
   D16     NC     NC   I117 @BASEBOARD_FAB2_LIB.BASEBOARD_FAB2(SCH_1):PAGE145
   E17     NC     NC   I117 @BASEBOARD_FAB2_LIB.BASEBOARD_FAB2(SCH_1):PAGE145
   H19 FM_OCP_MEZZB_PRES_N @BASEBOARD_FAB2_LIB.BASEBOARD_FAB2(SCH_1):FM_OCP_MEZZB_PRES_N   I117 @BASEBOARD_FAB2_LIB.BASEBOARD_FAB2(SCH_1):PAGE145
   H18 FM_OCP_MEZZC_PRES_N @BASEBOARD_FAB2_LIB.BASEBOARD_FAB2(SCH_1):FM_OCP_MEZZC_PRES_N   I117 @BASEBOARD_FAB2_LIB.BASEBOARD_FAB2(SCH_1):PAGE145
    U1 FM_HSC_TIMER_EXP_N @BASEBOARD_FAB2_LIB.BASEBOARD_FAB2(SCH_1):FM_HSC_TIMER_EXP_N   I117 @BASEBOARD_FAB2_LIB.BASEBOARD_FAB2(SCH_1):PAGE145
    U2 FM_BIOS_TOP_SWAP @BASEBOARD_FAB2_LIB.BASEBOARD_FAB2(SCH_1):FM_BIOS_TOP_SWAP   I117 @BASEBOARD_FAB2_LIB.BASEBOARD_FAB2(SCH_1):PAGE145
    P4 FM_MEM_THERM_EVENT_PCH_N @BASEBOARD_FAB2_LIB.BASEBOARD_FAB2(SCH_1):FM_MEM_THERM_EVENT_PCH_N   I117 @BASEBOARD_FAB2_LIB.BASEBOARD_FAB2(SCH_1):PAGE145
   K22 CLK_100M_BMC_PE_R_DN @BASEBOARD_FAB2_LIB.BASEBOARD_FAB2(SCH_1):CLK_100M_BMC_PE_R_DN   I117 @BASEBOARD_FAB2_LIB.BASEBOARD_FAB2(SCH_1):PAGE145
   K21 CLK_100M_BMC_PE_R_DP @BASEBOARD_FAB2_LIB.BASEBOARD_FAB2(SCH_1):CLK_100M_BMC_PE_R_DP   I117 @BASEBOARD_FAB2_LIB.BASEBOARD_FAB2(SCH_1):PAGE145
    K2 UART_BMC_RXD5 @BASEBOARD_FAB2_LIB.BASEBOARD_FAB2(SCH_1):UART_BMC_RXD5   I117 @BASEBOARD_FAB2_LIB.BASEBOARD_FAB2(SCH_1):PAGE145
  AB18 PECI_BMC_R @BASEBOARD_FAB2_LIB.BASEBOARD_FAB2(SCH_1):PECI_BMC_R   I117 @BASEBOARD_FAB2_LIB.BASEBOARD_FAB2(SCH_1):PAGE145
   D20 FM_BOARD_REV_ID0 @BASEBOARD_FAB2_LIB.BASEBOARD_FAB2(SCH_1):FM_BOARD_REV_ID0   I117 @BASEBOARD_FAB2_LIB.BASEBOARD_FAB2(SCH_1):PAGE145
   D21 FM_BOARD_REV_ID1 @BASEBOARD_FAB2_LIB.BASEBOARD_FAB2(SCH_1):FM_BOARD_REV_ID1   I117 @BASEBOARD_FAB2_LIB.BASEBOARD_FAB2(SCH_1):PAGE145
   E21 FM_MB_SLOT_ID1 @BASEBOARD_FAB2_LIB.BASEBOARD_FAB2(SCH_1):FM_MB_SLOT_ID1   I117 @BASEBOARD_FAB2_LIB.BASEBOARD_FAB2(SCH_1):PAGE145
   W18 CLK_24M_25M_BMC_CLKIN @BASEBOARD_FAB2_LIB.BASEBOARD_FAB2(SCH_1):CLK_24M_25M_BMC_CLKIN   I117 @BASEBOARD_FAB2_LIB.BASEBOARD_FAB2(SCH_1):PAGE145
   U18 RST_BMC_SRST_N @BASEBOARD_FAB2_LIB.BASEBOARD_FAB2(SCH_1):RST_BMC_SRST_N   I117 @BASEBOARD_FAB2_LIB.BASEBOARD_FAB2(SCH_1):PAGE145
   E13 FM_SSATA_PCIE_M2_SEL @BASEBOARD_FAB2_LIB.BASEBOARD_FAB2(SCH_1):FM_SSATA_PCIE_M2_SEL   I117 @BASEBOARD_FAB2_LIB.BASEBOARD_FAB2(SCH_1):PAGE145
   L20 RST_PLTRST_BUF_N @BASEBOARD_FAB2_LIB.BASEBOARD_FAB2(SCH_1):RST_PLTRST_BUF_N   I117 @BASEBOARD_FAB2_LIB.BASEBOARD_FAB2(SCH_1):PAGE145
   M22 P2E_SSB_BMC_TX_C_DN @BASEBOARD_FAB2_LIB.BASEBOARD_FAB2(SCH_1):P2E_SSB_BMC_TX_C_DN   I117 @BASEBOARD_FAB2_LIB.BASEBOARD_FAB2(SCH_1):PAGE145
   M21 P2E_SSB_BMC_TX_C_DP @BASEBOARD_FAB2_LIB.BASEBOARD_FAB2(SCH_1):P2E_SSB_BMC_TX_C_DP   I117 @BASEBOARD_FAB2_LIB.BASEBOARD_FAB2(SCH_1):PAGE145
    Y1 FM_CPU0_RC_ERROR_N @BASEBOARD_FAB2_LIB.BASEBOARD_FAB2(SCH_1):FM_CPU0_RC_ERROR_N   I117 @BASEBOARD_FAB2_LIB.BASEBOARD_FAB2(SCH_1):PAGE145
   AB2 FM_CPU1_RC_ERROR_N @BASEBOARD_FAB2_LIB.BASEBOARD_FAB2(SCH_1):FM_CPU1_RC_ERROR_N   I117 @BASEBOARD_FAB2_LIB.BASEBOARD_FAB2(SCH_1):PAGE145
   AA1 IRQ_BOARD_BMC_ALERT_N @BASEBOARD_FAB2_LIB.BASEBOARD_FAB2(SCH_1):IRQ_BOARD_BMC_ALERT_N   I117 @BASEBOARD_FAB2_LIB.BASEBOARD_FAB2(SCH_1):PAGE145
    Y2 FM_OC_DETECT_EN_N @BASEBOARD_FAB2_LIB.BASEBOARD_FAB2(SCH_1):FM_OC_DETECT_EN_N   I117 @BASEBOARD_FAB2_LIB.BASEBOARD_FAB2(SCH_1):PAGE145
   AA2 FM_BB_BMC_MP_GPIO @BASEBOARD_FAB2_LIB.BASEBOARD_FAB2(SCH_1):FM_BB_BMC_MP_GPIO   I117 @BASEBOARD_FAB2_LIB.BASEBOARD_FAB2(SCH_1):PAGE145
    P5 FM_BMC_CPLD_MP_RST_N @BASEBOARD_FAB2_LIB.BASEBOARD_FAB2(SCH_1):FM_BMC_CPLD_MP_RST_N   I117 @BASEBOARD_FAB2_LIB.BASEBOARD_FAB2(SCH_1):PAGE145
    R5 SP2_BMC_CM_UART_TX @BASEBOARD_FAB2_LIB.BASEBOARD_FAB2(SCH_1):SP2_BMC_CM_UART_TX   I117 @BASEBOARD_FAB2_LIB.BASEBOARD_FAB2(SCH_1):PAGE145
    T5 SP2_BMC_CM_UART_RX @BASEBOARD_FAB2_LIB.BASEBOARD_FAB2(SCH_1):SP2_BMC_CM_UART_RX   I117 @BASEBOARD_FAB2_LIB.BASEBOARD_FAB2(SCH_1):PAGE145
    T1 IRQ_OC_DETECT_N @BASEBOARD_FAB2_LIB.BASEBOARD_FAB2(SCH_1):IRQ_OC_DETECT_N   I117 @BASEBOARD_FAB2_LIB.BASEBOARD_FAB2(SCH_1):PAGE145
    P3 FM_PMBUS_ALERT_BUF_EN_N @BASEBOARD_FAB2_LIB.BASEBOARD_FAB2(SCH_1):FM_PMBUS_ALERT_BUF_EN_N   I117 @BASEBOARD_FAB2_LIB.BASEBOARD_FAB2(SCH_1):PAGE145
    W1 SP1_BMC_HOST_UART_RX @BASEBOARD_FAB2_LIB.BASEBOARD_FAB2(SCH_1):SP1_BMC_HOST_UART_RX   I117 @BASEBOARD_FAB2_LIB.BASEBOARD_FAB2(SCH_1):PAGE145
   J19 IRQ_PVDDQ_ABC_VRHOT_LVT3_N @BASEBOARD_FAB2_LIB.BASEBOARD_FAB2(SCH_1):IRQ_PVDDQ_ABC_VRHOT_LVT3_N   I117 @BASEBOARD_FAB2_LIB.BASEBOARD_FAB2(SCH_1):PAGE145
   J18     NC     NC   I117 @BASEBOARD_FAB2_LIB.BASEBOARD_FAB2(SCH_1):PAGE145
   B22 IRQ_PVCCIN_CPU0_VRHOT_LVC3_N @BASEBOARD_FAB2_LIB.BASEBOARD_FAB2(SCH_1):IRQ_PVCCIN_CPU0_VRHOT_LVC3_N   I117 @BASEBOARD_FAB2_LIB.BASEBOARD_FAB2(SCH_1):PAGE145
   F18 FM_PWR_BTN_N @BASEBOARD_FAB2_LIB.BASEBOARD_FAB2(SCH_1):FM_PWR_BTN_N   I117 @BASEBOARD_FAB2_LIB.BASEBOARD_FAB2(SCH_1):PAGE145
   F17 FM_BMC_PWRBTN_OUT_N @BASEBOARD_FAB2_LIB.BASEBOARD_FAB2(SCH_1):FM_BMC_PWRBTN_OUT_N   I117 @BASEBOARD_FAB2_LIB.BASEBOARD_FAB2(SCH_1):PAGE145
   E18 FP_NMI_BTN_N @BASEBOARD_FAB2_LIB.BASEBOARD_FAB2(SCH_1):FP_NMI_BTN_N   I117 @BASEBOARD_FAB2_LIB.BASEBOARD_FAB2(SCH_1):PAGE145
   A20 FM_CPU0_PROCHOT_LVT3_BMC_N @BASEBOARD_FAB2_LIB.BASEBOARD_FAB2(SCH_1):FM_CPU0_PROCHOT_LVT3_BMC_N   I117 @BASEBOARD_FAB2_LIB.BASEBOARD_FAB2(SCH_1):PAGE145
   B19 FM_CPU1_PROCHOT_LVT3_BMC_N @BASEBOARD_FAB2_LIB.BASEBOARD_FAB2(SCH_1):FM_CPU1_PROCHOT_LVT3_BMC_N   I117 @BASEBOARD_FAB2_LIB.BASEBOARD_FAB2(SCH_1):PAGE145
    K1 UART_BMC_TXD5 @BASEBOARD_FAB2_LIB.BASEBOARD_FAB2(SCH_1):UART_BMC_TXD5   I117 @BASEBOARD_FAB2_LIB.BASEBOARD_FAB2(SCH_1):PAGE145
   K20 PD_PEREXT @BASEBOARD_FAB2_LIB.BASEBOARD_FAB2(SCH_1):PD_PEREXT   I117 @BASEBOARD_FAB2_LIB.BASEBOARD_FAB2(SCH_1):PAGE145
   L22 P2E_SSB_BMC_RX_DN @BASEBOARD_FAB2_LIB.BASEBOARD_FAB2(SCH_1):P2E_SSB_BMC_RX_DN   I117 @BASEBOARD_FAB2_LIB.BASEBOARD_FAB2(SCH_1):PAGE145
   L21 P2E_SSB_BMC_RX_DP @BASEBOARD_FAB2_LIB.BASEBOARD_FAB2(SCH_1):P2E_SSB_BMC_RX_DP   I117 @BASEBOARD_FAB2_LIB.BASEBOARD_FAB2(SCH_1):PAGE145
   D19 IRQ_BMC_PCH_NMI_STBY_N @BASEBOARD_FAB2_LIB.BASEBOARD_FAB2(SCH_1):IRQ_BMC_PCH_NMI_STBY_N   I117 @BASEBOARD_FAB2_LIB.BASEBOARD_FAB2(SCH_1):PAGE145
   C20 RST_BMC_SYSRST_BTN_OUT_N @BASEBOARD_FAB2_LIB.BASEBOARD_FAB2(SCH_1):RST_BMC_SYSRST_BTN_OUT_N   I117 @BASEBOARD_FAB2_LIB.BASEBOARD_FAB2(SCH_1):PAGE145
   B20 RST_SYSTEM_BTN_N @BASEBOARD_FAB2_LIB.BASEBOARD_FAB2(SCH_1):RST_SYSTEM_BTN_N   I117 @BASEBOARD_FAB2_LIB.BASEBOARD_FAB2(SCH_1):PAGE145
   F19 FM_MB_SLOT_ID0 @BASEBOARD_FAB2_LIB.BASEBOARD_FAB2(SCH_1):FM_MB_SLOT_ID0   I117 @BASEBOARD_FAB2_LIB.BASEBOARD_FAB2(SCH_1):PAGE145
   F20 FM_MB_SLOT_ID2 @BASEBOARD_FAB2_LIB.BASEBOARD_FAB2(SCH_1):FM_MB_SLOT_ID2   I117 @BASEBOARD_FAB2_LIB.BASEBOARD_FAB2(SCH_1):PAGE145
   C21 FM_CPU_ERR1_LVT3_BMC_N @BASEBOARD_FAB2_LIB.BASEBOARD_FAB2(SCH_1):FM_CPU_ERR1_LVT3_BMC_N   I117 @BASEBOARD_FAB2_LIB.BASEBOARD_FAB2(SCH_1):PAGE145
   B11 SMB_IE_3V3AUX_SDA @BASEBOARD_FAB2_LIB.BASEBOARD_FAB2(SCH_1):SMB_IE_3V3AUX_SDA   I117 @BASEBOARD_FAB2_LIB.BASEBOARD_FAB2(SCH_1):PAGE145
   E12 SMB_LAN_STBY_LVC3_SDA_R @BASEBOARD_FAB2_LIB.BASEBOARD_FAB2(SCH_1):SMB_LAN_STBY_LVC3_SDA_R   I117 @BASEBOARD_FAB2_LIB.BASEBOARD_FAB2(SCH_1):PAGE145
    T2 IRQ_UV_DETECT_N @BASEBOARD_FAB2_LIB.BASEBOARD_FAB2(SCH_1):IRQ_UV_DETECT_N   I117 @BASEBOARD_FAB2_LIB.BASEBOARD_FAB2(SCH_1):PAGE145
   B21 IRQ_PVCCIN_CPU1_VRHOT_LVC3_N @BASEBOARD_FAB2_LIB.BASEBOARD_FAB2(SCH_1):IRQ_PVCCIN_CPU1_VRHOT_LVC3_N   I117 @BASEBOARD_FAB2_LIB.BASEBOARD_FAB2(SCH_1):PAGE145
   A21 IRQ_PVDDQ_KLM_VRHOT_LVT3_N @BASEBOARD_FAB2_LIB.BASEBOARD_FAB2(SCH_1):IRQ_PVDDQ_KLM_VRHOT_LVT3_N   I117 @BASEBOARD_FAB2_LIB.BASEBOARD_FAB2(SCH_1):PAGE145
   G17 FM_BATTERY_SENSE_EN_N @BASEBOARD_FAB2_LIB.BASEBOARD_FAB2(SCH_1):FM_BATTERY_SENSE_EN_N   I117 @BASEBOARD_FAB2_LIB.BASEBOARD_FAB2(SCH_1):PAGE145
    V1 SP1_BMC_HOST_UART_TX @BASEBOARD_FAB2_LIB.BASEBOARD_FAB2(SCH_1):SP1_BMC_HOST_UART_TX   I117 @BASEBOARD_FAB2_LIB.BASEBOARD_FAB2(SCH_1):PAGE145
   G18 FM_CPU_ERR0_LVT3_BMC_N @BASEBOARD_FAB2_LIB.BASEBOARD_FAB2(SCH_1):FM_CPU_ERR0_LVT3_BMC_N   I117 @BASEBOARD_FAB2_LIB.BASEBOARD_FAB2(SCH_1):PAGE145
   E20 FM_BOARD_REV_ID2 @BASEBOARD_FAB2_LIB.BASEBOARD_FAB2(SCH_1):FM_BOARD_REV_ID2   I117 @BASEBOARD_FAB2_LIB.BASEBOARD_FAB2(SCH_1):PAGE145
    B7 A_USB2BVRES @BASEBOARD_FAB2_LIB.BASEBOARD_FAB2(SCH_1):A_USB2BVRES   I104 @BASEBOARD_FAB2_LIB.BASEBOARD_FAB2(SCH_1):PAGE146
    B8 A_USB2AVRES @BASEBOARD_FAB2_LIB.BASEBOARD_FAB2(SCH_1):A_USB2AVRES   I104 @BASEBOARD_FAB2_LIB.BASEBOARD_FAB2(SCH_1):PAGE146
   A18 LED_POSTCODE_0 @BASEBOARD_FAB2_LIB.BASEBOARD_FAB2(SCH_1):LED_POSTCODE_0   I104 @BASEBOARD_FAB2_LIB.BASEBOARD_FAB2(SCH_1):PAGE146
   D17 LED_POSTCODE_2 @BASEBOARD_FAB2_LIB.BASEBOARD_FAB2(SCH_1):LED_POSTCODE_2   I104 @BASEBOARD_FAB2_LIB.BASEBOARD_FAB2(SCH_1):PAGE146
   B18 LED_POSTCODE_1 @BASEBOARD_FAB2_LIB.BASEBOARD_FAB2(SCH_1):LED_POSTCODE_1   I104 @BASEBOARD_FAB2_LIB.BASEBOARD_FAB2(SCH_1):PAGE146
   A17 LED_POSTCODE_4 @BASEBOARD_FAB2_LIB.BASEBOARD_FAB2(SCH_1):LED_POSTCODE_4   I104 @BASEBOARD_FAB2_LIB.BASEBOARD_FAB2(SCH_1):PAGE146
   C17 LED_POSTCODE_3 @BASEBOARD_FAB2_LIB.BASEBOARD_FAB2(SCH_1):LED_POSTCODE_3   I104 @BASEBOARD_FAB2_LIB.BASEBOARD_FAB2(SCH_1):PAGE146
   B17 LED_POSTCODE_5 @BASEBOARD_FAB2_LIB.BASEBOARD_FAB2(SCH_1):LED_POSTCODE_5   I104 @BASEBOARD_FAB2_LIB.BASEBOARD_FAB2(SCH_1):PAGE146
   D18 LED_POSTCODE_7 @BASEBOARD_FAB2_LIB.BASEBOARD_FAB2(SCH_1):LED_POSTCODE_7   I104 @BASEBOARD_FAB2_LIB.BASEBOARD_FAB2(SCH_1):PAGE146
   A16 LED_POSTCODE_6 @BASEBOARD_FAB2_LIB.BASEBOARD_FAB2(SCH_1):LED_POSTCODE_6   I104 @BASEBOARD_FAB2_LIB.BASEBOARD_FAB2(SCH_1):PAGE146
   V20 FM_THROTTLE_N @BASEBOARD_FAB2_LIB.BASEBOARD_FAB2(SCH_1):FM_THROTTLE_N   I104 @BASEBOARD_FAB2_LIB.BASEBOARD_FAB2(SCH_1):PAGE146
   R18 IRQ_MEZZ_LAN_ALERT_N @BASEBOARD_FAB2_LIB.BASEBOARD_FAB2(SCH_1):IRQ_MEZZ_LAN_ALERT_N   I104 @BASEBOARD_FAB2_LIB.BASEBOARD_FAB2(SCH_1):PAGE146
  AB20 FM_BMC_NMI_N_R @BASEBOARD_FAB2_LIB.BASEBOARD_FAB2(SCH_1):FM_BMC_NMI_N_R   I104 @BASEBOARD_FAB2_LIB.BASEBOARD_FAB2(SCH_1):PAGE146
  AB21 FM_BMC_SYS_THROTTLE_R_N @BASEBOARD_FAB2_LIB.BASEBOARD_FAB2(SCH_1):FM_BMC_SYS_THROTTLE_R_N   I104 @BASEBOARD_FAB2_LIB.BASEBOARD_FAB2(SCH_1):PAGE146
  AA21 IRQ_BMC_PCH_SCI_LPC_N @BASEBOARD_FAB2_LIB.BASEBOARD_FAB2(SCH_1):IRQ_BMC_PCH_SCI_LPC_N   I104 @BASEBOARD_FAB2_LIB.BASEBOARD_FAB2(SCH_1):PAGE146
   U21 HSC_SMBUS_SWITCH_EN @BASEBOARD_FAB2_LIB.BASEBOARD_FAB2(SCH_1):HSC_SMBUS_SWITCH_EN   I104 @BASEBOARD_FAB2_LIB.BASEBOARD_FAB2(SCH_1):PAGE146
   W22 FM_CPU0_THERMTRIP_LATCH_LVT3_N @BASEBOARD_FAB2_LIB.BASEBOARD_FAB2(SCH_1):FM_CPU0_THERMTRIP_LATCH_LVT3_N   I104 @BASEBOARD_FAB2_LIB.BASEBOARD_FAB2(SCH_1):PAGE146
   V22 H_CPU0_MEMABC_MEMHOT_LVT3_BMC_N @BASEBOARD_FAB2_LIB.BASEBOARD_FAB2(SCH_1):H_CPU0_MEMABC_MEMHOT_LVT3_BMC_N   I104 @BASEBOARD_FAB2_LIB.BASEBOARD_FAB2(SCH_1):PAGE146
   W21 FM_CPU1_PROC_ID0 @BASEBOARD_FAB2_LIB.BASEBOARD_FAB2(SCH_1):FM_CPU1_PROC_ID0   I104 @BASEBOARD_FAB2_LIB.BASEBOARD_FAB2(SCH_1):PAGE146
   Y21 FM_CPU1_PROC_ID1 @BASEBOARD_FAB2_LIB.BASEBOARD_FAB2(SCH_1):FM_CPU1_PROC_ID1   I104 @BASEBOARD_FAB2_LIB.BASEBOARD_FAB2(SCH_1):PAGE146
   P18 IRQ_LOM_ALERT_N @BASEBOARD_FAB2_LIB.BASEBOARD_FAB2(SCH_1):IRQ_LOM_ALERT_N   I104 @BASEBOARD_FAB2_LIB.BASEBOARD_FAB2(SCH_1):PAGE146
  AA20 GPIOS7 @BASEBOARD_FAB2_LIB.BASEBOARD_FAB2(SCH_1):GPIOS7   I104 @BASEBOARD_FAB2_LIB.BASEBOARD_FAB2(SCH_1):PAGE146
   Y20 FM_BIOS_SPI_BMC_CTRL @BASEBOARD_FAB2_LIB.BASEBOARD_FAB2(SCH_1):FM_BIOS_SPI_BMC_CTRL   I104 @BASEBOARD_FAB2_LIB.BASEBOARD_FAB2(SCH_1):PAGE146
   Y22 IRQ_OOB_MGMT_RISER_ALERT_N @BASEBOARD_FAB2_LIB.BASEBOARD_FAB2(SCH_1):IRQ_OOB_MGMT_RISER_ALERT_N   I104 @BASEBOARD_FAB2_LIB.BASEBOARD_FAB2(SCH_1):PAGE146
    A7 USB2_PCH_BMC_P5_DP @BASEBOARD_FAB2_LIB.BASEBOARD_FAB2(SCH_1):USB2_PCH_BMC_P5_DP   I104 @BASEBOARD_FAB2_LIB.BASEBOARD_FAB2(SCH_1):PAGE146
    A8 USB2_PCH_BMC_P5_DN @BASEBOARD_FAB2_LIB.BASEBOARD_FAB2(SCH_1):USB2_PCH_BMC_P5_DN   I104 @BASEBOARD_FAB2_LIB.BASEBOARD_FAB2(SCH_1):PAGE146
    B6 USB_PCH_BMC_P4_DP @BASEBOARD_FAB2_LIB.BASEBOARD_FAB2(SCH_1):USB_PCH_BMC_P4_DP   I104 @BASEBOARD_FAB2_LIB.BASEBOARD_FAB2(SCH_1):PAGE146
    A6 USB_PCH_BMC_P4_DN @BASEBOARD_FAB2_LIB.BASEBOARD_FAB2(SCH_1):USB_PCH_BMC_P4_DN   I104 @BASEBOARD_FAB2_LIB.BASEBOARD_FAB2(SCH_1):PAGE146
   U20 FP_PWR_ID_LED_N @BASEBOARD_FAB2_LIB.BASEBOARD_FAB2(SCH_1):FP_PWR_ID_LED_N   I104 @BASEBOARD_FAB2_LIB.BASEBOARD_FAB2(SCH_1):PAGE146
   W20 FM_SPEAKER_PCH_N @BASEBOARD_FAB2_LIB.BASEBOARD_FAB2(SCH_1):FM_SPEAKER_PCH_N   I104 @BASEBOARD_FAB2_LIB.BASEBOARD_FAB2(SCH_1):PAGE146
   R19 H_CPU0_MEMDEF_MEMHOT_LVT3_BMC_N @BASEBOARD_FAB2_LIB.BASEBOARD_FAB2(SCH_1):H_CPU0_MEMDEF_MEMHOT_LVT3_BMC_N   I104 @BASEBOARD_FAB2_LIB.BASEBOARD_FAB2(SCH_1):PAGE146
   U19 FM_BMC_READY_N @BASEBOARD_FAB2_LIB.BASEBOARD_FAB2(SCH_1):FM_BMC_READY_N   I104 @BASEBOARD_FAB2_LIB.BASEBOARD_FAB2(SCH_1):PAGE146
   V21 IRQ_SML1_PMBUS_ALERT_N @BASEBOARD_FAB2_LIB.BASEBOARD_FAB2(SCH_1):IRQ_SML1_PMBUS_ALERT_N   I104 @BASEBOARD_FAB2_LIB.BASEBOARD_FAB2(SCH_1):PAGE146
   P19 FM_BIOS_POST_CMPLT_N @BASEBOARD_FAB2_LIB.BASEBOARD_FAB2(SCH_1):FM_BIOS_POST_CMPLT_N   I104 @BASEBOARD_FAB2_LIB.BASEBOARD_FAB2(SCH_1):PAGE146
   N18     NC     NC   I104 @BASEBOARD_FAB2_LIB.BASEBOARD_FAB2(SCH_1):PAGE146
   T20     NC     NC   I104 @BASEBOARD_FAB2_LIB.BASEBOARD_FAB2(SCH_1):PAGE146
   U22     NC     NC   I104 @BASEBOARD_FAB2_LIB.BASEBOARD_FAB2(SCH_1):PAGE146
  AA22     NC     NC   I104 @BASEBOARD_FAB2_LIB.BASEBOARD_FAB2(SCH_1):PAGE146
   G22 RST_BMC_LVC3_N @BASEBOARD_FAB2_LIB.BASEBOARD_FAB2(SCH_1):RST_BMC_LVC3_N   I105 @BASEBOARD_FAB2_LIB.BASEBOARD_FAB2(SCH_1):PAGE146
    K3 PD_SP_ENTEST @BASEBOARD_FAB2_LIB.BASEBOARD_FAB2(SCH_1):PD_SP_ENTEST   I105 @BASEBOARD_FAB2_LIB.BASEBOARD_FAB2(SCH_1):PAGE146
   V18     NC     NC   I105 @BASEBOARD_FAB2_LIB.BASEBOARD_FAB2(SCH_1):PAGE146
   B10 FM_CPU0_FIVR_FAULT_LVT3_R_N @BASEBOARD_FAB2_LIB.BASEBOARD_FAB2(SCH_1):FM_CPU0_FIVR_FAULT_LVT3_R_N   I105 @BASEBOARD_FAB2_LIB.BASEBOARD_FAB2(SCH_1):PAGE146
   N20 FM_PE_BMC_WAKE_N @BASEBOARD_FAB2_LIB.BASEBOARD_FAB2(SCH_1):FM_PE_BMC_WAKE_N   I105 @BASEBOARD_FAB2_LIB.BASEBOARD_FAB2(SCH_1):PAGE146
   V19 SPI_BMC_DI @BASEBOARD_FAB2_LIB.BASEBOARD_FAB2(SCH_1):SPI_BMC_DI   I105 @BASEBOARD_FAB2_LIB.BASEBOARD_FAB2(SCH_1):PAGE146
   T17 SPI_BMC_CS0_N @BASEBOARD_FAB2_LIB.BASEBOARD_FAB2(SCH_1):SPI_BMC_CS0_N   I105 @BASEBOARD_FAB2_LIB.BASEBOARD_FAB2(SCH_1):PAGE146
   T19 FM_CPU1_THERMTRIP_LATCH_LVT3_N @BASEBOARD_FAB2_LIB.BASEBOARD_FAB2(SCH_1):FM_CPU1_THERMTRIP_LATCH_LVT3_N   I105 @BASEBOARD_FAB2_LIB.BASEBOARD_FAB2(SCH_1):PAGE146
  AA19 SPI_BMC_BT_CS1_N @BASEBOARD_FAB2_LIB.BASEBOARD_FAB2(SCH_1):SPI_BMC_BT_CS1_N   I105 @BASEBOARD_FAB2_LIB.BASEBOARD_FAB2(SCH_1):PAGE146
  AB17 BMC_M_RST_N @BASEBOARD_FAB2_LIB.BASEBOARD_FAB2(SCH_1):BMC_M_RST_N   I105 @BASEBOARD_FAB2_LIB.BASEBOARD_FAB2(SCH_1):PAGE146
   U16 BMC_M_MALERT_N @BASEBOARD_FAB2_LIB.BASEBOARD_FAB2(SCH_1):BMC_M_MALERT_N   I105 @BASEBOARD_FAB2_LIB.BASEBOARD_FAB2(SCH_1):PAGE146
   Y18     NC     NC   I105 @BASEBOARD_FAB2_LIB.BASEBOARD_FAB2(SCH_1):PAGE146
    N5 TP_VGAHS_GPIOJ4 @BASEBOARD_FAB2_LIB.BASEBOARD_FAB2(SCH_1):TP_VGAHS_GPIOJ4   I105 @BASEBOARD_FAB2_LIB.BASEBOARD_FAB2(SCH_1):PAGE146
   U17 SPI_BMC_BT_DO_R @BASEBOARD_FAB2_LIB.BASEBOARD_FAB2(SCH_1):SPI_BMC_BT_DO_R   I105 @BASEBOARD_FAB2_LIB.BASEBOARD_FAB2(SCH_1):PAGE146
  AA18 SPI_BMC_BT_CLK_R @BASEBOARD_FAB2_LIB.BASEBOARD_FAB2(SCH_1):SPI_BMC_BT_CLK_R   I105 @BASEBOARD_FAB2_LIB.BASEBOARD_FAB2(SCH_1):PAGE146
    T3 TP_DDCDAT_GPIOJ7 @BASEBOARD_FAB2_LIB.BASEBOARD_FAB2(SCH_1):TP_DDCDAT_GPIOJ7   I105 @BASEBOARD_FAB2_LIB.BASEBOARD_FAB2(SCH_1):PAGE146
    R3 TP_DDCCLK_GPIOJ6 @BASEBOARD_FAB2_LIB.BASEBOARD_FAB2(SCH_1):TP_DDCCLK_GPIOJ6   I105 @BASEBOARD_FAB2_LIB.BASEBOARD_FAB2(SCH_1):PAGE146
    R4 TP_VGAVS_GPIOJ5 @BASEBOARD_FAB2_LIB.BASEBOARD_FAB2(SCH_1):TP_VGAVS_GPIOJ5   I105 @BASEBOARD_FAB2_LIB.BASEBOARD_FAB2(SCH_1):PAGE146
   R20     NC     NC   I105 @BASEBOARD_FAB2_LIB.BASEBOARD_FAB2(SCH_1):PAGE146
   T22     NC     NC   I105 @BASEBOARD_FAB2_LIB.BASEBOARD_FAB2(SCH_1):PAGE146
   T21     NC     NC   I105 @BASEBOARD_FAB2_LIB.BASEBOARD_FAB2(SCH_1):PAGE146
   N19     NC     NC   I105 @BASEBOARD_FAB2_LIB.BASEBOARD_FAB2(SCH_1):PAGE146
   C22 CLK_24M_BMC_LPC_R1 @BASEBOARD_FAB2_LIB.BASEBOARD_FAB2(SCH_1):CLK_24M_BMC_LPC_R1   I105 @BASEBOARD_FAB2_LIB.BASEBOARD_FAB2(SCH_1):PAGE146
   E22 LPC_LAD3_IO3_R @BASEBOARD_FAB2_LIB.BASEBOARD_FAB2(SCH_1):LPC_LAD3_IO3_R   I105 @BASEBOARD_FAB2_LIB.BASEBOARD_FAB2(SCH_1):PAGE146
   D22 LPC_LAD2_IO2_R @BASEBOARD_FAB2_LIB.BASEBOARD_FAB2(SCH_1):LPC_LAD2_IO2_R   I105 @BASEBOARD_FAB2_LIB.BASEBOARD_FAB2(SCH_1):PAGE146
   G20 LPC_LAD1_IO1_R @BASEBOARD_FAB2_LIB.BASEBOARD_FAB2(SCH_1):LPC_LAD1_IO1_R   I105 @BASEBOARD_FAB2_LIB.BASEBOARD_FAB2(SCH_1):PAGE146
   G21 LPC_LAD0_IO0_R @BASEBOARD_FAB2_LIB.BASEBOARD_FAB2(SCH_1):LPC_LAD0_IO0_R   I105 @BASEBOARD_FAB2_LIB.BASEBOARD_FAB2(SCH_1):PAGE146
   T18 SPI_BMC_BT_DI @BASEBOARD_FAB2_LIB.BASEBOARD_FAB2(SCH_1):SPI_BMC_BT_DI   I105 @BASEBOARD_FAB2_LIB.BASEBOARD_FAB2(SCH_1):PAGE146
  AB19 SPI_BMC_BT_CS_R_N @BASEBOARD_FAB2_LIB.BASEBOARD_FAB2(SCH_1):SPI_BMC_BT_CS_R_N   I105 @BASEBOARD_FAB2_LIB.BASEBOARD_FAB2(SCH_1):PAGE146
   F22 IRQ_LPC_SERIRQ_R @BASEBOARD_FAB2_LIB.BASEBOARD_FAB2(SCH_1):IRQ_LPC_SERIRQ_R   I105 @BASEBOARD_FAB2_LIB.BASEBOARD_FAB2(SCH_1):PAGE146
   F21 LPC_LFRAME_N_CS0_R_N @BASEBOARD_FAB2_LIB.BASEBOARD_FAB2(SCH_1):LPC_LFRAME_N_CS0_R_N   I105 @BASEBOARD_FAB2_LIB.BASEBOARD_FAB2(SCH_1):PAGE146
   Y19 SPI_BMC_CLK @BASEBOARD_FAB2_LIB.BASEBOARD_FAB2(SCH_1):SPI_BMC_CLK   I105 @BASEBOARD_FAB2_LIB.BASEBOARD_FAB2(SCH_1):PAGE146
   W19 SPI_BMC_DO @BASEBOARD_FAB2_LIB.BASEBOARD_FAB2(SCH_1):SPI_BMC_DO   I105 @BASEBOARD_FAB2_LIB.BASEBOARD_FAB2(SCH_1):PAGE146
    F2     NC     NC   I106 @BASEBOARD_FAB2_LIB.BASEBOARD_FAB2(SCH_1):PAGE147
    G4 A_P3V_BAT_SCALED @BASEBOARD_FAB2_LIB.BASEBOARD_FAB2(SCH_1):A_P3V_BAT_SCALED   I106 @BASEBOARD_FAB2_LIB.BASEBOARD_FAB2(SCH_1):PAGE147
   C13 FM_FORCE_ADR_N @BASEBOARD_FAB2_LIB.BASEBOARD_FAB2(SCH_1):FM_FORCE_ADR_N   I106 @BASEBOARD_FAB2_LIB.BASEBOARD_FAB2(SCH_1):PAGE147
   B13 FM_UV_ADR_TRIGGER_EN @BASEBOARD_FAB2_LIB.BASEBOARD_FAB2(SCH_1):FM_UV_ADR_TRIGGER_EN   I106 @BASEBOARD_FAB2_LIB.BASEBOARD_FAB2(SCH_1):PAGE147
    D3    GND @BASEBOARD_FAB2_LIB.BASEBOARD_FAB2(SCH_1):GND   I106 @BASEBOARD_FAB2_LIB.BASEBOARD_FAB2(SCH_1):PAGE147
    Y3 FM_UARTSW_LSB_N @BASEBOARD_FAB2_LIB.BASEBOARD_FAB2(SCH_1):FM_UARTSW_LSB_N   I106 @BASEBOARD_FAB2_LIB.BASEBOARD_FAB2(SCH_1):PAGE147
    T4 FM_UARTSW_MSB_N @BASEBOARD_FAB2_LIB.BASEBOARD_FAB2(SCH_1):FM_UARTSW_MSB_N   I106 @BASEBOARD_FAB2_LIB.BASEBOARD_FAB2(SCH_1):PAGE147
    W3 FM_BACKUP_BIOS_SEL_N @BASEBOARD_FAB2_LIB.BASEBOARD_FAB2(SCH_1):FM_BACKUP_BIOS_SEL_N   I106 @BASEBOARD_FAB2_LIB.BASEBOARD_FAB2(SCH_1):PAGE147
   AA3 FM_CPLD_BMC_PWRDN_N @BASEBOARD_FAB2_LIB.BASEBOARD_FAB2(SCH_1):FM_CPLD_BMC_PWRDN_N   I106 @BASEBOARD_FAB2_LIB.BASEBOARD_FAB2(SCH_1):PAGE147
    U3 FM_CPU_MSMI_LVT3_N @BASEBOARD_FAB2_LIB.BASEBOARD_FAB2(SCH_1):FM_CPU_MSMI_LVT3_N   I106 @BASEBOARD_FAB2_LIB.BASEBOARD_FAB2(SCH_1):PAGE147
    W2 FAN_PWM_OUT_SYS1 @BASEBOARD_FAB2_LIB.BASEBOARD_FAB2(SCH_1):FAN_PWM_OUT_SYS1   I106 @BASEBOARD_FAB2_LIB.BASEBOARD_FAB2(SCH_1):PAGE147
    V3 FM_BIOS_PREFRB2_GOOD @BASEBOARD_FAB2_LIB.BASEBOARD_FAB2(SCH_1):FM_BIOS_PREFRB2_GOOD   I106 @BASEBOARD_FAB2_LIB.BASEBOARD_FAB2(SCH_1):PAGE147
    V2 FAN_PWM_OUT_SYS0 @BASEBOARD_FAB2_LIB.BASEBOARD_FAB2(SCH_1):FAN_PWM_OUT_SYS0   I106 @BASEBOARD_FAB2_LIB.BASEBOARD_FAB2(SCH_1):PAGE147
    H2 P3V3_STBY_BMC_ADCVREFP @BASEBOARD_FAB2_LIB.BASEBOARD_FAB2(SCH_1):P3V3_STBY_BMC_ADCVREFP   I106 @BASEBOARD_FAB2_LIB.BASEBOARD_FAB2(SCH_1):PAGE147
    J1 PD_ADCREXT @BASEBOARD_FAB2_LIB.BASEBOARD_FAB2(SCH_1):PD_ADCREXT   I106 @BASEBOARD_FAB2_LIB.BASEBOARD_FAB2(SCH_1):PAGE147
    H1 P3V3_STBY_BMC_ADCVREFN @BASEBOARD_FAB2_LIB.BASEBOARD_FAB2(SCH_1):P3V3_STBY_BMC_ADCVREFN   I106 @BASEBOARD_FAB2_LIB.BASEBOARD_FAB2(SCH_1):PAGE147
    H3     NC     NC   I106 @BASEBOARD_FAB2_LIB.BASEBOARD_FAB2(SCH_1):PAGE147
    H4     NC     NC   I106 @BASEBOARD_FAB2_LIB.BASEBOARD_FAB2(SCH_1):PAGE147
    G1     NC     NC   I106 @BASEBOARD_FAB2_LIB.BASEBOARD_FAB2(SCH_1):PAGE147
    H5     NC     NC   I106 @BASEBOARD_FAB2_LIB.BASEBOARD_FAB2(SCH_1):PAGE147
    F1     NC     NC   I106 @BASEBOARD_FAB2_LIB.BASEBOARD_FAB2(SCH_1):PAGE147
    G3     NC     NC   I106 @BASEBOARD_FAB2_LIB.BASEBOARD_FAB2(SCH_1):PAGE147
    G2     NC     NC   I106 @BASEBOARD_FAB2_LIB.BASEBOARD_FAB2(SCH_1):PAGE147
    G5 A_P3V3_STBY_SCALED @BASEBOARD_FAB2_LIB.BASEBOARD_FAB2(SCH_1):A_P3V3_STBY_SCALED   I106 @BASEBOARD_FAB2_LIB.BASEBOARD_FAB2(SCH_1):PAGE147
    F3 A_P5V_SCALED @BASEBOARD_FAB2_LIB.BASEBOARD_FAB2(SCH_1):A_P5V_SCALED   I106 @BASEBOARD_FAB2_LIB.BASEBOARD_FAB2(SCH_1):PAGE147
    E3 A_P12V_STBY_SCALED @BASEBOARD_FAB2_LIB.BASEBOARD_FAB2(SCH_1):A_P12V_STBY_SCALED   I106 @BASEBOARD_FAB2_LIB.BASEBOARD_FAB2(SCH_1):PAGE147
    E1 A_P1V05_STBY_PCH_SENSOR @BASEBOARD_FAB2_LIB.BASEBOARD_FAB2(SCH_1):A_P1V05_STBY_PCH_SENSOR   I106 @BASEBOARD_FAB2_LIB.BASEBOARD_FAB2(SCH_1):PAGE147
    E2 A_PVNN_STBY_PCH_SENSOR @BASEBOARD_FAB2_LIB.BASEBOARD_FAB2(SCH_1):A_PVNN_STBY_PCH_SENSOR   I106 @BASEBOARD_FAB2_LIB.BASEBOARD_FAB2(SCH_1):PAGE147
    F5 A_P3V3_SCALED @BASEBOARD_FAB2_LIB.BASEBOARD_FAB2(SCH_1):A_P3V3_SCALED   I106 @BASEBOARD_FAB2_LIB.BASEBOARD_FAB2(SCH_1):PAGE147
    F4 A_P5V_STBY_SCALED @BASEBOARD_FAB2_LIB.BASEBOARD_FAB2(SCH_1):A_P5V_STBY_SCALED   I106 @BASEBOARD_FAB2_LIB.BASEBOARD_FAB2(SCH_1):PAGE147
    V6 FM_TPM_PRES_N @BASEBOARD_FAB2_LIB.BASEBOARD_FAB2(SCH_1):FM_TPM_PRES_N   I106 @BASEBOARD_FAB2_LIB.BASEBOARD_FAB2(SCH_1):PAGE147
    W6 FM_BOARD_SKU_ID4 @BASEBOARD_FAB2_LIB.BASEBOARD_FAB2(SCH_1):FM_BOARD_SKU_ID4   I106 @BASEBOARD_FAB2_LIB.BASEBOARD_FAB2(SCH_1):PAGE147
   AB5 FM_BOARD_SKU_ID1 @BASEBOARD_FAB2_LIB.BASEBOARD_FAB2(SCH_1):FM_BOARD_SKU_ID1   I106 @BASEBOARD_FAB2_LIB.BASEBOARD_FAB2(SCH_1):PAGE147
    Y6 FM_BOARD_SKU_ID2 @BASEBOARD_FAB2_LIB.BASEBOARD_FAB2(SCH_1):FM_BOARD_SKU_ID2   I106 @BASEBOARD_FAB2_LIB.BASEBOARD_FAB2(SCH_1):PAGE147
    Y5 FM_BOARD_SKU_ID3 @BASEBOARD_FAB2_LIB.BASEBOARD_FAB2(SCH_1):FM_BOARD_SKU_ID3   I106 @BASEBOARD_FAB2_LIB.BASEBOARD_FAB2(SCH_1):PAGE147
   AA5 FM_BOARD_SKU_ID0 @BASEBOARD_FAB2_LIB.BASEBOARD_FAB2(SCH_1):FM_BOARD_SKU_ID0   I106 @BASEBOARD_FAB2_LIB.BASEBOARD_FAB2(SCH_1):PAGE147
    W5 BMC_UV_HIGH_SET @BASEBOARD_FAB2_LIB.BASEBOARD_FAB2(SCH_1):BMC_UV_HIGH_SET   I106 @BASEBOARD_FAB2_LIB.BASEBOARD_FAB2(SCH_1):PAGE147
   AA4 FM_XRC_PRESENT_N @BASEBOARD_FAB2_LIB.BASEBOARD_FAB2(SCH_1):FM_XRC_PRESENT_N   I106 @BASEBOARD_FAB2_LIB.BASEBOARD_FAB2(SCH_1):PAGE147
    W4 FM_XRC_READY_N @BASEBOARD_FAB2_LIB.BASEBOARD_FAB2(SCH_1):FM_XRC_READY_N   I106 @BASEBOARD_FAB2_LIB.BASEBOARD_FAB2(SCH_1):PAGE147
    V4 BMC_TPM_HW_RST @BASEBOARD_FAB2_LIB.BASEBOARD_FAB2(SCH_1):BMC_TPM_HW_RST   I106 @BASEBOARD_FAB2_LIB.BASEBOARD_FAB2(SCH_1):PAGE147
   AB3 FM_POST_CARD_PRES_BMC_N @BASEBOARD_FAB2_LIB.BASEBOARD_FAB2(SCH_1):FM_POST_CARD_PRES_BMC_N   I106 @BASEBOARD_FAB2_LIB.BASEBOARD_FAB2(SCH_1):PAGE147
    Y4 FM_MP_PS_REDUNDANT_LOST_N @BASEBOARD_FAB2_LIB.BASEBOARD_FAB2(SCH_1):FM_MP_PS_REDUNDANT_LOST_N   I106 @BASEBOARD_FAB2_LIB.BASEBOARD_FAB2(SCH_1):PAGE147
   AB4 FAN_TACH3 @BASEBOARD_FAB2_LIB.BASEBOARD_FAB2(SCH_1):FAN_TACH3   I106 @BASEBOARD_FAB2_LIB.BASEBOARD_FAB2(SCH_1):PAGE147
    U4 FAN_TACH1 @BASEBOARD_FAB2_LIB.BASEBOARD_FAB2(SCH_1):FAN_TACH1   I106 @BASEBOARD_FAB2_LIB.BASEBOARD_FAB2(SCH_1):PAGE147
    V5 FAN_TACH2 @BASEBOARD_FAB2_LIB.BASEBOARD_FAB2(SCH_1):FAN_TACH2   I106 @BASEBOARD_FAB2_LIB.BASEBOARD_FAB2(SCH_1):PAGE147
    U5 FAN_TACH0 @BASEBOARD_FAB2_LIB.BASEBOARD_FAB2(SCH_1):FAN_TACH0   I106 @BASEBOARD_FAB2_LIB.BASEBOARD_FAB2(SCH_1):PAGE147
    B1 RMII_BMC_SPRNGVLLE_TXEN_R @BASEBOARD_FAB2_LIB.BASEBOARD_FAB2(SCH_1):RMII_BMC_SPRNGVLLE_TXEN_R   I106 @BASEBOARD_FAB2_LIB.BASEBOARD_FAB2(SCH_1):PAGE147
    B2     NC     NC   I106 @BASEBOARD_FAB2_LIB.BASEBOARD_FAB2(SCH_1):PAGE147
    D5 TP_RGMII2TXD2_GPIOT4 @BASEBOARD_FAB2_LIB.BASEBOARD_FAB2(SCH_1):TP_RGMII2TXD2_GPIOT4   I106 @BASEBOARD_FAB2_LIB.BASEBOARD_FAB2(SCH_1):PAGE147
    D4 TP_RGMII2TXD3_GPIOT5 @BASEBOARD_FAB2_LIB.BASEBOARD_FAB2(SCH_1):TP_RGMII2TXD3_GPIOT5   I106 @BASEBOARD_FAB2_LIB.BASEBOARD_FAB2(SCH_1):PAGE147
    B3 RMII_BMC_PCH_SPRNGVLLE_TXD1_R @BASEBOARD_FAB2_LIB.BASEBOARD_FAB2(SCH_1):RMII_BMC_PCH_SPRNGVLLE_TXD1_R   I106 @BASEBOARD_FAB2_LIB.BASEBOARD_FAB2(SCH_1):PAGE147
    A2 RMII_BMC_PCH_SPRNGVLLE_TXD0_R @BASEBOARD_FAB2_LIB.BASEBOARD_FAB2(SCH_1):RMII_BMC_PCH_SPRNGVLLE_TXD0_R   I106 @BASEBOARD_FAB2_LIB.BASEBOARD_FAB2(SCH_1):PAGE147
    B5 H_CPU0_FAST_WAKE_LVT3_N @BASEBOARD_FAB2_LIB.BASEBOARD_FAB2(SCH_1):H_CPU0_FAST_WAKE_LVT3_N   I106 @BASEBOARD_FAB2_LIB.BASEBOARD_FAB2(SCH_1):PAGE147
    E9 RMII_BMC_OCP_TXEN_R @BASEBOARD_FAB2_LIB.BASEBOARD_FAB2(SCH_1):RMII_BMC_OCP_TXEN_R   I106 @BASEBOARD_FAB2_LIB.BASEBOARD_FAB2(SCH_1):PAGE147
    E7 TP_RGMII1TXD2_GPIOT4 @BASEBOARD_FAB2_LIB.BASEBOARD_FAB2(SCH_1):TP_RGMII1TXD2_GPIOT4   I106 @BASEBOARD_FAB2_LIB.BASEBOARD_FAB2(SCH_1):PAGE147
    D7 TP_RGMII1TXD3_GPIOT5 @BASEBOARD_FAB2_LIB.BASEBOARD_FAB2(SCH_1):TP_RGMII1TXD3_GPIOT5   I106 @BASEBOARD_FAB2_LIB.BASEBOARD_FAB2(SCH_1):PAGE147
    F9 RMII_BMC_OCP_TXD0_R @BASEBOARD_FAB2_LIB.BASEBOARD_FAB2(SCH_1):RMII_BMC_OCP_TXD0_R   I106 @BASEBOARD_FAB2_LIB.BASEBOARD_FAB2(SCH_1):PAGE147
    A5 RMII_BMC_OCP_TXD1_R @BASEBOARD_FAB2_LIB.BASEBOARD_FAB2(SCH_1):RMII_BMC_OCP_TXD1_R   I106 @BASEBOARD_FAB2_LIB.BASEBOARD_FAB2(SCH_1):PAGE147
    C1    GND @BASEBOARD_FAB2_LIB.BASEBOARD_FAB2(SCH_1):GND   I106 @BASEBOARD_FAB2_LIB.BASEBOARD_FAB2(SCH_1):PAGE147
    D8 FM_CPU0_PROC_ID0 @BASEBOARD_FAB2_LIB.BASEBOARD_FAB2(SCH_1):FM_CPU0_PROC_ID0   I106 @BASEBOARD_FAB2_LIB.BASEBOARD_FAB2(SCH_1):PAGE147
   E10 FM_CPU0_PROC_ID1 @BASEBOARD_FAB2_LIB.BASEBOARD_FAB2(SCH_1):FM_CPU0_PROC_ID1   I106 @BASEBOARD_FAB2_LIB.BASEBOARD_FAB2(SCH_1):PAGE147
    A3 RMII_BMC_OCP_RXD0 @BASEBOARD_FAB2_LIB.BASEBOARD_FAB2(SCH_1):RMII_BMC_OCP_RXD0   I106 @BASEBOARD_FAB2_LIB.BASEBOARD_FAB2(SCH_1):PAGE147
    D6 RMII_BMC_OCP_RXD1 @BASEBOARD_FAB2_LIB.BASEBOARD_FAB2(SCH_1):RMII_BMC_OCP_RXD1   I106 @BASEBOARD_FAB2_LIB.BASEBOARD_FAB2(SCH_1):PAGE147
    C5 RMII_BMC_OCP_CRSDV @BASEBOARD_FAB2_LIB.BASEBOARD_FAB2(SCH_1):RMII_BMC_OCP_CRSDV   I106 @BASEBOARD_FAB2_LIB.BASEBOARD_FAB2(SCH_1):PAGE147
    C4 RMII_BMC_OCP_RXER @BASEBOARD_FAB2_LIB.BASEBOARD_FAB2(SCH_1):RMII_BMC_OCP_RXER   I106 @BASEBOARD_FAB2_LIB.BASEBOARD_FAB2(SCH_1):PAGE147
    A4 H_CPU1_MEMKLM_MEMHOT_LVT3_BMC_N @BASEBOARD_FAB2_LIB.BASEBOARD_FAB2(SCH_1):H_CPU1_MEMKLM_MEMHOT_LVT3_BMC_N   I106 @BASEBOARD_FAB2_LIB.BASEBOARD_FAB2(SCH_1):PAGE147
    B4 CLK_50M_CKMNG_BMC_1 @BASEBOARD_FAB2_LIB.BASEBOARD_FAB2(SCH_1):CLK_50M_CKMNG_BMC_1   I106 @BASEBOARD_FAB2_LIB.BASEBOARD_FAB2(SCH_1):PAGE147
    C3 RMII_SPRNGVLLE_BMC_PCH_RXD0 @BASEBOARD_FAB2_LIB.BASEBOARD_FAB2(SCH_1):RMII_SPRNGVLLE_BMC_PCH_RXD0   I106 @BASEBOARD_FAB2_LIB.BASEBOARD_FAB2(SCH_1):PAGE147
    D1 RMII_SPRNGVLLE_BMC_PCH_RXD1 @BASEBOARD_FAB2_LIB.BASEBOARD_FAB2(SCH_1):RMII_SPRNGVLLE_BMC_PCH_RXD1   I106 @BASEBOARD_FAB2_LIB.BASEBOARD_FAB2(SCH_1):PAGE147
    D2 RMII_BMC_PCH_SPRNGVLLE_CRSDV @BASEBOARD_FAB2_LIB.BASEBOARD_FAB2(SCH_1):RMII_BMC_PCH_SPRNGVLLE_CRSDV   I106 @BASEBOARD_FAB2_LIB.BASEBOARD_FAB2(SCH_1):PAGE147
    E6 RMII_BMC_PCH_SPRNGVLLE_RXER @BASEBOARD_FAB2_LIB.BASEBOARD_FAB2(SCH_1):RMII_BMC_PCH_SPRNGVLLE_RXER   I106 @BASEBOARD_FAB2_LIB.BASEBOARD_FAB2(SCH_1):PAGE147
    C2 CLK_50M_CKMNG_BMC_2 @BASEBOARD_FAB2_LIB.BASEBOARD_FAB2(SCH_1):CLK_50M_CKMNG_BMC_2   I106 @BASEBOARD_FAB2_LIB.BASEBOARD_FAB2(SCH_1):PAGE147
   K17 P3V3_STBY @BASEBOARD_FAB2_LIB.BASEBOARD_FAB2(SCH_1):P3V3_STBY    I28 @BASEBOARD_FAB2_LIB.BASEBOARD_FAB2(SCH_1):PAGE148
   J17 P3V3_STBY @BASEBOARD_FAB2_LIB.BASEBOARD_FAB2(SCH_1):P3V3_STBY    I28 @BASEBOARD_FAB2_LIB.BASEBOARD_FAB2(SCH_1):PAGE148
    E5    GND @BASEBOARD_FAB2_LIB.BASEBOARD_FAB2(SCH_1):GND    I28 @BASEBOARD_FAB2_LIB.BASEBOARD_FAB2(SCH_1):PAGE148
    K6 VCC_DACAV3V3 @BASEBOARD_FAB2_LIB.BASEBOARD_FAB2(SCH_1):VCC_DACAV3V3    I28 @BASEBOARD_FAB2_LIB.BASEBOARD_FAB2(SCH_1):PAGE148
   F12 VCC_D_3V3 @BASEBOARD_FAB2_LIB.BASEBOARD_FAB2(SCH_1):VCC_D_3V3    I28 @BASEBOARD_FAB2_LIB.BASEBOARD_FAB2(SCH_1):PAGE148
    T8 P1V2_AUX_BMC @BASEBOARD_FAB2_LIB.BASEBOARD_FAB2(SCH_1):P1V2_AUX_BMC    I28 @BASEBOARD_FAB2_LIB.BASEBOARD_FAB2(SCH_1):PAGE148
   P22 FM_CPU1_FIVR_FAULT_LVT3_R_N @BASEBOARD_FAB2_LIB.BASEBOARD_FAB2(SCH_1):FM_CPU1_FIVR_FAULT_LVT3_R_N    I28 @BASEBOARD_FAB2_LIB.BASEBOARD_FAB2(SCH_1):PAGE148
   R21 FM_SLPS4_N @BASEBOARD_FAB2_LIB.BASEBOARD_FAB2(SCH_1):FM_SLPS4_N    I28 @BASEBOARD_FAB2_LIB.BASEBOARD_FAB2(SCH_1):PAGE148
   R22 FM_SLPS3_N @BASEBOARD_FAB2_LIB.BASEBOARD_FAB2(SCH_1):FM_SLPS3_N    I28 @BASEBOARD_FAB2_LIB.BASEBOARD_FAB2(SCH_1):PAGE148
    F6 P1V15_AUX_BMC @BASEBOARD_FAB2_LIB.BASEBOARD_FAB2(SCH_1):P1V15_AUX_BMC    I28 @BASEBOARD_FAB2_LIB.BASEBOARD_FAB2(SCH_1):PAGE148
   G10 P1V15_AUX_BMC @BASEBOARD_FAB2_LIB.BASEBOARD_FAB2(SCH_1):P1V15_AUX_BMC    I28 @BASEBOARD_FAB2_LIB.BASEBOARD_FAB2(SCH_1):PAGE148
   G11 P1V15_AUX_BMC @BASEBOARD_FAB2_LIB.BASEBOARD_FAB2(SCH_1):P1V15_AUX_BMC    I28 @BASEBOARD_FAB2_LIB.BASEBOARD_FAB2(SCH_1):PAGE148
   G12 P1V15_AUX_BMC @BASEBOARD_FAB2_LIB.BASEBOARD_FAB2(SCH_1):P1V15_AUX_BMC    I28 @BASEBOARD_FAB2_LIB.BASEBOARD_FAB2(SCH_1):PAGE148
   G13 P1V15_AUX_BMC @BASEBOARD_FAB2_LIB.BASEBOARD_FAB2(SCH_1):P1V15_AUX_BMC    I28 @BASEBOARD_FAB2_LIB.BASEBOARD_FAB2(SCH_1):PAGE148
   G14 P1V15_AUX_BMC @BASEBOARD_FAB2_LIB.BASEBOARD_FAB2(SCH_1):P1V15_AUX_BMC    I28 @BASEBOARD_FAB2_LIB.BASEBOARD_FAB2(SCH_1):PAGE148
   G15 P1V15_AUX_BMC @BASEBOARD_FAB2_LIB.BASEBOARD_FAB2(SCH_1):P1V15_AUX_BMC    I28 @BASEBOARD_FAB2_LIB.BASEBOARD_FAB2(SCH_1):PAGE148
    G7 P1V15_AUX_BMC @BASEBOARD_FAB2_LIB.BASEBOARD_FAB2(SCH_1):P1V15_AUX_BMC    I28 @BASEBOARD_FAB2_LIB.BASEBOARD_FAB2(SCH_1):PAGE148
    G8 P1V15_AUX_BMC @BASEBOARD_FAB2_LIB.BASEBOARD_FAB2(SCH_1):P1V15_AUX_BMC    I28 @BASEBOARD_FAB2_LIB.BASEBOARD_FAB2(SCH_1):PAGE148
    G9 P1V15_AUX_BMC @BASEBOARD_FAB2_LIB.BASEBOARD_FAB2(SCH_1):P1V15_AUX_BMC    I28 @BASEBOARD_FAB2_LIB.BASEBOARD_FAB2(SCH_1):PAGE148
   H16 P1V15_AUX_BMC @BASEBOARD_FAB2_LIB.BASEBOARD_FAB2(SCH_1):P1V15_AUX_BMC    I28 @BASEBOARD_FAB2_LIB.BASEBOARD_FAB2(SCH_1):PAGE148
   J16 P1V15_AUX_BMC @BASEBOARD_FAB2_LIB.BASEBOARD_FAB2(SCH_1):P1V15_AUX_BMC    I28 @BASEBOARD_FAB2_LIB.BASEBOARD_FAB2(SCH_1):PAGE148
    L7 P1V15_AUX_BMC @BASEBOARD_FAB2_LIB.BASEBOARD_FAB2(SCH_1):P1V15_AUX_BMC    I28 @BASEBOARD_FAB2_LIB.BASEBOARD_FAB2(SCH_1):PAGE148
   N16 P1V15_AUX_BMC @BASEBOARD_FAB2_LIB.BASEBOARD_FAB2(SCH_1):P1V15_AUX_BMC    I28 @BASEBOARD_FAB2_LIB.BASEBOARD_FAB2(SCH_1):PAGE148
    N7 P1V15_AUX_BMC @BASEBOARD_FAB2_LIB.BASEBOARD_FAB2(SCH_1):P1V15_AUX_BMC    I28 @BASEBOARD_FAB2_LIB.BASEBOARD_FAB2(SCH_1):PAGE148
   P10 P1V15_AUX_BMC @BASEBOARD_FAB2_LIB.BASEBOARD_FAB2(SCH_1):P1V15_AUX_BMC    I28 @BASEBOARD_FAB2_LIB.BASEBOARD_FAB2(SCH_1):PAGE148
   P11 P1V15_AUX_BMC @BASEBOARD_FAB2_LIB.BASEBOARD_FAB2(SCH_1):P1V15_AUX_BMC    I28 @BASEBOARD_FAB2_LIB.BASEBOARD_FAB2(SCH_1):PAGE148
   P12 P1V15_AUX_BMC @BASEBOARD_FAB2_LIB.BASEBOARD_FAB2(SCH_1):P1V15_AUX_BMC    I28 @BASEBOARD_FAB2_LIB.BASEBOARD_FAB2(SCH_1):PAGE148
   P13 P1V15_AUX_BMC @BASEBOARD_FAB2_LIB.BASEBOARD_FAB2(SCH_1):P1V15_AUX_BMC    I28 @BASEBOARD_FAB2_LIB.BASEBOARD_FAB2(SCH_1):PAGE148
   P14 P1V15_AUX_BMC @BASEBOARD_FAB2_LIB.BASEBOARD_FAB2(SCH_1):P1V15_AUX_BMC    I28 @BASEBOARD_FAB2_LIB.BASEBOARD_FAB2(SCH_1):PAGE148
   P16 P1V15_AUX_BMC @BASEBOARD_FAB2_LIB.BASEBOARD_FAB2(SCH_1):P1V15_AUX_BMC    I28 @BASEBOARD_FAB2_LIB.BASEBOARD_FAB2(SCH_1):PAGE148
    P7 P1V15_AUX_BMC @BASEBOARD_FAB2_LIB.BASEBOARD_FAB2(SCH_1):P1V15_AUX_BMC    I28 @BASEBOARD_FAB2_LIB.BASEBOARD_FAB2(SCH_1):PAGE148
    P9 P1V15_AUX_BMC @BASEBOARD_FAB2_LIB.BASEBOARD_FAB2(SCH_1):P1V15_AUX_BMC    I28 @BASEBOARD_FAB2_LIB.BASEBOARD_FAB2(SCH_1):PAGE148
   R16 P1V15_AUX_BMC @BASEBOARD_FAB2_LIB.BASEBOARD_FAB2(SCH_1):P1V15_AUX_BMC    I28 @BASEBOARD_FAB2_LIB.BASEBOARD_FAB2(SCH_1):PAGE148
    R7 P1V15_AUX_BMC @BASEBOARD_FAB2_LIB.BASEBOARD_FAB2(SCH_1):P1V15_AUX_BMC    I28 @BASEBOARD_FAB2_LIB.BASEBOARD_FAB2(SCH_1):PAGE148
    L5 VCC_A_1V1 @BASEBOARD_FAB2_LIB.BASEBOARD_FAB2(SCH_1):VCC_A_1V1    I28 @BASEBOARD_FAB2_LIB.BASEBOARD_FAB2(SCH_1):PAGE148
    L6 VCC_A_1V1 @BASEBOARD_FAB2_LIB.BASEBOARD_FAB2(SCH_1):VCC_A_1V1    I28 @BASEBOARD_FAB2_LIB.BASEBOARD_FAB2(SCH_1):PAGE148
   L17 P1V15_AUX_BMC @BASEBOARD_FAB2_LIB.BASEBOARD_FAB2(SCH_1):P1V15_AUX_BMC    I28 @BASEBOARD_FAB2_LIB.BASEBOARD_FAB2(SCH_1):PAGE148
   V17 P1V15_AUX_BMC @BASEBOARD_FAB2_LIB.BASEBOARD_FAB2(SCH_1):P1V15_AUX_BMC    I28 @BASEBOARD_FAB2_LIB.BASEBOARD_FAB2(SCH_1):PAGE148
  AA17 PVCCIO_CPU0 @BASEBOARD_FAB2_LIB.BASEBOARD_FAB2(SCH_1):PVCCIO_CPU0    I28 @BASEBOARD_FAB2_LIB.BASEBOARD_FAB2(SCH_1):PAGE148
   T10 P1V2_AUX_BMC @BASEBOARD_FAB2_LIB.BASEBOARD_FAB2(SCH_1):P1V2_AUX_BMC    I28 @BASEBOARD_FAB2_LIB.BASEBOARD_FAB2(SCH_1):PAGE148
   T12 P1V2_AUX_BMC @BASEBOARD_FAB2_LIB.BASEBOARD_FAB2(SCH_1):P1V2_AUX_BMC    I28 @BASEBOARD_FAB2_LIB.BASEBOARD_FAB2(SCH_1):PAGE148
   T13 P1V2_AUX_BMC @BASEBOARD_FAB2_LIB.BASEBOARD_FAB2(SCH_1):P1V2_AUX_BMC    I28 @BASEBOARD_FAB2_LIB.BASEBOARD_FAB2(SCH_1):PAGE148
   T14 P1V2_AUX_BMC @BASEBOARD_FAB2_LIB.BASEBOARD_FAB2(SCH_1):P1V2_AUX_BMC    I28 @BASEBOARD_FAB2_LIB.BASEBOARD_FAB2(SCH_1):PAGE148
   F13 VCC_D_3V3 @BASEBOARD_FAB2_LIB.BASEBOARD_FAB2(SCH_1):VCC_D_3V3    I28 @BASEBOARD_FAB2_LIB.BASEBOARD_FAB2(SCH_1):PAGE148
   F14 VCC_D_3V3 @BASEBOARD_FAB2_LIB.BASEBOARD_FAB2(SCH_1):VCC_D_3V3    I28 @BASEBOARD_FAB2_LIB.BASEBOARD_FAB2(SCH_1):PAGE148
   F15 VCC_D_3V3 @BASEBOARD_FAB2_LIB.BASEBOARD_FAB2(SCH_1):VCC_D_3V3    I28 @BASEBOARD_FAB2_LIB.BASEBOARD_FAB2(SCH_1):PAGE148
   G16 VCC_D_3V3 @BASEBOARD_FAB2_LIB.BASEBOARD_FAB2(SCH_1):VCC_D_3V3    I28 @BASEBOARD_FAB2_LIB.BASEBOARD_FAB2(SCH_1):PAGE148
   H17 VCC_D_3V3 @BASEBOARD_FAB2_LIB.BASEBOARD_FAB2(SCH_1):VCC_D_3V3    I28 @BASEBOARD_FAB2_LIB.BASEBOARD_FAB2(SCH_1):PAGE148
    K7 VCC_D_3V3 @BASEBOARD_FAB2_LIB.BASEBOARD_FAB2(SCH_1):VCC_D_3V3    I28 @BASEBOARD_FAB2_LIB.BASEBOARD_FAB2(SCH_1):PAGE148
   N17 VCC_D_3V3 @BASEBOARD_FAB2_LIB.BASEBOARD_FAB2(SCH_1):VCC_D_3V3    I28 @BASEBOARD_FAB2_LIB.BASEBOARD_FAB2(SCH_1):PAGE148
    N6 VCC_D_3V3 @BASEBOARD_FAB2_LIB.BASEBOARD_FAB2(SCH_1):VCC_D_3V3    I28 @BASEBOARD_FAB2_LIB.BASEBOARD_FAB2(SCH_1):PAGE148
   P17 VCC_D_3V3 @BASEBOARD_FAB2_LIB.BASEBOARD_FAB2(SCH_1):VCC_D_3V3    I28 @BASEBOARD_FAB2_LIB.BASEBOARD_FAB2(SCH_1):PAGE148
    P6 VCC_D_3V3 @BASEBOARD_FAB2_LIB.BASEBOARD_FAB2(SCH_1):VCC_D_3V3    I28 @BASEBOARD_FAB2_LIB.BASEBOARD_FAB2(SCH_1):PAGE148
   R17 VCC_D_3V3 @BASEBOARD_FAB2_LIB.BASEBOARD_FAB2(SCH_1):VCC_D_3V3    I28 @BASEBOARD_FAB2_LIB.BASEBOARD_FAB2(SCH_1):PAGE148
    R6 VCC_D_3V3 @BASEBOARD_FAB2_LIB.BASEBOARD_FAB2(SCH_1):VCC_D_3V3    I28 @BASEBOARD_FAB2_LIB.BASEBOARD_FAB2(SCH_1):PAGE148
   T11 VCC_D_PLL_3V3 @BASEBOARD_FAB2_LIB.BASEBOARD_FAB2(SCH_1):VCC_D_PLL_3V3    I28 @BASEBOARD_FAB2_LIB.BASEBOARD_FAB2(SCH_1):PAGE148
   T15 VCC_D_3V3 @BASEBOARD_FAB2_LIB.BASEBOARD_FAB2(SCH_1):VCC_D_3V3    I28 @BASEBOARD_FAB2_LIB.BASEBOARD_FAB2(SCH_1):PAGE148
   Y17 VCC_PA_3V3 @BASEBOARD_FAB2_LIB.BASEBOARD_FAB2(SCH_1):VCC_PA_3V3    I28 @BASEBOARD_FAB2_LIB.BASEBOARD_FAB2(SCH_1):PAGE148
   W17 VCC_PA_3V3 @BASEBOARD_FAB2_LIB.BASEBOARD_FAB2(SCH_1):VCC_PA_3V3    I28 @BASEBOARD_FAB2_LIB.BASEBOARD_FAB2(SCH_1):PAGE148
    J7 VCC_VA_3V3 @BASEBOARD_FAB2_LIB.BASEBOARD_FAB2(SCH_1):VCC_VA_3V3    I28 @BASEBOARD_FAB2_LIB.BASEBOARD_FAB2(SCH_1):PAGE148
    H7 VCC_VA_3V3 @BASEBOARD_FAB2_LIB.BASEBOARD_FAB2(SCH_1):VCC_VA_3V3    I28 @BASEBOARD_FAB2_LIB.BASEBOARD_FAB2(SCH_1):PAGE148
   L16 VCC_D_3V3 @BASEBOARD_FAB2_LIB.BASEBOARD_FAB2(SCH_1):VCC_D_3V3    I28 @BASEBOARD_FAB2_LIB.BASEBOARD_FAB2(SCH_1):PAGE148
    E4 VCCBAT_TW12 @BASEBOARD_FAB2_LIB.BASEBOARD_FAB2(SCH_1):VCCBAT_TW12    I28 @BASEBOARD_FAB2_LIB.BASEBOARD_FAB2(SCH_1):PAGE148
    C7 P3V3_USB2A_ALG @BASEBOARD_FAB2_LIB.BASEBOARD_FAB2(SCH_1):P3V3_USB2A_ALG    I28 @BASEBOARD_FAB2_LIB.BASEBOARD_FAB2(SCH_1):PAGE148
    K5 VCC_DACAV3V3 @BASEBOARD_FAB2_LIB.BASEBOARD_FAB2(SCH_1):VCC_DACAV3V3    I28 @BASEBOARD_FAB2_LIB.BASEBOARD_FAB2(SCH_1):PAGE148
    J6 VCC_ADCAV3V3 @BASEBOARD_FAB2_LIB.BASEBOARD_FAB2(SCH_1):VCC_ADCAV3V3    I28 @BASEBOARD_FAB2_LIB.BASEBOARD_FAB2(SCH_1):PAGE148
    F7 P3V3_STBY @BASEBOARD_FAB2_LIB.BASEBOARD_FAB2(SCH_1):P3V3_STBY    I28 @BASEBOARD_FAB2_LIB.BASEBOARD_FAB2(SCH_1):PAGE148
    F8 P3V3_STBY @BASEBOARD_FAB2_LIB.BASEBOARD_FAB2(SCH_1):P3V3_STBY    I28 @BASEBOARD_FAB2_LIB.BASEBOARD_FAB2(SCH_1):PAGE148
   F10 P3V3_STBY @BASEBOARD_FAB2_LIB.BASEBOARD_FAB2(SCH_1):P3V3_STBY    I28 @BASEBOARD_FAB2_LIB.BASEBOARD_FAB2(SCH_1):PAGE148
   F11 P3V3_STBY @BASEBOARD_FAB2_LIB.BASEBOARD_FAB2(SCH_1):P3V3_STBY    I28 @BASEBOARD_FAB2_LIB.BASEBOARD_FAB2(SCH_1):PAGE148
    V8    GND @BASEBOARD_FAB2_LIB.BASEBOARD_FAB2(SCH_1):GND    I28 @BASEBOARD_FAB2_LIB.BASEBOARD_FAB2(SCH_1):PAGE148
   V16    GND @BASEBOARD_FAB2_LIB.BASEBOARD_FAB2(SCH_1):GND    I28 @BASEBOARD_FAB2_LIB.BASEBOARD_FAB2(SCH_1):PAGE148
   V14    GND @BASEBOARD_FAB2_LIB.BASEBOARD_FAB2(SCH_1):GND    I28 @BASEBOARD_FAB2_LIB.BASEBOARD_FAB2(SCH_1):PAGE148
    T7    GND @BASEBOARD_FAB2_LIB.BASEBOARD_FAB2(SCH_1):GND    I28 @BASEBOARD_FAB2_LIB.BASEBOARD_FAB2(SCH_1):PAGE148
   U11    GND @BASEBOARD_FAB2_LIB.BASEBOARD_FAB2(SCH_1):GND    I28 @BASEBOARD_FAB2_LIB.BASEBOARD_FAB2(SCH_1):PAGE148
   V12    GND @BASEBOARD_FAB2_LIB.BASEBOARD_FAB2(SCH_1):GND    I28 @BASEBOARD_FAB2_LIB.BASEBOARD_FAB2(SCH_1):PAGE148
   V10    GND @BASEBOARD_FAB2_LIB.BASEBOARD_FAB2(SCH_1):GND    I28 @BASEBOARD_FAB2_LIB.BASEBOARD_FAB2(SCH_1):PAGE148
    U6    GND @BASEBOARD_FAB2_LIB.BASEBOARD_FAB2(SCH_1):GND    I28 @BASEBOARD_FAB2_LIB.BASEBOARD_FAB2(SCH_1):PAGE148
   N13    GND @BASEBOARD_FAB2_LIB.BASEBOARD_FAB2(SCH_1):GND    I28 @BASEBOARD_FAB2_LIB.BASEBOARD_FAB2(SCH_1):PAGE148
   N14    GND @BASEBOARD_FAB2_LIB.BASEBOARD_FAB2(SCH_1):GND    I28 @BASEBOARD_FAB2_LIB.BASEBOARD_FAB2(SCH_1):PAGE148
    T6    GND @BASEBOARD_FAB2_LIB.BASEBOARD_FAB2(SCH_1):GND    I28 @BASEBOARD_FAB2_LIB.BASEBOARD_FAB2(SCH_1):PAGE148
   T16    GND @BASEBOARD_FAB2_LIB.BASEBOARD_FAB2(SCH_1):GND    I28 @BASEBOARD_FAB2_LIB.BASEBOARD_FAB2(SCH_1):PAGE148
    N9    GND @BASEBOARD_FAB2_LIB.BASEBOARD_FAB2(SCH_1):GND    I28 @BASEBOARD_FAB2_LIB.BASEBOARD_FAB2(SCH_1):PAGE148
    M7    GND @BASEBOARD_FAB2_LIB.BASEBOARD_FAB2(SCH_1):GND    I28 @BASEBOARD_FAB2_LIB.BASEBOARD_FAB2(SCH_1):PAGE148
    M9    GND @BASEBOARD_FAB2_LIB.BASEBOARD_FAB2(SCH_1):GND    I28 @BASEBOARD_FAB2_LIB.BASEBOARD_FAB2(SCH_1):PAGE148
   N12    GND @BASEBOARD_FAB2_LIB.BASEBOARD_FAB2(SCH_1):GND    I28 @BASEBOARD_FAB2_LIB.BASEBOARD_FAB2(SCH_1):PAGE148
   N11    GND @BASEBOARD_FAB2_LIB.BASEBOARD_FAB2(SCH_1):GND    I28 @BASEBOARD_FAB2_LIB.BASEBOARD_FAB2(SCH_1):PAGE148
   N10    GND @BASEBOARD_FAB2_LIB.BASEBOARD_FAB2(SCH_1):GND    I28 @BASEBOARD_FAB2_LIB.BASEBOARD_FAB2(SCH_1):PAGE148
    M2    GND @BASEBOARD_FAB2_LIB.BASEBOARD_FAB2(SCH_1):GND    I28 @BASEBOARD_FAB2_LIB.BASEBOARD_FAB2(SCH_1):PAGE148
    M3    GND @BASEBOARD_FAB2_LIB.BASEBOARD_FAB2(SCH_1):GND    I28 @BASEBOARD_FAB2_LIB.BASEBOARD_FAB2(SCH_1):PAGE148
    M6    GND @BASEBOARD_FAB2_LIB.BASEBOARD_FAB2(SCH_1):GND    I28 @BASEBOARD_FAB2_LIB.BASEBOARD_FAB2(SCH_1):PAGE148
    M5    GND @BASEBOARD_FAB2_LIB.BASEBOARD_FAB2(SCH_1):GND    I28 @BASEBOARD_FAB2_LIB.BASEBOARD_FAB2(SCH_1):PAGE148
    M4    GND @BASEBOARD_FAB2_LIB.BASEBOARD_FAB2(SCH_1):GND    I28 @BASEBOARD_FAB2_LIB.BASEBOARD_FAB2(SCH_1):PAGE148
   M12    GND @BASEBOARD_FAB2_LIB.BASEBOARD_FAB2(SCH_1):GND    I28 @BASEBOARD_FAB2_LIB.BASEBOARD_FAB2(SCH_1):PAGE148
   M13    GND @BASEBOARD_FAB2_LIB.BASEBOARD_FAB2(SCH_1):GND    I28 @BASEBOARD_FAB2_LIB.BASEBOARD_FAB2(SCH_1):PAGE148
   M17    GND @BASEBOARD_FAB2_LIB.BASEBOARD_FAB2(SCH_1):GND    I28 @BASEBOARD_FAB2_LIB.BASEBOARD_FAB2(SCH_1):PAGE148
   M16    GND @BASEBOARD_FAB2_LIB.BASEBOARD_FAB2(SCH_1):GND    I28 @BASEBOARD_FAB2_LIB.BASEBOARD_FAB2(SCH_1):PAGE148
   M14    GND @BASEBOARD_FAB2_LIB.BASEBOARD_FAB2(SCH_1):GND    I28 @BASEBOARD_FAB2_LIB.BASEBOARD_FAB2(SCH_1):PAGE148
   L14    GND @BASEBOARD_FAB2_LIB.BASEBOARD_FAB2(SCH_1):GND    I28 @BASEBOARD_FAB2_LIB.BASEBOARD_FAB2(SCH_1):PAGE148
   M11    GND @BASEBOARD_FAB2_LIB.BASEBOARD_FAB2(SCH_1):GND    I28 @BASEBOARD_FAB2_LIB.BASEBOARD_FAB2(SCH_1):PAGE148
   M10    GND @BASEBOARD_FAB2_LIB.BASEBOARD_FAB2(SCH_1):GND    I28 @BASEBOARD_FAB2_LIB.BASEBOARD_FAB2(SCH_1):PAGE148
    M1    GND @BASEBOARD_FAB2_LIB.BASEBOARD_FAB2(SCH_1):GND    I28 @BASEBOARD_FAB2_LIB.BASEBOARD_FAB2(SCH_1):PAGE148
    L9    GND @BASEBOARD_FAB2_LIB.BASEBOARD_FAB2(SCH_1):GND    I28 @BASEBOARD_FAB2_LIB.BASEBOARD_FAB2(SCH_1):PAGE148
    K9    GND @BASEBOARD_FAB2_LIB.BASEBOARD_FAB2(SCH_1):GND    I28 @BASEBOARD_FAB2_LIB.BASEBOARD_FAB2(SCH_1):PAGE148
   L13    GND @BASEBOARD_FAB2_LIB.BASEBOARD_FAB2(SCH_1):GND    I28 @BASEBOARD_FAB2_LIB.BASEBOARD_FAB2(SCH_1):PAGE148
   L12    GND @BASEBOARD_FAB2_LIB.BASEBOARD_FAB2(SCH_1):GND    I28 @BASEBOARD_FAB2_LIB.BASEBOARD_FAB2(SCH_1):PAGE148
   L11    GND @BASEBOARD_FAB2_LIB.BASEBOARD_FAB2(SCH_1):GND    I28 @BASEBOARD_FAB2_LIB.BASEBOARD_FAB2(SCH_1):PAGE148
   L10    GND @BASEBOARD_FAB2_LIB.BASEBOARD_FAB2(SCH_1):GND    I28 @BASEBOARD_FAB2_LIB.BASEBOARD_FAB2(SCH_1):PAGE148
   K16    GND @BASEBOARD_FAB2_LIB.BASEBOARD_FAB2(SCH_1):GND    I28 @BASEBOARD_FAB2_LIB.BASEBOARD_FAB2(SCH_1):PAGE148
   K11    GND @BASEBOARD_FAB2_LIB.BASEBOARD_FAB2(SCH_1):GND    I28 @BASEBOARD_FAB2_LIB.BASEBOARD_FAB2(SCH_1):PAGE148
   K13    GND @BASEBOARD_FAB2_LIB.BASEBOARD_FAB2(SCH_1):GND    I28 @BASEBOARD_FAB2_LIB.BASEBOARD_FAB2(SCH_1):PAGE148
   K14    GND @BASEBOARD_FAB2_LIB.BASEBOARD_FAB2(SCH_1):GND    I28 @BASEBOARD_FAB2_LIB.BASEBOARD_FAB2(SCH_1):PAGE148
   K12    GND @BASEBOARD_FAB2_LIB.BASEBOARD_FAB2(SCH_1):GND    I28 @BASEBOARD_FAB2_LIB.BASEBOARD_FAB2(SCH_1):PAGE148
   K10    GND @BASEBOARD_FAB2_LIB.BASEBOARD_FAB2(SCH_1):GND    I28 @BASEBOARD_FAB2_LIB.BASEBOARD_FAB2(SCH_1):PAGE148
   J21    GND @BASEBOARD_FAB2_LIB.BASEBOARD_FAB2(SCH_1):GND    I28 @BASEBOARD_FAB2_LIB.BASEBOARD_FAB2(SCH_1):PAGE148
    J9    GND @BASEBOARD_FAB2_LIB.BASEBOARD_FAB2(SCH_1):GND    I28 @BASEBOARD_FAB2_LIB.BASEBOARD_FAB2(SCH_1):PAGE148
    J5    GND @BASEBOARD_FAB2_LIB.BASEBOARD_FAB2(SCH_1):GND    I28 @BASEBOARD_FAB2_LIB.BASEBOARD_FAB2(SCH_1):PAGE148
   J22    GND @BASEBOARD_FAB2_LIB.BASEBOARD_FAB2(SCH_1):GND    I28 @BASEBOARD_FAB2_LIB.BASEBOARD_FAB2(SCH_1):PAGE148
   J14    GND @BASEBOARD_FAB2_LIB.BASEBOARD_FAB2(SCH_1):GND    I28 @BASEBOARD_FAB2_LIB.BASEBOARD_FAB2(SCH_1):PAGE148
    H6    GND @BASEBOARD_FAB2_LIB.BASEBOARD_FAB2(SCH_1):GND    I28 @BASEBOARD_FAB2_LIB.BASEBOARD_FAB2(SCH_1):PAGE148
   J10    GND @BASEBOARD_FAB2_LIB.BASEBOARD_FAB2(SCH_1):GND    I28 @BASEBOARD_FAB2_LIB.BASEBOARD_FAB2(SCH_1):PAGE148
   J13    GND @BASEBOARD_FAB2_LIB.BASEBOARD_FAB2(SCH_1):GND    I28 @BASEBOARD_FAB2_LIB.BASEBOARD_FAB2(SCH_1):PAGE148
   J12    GND @BASEBOARD_FAB2_LIB.BASEBOARD_FAB2(SCH_1):GND    I28 @BASEBOARD_FAB2_LIB.BASEBOARD_FAB2(SCH_1):PAGE148
   J11    GND @BASEBOARD_FAB2_LIB.BASEBOARD_FAB2(SCH_1):GND    I28 @BASEBOARD_FAB2_LIB.BASEBOARD_FAB2(SCH_1):PAGE148
    C6    GND @BASEBOARD_FAB2_LIB.BASEBOARD_FAB2(SCH_1):GND    I28 @BASEBOARD_FAB2_LIB.BASEBOARD_FAB2(SCH_1):PAGE148
    E8    GND @BASEBOARD_FAB2_LIB.BASEBOARD_FAB2(SCH_1):GND    I28 @BASEBOARD_FAB2_LIB.BASEBOARD_FAB2(SCH_1):PAGE148
    G6    GND @BASEBOARD_FAB2_LIB.BASEBOARD_FAB2(SCH_1):GND    I28 @BASEBOARD_FAB2_LIB.BASEBOARD_FAB2(SCH_1):PAGE148
   G19    GND @BASEBOARD_FAB2_LIB.BASEBOARD_FAB2(SCH_1):GND    I28 @BASEBOARD_FAB2_LIB.BASEBOARD_FAB2(SCH_1):PAGE148
   F16    GND @BASEBOARD_FAB2_LIB.BASEBOARD_FAB2(SCH_1):GND    I28 @BASEBOARD_FAB2_LIB.BASEBOARD_FAB2(SCH_1):PAGE148
  AA15    GND @BASEBOARD_FAB2_LIB.BASEBOARD_FAB2(SCH_1):GND    I28 @BASEBOARD_FAB2_LIB.BASEBOARD_FAB2(SCH_1):PAGE148
   AA7    GND @BASEBOARD_FAB2_LIB.BASEBOARD_FAB2(SCH_1):GND    I28 @BASEBOARD_FAB2_LIB.BASEBOARD_FAB2(SCH_1):PAGE148
   AB1    GND @BASEBOARD_FAB2_LIB.BASEBOARD_FAB2(SCH_1):GND    I28 @BASEBOARD_FAB2_LIB.BASEBOARD_FAB2(SCH_1):PAGE148
  AB22    GND @BASEBOARD_FAB2_LIB.BASEBOARD_FAB2(SCH_1):GND    I28 @BASEBOARD_FAB2_LIB.BASEBOARD_FAB2(SCH_1):PAGE148
   AA9    GND @BASEBOARD_FAB2_LIB.BASEBOARD_FAB2(SCH_1):GND    I28 @BASEBOARD_FAB2_LIB.BASEBOARD_FAB2(SCH_1):PAGE148
  AA13    GND @BASEBOARD_FAB2_LIB.BASEBOARD_FAB2(SCH_1):GND    I28 @BASEBOARD_FAB2_LIB.BASEBOARD_FAB2(SCH_1):PAGE148
  AA11    GND @BASEBOARD_FAB2_LIB.BASEBOARD_FAB2(SCH_1):GND    I28 @BASEBOARD_FAB2_LIB.BASEBOARD_FAB2(SCH_1):PAGE148
   A22    GND @BASEBOARD_FAB2_LIB.BASEBOARD_FAB2(SCH_1):GND    I28 @BASEBOARD_FAB2_LIB.BASEBOARD_FAB2(SCH_1):PAGE148
    A1    GND @BASEBOARD_FAB2_LIB.BASEBOARD_FAB2(SCH_1):GND    I28 @BASEBOARD_FAB2_LIB.BASEBOARD_FAB2(SCH_1):PAGE148

U25W5 H5AN4G6NAFR-TFC-GP_MEMORY-G2-HA
    B1 P2V5_AUX_BMC @BASEBOARD_FAB2_LIB.BASEBOARD_FAB2(SCH_1):P2V5_AUX_BMC     I1 @BASEBOARD_FAB2_LIB.BASEBOARD_FAB2(SCH_1):PAGE149
    B3 P1V2_AUX_BMC @BASEBOARD_FAB2_LIB.BASEBOARD_FAB2(SCH_1):P1V2_AUX_BMC     I1 @BASEBOARD_FAB2_LIB.BASEBOARD_FAB2(SCH_1):PAGE149
    B9 P1V2_AUX_BMC @BASEBOARD_FAB2_LIB.BASEBOARD_FAB2(SCH_1):P1V2_AUX_BMC     I1 @BASEBOARD_FAB2_LIB.BASEBOARD_FAB2(SCH_1):PAGE149
    D1 P1V2_AUX_BMC @BASEBOARD_FAB2_LIB.BASEBOARD_FAB2(SCH_1):P1V2_AUX_BMC     I1 @BASEBOARD_FAB2_LIB.BASEBOARD_FAB2(SCH_1):PAGE149
    G7 P1V2_AUX_BMC @BASEBOARD_FAB2_LIB.BASEBOARD_FAB2(SCH_1):P1V2_AUX_BMC     I1 @BASEBOARD_FAB2_LIB.BASEBOARD_FAB2(SCH_1):PAGE149
    J1 P1V2_AUX_BMC @BASEBOARD_FAB2_LIB.BASEBOARD_FAB2(SCH_1):P1V2_AUX_BMC     I1 @BASEBOARD_FAB2_LIB.BASEBOARD_FAB2(SCH_1):PAGE149
    J9 P1V2_AUX_BMC @BASEBOARD_FAB2_LIB.BASEBOARD_FAB2(SCH_1):P1V2_AUX_BMC     I1 @BASEBOARD_FAB2_LIB.BASEBOARD_FAB2(SCH_1):PAGE149
    L1 P1V2_AUX_BMC @BASEBOARD_FAB2_LIB.BASEBOARD_FAB2(SCH_1):P1V2_AUX_BMC     I1 @BASEBOARD_FAB2_LIB.BASEBOARD_FAB2(SCH_1):PAGE149
    L9 P1V2_AUX_BMC @BASEBOARD_FAB2_LIB.BASEBOARD_FAB2(SCH_1):P1V2_AUX_BMC     I1 @BASEBOARD_FAB2_LIB.BASEBOARD_FAB2(SCH_1):PAGE149
    R1 P1V2_AUX_BMC @BASEBOARD_FAB2_LIB.BASEBOARD_FAB2(SCH_1):P1V2_AUX_BMC     I1 @BASEBOARD_FAB2_LIB.BASEBOARD_FAB2(SCH_1):PAGE149
    T9 P1V2_AUX_BMC @BASEBOARD_FAB2_LIB.BASEBOARD_FAB2(SCH_1):P1V2_AUX_BMC     I1 @BASEBOARD_FAB2_LIB.BASEBOARD_FAB2(SCH_1):PAGE149
    A1 P1V2_AUX_BMC @BASEBOARD_FAB2_LIB.BASEBOARD_FAB2(SCH_1):P1V2_AUX_BMC     I1 @BASEBOARD_FAB2_LIB.BASEBOARD_FAB2(SCH_1):PAGE149
    A9 P1V2_AUX_BMC @BASEBOARD_FAB2_LIB.BASEBOARD_FAB2(SCH_1):P1V2_AUX_BMC     I1 @BASEBOARD_FAB2_LIB.BASEBOARD_FAB2(SCH_1):PAGE149
    C1 P1V2_AUX_BMC @BASEBOARD_FAB2_LIB.BASEBOARD_FAB2(SCH_1):P1V2_AUX_BMC     I1 @BASEBOARD_FAB2_LIB.BASEBOARD_FAB2(SCH_1):PAGE149
    D9 P1V2_AUX_BMC @BASEBOARD_FAB2_LIB.BASEBOARD_FAB2(SCH_1):P1V2_AUX_BMC     I1 @BASEBOARD_FAB2_LIB.BASEBOARD_FAB2(SCH_1):PAGE149
    F2 P1V2_AUX_BMC @BASEBOARD_FAB2_LIB.BASEBOARD_FAB2(SCH_1):P1V2_AUX_BMC     I1 @BASEBOARD_FAB2_LIB.BASEBOARD_FAB2(SCH_1):PAGE149
    F8 P1V2_AUX_BMC @BASEBOARD_FAB2_LIB.BASEBOARD_FAB2(SCH_1):P1V2_AUX_BMC     I1 @BASEBOARD_FAB2_LIB.BASEBOARD_FAB2(SCH_1):PAGE149
    G1 P1V2_AUX_BMC @BASEBOARD_FAB2_LIB.BASEBOARD_FAB2(SCH_1):P1V2_AUX_BMC     I1 @BASEBOARD_FAB2_LIB.BASEBOARD_FAB2(SCH_1):PAGE149
    G9 P1V2_AUX_BMC @BASEBOARD_FAB2_LIB.BASEBOARD_FAB2(SCH_1):P1V2_AUX_BMC     I1 @BASEBOARD_FAB2_LIB.BASEBOARD_FAB2(SCH_1):PAGE149
    J2 P1V2_AUX_BMC @BASEBOARD_FAB2_LIB.BASEBOARD_FAB2(SCH_1):P1V2_AUX_BMC     I1 @BASEBOARD_FAB2_LIB.BASEBOARD_FAB2(SCH_1):PAGE149
    J8 P1V2_AUX_BMC @BASEBOARD_FAB2_LIB.BASEBOARD_FAB2(SCH_1):P1V2_AUX_BMC     I1 @BASEBOARD_FAB2_LIB.BASEBOARD_FAB2(SCH_1):PAGE149
    C2 BMC_M_DQ12 @BASEBOARD_FAB2_LIB.BASEBOARD_FAB2(SCH_1):BMC_M_DQ12     I1 @BASEBOARD_FAB2_LIB.BASEBOARD_FAB2(SCH_1):PAGE149
    C8 BMC_M_DQ13 @BASEBOARD_FAB2_LIB.BASEBOARD_FAB2(SCH_1):BMC_M_DQ13     I1 @BASEBOARD_FAB2_LIB.BASEBOARD_FAB2(SCH_1):PAGE149
    D3 BMC_M_DQ14 @BASEBOARD_FAB2_LIB.BASEBOARD_FAB2(SCH_1):BMC_M_DQ14     I1 @BASEBOARD_FAB2_LIB.BASEBOARD_FAB2(SCH_1):PAGE149
    D7 BMC_M_DQ15 @BASEBOARD_FAB2_LIB.BASEBOARD_FAB2(SCH_1):BMC_M_DQ15     I1 @BASEBOARD_FAB2_LIB.BASEBOARD_FAB2(SCH_1):PAGE149
    A3 BMC_M_DQ8 @BASEBOARD_FAB2_LIB.BASEBOARD_FAB2(SCH_1):BMC_M_DQ8     I1 @BASEBOARD_FAB2_LIB.BASEBOARD_FAB2(SCH_1):PAGE149
    B8 BMC_M_DQ9 @BASEBOARD_FAB2_LIB.BASEBOARD_FAB2(SCH_1):BMC_M_DQ9     I1 @BASEBOARD_FAB2_LIB.BASEBOARD_FAB2(SCH_1):PAGE149
    C3 BMC_M_DQ10 @BASEBOARD_FAB2_LIB.BASEBOARD_FAB2(SCH_1):BMC_M_DQ10     I1 @BASEBOARD_FAB2_LIB.BASEBOARD_FAB2(SCH_1):PAGE149
    C7 BMC_M_DQ11 @BASEBOARD_FAB2_LIB.BASEBOARD_FAB2(SCH_1):BMC_M_DQ11     I1 @BASEBOARD_FAB2_LIB.BASEBOARD_FAB2(SCH_1):PAGE149
    F7 BMC_M_DQ1 @BASEBOARD_FAB2_LIB.BASEBOARD_FAB2(SCH_1):BMC_M_DQ1     I1 @BASEBOARD_FAB2_LIB.BASEBOARD_FAB2(SCH_1):PAGE149
    G2 BMC_M_DQ0 @BASEBOARD_FAB2_LIB.BASEBOARD_FAB2(SCH_1):BMC_M_DQ0     I1 @BASEBOARD_FAB2_LIB.BASEBOARD_FAB2(SCH_1):PAGE149
    H2 BMC_M_DQ4 @BASEBOARD_FAB2_LIB.BASEBOARD_FAB2(SCH_1):BMC_M_DQ4     I1 @BASEBOARD_FAB2_LIB.BASEBOARD_FAB2(SCH_1):PAGE149
    H3 BMC_M_DQ2 @BASEBOARD_FAB2_LIB.BASEBOARD_FAB2(SCH_1):BMC_M_DQ2     I1 @BASEBOARD_FAB2_LIB.BASEBOARD_FAB2(SCH_1):PAGE149
    H7 BMC_M_DQ3 @BASEBOARD_FAB2_LIB.BASEBOARD_FAB2(SCH_1):BMC_M_DQ3     I1 @BASEBOARD_FAB2_LIB.BASEBOARD_FAB2(SCH_1):PAGE149
    H8 BMC_M_DQ5 @BASEBOARD_FAB2_LIB.BASEBOARD_FAB2(SCH_1):BMC_M_DQ5     I1 @BASEBOARD_FAB2_LIB.BASEBOARD_FAB2(SCH_1):PAGE149
    J3 BMC_M_DQ6 @BASEBOARD_FAB2_LIB.BASEBOARD_FAB2(SCH_1):BMC_M_DQ6     I1 @BASEBOARD_FAB2_LIB.BASEBOARD_FAB2(SCH_1):PAGE149
    J7 BMC_M_DQ7 @BASEBOARD_FAB2_LIB.BASEBOARD_FAB2(SCH_1):BMC_M_DQ7     I1 @BASEBOARD_FAB2_LIB.BASEBOARD_FAB2(SCH_1):PAGE149
    P3 BMC_M_A0 @BASEBOARD_FAB2_LIB.BASEBOARD_FAB2(SCH_1):BMC_M_A0     I1 @BASEBOARD_FAB2_LIB.BASEBOARD_FAB2(SCH_1):PAGE149
    P7 BMC_M_A1 @BASEBOARD_FAB2_LIB.BASEBOARD_FAB2(SCH_1):BMC_M_A1     I1 @BASEBOARD_FAB2_LIB.BASEBOARD_FAB2(SCH_1):PAGE149
    R3 BMC_M_A2 @BASEBOARD_FAB2_LIB.BASEBOARD_FAB2(SCH_1):BMC_M_A2     I1 @BASEBOARD_FAB2_LIB.BASEBOARD_FAB2(SCH_1):PAGE149
    N7 BMC_M_A3 @BASEBOARD_FAB2_LIB.BASEBOARD_FAB2(SCH_1):BMC_M_A3     I1 @BASEBOARD_FAB2_LIB.BASEBOARD_FAB2(SCH_1):PAGE149
    N3 BMC_M_A4 @BASEBOARD_FAB2_LIB.BASEBOARD_FAB2(SCH_1):BMC_M_A4     I1 @BASEBOARD_FAB2_LIB.BASEBOARD_FAB2(SCH_1):PAGE149
    P8 BMC_M_A5 @BASEBOARD_FAB2_LIB.BASEBOARD_FAB2(SCH_1):BMC_M_A5     I1 @BASEBOARD_FAB2_LIB.BASEBOARD_FAB2(SCH_1):PAGE149
    P2 BMC_M_A6 @BASEBOARD_FAB2_LIB.BASEBOARD_FAB2(SCH_1):BMC_M_A6     I1 @BASEBOARD_FAB2_LIB.BASEBOARD_FAB2(SCH_1):PAGE149
    R8 BMC_M_A7 @BASEBOARD_FAB2_LIB.BASEBOARD_FAB2(SCH_1):BMC_M_A7     I1 @BASEBOARD_FAB2_LIB.BASEBOARD_FAB2(SCH_1):PAGE149
    R2 BMC_M_A8 @BASEBOARD_FAB2_LIB.BASEBOARD_FAB2(SCH_1):BMC_M_A8     I1 @BASEBOARD_FAB2_LIB.BASEBOARD_FAB2(SCH_1):PAGE149
    R7 BMC_M_A9 @BASEBOARD_FAB2_LIB.BASEBOARD_FAB2(SCH_1):BMC_M_A9     I1 @BASEBOARD_FAB2_LIB.BASEBOARD_FAB2(SCH_1):PAGE149
    M3 BMC_M_A10 @BASEBOARD_FAB2_LIB.BASEBOARD_FAB2(SCH_1):BMC_M_A10     I1 @BASEBOARD_FAB2_LIB.BASEBOARD_FAB2(SCH_1):PAGE149
    T2 BMC_M_A11 @BASEBOARD_FAB2_LIB.BASEBOARD_FAB2(SCH_1):BMC_M_A11     I1 @BASEBOARD_FAB2_LIB.BASEBOARD_FAB2(SCH_1):PAGE149
    M7 BMC_M_A12 @BASEBOARD_FAB2_LIB.BASEBOARD_FAB2(SCH_1):BMC_M_A12     I1 @BASEBOARD_FAB2_LIB.BASEBOARD_FAB2(SCH_1):PAGE149
    T8 BMC_M_A13 @BASEBOARD_FAB2_LIB.BASEBOARD_FAB2(SCH_1):BMC_M_A13     I1 @BASEBOARD_FAB2_LIB.BASEBOARD_FAB2(SCH_1):PAGE149
    L2 BMC_M_WE_N @BASEBOARD_FAB2_LIB.BASEBOARD_FAB2(SCH_1):BMC_M_WE_N     I1 @BASEBOARD_FAB2_LIB.BASEBOARD_FAB2(SCH_1):PAGE149
    M8 BMC_M_CAS_N @BASEBOARD_FAB2_LIB.BASEBOARD_FAB2(SCH_1):BMC_M_CAS_N     I1 @BASEBOARD_FAB2_LIB.BASEBOARD_FAB2(SCH_1):PAGE149
    L8 BMC_M_RAS_N @BASEBOARD_FAB2_LIB.BASEBOARD_FAB2(SCH_1):BMC_M_RAS_N     I1 @BASEBOARD_FAB2_LIB.BASEBOARD_FAB2(SCH_1):PAGE149
    M1 BMC_M_VREFCA @BASEBOARD_FAB2_LIB.BASEBOARD_FAB2(SCH_1):BMC_M_VREFCA     I1 @BASEBOARD_FAB2_LIB.BASEBOARD_FAB2(SCH_1):PAGE149
    F9 BMC_ZQ @BASEBOARD_FAB2_LIB.BASEBOARD_FAB2(SCH_1):BMC_ZQ     I1 @BASEBOARD_FAB2_LIB.BASEBOARD_FAB2(SCH_1):PAGE149
    K2 BMC_M_CKE @BASEBOARD_FAB2_LIB.BASEBOARD_FAB2(SCH_1):BMC_M_CKE     I1 @BASEBOARD_FAB2_LIB.BASEBOARD_FAB2(SCH_1):PAGE149
    K3 BMC_M_ODT @BASEBOARD_FAB2_LIB.BASEBOARD_FAB2(SCH_1):BMC_M_ODT     I1 @BASEBOARD_FAB2_LIB.BASEBOARD_FAB2(SCH_1):PAGE149
    M2 BMC_M_BG0 @BASEBOARD_FAB2_LIB.BASEBOARD_FAB2(SCH_1):BMC_M_BG0     I1 @BASEBOARD_FAB2_LIB.BASEBOARD_FAB2(SCH_1):PAGE149
    N9    GND @BASEBOARD_FAB2_LIB.BASEBOARD_FAB2(SCH_1):GND     I1 @BASEBOARD_FAB2_LIB.BASEBOARD_FAB2(SCH_1):PAGE149
    T3 BMC_M_PAR @BASEBOARD_FAB2_LIB.BASEBOARD_FAB2(SCH_1):BMC_M_PAR     I1 @BASEBOARD_FAB2_LIB.BASEBOARD_FAB2(SCH_1):PAGE149
    T7     NC     NC     I1 @BASEBOARD_FAB2_LIB.BASEBOARD_FAB2(SCH_1):PAGE149
    K7 BMC_M_CLK_DP @BASEBOARD_FAB2_LIB.BASEBOARD_FAB2(SCH_1):BMC_M_CLK_DP     I1 @BASEBOARD_FAB2_LIB.BASEBOARD_FAB2(SCH_1):PAGE149
    K8 BMC_M_CLK_DN @BASEBOARD_FAB2_LIB.BASEBOARD_FAB2(SCH_1):BMC_M_CLK_DN     I1 @BASEBOARD_FAB2_LIB.BASEBOARD_FAB2(SCH_1):PAGE149
    R9    GND @BASEBOARD_FAB2_LIB.BASEBOARD_FAB2(SCH_1):GND     I1 @BASEBOARD_FAB2_LIB.BASEBOARD_FAB2(SCH_1):PAGE149
    L3 BMC_M_MACT_N @BASEBOARD_FAB2_LIB.BASEBOARD_FAB2(SCH_1):BMC_M_MACT_N     I1 @BASEBOARD_FAB2_LIB.BASEBOARD_FAB2(SCH_1):PAGE149
    L7 BMC_M_CS_N @BASEBOARD_FAB2_LIB.BASEBOARD_FAB2(SCH_1):BMC_M_CS_N     I1 @BASEBOARD_FAB2_LIB.BASEBOARD_FAB2(SCH_1):PAGE149
    P1 BMC_M_RST_N @BASEBOARD_FAB2_LIB.BASEBOARD_FAB2(SCH_1):BMC_M_RST_N     I1 @BASEBOARD_FAB2_LIB.BASEBOARD_FAB2(SCH_1):PAGE149
    P9 BMC_M_MALERT_N @BASEBOARD_FAB2_LIB.BASEBOARD_FAB2(SCH_1):BMC_M_MALERT_N     I1 @BASEBOARD_FAB2_LIB.BASEBOARD_FAB2(SCH_1):PAGE149
    B2    GND @BASEBOARD_FAB2_LIB.BASEBOARD_FAB2(SCH_1):GND     I1 @BASEBOARD_FAB2_LIB.BASEBOARD_FAB2(SCH_1):PAGE149
    E1    GND @BASEBOARD_FAB2_LIB.BASEBOARD_FAB2(SCH_1):GND     I1 @BASEBOARD_FAB2_LIB.BASEBOARD_FAB2(SCH_1):PAGE149
    E9    GND @BASEBOARD_FAB2_LIB.BASEBOARD_FAB2(SCH_1):GND     I1 @BASEBOARD_FAB2_LIB.BASEBOARD_FAB2(SCH_1):PAGE149
    G8    GND @BASEBOARD_FAB2_LIB.BASEBOARD_FAB2(SCH_1):GND     I1 @BASEBOARD_FAB2_LIB.BASEBOARD_FAB2(SCH_1):PAGE149
    K1    GND @BASEBOARD_FAB2_LIB.BASEBOARD_FAB2(SCH_1):GND     I1 @BASEBOARD_FAB2_LIB.BASEBOARD_FAB2(SCH_1):PAGE149
    K9    GND @BASEBOARD_FAB2_LIB.BASEBOARD_FAB2(SCH_1):GND     I1 @BASEBOARD_FAB2_LIB.BASEBOARD_FAB2(SCH_1):PAGE149
    M9    GND @BASEBOARD_FAB2_LIB.BASEBOARD_FAB2(SCH_1):GND     I1 @BASEBOARD_FAB2_LIB.BASEBOARD_FAB2(SCH_1):PAGE149
    N1    GND @BASEBOARD_FAB2_LIB.BASEBOARD_FAB2(SCH_1):GND     I1 @BASEBOARD_FAB2_LIB.BASEBOARD_FAB2(SCH_1):PAGE149
    T1    GND @BASEBOARD_FAB2_LIB.BASEBOARD_FAB2(SCH_1):GND     I1 @BASEBOARD_FAB2_LIB.BASEBOARD_FAB2(SCH_1):PAGE149
    A2    GND @BASEBOARD_FAB2_LIB.BASEBOARD_FAB2(SCH_1):GND     I1 @BASEBOARD_FAB2_LIB.BASEBOARD_FAB2(SCH_1):PAGE149
    A8    GND @BASEBOARD_FAB2_LIB.BASEBOARD_FAB2(SCH_1):GND     I1 @BASEBOARD_FAB2_LIB.BASEBOARD_FAB2(SCH_1):PAGE149
    C9    GND @BASEBOARD_FAB2_LIB.BASEBOARD_FAB2(SCH_1):GND     I1 @BASEBOARD_FAB2_LIB.BASEBOARD_FAB2(SCH_1):PAGE149
    D2    GND @BASEBOARD_FAB2_LIB.BASEBOARD_FAB2(SCH_1):GND     I1 @BASEBOARD_FAB2_LIB.BASEBOARD_FAB2(SCH_1):PAGE149
    D8    GND @BASEBOARD_FAB2_LIB.BASEBOARD_FAB2(SCH_1):GND     I1 @BASEBOARD_FAB2_LIB.BASEBOARD_FAB2(SCH_1):PAGE149
    E3    GND @BASEBOARD_FAB2_LIB.BASEBOARD_FAB2(SCH_1):GND     I1 @BASEBOARD_FAB2_LIB.BASEBOARD_FAB2(SCH_1):PAGE149
    E8    GND @BASEBOARD_FAB2_LIB.BASEBOARD_FAB2(SCH_1):GND     I1 @BASEBOARD_FAB2_LIB.BASEBOARD_FAB2(SCH_1):PAGE149
    F1    GND @BASEBOARD_FAB2_LIB.BASEBOARD_FAB2(SCH_1):GND     I1 @BASEBOARD_FAB2_LIB.BASEBOARD_FAB2(SCH_1):PAGE149
    H1    GND @BASEBOARD_FAB2_LIB.BASEBOARD_FAB2(SCH_1):GND     I1 @BASEBOARD_FAB2_LIB.BASEBOARD_FAB2(SCH_1):PAGE149
    H9    GND @BASEBOARD_FAB2_LIB.BASEBOARD_FAB2(SCH_1):GND     I1 @BASEBOARD_FAB2_LIB.BASEBOARD_FAB2(SCH_1):PAGE149
    A7 BMC_M_DQS1_DN @BASEBOARD_FAB2_LIB.BASEBOARD_FAB2(SCH_1):BMC_M_DQS1_DN     I1 @BASEBOARD_FAB2_LIB.BASEBOARD_FAB2(SCH_1):PAGE149
    B7 BMC_M_DQS1_DP @BASEBOARD_FAB2_LIB.BASEBOARD_FAB2(SCH_1):BMC_M_DQS1_DP     I1 @BASEBOARD_FAB2_LIB.BASEBOARD_FAB2(SCH_1):PAGE149
    F3 BMC_M_DQS0_DN @BASEBOARD_FAB2_LIB.BASEBOARD_FAB2(SCH_1):BMC_M_DQS0_DN     I1 @BASEBOARD_FAB2_LIB.BASEBOARD_FAB2(SCH_1):PAGE149
    G3 BMC_M_DQS0_DP @BASEBOARD_FAB2_LIB.BASEBOARD_FAB2(SCH_1):BMC_M_DQS0_DP     I1 @BASEBOARD_FAB2_LIB.BASEBOARD_FAB2(SCH_1):PAGE149
    E2 BMC_M_DM1 @BASEBOARD_FAB2_LIB.BASEBOARD_FAB2(SCH_1):BMC_M_DM1     I1 @BASEBOARD_FAB2_LIB.BASEBOARD_FAB2(SCH_1):PAGE149
    E7 BMC_M_DM0 @BASEBOARD_FAB2_LIB.BASEBOARD_FAB2(SCH_1):BMC_M_DM0     I1 @BASEBOARD_FAB2_LIB.BASEBOARD_FAB2(SCH_1):PAGE149
    N2 BMC_M_BA0 @BASEBOARD_FAB2_LIB.BASEBOARD_FAB2(SCH_1):BMC_M_BA0     I1 @BASEBOARD_FAB2_LIB.BASEBOARD_FAB2(SCH_1):PAGE149
    N8 BMC_M_BA1 @BASEBOARD_FAB2_LIB.BASEBOARD_FAB2(SCH_1):BMC_M_BA1     I1 @BASEBOARD_FAB2_LIB.BASEBOARD_FAB2(SCH_1):PAGE149

UN8F2 W25Q256_XSOI-IC,H25002-001
     9 PU_TPM_SPI_BMC_WP_N @BASEBOARD_FAB2_LIB.BASEBOARD_FAB2(SCH_1):PU_TPM_SPI_BMC_WP_N    I17 @BASEBOARD_FAB2_LIB.BASEBOARD_FAB2(SCH_1):PAGE246
    14 TP_TPM_SPI_0 @BASEBOARD_FAB2_LIB.BASEBOARD_FAB2(SCH_1):TP_TPM_SPI_0    I17 @BASEBOARD_FAB2_LIB.BASEBOARD_FAB2(SCH_1):PAGE246
    13 TP_TPM_SPI_1 @BASEBOARD_FAB2_LIB.BASEBOARD_FAB2(SCH_1):TP_TPM_SPI_1    I17 @BASEBOARD_FAB2_LIB.BASEBOARD_FAB2(SCH_1):PAGE246
    12 TP_TPM_SPI_2 @BASEBOARD_FAB2_LIB.BASEBOARD_FAB2(SCH_1):TP_TPM_SPI_2    I17 @BASEBOARD_FAB2_LIB.BASEBOARD_FAB2(SCH_1):PAGE246
    11 TP_TPM_SPI_3 @BASEBOARD_FAB2_LIB.BASEBOARD_FAB2(SCH_1):TP_TPM_SPI_3    I17 @BASEBOARD_FAB2_LIB.BASEBOARD_FAB2(SCH_1):PAGE246
     6 TP_TPM_SPI_4 @BASEBOARD_FAB2_LIB.BASEBOARD_FAB2(SCH_1):TP_TPM_SPI_4    I17 @BASEBOARD_FAB2_LIB.BASEBOARD_FAB2(SCH_1):PAGE246
     5 TP_TPM_SPI_5 @BASEBOARD_FAB2_LIB.BASEBOARD_FAB2(SCH_1):TP_TPM_SPI_5    I17 @BASEBOARD_FAB2_LIB.BASEBOARD_FAB2(SCH_1):PAGE246
     4 TP_TPM_SPI_6 @BASEBOARD_FAB2_LIB.BASEBOARD_FAB2(SCH_1):TP_TPM_SPI_6    I17 @BASEBOARD_FAB2_LIB.BASEBOARD_FAB2(SCH_1):PAGE246
    10    GND @BASEBOARD_FAB2_LIB.BASEBOARD_FAB2(SCH_1):GND    I17 @BASEBOARD_FAB2_LIB.BASEBOARD_FAB2(SCH_1):PAGE246
     8 SPI_TPM_BMC_DI_R_ @BASEBOARD_FAB2_LIB.BASEBOARD_FAB2(SCH_1):SPI_TPM_BMC_DI_R_    I17 @BASEBOARD_FAB2_LIB.BASEBOARD_FAB2(SCH_1):PAGE246
    16 SPI_BMC_BT_CLK @BASEBOARD_FAB2_LIB.BASEBOARD_FAB2(SCH_1):SPI_BMC_BT_CLK    I17 @BASEBOARD_FAB2_LIB.BASEBOARD_FAB2(SCH_1):PAGE246
     2 P3V3_STBY @BASEBOARD_FAB2_LIB.BASEBOARD_FAB2(SCH_1):P3V3_STBY    I17 @BASEBOARD_FAB2_LIB.BASEBOARD_FAB2(SCH_1):PAGE246
     7 SPI_BMC_BT_CS1_N @BASEBOARD_FAB2_LIB.BASEBOARD_FAB2(SCH_1):SPI_BMC_BT_CS1_N    I17 @BASEBOARD_FAB2_LIB.BASEBOARD_FAB2(SCH_1):PAGE246
    15 SPI_BMC_BT_DO @BASEBOARD_FAB2_LIB.BASEBOARD_FAB2(SCH_1):SPI_BMC_BT_DO    I17 @BASEBOARD_FAB2_LIB.BASEBOARD_FAB2(SCH_1):PAGE246
     3 PU_TPM_SPI_FLASH_RESET_2_N @BASEBOARD_FAB2_LIB.BASEBOARD_FAB2(SCH_1):PU_TPM_SPI_FLASH_RESET_2_N    I17 @BASEBOARD_FAB2_LIB.BASEBOARD_FAB2(SCH_1):PAGE246
     1 PU_TPM_SPI_BMC_HOLD_N @BASEBOARD_FAB2_LIB.BASEBOARD_FAB2(SCH_1):PU_TPM_SPI_BMC_HOLD_N    I17 @BASEBOARD_FAB2_LIB.BASEBOARD_FAB2(SCH_1):PAGE246

VR1D1 ZENER_SM-13V,IC,H69095-001
     2    GND @BASEBOARD_FAB2_LIB.BASEBOARD_FAB2(SCH_1):GND    I99 @BASEBOARD_FAB2_LIB.BASEBOARD_FAB2(SCH_1):PAGE199
     1 P12V_PSU @BASEBOARD_FAB2_LIB.BASEBOARD_FAB2(SCH_1):P12V_PSU    I99 @BASEBOARD_FAB2_LIB.BASEBOARD_FAB2(SCH_1):PAGE199

XBT8G1 VERT_BATT_3PIN_PIP-3PVERT,C686A
     3    GND @BASEBOARD_FAB2_LIB.BASEBOARD_FAB2(SCH_1):GND    I51 @BASEBOARD_FAB2_LIB.BASEBOARD_FAB2(SCH_1):PAGE196
     1 P3V_BAT_SOURCE @BASEBOARD_FAB2_LIB.BASEBOARD_FAB2(SCH_1):P3V_BAT_SOURCE    I51 @BASEBOARD_FAB2_LIB.BASEBOARD_FAB2(SCH_1):PAGE196
     2 P3V_BAT_SOURCE @BASEBOARD_FAB2_LIB.BASEBOARD_FAB2(SCH_1):P3V_BAT_SOURCE    I51 @BASEBOARD_FAB2_LIB.BASEBOARD_FAB2(SCH_1):PAGE196

XLU1 SOCKET_P_MECH_A_LEFT-P0,PLASTIA

XLU2 SOCKET_P_MECH_A_LEFT-P0,PLASTIA

XRU1 SOCKET_P_MECH_A_RIGHT-P0,PLASTA

XRU2 SOCKET_P_MECH_A_RIGHT-P0,PLASTA

Y3F1 OSC_C_6P10-156.25MHZ,OSC,G6383A
     1 FM_CPU1_STL_BRD_OSC_EN @BASEBOARD_FAB2_LIB.BASEBOARD_FAB2(SCH_1):FM_CPU1_STL_BRD_OSC_EN    I72 @BASEBOARD_FAB2_LIB.BASEBOARD_FAB2(SCH_1):PAGE104
     2 NC_CLK_156M_CPU1_OSC @BASEBOARD_FAB2_LIB.BASEBOARD_FAB2(SCH_1):NC_CLK_156M_CPU1_OSC    I72 @BASEBOARD_FAB2_LIB.BASEBOARD_FAB2(SCH_1):PAGE104
     3    GND @BASEBOARD_FAB2_LIB.BASEBOARD_FAB2(SCH_1):GND    I72 @BASEBOARD_FAB2_LIB.BASEBOARD_FAB2(SCH_1):PAGE104
     4 CLK_156M_OSC_BRD_CPU1_DP @BASEBOARD_FAB2_LIB.BASEBOARD_FAB2(SCH_1):CLK_156M_OSC_BRD_CPU1_DP    I72 @BASEBOARD_FAB2_LIB.BASEBOARD_FAB2(SCH_1):PAGE104
     5 CLK_156M_OSC_BRD_CPU1_DN @BASEBOARD_FAB2_LIB.BASEBOARD_FAB2(SCH_1):CLK_156M_OSC_BRD_CPU1_DN    I72 @BASEBOARD_FAB2_LIB.BASEBOARD_FAB2(SCH_1):PAGE104
     6   P3V3 @BASEBOARD_FAB2_LIB.BASEBOARD_FAB2(SCH_1):P3V3    I72 @BASEBOARD_FAB2_LIB.BASEBOARD_FAB2(SCH_1):PAGE104

Y6F1 OSC_C_6P10-156.25MHZ,OSC,G6383A
     1 FM_CPU0_STL_BRD_OSC_EN @BASEBOARD_FAB2_LIB.BASEBOARD_FAB2(SCH_1):FM_CPU0_STL_BRD_OSC_EN    I71 @BASEBOARD_FAB2_LIB.BASEBOARD_FAB2(SCH_1):PAGE104
     2 NC_CLK_156M_CPU0_OSC @BASEBOARD_FAB2_LIB.BASEBOARD_FAB2(SCH_1):NC_CLK_156M_CPU0_OSC    I71 @BASEBOARD_FAB2_LIB.BASEBOARD_FAB2(SCH_1):PAGE104
     3    GND @BASEBOARD_FAB2_LIB.BASEBOARD_FAB2(SCH_1):GND    I71 @BASEBOARD_FAB2_LIB.BASEBOARD_FAB2(SCH_1):PAGE104
     4 CLK_156M_OSC_BRD_CPU0_DP @BASEBOARD_FAB2_LIB.BASEBOARD_FAB2(SCH_1):CLK_156M_OSC_BRD_CPU0_DP    I71 @BASEBOARD_FAB2_LIB.BASEBOARD_FAB2(SCH_1):PAGE104
     5 CLK_156M_OSC_BRD_CPU0_DN @BASEBOARD_FAB2_LIB.BASEBOARD_FAB2(SCH_1):CLK_156M_OSC_BRD_CPU0_DN    I71 @BASEBOARD_FAB2_LIB.BASEBOARD_FAB2(SCH_1):PAGE104
     6   P3V3 @BASEBOARD_FAB2_LIB.BASEBOARD_FAB2(SCH_1):P3V3    I71 @BASEBOARD_FAB2_LIB.BASEBOARD_FAB2(SCH_1):PAGE104

Y7C1 CRYSTAL_2013-48.000MHZ,IC,D717A
     1 XTAL_PCH_48M_IN @BASEBOARD_FAB2_LIB.BASEBOARD_FAB2(SCH_1):XTAL_PCH_48M_IN    I49 @BASEBOARD_FAB2_LIB.BASEBOARD_FAB2(SCH_1):PAGE114
     3 XTAL_PCH_48M_OUT @BASEBOARD_FAB2_LIB.BASEBOARD_FAB2(SCH_1):XTAL_PCH_48M_OUT    I49 @BASEBOARD_FAB2_LIB.BASEBOARD_FAB2(SCH_1):PAGE114

Y7C2 CRYSTAL_SM-32.768KHZ,IC,C13544A
     1 XTAL_33K_RTC1 @BASEBOARD_FAB2_LIB.BASEBOARD_FAB2(SCH_1):XTAL_33K_RTC1    I55 @BASEBOARD_FAB2_LIB.BASEBOARD_FAB2(SCH_1):PAGE114
     2 XTAL_33K_RTC2 @BASEBOARD_FAB2_LIB.BASEBOARD_FAB2(SCH_1):XTAL_33K_RTC2    I55 @BASEBOARD_FAB2_LIB.BASEBOARD_FAB2(SCH_1):PAGE114

Y8C1 CRYSTAL_2013-25.000MHZ,IC,H196A
     1 XTAL_KR_25M_IN @BASEBOARD_FAB2_LIB.BASEBOARD_FAB2(SCH_1):XTAL_KR_25M_IN    I76 @BASEBOARD_FAB2_LIB.BASEBOARD_FAB2(SCH_1):PAGE118
     3 XTAL_KR_25M_OUT @BASEBOARD_FAB2_LIB.BASEBOARD_FAB2(SCH_1):XTAL_KR_25M_OUT    I76 @BASEBOARD_FAB2_LIB.BASEBOARD_FAB2(SCH_1):PAGE118

Y8F1 CRYSTAL_2013LF-25.000MHZ,IC,D7B
     1 XTAL_CK_MNG_IN @BASEBOARD_FAB2_LIB.BASEBOARD_FAB2(SCH_1):XTAL_CK_MNG_IN    I52 @BASEBOARD_FAB2_LIB.BASEBOARD_FAB2(SCH_1):PAGE101
     3 XTAL_CK_MNG_OUT @BASEBOARD_FAB2_LIB.BASEBOARD_FAB2(SCH_1):XTAL_CK_MNG_OUT    I52 @BASEBOARD_FAB2_LIB.BASEBOARD_FAB2(SCH_1):PAGE101

Y9E1 CRYSTAL_2013-25.000MHZ,IC,D717A
     1 XTAL_25MHZ_IN @BASEBOARD_FAB2_LIB.BASEBOARD_FAB2(SCH_1):XTAL_25MHZ_IN   I109 @BASEBOARD_FAB2_LIB.BASEBOARD_FAB2(SCH_1):PAGE139
     3 XTAL_25MHZ_OUT_R @BASEBOARD_FAB2_LIB.BASEBOARD_FAB2(SCH_1):XTAL_25MHZ_OUT_R   I109 @BASEBOARD_FAB2_LIB.BASEBOARD_FAB2(SCH_1):PAGE139

Y9F1 CRYSTAL_SM-24.000MHZ,IC,D95126A
     1 XTAL_24MHZ_PI7C9X1172_IN @BASEBOARD_FAB2_LIB.BASEBOARD_FAB2(SCH_1):XTAL_24MHZ_PI7C9X1172_IN    I19 @BASEBOARD_FAB2_LIB.BASEBOARD_FAB2(SCH_1):PAGE183
     2 XTAL_24MHZ_PI7C9X1172_OUT @BASEBOARD_FAB2_LIB.BASEBOARD_FAB2(SCH_1):XTAL_24MHZ_PI7C9X1172_OUT    I19 @BASEBOARD_FAB2_LIB.BASEBOARD_FAB2(SCH_1):PAGE183

Y9F2 OSC_C_SM4-24MHZ,OSC,D34520-021
     1 PU_24M_OSC_OE @BASEBOARD_FAB2_LIB.BASEBOARD_FAB2(SCH_1):PU_24M_OSC_OE     I8 @BASEBOARD_FAB2_LIB.BASEBOARD_FAB2(SCH_1):PAGE145
     2    GND @BASEBOARD_FAB2_LIB.BASEBOARD_FAB2(SCH_1):GND     I8 @BASEBOARD_FAB2_LIB.BASEBOARD_FAB2(SCH_1):PAGE145
     3 CLK_24M_BMC_CLKIN_R @BASEBOARD_FAB2_LIB.BASEBOARD_FAB2(SCH_1):CLK_24M_BMC_CLKIN_R     I8 @BASEBOARD_FAB2_LIB.BASEBOARD_FAB2(SCH_1):PAGE145
     4 P3V3_STBY @BASEBOARD_FAB2_LIB.BASEBOARD_FAB2(SCH_1):P3V3_STBY     I8 @BASEBOARD_FAB2_LIB.BASEBOARD_FAB2(SCH_1):PAGE145

END GLOBAL PART CROSS REFERENCE
